(kicad_pcb
	(version 20260206)
	(generator "pcbnew")
	(generator_version "10.0")
	(general
		(thickness 1.6)
		(legacy_teardrops no)
	)
	(paper "A4")
	(layers
		(0 "F.Cu" signal "TOP")
		(4 "In1.Cu" signal "GND1")
		(6 "In2.Cu" signal "IN1")
		(8 "In3.Cu" signal "VCC1")
		(10 "In4.Cu" signal "VCC2")
		(12 "In5.Cu" signal "GND2")
		(14 "In6.Cu" signal "IN2")
		(16 "In7.Cu" signal "IN3")
		(18 "In8.Cu" signal "GND3")
		(2 "B.Cu" signal "BOTTOM")
		(9 "F.Adhes" user "F.Adhesive")
		(11 "B.Adhes" user "B.Adhesive")
		(13 "F.Paste" user "Package Geometry/Pastemask Top")
		(15 "B.Paste" user "Package Geometry/Pastemask Bottom")
		(5 "F.SilkS" user "Ref Des/Silkscreen Top")
		(7 "B.SilkS" user "Ref Des/Silkscreen Bottom")
		(1 "F.Mask" user "Board Geometry/Soldermask Top")
		(3 "B.Mask" user "Board Geometry/Soldermask Bottom")
		(17 "Dwgs.User" user "User.Drawings")
		(19 "Cmts.User" user "User.Comments")
		(21 "Eco1.User" user "User.Eco1")
		(23 "Eco2.User" user "User.Eco2")
		(25 "Edge.Cuts" user "Board Geometry/Outline")
		(27 "Margin" user)
		(31 "F.CrtYd" user "Package Geometry/Place Bound Top")
		(29 "B.CrtYd" user "Package Geometry/Place Bound Bottom")
		(35 "F.Fab" user "Ref Des/Assembly Top")
		(33 "B.Fab" user "Ref Des/Assembly Bottom")
	)
	(setup
		(pad_to_mask_clearance 0)
		(allow_soldermask_bridges_in_footprints no)
		(tenting
			(front yes)
			(back yes)
		)
		(covering
			(front no)
			(back no)
		)
		(plugging
			(front no)
			(back no)
		)
		(capping no)
		(filling no)
		(pcbplotparams
			(layerselection 0x00000000_00000000_55555555_5755f5ff)
			(plot_on_all_layers_selection 0x00000000_00000000_00000000_00000000)
			(disableapertmacros no)
			(usegerberextensions no)
			(usegerberattributes yes)
			(usegerberadvancedattributes yes)
			(creategerberjobfile yes)
			(dashed_line_dash_ratio 12)
			(dashed_line_gap_ratio 3)
			(svgprecision 4)
			(plotframeref no)
			(mode 1)
			(useauxorigin no)
			(pdf_front_fp_property_popups yes)
			(pdf_back_fp_property_popups yes)
			(pdf_metadata yes)
			(pdf_single_document no)
			(dxfpolygonmode yes)
			(dxfimperialunits yes)
			(dxfusepcbnewfont yes)
			(psnegative no)
			(psa4output no)
			(plot_black_and_white yes)
			(sketchpadsonfab no)
			(plotpadnumbers no)
			(hidednponfab no)
			(sketchdnponfab yes)
			(crossoutdnponfab yes)
			(subtractmaskfromsilk no)
			(outputformat 1)
			(mirror no)
			(drillshape 1)
			(scaleselection 1)
			(outputdirectory "")
		)
	)
	(footprint ""
		(layer "F.Cu")
		(at 35.669728 -78.877922)
		(property "Reference" "R43"
			(at -4.58851 -0.106934 0)
			(unlocked yes)
			(layer "F.SilkS")
			(effects
				(font
					(size 0.7874 0.5842)
					(thickness 0.1524)
				)
				(justify left)
			)
		)
		(property "Value" ""
			(at 0 0 0)
			(layer "F.Fab")
			(effects
				(font
					(size 1.27 1.27)
				)
			)
		)
		(duplicate_pad_numbers_are_jumpers no)
		(fp_line
			(start -0.7874 -0.4064)
			(end 0.7874 -0.4064)
			(stroke
				(width 0.1524)
				(type default)
			)
			(layer "F.SilkS")
		)
		(fp_line
			(start -0.7874 0.4064)
			(end -0.7874 -0.4064)
			(stroke
				(width 0.1524)
				(type default)
			)
			(layer "F.SilkS")
		)
		(fp_line
			(start 0.7874 -0.4064)
			(end 0.7874 0.4064)
			(stroke
				(width 0.1524)
				(type default)
			)
			(layer "F.SilkS")
		)
		(fp_line
			(start 0.7874 0.4064)
			(end -0.7874 0.4064)
			(stroke
				(width 0.1524)
				(type default)
			)
			(layer "F.SilkS")
		)
		(fp_poly
			(pts
				(xy -0.508 0.2794) (xy -0.508 0.2286) (xy -0.635 0.2286) (xy -0.635 -0.254) (xy -0.5334 -0.254)
				(xy -0.5334 -0.2794) (xy 0.5334 -0.2794) (xy 0.5334 -0.254) (xy 0.635 -0.254) (xy 0.635 0.254) (xy 0.5334 0.254)
				(xy 0.5334 0.2794)
			)
			(stroke
				(width 0)
				(type default)
			)
			(fill no)
			(layer "F.CrtYd")
		)
		(pad "1" smd rect
			(at 0.40005 0)
			(size 0.4572 0.508)
			(layers "F.Cu" "F.Mask" "F.Paste")
			(net "PD_CPU_NODE1_RP2_PERP")
		)
		(pad "2" smd rect
			(at -0.40005 0)
			(size 0.4572 0.508)
			(layers "F.Cu" "F.Mask" "F.Paste")
			(net "GND")
		)
	)
	(footprint ""
		(layer "F.Cu")
		(at 149.411944 -44.680124)
		(property "Reference" "R1010"
			(at -2.3368 -2.962148 0)
			(unlocked yes)
			(layer "F.SilkS")
			(effects
				(font
					(size 0.7874 0.5842)
					(thickness 0.1524)
				)
				(justify left)
			)
		)
		(property "Value" ""
			(at 0 0 0)
			(layer "F.Fab")
			(effects
				(font
					(size 1.27 1.27)
				)
			)
		)
		(duplicate_pad_numbers_are_jumpers no)
		(fp_line
			(start -0.7874 -0.4064)
			(end 0.7874 -0.4064)
			(stroke
				(width 0.1524)
				(type default)
			)
			(layer "F.SilkS")
		)
		(fp_line
			(start -0.7874 0.4064)
			(end -0.7874 -0.4064)
			(stroke
				(width 0.1524)
				(type default)
			)
			(layer "F.SilkS")
		)
		(fp_line
			(start 0.7874 -0.4064)
			(end 0.7874 0.4064)
			(stroke
				(width 0.1524)
				(type default)
			)
			(layer "F.SilkS")
		)
		(fp_line
			(start 0.7874 0.4064)
			(end -0.7874 0.4064)
			(stroke
				(width 0.1524)
				(type default)
			)
			(layer "F.SilkS")
		)
		(fp_poly
			(pts
				(xy -0.508 0.2794) (xy -0.508 0.2286) (xy -0.635 0.2286) (xy -0.635 -0.254) (xy -0.5334 -0.254)
				(xy -0.5334 -0.2794) (xy 0.5334 -0.2794) (xy 0.5334 -0.254) (xy 0.635 -0.254) (xy 0.635 0.254) (xy 0.5334 0.254)
				(xy 0.5334 0.2794)
			)
			(stroke
				(width 0)
				(type default)
			)
			(fill no)
			(layer "F.CrtYd")
		)
		(pad "1" smd rect
			(at 0.40005 0)
			(size 0.4572 0.508)
			(layers "F.Cu" "F.Mask" "F.Paste")
			(net "GND")
		)
		(pad "2" smd rect
			(at -0.40005 0)
			(size 0.4572 0.508)
			(layers "F.Cu" "F.Mask" "F.Paste")
			(net "UART_TX_P1")
		)
	)
	(footprint ""
		(layer "F.Cu")
		(at 54.344062 -151.627078)
		(property "Reference" "C392"
			(at -2.298192 -2.007362 0)
			(unlocked yes)
			(layer "F.SilkS")
			(effects
				(font
					(size 0.7874 0.5842)
					(thickness 0.1524)
				)
				(justify left)
			)
		)
		(property "Value" ""
			(at 0 0 0)
			(layer "F.Fab")
			(effects
				(font
					(size 1.27 1.27)
				)
			)
		)
		(duplicate_pad_numbers_are_jumpers no)
		(fp_line
			(start -0.7874 -0.4064)
			(end 0.7874 -0.4064)
			(stroke
				(width 0.1524)
				(type default)
			)
			(layer "F.SilkS")
		)
		(fp_line
			(start -0.7874 0.4064)
			(end -0.7874 -0.4064)
			(stroke
				(width 0.1524)
				(type default)
			)
			(layer "F.SilkS")
		)
		(fp_line
			(start 0 0.381)
			(end 0 -0.381)
			(stroke
				(width 0.1524)
				(type default)
			)
			(layer "F.SilkS")
		)
		(fp_line
			(start 0.7874 -0.4064)
			(end 0.7874 0.4064)
			(stroke
				(width 0.1524)
				(type default)
			)
			(layer "F.SilkS")
		)
		(fp_line
			(start 0.7874 0.4064)
			(end -0.7874 0.4064)
			(stroke
				(width 0.1524)
				(type default)
			)
			(layer "F.SilkS")
		)
		(fp_poly
			(pts
				(xy -0.5334 0.254) (xy -0.635 0.254) (xy -0.635 0.2286) (xy -0.635 -0.254) (xy -0.5334 -0.254) (xy -0.5334 -0.2794)
				(xy 0.5334 -0.2794) (xy 0.5334 -0.254) (xy 0.635 -0.254) (xy 0.635 0.254) (xy 0.5334 0.254) (xy 0.5334 0.2794)
				(xy -0.508 0.2794) (xy -0.5334 0.2794)
			)
			(stroke
				(width 0)
				(type default)
			)
			(fill no)
			(layer "F.CrtYd")
		)
		(pad "1" smd rect
			(at 0.40005 0)
			(size 0.4572 0.508)
			(layers "F.Cu" "F.Mask" "F.Paste")
			(net "P2E_CPU_NIC1_NODE1_RX_DN")
		)
		(pad "2" smd rect
			(at -0.40005 0)
			(size 0.4572 0.508)
			(layers "F.Cu" "F.Mask" "F.Paste")
			(net "PCIE_LAN1_RX_C_DN")
		)
	)
	(footprint ""
		(layer "F.Cu")
		(at 69.084698 -17.679416 90)
		(property "Reference" "C161"
			(at -2.143252 -2.04597 90)
			(unlocked yes)
			(layer "F.SilkS")
			(effects
				(font
					(size 0.7874 0.5842)
					(thickness 0.1524)
				)
				(justify left)
			)
		)
		(property "Value" ""
			(at 0 0 90)
			(layer "F.Fab")
			(effects
				(font
					(size 1.27 1.27)
				)
			)
		)
		(duplicate_pad_numbers_are_jumpers no)
		(fp_line
			(start 0.7874 -0.4064)
			(end 0.7874 0.4064)
			(stroke
				(width 0.1524)
				(type default)
			)
			(layer "F.SilkS")
		)
		(fp_line
			(start -0.7874 -0.4064)
			(end 0.7874 -0.4064)
			(stroke
				(width 0.1524)
				(type default)
			)
			(layer "F.SilkS")
		)
		(fp_line
			(start 0 0.381)
			(end 0 -0.381)
			(stroke
				(width 0.1524)
				(type default)
			)
			(layer "F.SilkS")
		)
		(fp_line
			(start 0.7874 0.4064)
			(end -0.7874 0.4064)
			(stroke
				(width 0.1524)
				(type default)
			)
			(layer "F.SilkS")
		)
		(fp_line
			(start -0.7874 0.4064)
			(end -0.7874 -0.4064)
			(stroke
				(width 0.1524)
				(type default)
			)
			(layer "F.SilkS")
		)
		(fp_poly
			(pts
				(xy -0.5334 0.254) (xy -0.635 0.254) (xy -0.635 0.2286) (xy -0.635 -0.254) (xy -0.5334 -0.254) (xy -0.5334 -0.2794)
				(xy 0.5334 -0.2794) (xy 0.5334 -0.254) (xy 0.635 -0.254) (xy 0.635 0.254) (xy 0.5334 0.254) (xy 0.5334 0.2794)
				(xy -0.508 0.2794) (xy -0.5334 0.2794)
			)
			(stroke
				(width 0)
				(type default)
			)
			(fill no)
			(layer "F.CrtYd")
		)
		(pad "1" smd rect
			(at 0.40005 0 90)
			(size 0.4572 0.508)
			(layers "F.Cu" "F.Mask" "F.Paste")
			(net "PV_VDDR_NODE1")
		)
		(pad "2" smd rect
			(at -0.40005 0 90)
			(size 0.4572 0.508)
			(layers "F.Cu" "F.Mask" "F.Paste")
			(net "GND")
		)
	)
	(footprint ""
		(layer "F.Cu")
		(at 89.39276 -185.205624 90)
		(property "Reference" "C708"
			(at 4.198112 -2.154682 90)
			(unlocked yes)
			(layer "F.SilkS")
			(effects
				(font
					(size 0.7874 0.5842)
					(thickness 0.1524)
				)
				(justify left)
			)
		)
		(property "Value" ""
			(at 0 0 90)
			(layer "F.Fab")
			(effects
				(font
					(size 1.27 1.27)
				)
			)
		)
		(duplicate_pad_numbers_are_jumpers no)
		(fp_line
			(start 0.7874 -0.4064)
			(end 0.7874 0.4064)
			(stroke
				(width 0.1524)
				(type default)
			)
			(layer "F.SilkS")
		)
		(fp_line
			(start -0.7874 -0.4064)
			(end 0.7874 -0.4064)
			(stroke
				(width 0.1524)
				(type default)
			)
			(layer "F.SilkS")
		)
		(fp_line
			(start 0 0.381)
			(end 0 -0.381)
			(stroke
				(width 0.1524)
				(type default)
			)
			(layer "F.SilkS")
		)
		(fp_line
			(start 0.7874 0.4064)
			(end -0.7874 0.4064)
			(stroke
				(width 0.1524)
				(type default)
			)
			(layer "F.SilkS")
		)
		(fp_line
			(start -0.7874 0.4064)
			(end -0.7874 -0.4064)
			(stroke
				(width 0.1524)
				(type default)
			)
			(layer "F.SilkS")
		)
		(fp_poly
			(pts
				(xy -0.5334 0.254) (xy -0.635 0.254) (xy -0.635 0.2286) (xy -0.635 -0.254) (xy -0.5334 -0.254) (xy -0.5334 -0.2794)
				(xy 0.5334 -0.2794) (xy 0.5334 -0.254) (xy 0.635 -0.254) (xy 0.635 0.254) (xy 0.5334 0.254) (xy 0.5334 0.2794)
				(xy -0.508 0.2794) (xy -0.5334 0.2794)
			)
			(stroke
				(width 0)
				(type default)
			)
			(fill no)
			(layer "F.CrtYd")
		)
		(pad "1" smd rect
			(at 0.40005 0 90)
			(size 0.4572 0.508)
			(layers "F.Cu" "F.Mask" "F.Paste")
			(net "UART_T6_NODE3_RXD")
		)
		(pad "2" smd rect
			(at -0.40005 0 90)
			(size 0.4572 0.508)
			(layers "F.Cu" "F.Mask" "F.Paste")
			(net "GND")
		)
	)
	(footprint ""
		(layer "F.Cu")
		(at 73.442068 -94.131892 -90)
		(property "Reference" "R151"
			(at 55.53329 -24.083264 90)
			(unlocked yes)
			(layer "F.SilkS")
			(effects
				(font
					(size 0.7874 0.5842)
					(thickness 0.1524)
				)
				(justify left)
			)
		)
		(property "Value" ""
			(at 0 0 270)
			(layer "F.Fab")
			(effects
				(font
					(size 1.27 1.27)
				)
			)
		)
		(duplicate_pad_numbers_are_jumpers no)
		(fp_line
			(start -0.7874 0.4064)
			(end -0.7874 -0.4064)
			(stroke
				(width 0.1524)
				(type default)
			)
			(layer "F.SilkS")
		)
		(fp_line
			(start 0.7874 0.4064)
			(end -0.7874 0.4064)
			(stroke
				(width 0.1524)
				(type default)
			)
			(layer "F.SilkS")
		)
		(fp_line
			(start -0.7874 -0.4064)
			(end 0.7874 -0.4064)
			(stroke
				(width 0.1524)
				(type default)
			)
			(layer "F.SilkS")
		)
		(fp_line
			(start 0.7874 -0.4064)
			(end 0.7874 0.4064)
			(stroke
				(width 0.1524)
				(type default)
			)
			(layer "F.SilkS")
		)
		(fp_poly
			(pts
				(xy -0.508 0.2794) (xy -0.508 0.2286) (xy -0.635 0.2286) (xy -0.635 -0.254) (xy -0.5334 -0.254)
				(xy -0.5334 -0.2794) (xy 0.5334 -0.2794) (xy 0.5334 -0.254) (xy 0.635 -0.254) (xy 0.635 0.254) (xy 0.5334 0.254)
				(xy 0.5334 0.2794)
			)
			(stroke
				(width 0)
				(type default)
			)
			(fill no)
			(layer "F.CrtYd")
		)
		(pad "1" smd rect
			(at 0.40005 0 270)
			(size 0.4572 0.508)
			(layers "F.Cu" "F.Mask" "F.Paste")
			(net "PD_CPU_NODE1_BOOTDEVSEL")
		)
		(pad "2" smd rect
			(at -0.40005 0 270)
			(size 0.4572 0.508)
			(layers "F.Cu" "F.Mask" "F.Paste")
			(net "P3V3_NODE1")
		)
	)
	(footprint ""
		(layer "F.Cu")
		(at 135.109966 -55.324502 90)
		(property "Reference" "R1134"
			(at 0.936498 -0.285496 90)
			(unlocked yes)
			(layer "F.SilkS")
			(effects
				(font
					(size 0.7874 0.5842)
					(thickness 0.1524)
				)
				(justify left)
			)
		)
		(property "Value" ""
			(at 0 0 90)
			(layer "F.Fab")
			(effects
				(font
					(size 1.27 1.27)
				)
			)
		)
		(duplicate_pad_numbers_are_jumpers no)
		(fp_line
			(start 0.7874 -0.4064)
			(end 0.7874 0.4064)
			(stroke
				(width 0.1524)
				(type default)
			)
			(layer "F.SilkS")
		)
		(fp_line
			(start -0.7874 -0.4064)
			(end 0.7874 -0.4064)
			(stroke
				(width 0.1524)
				(type default)
			)
			(layer "F.SilkS")
		)
		(fp_line
			(start 0.7874 0.4064)
			(end -0.7874 0.4064)
			(stroke
				(width 0.1524)
				(type default)
			)
			(layer "F.SilkS")
		)
		(fp_line
			(start -0.7874 0.4064)
			(end -0.7874 -0.4064)
			(stroke
				(width 0.1524)
				(type default)
			)
			(layer "F.SilkS")
		)
		(fp_poly
			(pts
				(xy -0.508 0.2794) (xy -0.508 0.2286) (xy -0.635 0.2286) (xy -0.635 -0.254) (xy -0.5334 -0.254)
				(xy -0.5334 -0.2794) (xy 0.5334 -0.2794) (xy 0.5334 -0.254) (xy 0.635 -0.254) (xy 0.635 0.254) (xy 0.5334 0.254)
				(xy 0.5334 0.2794)
			)
			(stroke
				(width 0)
				(type default)
			)
			(fill no)
			(layer "F.CrtYd")
		)
		(pad "1" smd rect
			(at 0.40005 0 90)
			(size 0.4572 0.508)
			(layers "F.Cu" "F.Mask" "F.Paste")
			(net "P5V_NODE1")
		)
		(pad "2" smd rect
			(at -0.40005 0 90)
			(size 0.4572 0.508)
			(layers "F.Cu" "F.Mask" "F.Paste")
			(net "UART_TX_P3_R")
		)
	)
	(footprint ""
		(layer "F.Cu")
		(at 88.77046 -15.804388 90)
		(property "Reference" "R194"
			(at -1.882394 1.419606 90)
			(unlocked yes)
			(layer "F.SilkS")
			(effects
				(font
					(size 0.7874 0.5842)
					(thickness 0.1524)
				)
				(justify left)
			)
		)
		(property "Value" ""
			(at 0 0 90)
			(layer "F.Fab")
			(effects
				(font
					(size 1.27 1.27)
				)
			)
		)
		(duplicate_pad_numbers_are_jumpers no)
		(fp_line
			(start 0.7874 -0.406146)
			(end 0.7874 0.406146)
			(stroke
				(width 0.1524)
				(type default)
			)
			(layer "F.SilkS")
		)
		(fp_line
			(start -0.7874 -0.406146)
			(end 0.7874 -0.406146)
			(stroke
				(width 0.1524)
				(type default)
			)
			(layer "F.SilkS")
		)
		(fp_line
			(start 0.7874 0.406146)
			(end -0.7874 0.406146)
			(stroke
				(width 0.1524)
				(type default)
			)
			(layer "F.SilkS")
		)
		(fp_line
			(start -0.7874 0.406146)
			(end -0.7874 -0.406146)
			(stroke
				(width 0.1524)
				(type default)
			)
			(layer "F.SilkS")
		)
		(fp_poly
			(pts
				(xy -0.508 0.2794) (xy -0.508 0.2286) (xy -0.635 0.2286) (xy -0.635 -0.254) (xy -0.5334 -0.254)
				(xy -0.5334 -0.2794) (xy 0.5334 -0.2794) (xy 0.5334 -0.254) (xy 0.635 -0.254) (xy 0.635 0.254) (xy 0.5334 0.254)
				(xy 0.5334 0.2794)
			)
			(stroke
				(width 0)
				(type default)
			)
			(fill no)
			(layer "F.CrtYd")
		)
		(pad "1" smd rect
			(at 0.40005 0 90)
			(size 0.4572 0.508)
			(layers "F.Cu" "F.Mask" "F.Paste")
			(net "LPC_CPU_NODE1_FRAME_L")
		)
		(pad "2" smd rect
			(at -0.40005 0 90)
			(size 0.4572 0.508)
			(layers "F.Cu" "F.Mask" "F.Paste")
			(net "N20512383")
		)
	)
	(footprint ""
		(layer "F.Cu")
		(at 88.11641 -120.891554 -90)
		(property "Reference" "U115"
			(at 6.110986 5.566664 90)
			(unlocked yes)
			(layer "F.SilkS")
			(effects
				(font
					(size 0.7874 0.5842)
					(thickness 0.1524)
				)
				(justify left)
			)
		)
		(property "Value" ""
			(at 0 0 270)
			(layer "F.Fab")
			(effects
				(font
					(size 1.27 1.27)
				)
			)
		)
		(duplicate_pad_numbers_are_jumpers no)
		(fp_line
			(start -0.750062 5.1816)
			(end -0.750062 5.969)
			(stroke
				(width 0.1524)
				(type default)
			)
			(layer "F.SilkS")
		)
		(fp_line
			(start 1.75006 5.1816)
			(end 1.75006 6.5278)
			(stroke
				(width 0.1524)
				(type default)
			)
			(layer "F.SilkS")
		)
		(fp_line
			(start -2.794 3.429)
			(end 3.429 3.429)
			(stroke
				(width 0.1524)
				(type default)
			)
			(layer "F.SilkS")
		)
		(fp_line
			(start 3.429 3.429)
			(end 3.429 -3.429)
			(stroke
				(width 0.1524)
				(type default)
			)
			(layer "F.SilkS")
		)
		(fp_line
			(start -3.429 2.794)
			(end -2.794 3.429)
			(stroke
				(width 0.1524)
				(type default)
			)
			(layer "F.SilkS")
		)
		(fp_line
			(start 5.249926 1.7272)
			(end 6.249924 1.7272)
			(stroke
				(width 0.1524)
				(type default)
			)
			(layer "F.SilkS")
		)
		(fp_line
			(start -6.249924 1.2192)
			(end -5.249926 1.2192)
			(stroke
				(width 0.1524)
				(type default)
			)
			(layer "F.SilkS")
		)
		(fp_line
			(start 5.249926 -0.6858)
			(end 6.75005 -0.6858)
			(stroke
				(width 0.1524)
				(type default)
			)
			(layer "F.SilkS")
		)
		(fp_line
			(start -6.75005 -1.2192)
			(end -5.249926 -1.2192)
			(stroke
				(width 0.1524)
				(type default)
			)
			(layer "F.SilkS")
		)
		(fp_line
			(start -3.429 -3.429)
			(end -3.429 2.794)
			(stroke
				(width 0.1524)
				(type default)
			)
			(layer "F.SilkS")
		)
		(fp_line
			(start 3.429 -3.429)
			(end -3.429 -3.429)
			(stroke
				(width 0.1524)
				(type default)
			)
			(layer "F.SilkS")
		)
		(fp_line
			(start 0.249936 -5.1816)
			(end 0.249936 -6.3246)
			(stroke
				(width 0.1524)
				(type default)
			)
			(layer "F.SilkS")
		)
		(fp_line
			(start 2.750058 -5.1816)
			(end 2.750058 -5.8928)
			(stroke
				(width 0.1524)
				(type default)
			)
			(layer "F.SilkS")
		)
		(fp_line
			(start -2.249932 -5.207)
			(end -2.249932 -5.9182)
			(stroke
				(width 0.1524)
				(type default)
			)
			(layer "F.SilkS")
		)
		(fp_poly
			(pts
				(xy -3.127248 4.51993) (xy -4.448048 4.08813) (xy -4.448048 4.92633)
			)
			(stroke
				(width 0)
				(type default)
			)
			(fill yes)
			(layer "F.SilkS")
		)
		(fp_poly
			(pts
				(xy -2.921 5.0038) (xy -2.921 3.6068) (xy -3.6068 3.6068) (xy -3.6068 2.921) (xy -5.0038 2.921)
				(xy -5.0038 -2.921) (xy -3.6068 -2.921) (xy -3.6068 -3.6068) (xy -2.921 -3.6068) (xy -2.921 -5.0038)
				(xy 2.921 -5.0038) (xy 2.921 -3.6068) (xy 3.6068 -3.6068) (xy 3.6068 -2.921) (xy 5.0038 -2.921)
				(xy 5.0038 2.921) (xy 3.6068 2.921) (xy 3.6068 3.6068) (xy 2.921 3.6068) (xy 2.921 5.0038)
			)
			(stroke
				(width 0)
				(type default)
			)
			(fill no)
			(layer "F.CrtYd")
		)
		(fp_text user "12"
			(at 3.953764 4.94411 0)
			(unlocked yes)
			(layer "F.SilkS")
			(effects
				(font
					(size 0.7874 0.5842)
					(thickness 0.1524)
				)
				(justify left)
			)
		)
		(fp_text user "48"
			(at -5.197348 4.64947 0)
			(unlocked yes)
			(layer "F.SilkS")
			(effects
				(font
					(size 0.7874 0.5842)
					(thickness 0.1524)
				)
				(justify left)
			)
		)
		(fp_text user "13"
			(at 6.45414 3.56235 0)
			(unlocked yes)
			(layer "F.SilkS")
			(effects
				(font
					(size 0.7874 0.5842)
					(thickness 0.1524)
				)
				(justify left)
			)
		)
		(fp_text user "24"
			(at 5.349748 -3.109214 0)
			(unlocked yes)
			(layer "F.SilkS")
			(effects
				(font
					(size 0.7874 0.5842)
					(thickness 0.1524)
				)
				(justify left)
			)
		)
		(fp_text user "37"
			(at -3.771646 -4.138422 90)
			(unlocked yes)
			(layer "F.SilkS")
			(effects
				(font
					(size 0.7874 0.5842)
					(thickness 0.1524)
				)
				(justify left)
			)
		)
		(fp_text user "25"
			(at 4.545838 -4.76377 0)
			(unlocked yes)
			(layer "F.SilkS")
			(effects
				(font
					(size 0.7874 0.5842)
					(thickness 0.1524)
				)
				(justify left)
			)
		)
		(fp_text user "36"
			(at -2.588006 -5.626862 90)
			(unlocked yes)
			(layer "F.SilkS")
			(effects
				(font
					(size 0.7874 0.5842)
					(thickness 0.1524)
				)
				(justify left)
			)
		)
		(pad "1" smd rect
			(at -2.750058 4.299966 270)
			(size 0.2286 1.397)
			(layers "F.Cu" "F.Mask" "F.Paste")
			(net "N53313325")
		)
		(pad "2" smd rect
			(at -2.249932 4.299966 270)
			(size 0.2286 1.397)
			(layers "F.Cu" "F.Mask" "F.Paste")
			(net "PORT80_LOUT0")
		)
		(pad "3" smd rect
			(at -1.75006 4.299966 270)
			(size 0.2286 1.397)
			(layers "F.Cu" "F.Mask" "F.Paste")
			(net "LPC_CPU_NODE1_LAD3")
		)
		(pad "4" smd rect
			(at -1.249934 4.299966 270)
			(size 0.2286 1.397)
			(layers "F.Cu" "F.Mask" "F.Paste")
			(net "LPC_CPU_NODE1_LAD2")
		)
		(pad "5" smd rect
			(at -0.750062 4.299966 270)
			(size 0.2286 1.397)
			(layers "F.Cu" "F.Mask" "F.Paste")
			(net "GND")
		)
		(pad "6" smd rect
			(at -0.249936 4.299966 270)
			(size 0.2286 1.397)
			(layers "F.Cu" "F.Mask" "F.Paste")
			(net "P3V3_NODE1")
		)
		(pad "7" smd rect
			(at 0.249936 4.299966 270)
			(size 0.2286 1.397)
			(layers "F.Cu" "F.Mask" "F.Paste")
			(net "Net_2323")
		)
		(pad "8" smd rect
			(at 0.750062 4.299966 270)
			(size 0.2286 1.397)
			(layers "F.Cu" "F.Mask" "F.Paste")
			(net "Net_2322")
		)
		(pad "9" smd rect
			(at 1.249934 4.299966 270)
			(size 0.2286 1.397)
			(layers "F.Cu" "F.Mask" "F.Paste")
			(net "Net_2329")
		)
		(pad "10" smd rect
			(at 1.75006 4.299966 270)
			(size 0.2286 1.397)
			(layers "F.Cu" "F.Mask" "F.Paste")
			(net "Net_2328")
		)
		(pad "11" smd rect
			(at 2.249932 4.299966 270)
			(size 0.2286 1.397)
			(layers "F.Cu" "F.Mask" "F.Paste")
			(net "N53313175")
		)
		(pad "12" smd rect
			(at 2.750058 4.299966 270)
			(size 0.2286 1.397)
			(layers "F.Cu" "F.Mask" "F.Paste")
			(net "P3V3_NODE1")
		)
		(pad "13" smd rect
			(at 4.299966 2.750058 180)
			(size 0.2286 1.397)
			(layers "F.Cu" "F.Mask" "F.Paste")
			(net "GND")
		)
		(pad "14" smd rect
			(at 4.299966 2.249932 180)
			(size 0.2286 1.397)
			(layers "F.Cu" "F.Mask" "F.Paste")
			(net "Net_2327")
		)
		(pad "15" smd rect
			(at 4.299966 1.75006 180)
			(size 0.2286 1.397)
			(layers "F.Cu" "F.Mask" "F.Paste")
			(net "Net_2326")
		)
		(pad "16" smd rect
			(at 4.299966 1.249934 180)
			(size 0.2286 1.397)
			(layers "F.Cu" "F.Mask" "F.Paste")
			(net "Net_2325")
		)
		(pad "17" smd rect
			(at 4.299966 0.750062 180)
			(size 0.2286 1.397)
			(layers "F.Cu" "F.Mask" "F.Paste")
			(net "Net_2324")
		)
		(pad "18" smd rect
			(at 4.299966 0.249936 180)
			(size 0.2286 1.397)
			(layers "F.Cu" "F.Mask" "F.Paste")
			(net "FM_CPLD_NODE1_LPCRST_L")
		)
		(pad "19" smd rect
			(at 4.299966 -0.249936 180)
			(size 0.2286 1.397)
			(layers "F.Cu" "F.Mask" "F.Paste")
			(net "LPC_CPU_NODE1_LAD1")
		)
		(pad "20" smd rect
			(at 4.299966 -0.750062 180)
			(size 0.2286 1.397)
			(layers "F.Cu" "F.Mask" "F.Paste")
			(net "LPC_CPU_NODE1_FRAME_L")
		)
		(pad "21" smd rect
			(at 4.299966 -1.249934 180)
			(size 0.2286 1.397)
			(layers "F.Cu" "F.Mask" "F.Paste")
			(net "Net_2321")
		)
		(pad "22" smd rect
			(at 4.299966 -1.75006 180)
			(size 0.2286 1.397)
			(layers "F.Cu" "F.Mask" "F.Paste")
			(net "PORT80_LOUT6")
		)
		(pad "23" smd rect
			(at 4.299966 -2.249932 180)
			(size 0.2286 1.397)
			(layers "F.Cu" "F.Mask" "F.Paste")
			(net "Net_2314")
		)
		(pad "24" smd rect
			(at 4.299966 -2.750058 180)
			(size 0.2286 1.397)
			(layers "F.Cu" "F.Mask" "F.Paste")
			(net "Net_2313")
		)
		(pad "25" smd rect
			(at 2.750058 -4.299966 270)
			(size 0.2286 1.397)
			(layers "F.Cu" "F.Mask" "F.Paste")
			(net "N53313289")
		)
		(pad "26" smd rect
			(at 2.249932 -4.299966 270)
			(size 0.2286 1.397)
			(layers "F.Cu" "F.Mask" "F.Paste")
			(net "PORT80_LOUT5")
		)
		(pad "27" smd rect
			(at 1.75006 -4.299966 270)
			(size 0.2286 1.397)
			(layers "F.Cu" "F.Mask" "F.Paste")
			(net "Net_2312")
		)
		(pad "28" smd rect
			(at 1.249934 -4.299966 270)
			(size 0.2286 1.397)
			(layers "F.Cu" "F.Mask" "F.Paste")
			(net "Net_2311")
		)
		(pad "29" smd rect
			(at 0.750062 -4.299966 270)
			(size 0.2286 1.397)
			(layers "F.Cu" "F.Mask" "F.Paste")
			(net "GND")
		)
		(pad "30" smd rect
			(at 0.249936 -4.299966 270)
			(size 0.2286 1.397)
			(layers "F.Cu" "F.Mask" "F.Paste")
			(net "P3V3_NODE1")
		)
		(pad "31" smd rect
			(at -0.249936 -4.299966 270)
			(size 0.2286 1.397)
			(layers "F.Cu" "F.Mask" "F.Paste")
			(net "Net_2310")
		)
		(pad "32" smd rect
			(at -0.750062 -4.299966 270)
			(size 0.2286 1.397)
			(layers "F.Cu" "F.Mask" "F.Paste")
			(net "Net_2309")
		)
		(pad "33" smd rect
			(at -1.249934 -4.299966 270)
			(size 0.2286 1.397)
			(layers "F.Cu" "F.Mask" "F.Paste")
			(net "Net_2320")
		)
		(pad "34" smd rect
			(at -1.75006 -4.299966 270)
			(size 0.2286 1.397)
			(layers "F.Cu" "F.Mask" "F.Paste")
			(net "Net_2319")
		)
		(pad "35" smd rect
			(at -2.249932 -4.299966 270)
			(size 0.2286 1.397)
			(layers "F.Cu" "F.Mask" "F.Paste")
			(net "N53313389")
		)
		(pad "36" smd rect
			(at -2.750058 -4.299966 270)
			(size 0.2286 1.397)
			(layers "F.Cu" "F.Mask" "F.Paste")
			(net "P3V3_NODE1")
		)
		(pad "37" smd rect
			(at -4.299966 -2.750058)
			(size 0.2286 1.397)
			(layers "F.Cu" "F.Mask" "F.Paste")
			(net "GND")
		)
		(pad "38" smd rect
			(at -4.299966 -2.249932)
			(size 0.2286 1.397)
			(layers "F.Cu" "F.Mask" "F.Paste")
			(net "Net_2318")
		)
		(pad "39" smd rect
			(at -4.299966 -1.75006)
			(size 0.2286 1.397)
			(layers "F.Cu" "F.Mask" "F.Paste")
			(net "Net_2317")
		)
		(pad "40" smd rect
			(at -4.299966 -1.249934)
			(size 0.2286 1.397)
			(layers "F.Cu" "F.Mask" "F.Paste")
			(net "Net_2316")
		)
		(pad "41" smd rect
			(at -4.299966 -0.750062)
			(size 0.2286 1.397)
			(layers "F.Cu" "F.Mask" "F.Paste")
			(net "Net_2315")
		)
		(pad "42" smd rect
			(at -4.299966 -0.249936)
			(size 0.2286 1.397)
			(layers "F.Cu" "F.Mask" "F.Paste")
			(net "LPC_CPU_NODE1_LAD0")
		)
		(pad "43" smd rect
			(at -4.299966 0.249936)
			(size 0.2286 1.397)
			(layers "F.Cu" "F.Mask" "F.Paste")
			(net "CLK_33M_PORT80")
		)
		(pad "44" smd rect
			(at -4.299966 0.750062)
			(size 0.2286 1.397)
			(layers "F.Cu" "F.Mask" "F.Paste")
			(net "PORT80_LOUT7")
		)
		(pad "45" smd rect
			(at -4.299966 1.249934)
			(size 0.2286 1.397)
			(layers "F.Cu" "F.Mask" "F.Paste")
			(net "PORT80_LOUT4")
		)
		(pad "46" smd rect
			(at -4.299966 1.75006)
			(size 0.2286 1.397)
			(layers "F.Cu" "F.Mask" "F.Paste")
			(net "PORT80_LOUT3")
		)
		(pad "47" smd rect
			(at -4.299966 2.249932)
			(size 0.2286 1.397)
			(layers "F.Cu" "F.Mask" "F.Paste")
			(net "PORT80_LOUT2")
		)
		(pad "48" smd rect
			(at -4.299966 2.750058)
			(size 0.2286 1.397)
			(layers "F.Cu" "F.Mask" "F.Paste")
			(net "PORT80_LOUT1")
		)
	)
	(footprint ""
		(layer "F.Cu")
		(at 107.65663 -140.347192 90)
		(property "Reference" "PC111"
			(at 2.62636 4.345432 90)
			(unlocked yes)
			(layer "F.SilkS")
			(effects
				(font
					(size 0.635 0.4064)
					(thickness 0.1524)
				)
				(justify left)
			)
		)
		(property "Value" ""
			(at 0 0 90)
			(layer "F.Fab")
			(effects
				(font
					(size 1.27 1.27)
				)
			)
		)
		(duplicate_pad_numbers_are_jumpers no)
		(fp_line
			(start 0.7874 -0.4064)
			(end 0.7874 0.4064)
			(stroke
				(width 0.1524)
				(type default)
			)
			(layer "F.SilkS")
		)
		(fp_line
			(start -0.7874 -0.4064)
			(end 0.7874 -0.4064)
			(stroke
				(width 0.1524)
				(type default)
			)
			(layer "F.SilkS")
		)
		(fp_line
			(start 0 0.381)
			(end 0 -0.381)
			(stroke
				(width 0.1524)
				(type default)
			)
			(layer "F.SilkS")
		)
		(fp_line
			(start 0.7874 0.4064)
			(end -0.7874 0.4064)
			(stroke
				(width 0.1524)
				(type default)
			)
			(layer "F.SilkS")
		)
		(fp_line
			(start -0.7874 0.4064)
			(end -0.7874 -0.4064)
			(stroke
				(width 0.1524)
				(type default)
			)
			(layer "F.SilkS")
		)
		(fp_poly
			(pts
				(xy -0.5334 0.254) (xy -0.635 0.254) (xy -0.635 0.2286) (xy -0.635 -0.254) (xy -0.5334 -0.254) (xy -0.5334 -0.2794)
				(xy 0.5334 -0.2794) (xy 0.5334 -0.254) (xy 0.635 -0.254) (xy 0.635 0.254) (xy 0.5334 0.254) (xy 0.5334 0.2794)
				(xy -0.508 0.2794) (xy -0.5334 0.2794)
			)
			(stroke
				(width 0)
				(type default)
			)
			(fill no)
			(layer "F.CrtYd")
		)
		(pad "1" smd rect
			(at 0.40005 0 90)
			(size 0.4572 0.508)
			(layers "F.Cu" "F.Mask" "F.Paste")
			(net "AGND_PVCCP_NODE1")
		)
		(pad "2" smd rect
			(at -0.40005 0 90)
			(size 0.4572 0.508)
			(layers "F.Cu" "F.Mask" "F.Paste")
			(net "VR_PVCCP_NODE1_TSEN")
		)
	)
	(footprint ""
		(layer "F.Cu")
		(at 22.537166 -135.941308)
		(property "Reference" "C433"
			(at -0.675386 2.27076 0)
			(unlocked yes)
			(layer "F.SilkS")
			(effects
				(font
					(size 0.7874 0.5842)
					(thickness 0.1524)
				)
			)
		)
		(property "Value" ""
			(at 0 0 0)
			(layer "F.Fab")
			(effects
				(font
					(size 1.27 1.27)
				)
			)
		)
		(duplicate_pad_numbers_are_jumpers no)
		(fp_line
			(start -1.2954 -0.5842)
			(end 1.2954 -0.5842)
			(stroke
				(width 0.1524)
				(type default)
			)
			(layer "F.SilkS")
		)
		(fp_line
			(start -1.2954 0.5842)
			(end -1.2954 -0.5842)
			(stroke
				(width 0.1524)
				(type default)
			)
			(layer "F.SilkS")
		)
		(fp_line
			(start 0 -0.5842)
			(end 0 0.5842)
			(stroke
				(width 0.1524)
				(type default)
			)
			(layer "F.SilkS")
		)
		(fp_line
			(start 1.2954 -0.5842)
			(end 1.2954 0.5842)
			(stroke
				(width 0.1524)
				(type default)
			)
			(layer "F.SilkS")
		)
		(fp_line
			(start 1.2954 0.5842)
			(end -1.2954 0.5842)
			(stroke
				(width 0.1524)
				(type default)
			)
			(layer "F.SilkS")
		)
		(fp_poly
			(pts
				(xy 0.8636 -0.4572) (xy 0.8636 -0.3556) (xy 1.143 -0.3556) (xy 1.143 0.3556) (xy 0.8636 0.3556)
				(xy 0.8636 0.4572) (xy -0.8636 0.4572) (xy -0.8636 0.3556) (xy -1.143 0.3556) (xy -1.143 -0.3556)
				(xy -0.8636 -0.3556) (xy -0.8636 -0.4572)
			)
			(stroke
				(width 0)
				(type default)
			)
			(fill no)
			(layer "F.CrtYd")
		)
		(fp_line
			(start -0.884936 -0.504952)
			(end 0.884936 -0.504952)
			(stroke
				(width 0.1)
				(type default)
			)
			(layer "F.Fab")
		)
		(fp_line
			(start -0.884936 0.504952)
			(end -0.884936 -0.504952)
			(stroke
				(width 0.1)
				(type default)
			)
			(layer "F.Fab")
		)
		(fp_line
			(start 0.884936 -0.504952)
			(end 0.884936 0.504952)
			(stroke
				(width 0.1)
				(type default)
			)
			(layer "F.Fab")
		)
		(fp_line
			(start 0.884936 0.504952)
			(end -0.884936 0.504952)
			(stroke
				(width 0.1)
				(type default)
			)
			(layer "F.Fab")
		)
		(pad "1" smd rect
			(at 0.7366 0 90)
			(size 0.7112 0.8128)
			(layers "F.Cu" "F.Mask" "F.Paste")
			(net "P1V9_LAN1")
		)
		(pad "2" smd rect
			(at -0.7366 0 90)
			(size 0.7112 0.8128)
			(layers "F.Cu" "F.Mask" "F.Paste")
			(net "GND")
		)
	)
	(footprint ""
		(layer "F.Cu")
		(at 171.151042 -135.24738)
		(property "Reference" "R1122"
			(at -2.942082 -9.407398 0)
			(unlocked yes)
			(layer "F.SilkS")
			(effects
				(font
					(size 0.7874 0.5842)
					(thickness 0.1524)
				)
				(justify left)
			)
		)
		(property "Value" ""
			(at 0 0 0)
			(layer "F.Fab")
			(effects
				(font
					(size 1.27 1.27)
				)
			)
		)
		(duplicate_pad_numbers_are_jumpers no)
		(fp_line
			(start -0.7874 -0.4064)
			(end 0.7874 -0.4064)
			(stroke
				(width 0.1524)
				(type default)
			)
			(layer "F.SilkS")
		)
		(fp_line
			(start -0.7874 0.4064)
			(end -0.7874 -0.4064)
			(stroke
				(width 0.1524)
				(type default)
			)
			(layer "F.SilkS")
		)
		(fp_line
			(start 0.7874 -0.4064)
			(end 0.7874 0.4064)
			(stroke
				(width 0.1524)
				(type default)
			)
			(layer "F.SilkS")
		)
		(fp_line
			(start 0.7874 0.4064)
			(end -0.7874 0.4064)
			(stroke
				(width 0.1524)
				(type default)
			)
			(layer "F.SilkS")
		)
		(fp_poly
			(pts
				(xy -0.508 0.2794) (xy -0.508 0.2286) (xy -0.635 0.2286) (xy -0.635 -0.254) (xy -0.5334 -0.254)
				(xy -0.5334 -0.2794) (xy 0.5334 -0.2794) (xy 0.5334 -0.254) (xy 0.635 -0.254) (xy 0.635 0.254) (xy 0.5334 0.254)
				(xy 0.5334 0.2794)
			)
			(stroke
				(width 0)
				(type default)
			)
			(fill no)
			(layer "F.CrtYd")
		)
		(pad "1" smd rect
			(at 0.40005 0)
			(size 0.4572 0.508)
			(layers "F.Cu" "F.Mask" "F.Paste")
			(net "N41777080")
		)
		(pad "2" smd rect
			(at -0.40005 0)
			(size 0.4572 0.508)
			(layers "F.Cu" "F.Mask" "F.Paste")
			(net "P1V05_NODE1")
		)
	)
	(footprint ""
		(layer "F.Cu")
		(at 83.702906 -96.604836)
		(property "Reference" "C841"
			(at 3.238754 2.231136 0)
			(unlocked yes)
			(layer "F.SilkS")
			(effects
				(font
					(size 0.7874 0.5842)
					(thickness 0.1524)
				)
			)
		)
		(property "Value" ""
			(at 0 0 0)
			(layer "F.Fab")
			(effects
				(font
					(size 1.27 1.27)
				)
			)
		)
		(duplicate_pad_numbers_are_jumpers no)
		(fp_line
			(start -1.2954 -0.5842)
			(end 1.2954 -0.5842)
			(stroke
				(width 0.1524)
				(type default)
			)
			(layer "F.SilkS")
		)
		(fp_line
			(start -1.2954 0.5842)
			(end -1.2954 -0.5842)
			(stroke
				(width 0.1524)
				(type default)
			)
			(layer "F.SilkS")
		)
		(fp_line
			(start 0 -0.5842)
			(end 0 0.5842)
			(stroke
				(width 0.1524)
				(type default)
			)
			(layer "F.SilkS")
		)
		(fp_line
			(start 1.2954 -0.5842)
			(end 1.2954 0.5842)
			(stroke
				(width 0.1524)
				(type default)
			)
			(layer "F.SilkS")
		)
		(fp_line
			(start 1.2954 0.5842)
			(end -1.2954 0.5842)
			(stroke
				(width 0.1524)
				(type default)
			)
			(layer "F.SilkS")
		)
		(fp_poly
			(pts
				(xy 0.8636 -0.4572) (xy 0.8636 -0.3556) (xy 1.143 -0.3556) (xy 1.143 0.3556) (xy 0.8636 0.3556)
				(xy 0.8636 0.4572) (xy -0.8636 0.4572) (xy -0.8636 0.3556) (xy -1.143 0.3556) (xy -1.143 -0.3556)
				(xy -0.8636 -0.3556) (xy -0.8636 -0.4572)
			)
			(stroke
				(width 0)
				(type default)
			)
			(fill no)
			(layer "F.CrtYd")
		)
		(fp_line
			(start -0.884936 -0.504952)
			(end 0.884936 -0.504952)
			(stroke
				(width 0.1)
				(type default)
			)
			(layer "F.Fab")
		)
		(fp_line
			(start -0.884936 0.504952)
			(end -0.884936 -0.504952)
			(stroke
				(width 0.1)
				(type default)
			)
			(layer "F.Fab")
		)
		(fp_line
			(start 0.884936 -0.504952)
			(end 0.884936 0.504952)
			(stroke
				(width 0.1)
				(type default)
			)
			(layer "F.Fab")
		)
		(fp_line
			(start 0.884936 0.504952)
			(end -0.884936 0.504952)
			(stroke
				(width 0.1)
				(type default)
			)
			(layer "F.Fab")
		)
		(pad "1" smd rect
			(at 0.7366 0 90)
			(size 0.7112 0.8128)
			(layers "F.Cu" "F.Mask" "F.Paste")
			(net "FM_CPLD_NODE1_P3V3_SUS_EN_LV")
		)
		(pad "2" smd rect
			(at -0.7366 0 90)
			(size 0.7112 0.8128)
			(layers "F.Cu" "F.Mask" "F.Paste")
			(net "P3V3_SUS_NODE1")
		)
	)
	(footprint ""
		(layer "F.Cu")
		(at 88.232488 -155.705302)
		(property "Reference" "PC37"
			(at -1.467104 5.634228 0)
			(unlocked yes)
			(layer "F.SilkS")
			(effects
				(font
					(size 0.7874 0.5842)
					(thickness 0.1524)
				)
				(justify left)
			)
		)
		(property "Value" ""
			(at 0 0 0)
			(layer "F.Fab")
			(effects
				(font
					(size 1.27 1.27)
				)
			)
		)
		(duplicate_pad_numbers_are_jumpers no)
		(fp_line
			(start -1.905 -0.8636)
			(end 1.905 -0.8636)
			(stroke
				(width 0.1524)
				(type default)
			)
			(layer "F.SilkS")
		)
		(fp_line
			(start -1.905 0.8636)
			(end -1.905 -0.8636)
			(stroke
				(width 0.1524)
				(type default)
			)
			(layer "F.SilkS")
		)
		(fp_line
			(start 0 0.8382)
			(end 0 -0.8382)
			(stroke
				(width 0.1524)
				(type default)
			)
			(layer "F.SilkS")
		)
		(fp_line
			(start 1.905 -0.8636)
			(end 1.905 0.8636)
			(stroke
				(width 0.1524)
				(type default)
			)
			(layer "F.SilkS")
		)
		(fp_line
			(start 1.905 0.8636)
			(end -1.905 0.8636)
			(stroke
				(width 0.1524)
				(type default)
			)
			(layer "F.SilkS")
		)
		(fp_rect
			(start -1.524 0.7366)
			(end 1.524 -0.7366)
			(stroke
				(width 0)
				(type default)
			)
			(fill no)
			(layer "F.CrtYd")
		)
		(pad "1" smd rect
			(at 0.94996 0)
			(size 1.1176 1.3716)
			(layers "F.Cu" "F.Mask" "F.Paste")
			(net "P1V8_STB_NODE1")
		)
		(pad "2" smd rect
			(at -0.94996 0)
			(size 1.1176 1.3716)
			(layers "F.Cu" "F.Mask" "F.Paste")
			(net "GND")
		)
	)
	(footprint ""
		(layer "F.Cu")
		(at 26.825702 -37.473128 -90)
		(property "Reference" ""
			(at 0 0 270)
			(layer "F.SilkS")
			(hide yes)
			(effects
				(font
					(size 1.27 1.27)
				)
			)
		)
		(property "Value" ""
			(at 0 0 270)
			(layer "F.Fab")
			(effects
				(font
					(size 1.27 1.27)
				)
			)
		)
		(duplicate_pad_numbers_are_jumpers no)
		(fp_poly
			(pts
				(arc
					(start 0 -1.4986)
					(mid 0 1.4986)
					(end 0 -1.4986)
				)
			)
			(stroke
				(width 0)
				(type default)
			)
			(fill no)
			(layer "F.CrtYd")
		)
		(pad "1" smd circle
			(at 0 0 270)
			(size 0.9906 0.9906)
			(layers "F.Cu" "F.Mask" "F.Paste")
			(net "Net_41")
		)
		(zone
			(layer "F.Cu")
			(hatch none 0.5)
			(connect_pads
				(clearance 0)
			)
			(min_thickness 0.25)
			(keepout
				(tracks not_allowed)
				(vias allowed)
				(pads allowed)
				(copperpour not_allowed)
				(footprints allowed)
			)
			(placement
				(enabled no)
				(sheetname "")
			)
			(fill
				(thermal_gap 0.5)
				(thermal_bridge_width 0.5)
				(island_removal_mode 0)
			)
			(polygon
				(pts
					(arc
						(start 25.200102 -37.473128)
						(mid 28.451302 -37.473128)
						(end 25.200102 -37.473128)
					)
				)
			)
		)
	)
	(footprint ""
		(layer "F.Cu")
		(at 48.192182 -173.527466 180)
		(property "Reference" "U87"
			(at 1.185418 -133.039612 90)
			(unlocked yes)
			(layer "F.SilkS")
			(effects
				(font
					(size 0.7874 0.5842)
					(thickness 0.1524)
				)
				(justify left)
			)
		)
		(property "Value" ""
			(at 0 0 180)
			(layer "F.Fab")
			(effects
				(font
					(size 1.27 1.27)
				)
			)
		)
		(duplicate_pad_numbers_are_jumpers no)
		(fp_line
			(start 1.549908 2.032)
			(end -1.549908 2.032)
			(stroke
				(width 0.1524)
				(type default)
			)
			(layer "F.SilkS")
		)
		(fp_line
			(start 1.549908 -2.032)
			(end 1.549908 2.032)
			(stroke
				(width 0.1524)
				(type default)
			)
			(layer "F.SilkS")
		)
		(fp_line
			(start -1.549908 2.032)
			(end -1.549908 -2.032)
			(stroke
				(width 0.1524)
				(type default)
			)
			(layer "F.SilkS")
		)
		(fp_line
			(start -1.549908 -2.032)
			(end 1.549908 -2.032)
			(stroke
				(width 0.1524)
				(type default)
			)
			(layer "F.SilkS")
		)
		(fp_poly
			(pts
				(xy -2.9464 1.016) (xy -2.9464 1.524) (xy -2.1844 1.27)
			)
			(stroke
				(width 0)
				(type default)
			)
			(fill yes)
			(layer "F.SilkS")
		)
		(fp_poly
			(pts
				(xy -1.549908 0.849884) (xy -1.2319 0.849884) (xy -1.2319 1.9431) (xy -1.1811 1.9431) (xy 1.1811 1.9431)
				(xy 1.2319 1.9431) (xy 1.2319 0.849884) (xy 1.549908 0.849884) (xy 1.549908 -0.849884) (xy 1.2319 -0.849884)
				(xy 1.2319 -1.9431) (xy 1.1811 -1.9431) (xy -1.1811 -1.9431) (xy -1.2319 -1.9431) (xy -1.2319 -0.849884)
				(xy -1.549908 -0.849884)
			)
			(stroke
				(width 0)
				(type default)
			)
			(fill no)
			(layer "F.CrtYd")
		)
		(fp_line
			(start 1.549908 0.849884)
			(end 1.549908 -0.849884)
			(stroke
				(width 0.1)
				(type default)
			)
			(layer "F.Fab")
		)
		(fp_line
			(start 1.549908 -0.849884)
			(end -1.549908 -0.849884)
			(stroke
				(width 0.1)
				(type default)
			)
			(layer "F.Fab")
		)
		(fp_line
			(start -1.549908 0.849884)
			(end 1.549908 0.849884)
			(stroke
				(width 0.1)
				(type default)
			)
			(layer "F.Fab")
		)
		(fp_line
			(start -1.549908 -0.849884)
			(end -1.549908 0.849884)
			(stroke
				(width 0.1)
				(type default)
			)
			(layer "F.Fab")
		)
		(fp_text user "3"
			(at 2.377186 2.550668 0)
			(unlocked yes)
			(layer "F.SilkS")
			(effects
				(font
					(size 0.635 0.4064)
					(thickness 0.1524)
				)
				(justify left)
			)
		)
		(fp_text user "4"
			(at 0.95885 -2.513076 0)
			(unlocked yes)
			(layer "F.SilkS")
			(effects
				(font
					(size 0.635 0.4064)
					(thickness 0.1524)
				)
				(justify left)
			)
		)
		(fp_text user "1"
			(at -1.537462 2.55905 0)
			(unlocked yes)
			(layer "F.SilkS")
			(effects
				(font
					(size 0.635 0.4064)
					(thickness 0.1524)
				)
				(justify left)
			)
		)
		(fp_text user "5"
			(at -1.883156 -2.59334 0)
			(unlocked yes)
			(layer "F.SilkS")
			(effects
				(font
					(size 0.635 0.4064)
					(thickness 0.1524)
				)
				(justify left)
			)
		)
		(pad "1" smd rect
			(at -0.94996 1.225042 180)
			(size 0.4572 1.3208)
			(layers "F.Cu" "F.Mask" "F.Paste")
			(net "Net_1708")
		)
		(pad "2" smd rect
			(at 0 1.225042 180)
			(size 0.4572 1.3208)
			(layers "F.Cu" "F.Mask" "F.Paste")
			(net "PSU6_DC_OK_R_BUF")
		)
		(pad "3" smd rect
			(at 0.94996 1.225042 180)
			(size 0.4572 1.3208)
			(layers "F.Cu" "F.Mask" "F.Paste")
			(net "GND")
		)
		(pad "4" smd rect
			(at 0.94996 -1.225042 180)
			(size 0.4572 1.3208)
			(layers "F.Cu" "F.Mask" "F.Paste")
			(net "PSU6_DC_OK")
		)
		(pad "5" smd rect
			(at -0.94996 -1.225042 180)
			(size 0.4572 1.3208)
			(layers "F.Cu" "F.Mask" "F.Paste")
			(net "P3V3_NODE1")
		)
	)
	(footprint ""
		(layer "F.Cu")
		(at 47.419768 -105.38079)
		(property "Reference" "R1103"
			(at -0.191008 2.048002 0)
			(unlocked yes)
			(layer "F.SilkS")
			(effects
				(font
					(size 0.7874 0.5842)
					(thickness 0.1524)
				)
				(justify left)
			)
		)
		(property "Value" ""
			(at 0 0 0)
			(layer "F.Fab")
			(effects
				(font
					(size 1.27 1.27)
				)
			)
		)
		(duplicate_pad_numbers_are_jumpers no)
		(fp_line
			(start -0.7874 -0.4064)
			(end 0.7874 -0.4064)
			(stroke
				(width 0.1524)
				(type default)
			)
			(layer "F.SilkS")
		)
		(fp_line
			(start -0.7874 0.4064)
			(end -0.7874 -0.4064)
			(stroke
				(width 0.1524)
				(type default)
			)
			(layer "F.SilkS")
		)
		(fp_line
			(start 0.7874 -0.4064)
			(end 0.7874 0.4064)
			(stroke
				(width 0.1524)
				(type default)
			)
			(layer "F.SilkS")
		)
		(fp_line
			(start 0.7874 0.4064)
			(end -0.7874 0.4064)
			(stroke
				(width 0.1524)
				(type default)
			)
			(layer "F.SilkS")
		)
		(fp_poly
			(pts
				(xy -0.508 0.2794) (xy -0.508 0.2286) (xy -0.635 0.2286) (xy -0.635 -0.254) (xy -0.5334 -0.254)
				(xy -0.5334 -0.2794) (xy 0.5334 -0.2794) (xy 0.5334 -0.254) (xy 0.635 -0.254) (xy 0.635 0.254) (xy 0.5334 0.254)
				(xy 0.5334 0.2794)
			)
			(stroke
				(width 0)
				(type default)
			)
			(fill no)
			(layer "F.CrtYd")
		)
		(pad "1" smd rect
			(at 0.40005 0)
			(size 0.4572 0.508)
			(layers "F.Cu" "F.Mask" "F.Paste")
			(net "GND")
		)
		(pad "2" smd rect
			(at -0.40005 0)
			(size 0.4572 0.508)
			(layers "F.Cu" "F.Mask" "F.Paste")
			(net "PWRGD_NODE1_P5V_STB_PG")
		)
	)
	(footprint ""
		(layer "F.Cu")
		(at 116.18976 -185.205624 90)
		(property "Reference" "C754"
			(at 4.768088 0.929132 90)
			(unlocked yes)
			(layer "F.SilkS")
			(effects
				(font
					(size 0.7874 0.5842)
					(thickness 0.1524)
				)
				(justify left)
			)
		)
		(property "Value" ""
			(at 0 0 90)
			(layer "F.Fab")
			(effects
				(font
					(size 1.27 1.27)
				)
			)
		)
		(duplicate_pad_numbers_are_jumpers no)
		(fp_line
			(start 0.7874 -0.4064)
			(end 0.7874 0.4064)
			(stroke
				(width 0.1524)
				(type default)
			)
			(layer "F.SilkS")
		)
		(fp_line
			(start -0.7874 -0.4064)
			(end 0.7874 -0.4064)
			(stroke
				(width 0.1524)
				(type default)
			)
			(layer "F.SilkS")
		)
		(fp_line
			(start 0 0.381)
			(end 0 -0.381)
			(stroke
				(width 0.1524)
				(type default)
			)
			(layer "F.SilkS")
		)
		(fp_line
			(start 0.7874 0.4064)
			(end -0.7874 0.4064)
			(stroke
				(width 0.1524)
				(type default)
			)
			(layer "F.SilkS")
		)
		(fp_line
			(start -0.7874 0.4064)
			(end -0.7874 -0.4064)
			(stroke
				(width 0.1524)
				(type default)
			)
			(layer "F.SilkS")
		)
		(fp_poly
			(pts
				(xy -0.5334 0.254) (xy -0.635 0.254) (xy -0.635 0.2286) (xy -0.635 -0.254) (xy -0.5334 -0.254) (xy -0.5334 -0.2794)
				(xy 0.5334 -0.2794) (xy 0.5334 -0.254) (xy 0.635 -0.254) (xy 0.635 0.254) (xy 0.5334 0.254) (xy 0.5334 0.2794)
				(xy -0.508 0.2794) (xy -0.5334 0.2794)
			)
			(stroke
				(width 0)
				(type default)
			)
			(fill no)
			(layer "F.CrtYd")
		)
		(pad "1" smd rect
			(at 0.40005 0 90)
			(size 0.4572 0.508)
			(layers "F.Cu" "F.Mask" "F.Paste")
			(net "UART_T8_NODE3_RXD")
		)
		(pad "2" smd rect
			(at -0.40005 0 90)
			(size 0.4572 0.508)
			(layers "F.Cu" "F.Mask" "F.Paste")
			(net "GND")
		)
	)
	(footprint ""
		(layer "F.Cu")
		(at 31.641288 -128.354582)
		(property "Reference" "U121"
			(at -6.505448 3.244088 0)
			(unlocked yes)
			(layer "F.SilkS")
			(effects
				(font
					(size 0.7874 0.5842)
					(thickness 0.1524)
				)
				(justify left)
			)
		)
		(property "Value" ""
			(at 0 0 0)
			(layer "F.Fab")
			(effects
				(font
					(size 1.27 1.27)
				)
			)
		)
		(duplicate_pad_numbers_are_jumpers no)
		(fp_line
			(start -2.525014 0.025146)
			(end -2.525014 0.661162)
			(stroke
				(width 0.1524)
				(type default)
			)
			(layer "F.SilkS")
		)
		(fp_line
			(start -2.525014 2.540762)
			(end -2.525014 3.075178)
			(stroke
				(width 0.1524)
				(type default)
			)
			(layer "F.SilkS")
		)
		(fp_line
			(start -2.525014 3.075178)
			(end -2.525014 0.025146)
			(stroke
				(width 0.1524)
				(type default)
			)
			(layer "F.SilkS")
		)
		(fp_line
			(start -2.525014 3.075178)
			(end -2.320798 3.075178)
			(stroke
				(width 0.1524)
				(type default)
			)
			(layer "F.SilkS")
		)
		(fp_line
			(start -2.320798 0.025146)
			(end -2.525014 0.025146)
			(stroke
				(width 0.1524)
				(type default)
			)
			(layer "F.SilkS")
		)
		(fp_line
			(start 0.320802 3.075178)
			(end 0.525018 3.075178)
			(stroke
				(width 0.1524)
				(type default)
			)
			(layer "F.SilkS")
		)
		(fp_line
			(start 0.525018 0.025146)
			(end 0.320802 0.025146)
			(stroke
				(width 0.1524)
				(type default)
			)
			(layer "F.SilkS")
		)
		(fp_line
			(start 0.525018 0.686562)
			(end 0.525018 0.025146)
			(stroke
				(width 0.1524)
				(type default)
			)
			(layer "F.SilkS")
		)
		(fp_line
			(start 0.525018 3.075178)
			(end 0.525018 0.025146)
			(stroke
				(width 0.1524)
				(type default)
			)
			(layer "F.SilkS")
		)
		(fp_line
			(start 0.525018 3.075178)
			(end 0.525018 2.489962)
			(stroke
				(width 0.1524)
				(type default)
			)
			(layer "F.SilkS")
		)
		(fp_poly
			(pts
				(xy 0 -0.519938) (xy 0.299974 -1.420114) (xy -0.299974 -1.420114)
			)
			(stroke
				(width 0)
				(type default)
			)
			(fill yes)
			(layer "F.SilkS")
		)
		(fp_poly
			(pts
				(xy 0.525018 0.025146) (xy 0.244602 0.025146) (xy 0.244602 -0.532638) (xy -2.244598 -0.532638) (xy -2.244598 0.025146)
				(xy -2.525014 0.025146) (xy -2.525014 3.075178) (xy -2.244598 3.075178) (xy -2.244598 3.632962)
				(xy 0.244602 3.632962) (xy 0.244602 3.075178) (xy 0.525018 3.075178)
			)
			(stroke
				(width 0)
				(type default)
			)
			(fill no)
			(layer "F.CrtYd")
		)
		(fp_line
			(start -2.525014 0.025146)
			(end 0.525018 0.025146)
			(stroke
				(width 0.1)
				(type default)
			)
			(layer "F.Fab")
		)
		(fp_line
			(start -2.525014 3.075178)
			(end -2.525014 0.025146)
			(stroke
				(width 0.1)
				(type default)
			)
			(layer "F.Fab")
		)
		(fp_line
			(start 0.525018 0.025146)
			(end 0.525018 3.075178)
			(stroke
				(width 0.1)
				(type default)
			)
			(layer "F.Fab")
		)
		(fp_line
			(start 0.525018 3.075178)
			(end -2.525014 3.075178)
			(stroke
				(width 0.1)
				(type default)
			)
			(layer "F.Fab")
		)
		(fp_poly
			(pts
				(xy 0 -0.519938) (xy 0.302514 -1.427734) (xy -0.302514 -1.427734)
			)
			(stroke
				(width 0)
				(type default)
			)
			(fill yes)
			(layer "F.Fab")
		)
		(fp_text user "5"
			(at -2.123948 -0.583692 90)
			(unlocked yes)
			(layer "F.SilkS")
			(effects
				(font
					(size 0.635 0.4064)
					(thickness 0.1524)
				)
				(justify left)
			)
		)
		(fp_text user "6"
			(at -2.105914 4.059682 90)
			(unlocked yes)
			(layer "F.SilkS")
			(effects
				(font
					(size 0.635 0.4064)
					(thickness 0.1524)
				)
				(justify left)
			)
		)
		(fp_text user "1"
			(at 0.61468 -0.441198 90)
			(unlocked yes)
			(layer "F.SilkS")
			(effects
				(font
					(size 0.635 0.4064)
					(thickness 0.1524)
				)
				(justify left)
			)
		)
		(fp_text user "10"
			(at 0.750316 4.322572 90)
			(unlocked yes)
			(layer "F.SilkS")
			(effects
				(font
					(size 0.635 0.4064)
					(thickness 0.1524)
				)
				(justify left)
			)
		)
		(fp_text user "5"
			(at -2.155698 -0.695706 180)
			(unlocked yes)
			(layer "F.Fab")
			(effects
				(font
					(size 0.7874 0.5842)
					(thickness 0.000001)
				)
				(justify left)
			)
		)
		(fp_text user "6"
			(at -2.155698 3.725672 180)
			(unlocked yes)
			(layer "F.Fab")
			(effects
				(font
					(size 0.7874 0.5842)
					(thickness 0.000001)
				)
				(justify left)
			)
		)
		(fp_text user "1"
			(at 0.790702 -0.695706 180)
			(unlocked yes)
			(layer "F.Fab")
			(effects
				(font
					(size 0.7874 0.5842)
					(thickness 0.000001)
				)
				(justify left)
			)
		)
		(fp_text user "10"
			(at 1.565402 3.700272 180)
			(unlocked yes)
			(layer "F.Fab")
			(effects
				(font
					(size 0.7874 0.5842)
					(thickness 0.000001)
				)
				(justify left)
			)
		)
		(pad "1" smd rect
			(at 0 0 180)
			(size 0.2794 0.9144)
			(layers "F.Cu" "F.Mask" "F.Paste")
			(net "P1V538_BMC_NODE1")
		)
		(pad "2" smd rect
			(at -0.499872 0 180)
			(size 0.2794 0.9144)
			(layers "F.Cu" "F.Mask" "F.Paste")
			(net "P1V538_BMC_NODE1")
		)
		(pad "3" smd rect
			(at -0.999998 0 180)
			(size 0.2794 0.9144)
			(layers "F.Cu" "F.Mask" "F.Paste")
			(net "P1V538_BMC_NODE1")
		)
		(pad "4" smd rect
			(at -1.500124 0 180)
			(size 0.2794 0.9144)
			(layers "F.Cu" "F.Mask" "F.Paste")
			(net "P1V538_BMC_NODE1_ADJ")
		)
		(pad "5" smd rect
			(at -1.999996 0)
			(size 0.2794 0.9144)
			(layers "F.Cu" "F.Mask" "F.Paste")
			(net "PWRGD_NODE1_P1V538_BMC_PG")
		)
		(pad "6" smd rect
			(at -1.999996 3.100324)
			(size 0.2794 0.9144)
			(layers "F.Cu" "F.Mask" "F.Paste")
			(net "FM_CPLD_NODE1_P1V538_BMC_EN")
		)
		(pad "7" smd rect
			(at -1.500124 3.100324 180)
			(size 0.2794 0.9144)
			(layers "F.Cu" "F.Mask" "F.Paste")
			(net "P1V8_NODE1")
		)
		(pad "8" smd rect
			(at -0.999998 3.100324 180)
			(size 0.2794 0.9144)
			(layers "F.Cu" "F.Mask" "F.Paste")
			(net "P1V8_NODE1")
		)
		(pad "9" smd rect
			(at -0.499872 3.100324 180)
			(size 0.2794 0.9144)
			(layers "F.Cu" "F.Mask" "F.Paste")
			(net "P1V8_NODE1")
		)
		(pad "10" smd rect
			(at 0 3.100324 180)
			(size 0.2794 0.9144)
			(layers "F.Cu" "F.Mask" "F.Paste")
			(net "P5V_STB_NODE1")
		)
		(pad "TH" smd rect
			(at -0.999998 1.550162 270)
			(size 1.7526 2.667)
			(layers "F.Cu" "F.Mask" "F.Paste")
			(net "GND")
		)
		(zone
			(layer "F.Cu")
			(hatch none 0.5)
			(connect_pads
				(clearance 0)
			)
			(min_thickness 0.25)
			(keepout
				(tracks allowed)
				(vias not_allowed)
				(pads allowed)
				(copperpour not_allowed)
				(footprints allowed)
			)
			(placement
				(enabled no)
				(sheetname "")
			)
			(fill
				(thermal_gap 0.5)
				(thermal_bridge_width 0.5)
				(island_removal_mode 0)
			)
			(polygon
				(pts
					(xy 32.174688 -127.821182) (xy 29.126688 -127.821182) (xy 29.126688 -125.789182) (xy 32.174688 -125.789182)
					(xy 32.174688 -127.719582) (xy 32.047688 -127.719582) (xy 32.047688 -125.865382) (xy 29.228288 -125.865382)
					(xy 29.228288 -127.744982) (xy 32.174688 -127.744982)
				)
			)
		)
	)
	(footprint ""
		(layer "F.Cu")
		(at 67.241166 -96.709992 -90)
		(property "Reference" "R73"
			(at 54.98719 -28.370276 90)
			(unlocked yes)
			(layer "F.SilkS")
			(effects
				(font
					(size 0.7874 0.5842)
					(thickness 0.1524)
				)
				(justify left)
			)
		)
		(property "Value" ""
			(at 0 0 270)
			(layer "F.Fab")
			(effects
				(font
					(size 1.27 1.27)
				)
			)
		)
		(duplicate_pad_numbers_are_jumpers no)
		(fp_line
			(start -0.7874 0.4064)
			(end -0.7874 -0.4064)
			(stroke
				(width 0.1524)
				(type default)
			)
			(layer "F.SilkS")
		)
		(fp_line
			(start 0.7874 0.4064)
			(end -0.7874 0.4064)
			(stroke
				(width 0.1524)
				(type default)
			)
			(layer "F.SilkS")
		)
		(fp_line
			(start -0.7874 -0.4064)
			(end 0.7874 -0.4064)
			(stroke
				(width 0.1524)
				(type default)
			)
			(layer "F.SilkS")
		)
		(fp_line
			(start 0.7874 -0.4064)
			(end 0.7874 0.4064)
			(stroke
				(width 0.1524)
				(type default)
			)
			(layer "F.SilkS")
		)
		(fp_poly
			(pts
				(xy -0.508 0.2794) (xy -0.508 0.2286) (xy -0.635 0.2286) (xy -0.635 -0.254) (xy -0.5334 -0.254)
				(xy -0.5334 -0.2794) (xy 0.5334 -0.2794) (xy 0.5334 -0.254) (xy 0.635 -0.254) (xy 0.635 0.254) (xy 0.5334 0.254)
				(xy 0.5334 0.2794)
			)
			(stroke
				(width 0)
				(type default)
			)
			(fill no)
			(layer "F.CrtYd")
		)
		(pad "1" smd rect
			(at 0.40005 0 270)
			(size 0.4572 0.508)
			(layers "F.Cu" "F.Mask" "F.Paste")
			(net "LPC_CPU_NODE1_R_CLKOUT0")
		)
		(pad "2" smd rect
			(at -0.40005 0 270)
			(size 0.4572 0.508)
			(layers "F.Cu" "F.Mask" "F.Paste")
			(net "LPC_CPU_NODE1_CLKOUT0")
		)
	)
	(footprint ""
		(layer "F.Cu")
		(at 39.297356 -14.200124)
		(property "Reference" "PR33"
			(at -1.999996 -2.53873 0)
			(unlocked yes)
			(layer "F.SilkS")
			(effects
				(font
					(size 0.7874 0.5842)
					(thickness 0.1524)
				)
				(justify left)
			)
		)
		(property "Value" ""
			(at 0 0 0)
			(layer "F.Fab")
			(effects
				(font
					(size 1.27 1.27)
				)
			)
		)
		(duplicate_pad_numbers_are_jumpers no)
		(fp_line
			(start -0.7874 -0.4064)
			(end 0.7874 -0.4064)
			(stroke
				(width 0.1524)
				(type default)
			)
			(layer "F.SilkS")
		)
		(fp_line
			(start -0.7874 0.4064)
			(end -0.7874 -0.4064)
			(stroke
				(width 0.1524)
				(type default)
			)
			(layer "F.SilkS")
		)
		(fp_line
			(start 0.7874 -0.4064)
			(end 0.7874 0.4064)
			(stroke
				(width 0.1524)
				(type default)
			)
			(layer "F.SilkS")
		)
		(fp_line
			(start 0.7874 0.4064)
			(end -0.7874 0.4064)
			(stroke
				(width 0.1524)
				(type default)
			)
			(layer "F.SilkS")
		)
		(fp_poly
			(pts
				(xy -0.508 0.2794) (xy -0.508 0.2286) (xy -0.635 0.2286) (xy -0.635 -0.254) (xy -0.5334 -0.254)
				(xy -0.5334 -0.2794) (xy 0.5334 -0.2794) (xy 0.5334 -0.254) (xy 0.635 -0.254) (xy 0.635 0.254) (xy 0.5334 0.254)
				(xy 0.5334 0.2794)
			)
			(stroke
				(width 0)
				(type default)
			)
			(fill no)
			(layer "F.CrtYd")
		)
		(pad "1" smd rect
			(at 0.40005 0)
			(size 0.4572 0.508)
			(layers "F.Cu" "F.Mask" "F.Paste")
			(net "PV_VDDR_NODE1_MODE")
		)
		(pad "2" smd rect
			(at -0.40005 0)
			(size 0.4572 0.508)
			(layers "F.Cu" "F.Mask" "F.Paste")
			(net "GND")
		)
	)
	(footprint ""
		(layer "F.Cu")
		(at 71.014844 -156.09443 -90)
		(property "Reference" "PL12"
			(at -3.872738 -0.978916 0)
			(unlocked yes)
			(layer "F.SilkS")
			(effects
				(font
					(size 0.7874 0.5842)
					(thickness 0.1524)
				)
				(justify left)
			)
		)
		(property "Value" ""
			(at 0 0 270)
			(layer "F.Fab")
			(effects
				(font
					(size 1.27 1.27)
				)
			)
		)
		(duplicate_pad_numbers_are_jumpers no)
		(fp_line
			(start -3.350006 4.1656)
			(end -3.350006 -4.1656)
			(stroke
				(width 0.1524)
				(type default)
			)
			(layer "F.SilkS")
		)
		(fp_line
			(start 3.350006 4.1656)
			(end -3.350006 4.1656)
			(stroke
				(width 0.1524)
				(type default)
			)
			(layer "F.SilkS")
		)
		(fp_line
			(start -3.350006 -4.1656)
			(end 3.350006 -4.1656)
			(stroke
				(width 0.1524)
				(type default)
			)
			(layer "F.SilkS")
		)
		(fp_line
			(start 3.350006 -4.1656)
			(end 3.350006 4.1656)
			(stroke
				(width 0.1524)
				(type default)
			)
			(layer "F.SilkS")
		)
		(fp_poly
			(pts
				(xy -3.350006 -3.64998) (xy -1.7018 -3.64998) (xy -1.7018 -4.05257) (xy 1.7018 -4.05257) (xy 1.7018 -3.64998)
				(xy 3.350006 -3.64998) (xy 3.350006 3.64998) (xy 1.7018 3.64998) (xy 1.7018 4.05257) (xy -1.7018 4.05257)
				(xy -1.7018 3.64998) (xy -3.350006 3.64998)
			)
			(stroke
				(width 0)
				(type default)
			)
			(fill no)
			(layer "F.CrtYd")
		)
		(fp_line
			(start -3.350006 3.64998)
			(end -3.350006 -3.64998)
			(stroke
				(width 0.1)
				(type default)
			)
			(layer "F.Fab")
		)
		(fp_line
			(start 3.350006 3.64998)
			(end -3.350006 3.64998)
			(stroke
				(width 0.1)
				(type default)
			)
			(layer "F.Fab")
		)
		(fp_line
			(start -3.350006 -3.64998)
			(end 3.350006 -3.64998)
			(stroke
				(width 0.1)
				(type default)
			)
			(layer "F.Fab")
		)
		(fp_line
			(start 3.350006 -3.64998)
			(end 3.350006 3.64998)
			(stroke
				(width 0.1)
				(type default)
			)
			(layer "F.Fab")
		)
		(pad "1" smd rect
			(at 0 -2.92481 180)
			(size 2.15392 3.302)
			(layers "F.Cu" "F.Mask" "F.Paste")
			(net "SW_P5V_STB_NODE1_PH")
		)
		(pad "2" smd rect
			(at 0 2.92481 180)
			(size 2.15392 3.302)
			(layers "F.Cu" "F.Mask" "F.Paste")
			(net "P5V_STB_NODE1")
		)
	)
	(footprint ""
		(layer "F.Cu")
		(at 189.37732 -15.96898 -90)
		(property "Reference" ""
			(at 0 0 270)
			(layer "F.SilkS")
			(hide yes)
			(effects
				(font
					(size 1.27 1.27)
				)
			)
		)
		(property "Value" ""
			(at 0 0 270)
			(layer "F.Fab")
			(effects
				(font
					(size 1.27 1.27)
				)
			)
		)
		(duplicate_pad_numbers_are_jumpers no)
		(fp_poly
			(pts
				(arc
					(start 0 -1.4986)
					(mid 0 1.4986)
					(end 0 -1.4986)
				)
			)
			(stroke
				(width 0)
				(type default)
			)
			(fill no)
			(layer "F.CrtYd")
		)
		(pad "1" smd circle
			(at 0 0 270)
			(size 0.9906 0.9906)
			(layers "F.Cu" "F.Mask" "F.Paste")
			(net "Net_39")
		)
		(zone
			(layer "F.Cu")
			(hatch none 0.5)
			(connect_pads
				(clearance 0)
			)
			(min_thickness 0.25)
			(keepout
				(tracks not_allowed)
				(vias allowed)
				(pads allowed)
				(copperpour not_allowed)
				(footprints allowed)
			)
			(placement
				(enabled no)
				(sheetname "")
			)
			(fill
				(thermal_gap 0.5)
				(thermal_bridge_width 0.5)
				(island_removal_mode 0)
			)
			(polygon
				(pts
					(arc
						(start 191.00292 -15.96898)
						(mid 187.75172 -15.96898)
						(end 191.00292 -15.96898)
					)
				)
			)
		)
	)
	(footprint ""
		(layer "F.Cu")
		(at 166.801038 -79.08671 180)
		(property "Reference" "C883"
			(at -1.545336 0.064008 0)
			(unlocked yes)
			(layer "F.SilkS")
			(effects
				(font
					(size 0.7874 0.5842)
					(thickness 0.1524)
				)
				(justify left)
			)
		)
		(property "Value" ""
			(at 0 0 180)
			(layer "F.Fab")
			(effects
				(font
					(size 1.27 1.27)
				)
			)
		)
		(duplicate_pad_numbers_are_jumpers no)
		(fp_line
			(start 0.7874 0.4064)
			(end -0.7874 0.4064)
			(stroke
				(width 0.1524)
				(type default)
			)
			(layer "F.SilkS")
		)
		(fp_line
			(start 0.7874 -0.4064)
			(end 0.7874 0.4064)
			(stroke
				(width 0.1524)
				(type default)
			)
			(layer "F.SilkS")
		)
		(fp_line
			(start 0 0.381)
			(end 0 -0.381)
			(stroke
				(width 0.1524)
				(type default)
			)
			(layer "F.SilkS")
		)
		(fp_line
			(start -0.7874 0.4064)
			(end -0.7874 -0.4064)
			(stroke
				(width 0.1524)
				(type default)
			)
			(layer "F.SilkS")
		)
		(fp_line
			(start -0.7874 -0.4064)
			(end 0.7874 -0.4064)
			(stroke
				(width 0.1524)
				(type default)
			)
			(layer "F.SilkS")
		)
		(fp_poly
			(pts
				(xy -0.5334 0.254) (xy -0.635 0.254) (xy -0.635 0.2286) (xy -0.635 -0.254) (xy -0.5334 -0.254) (xy -0.5334 -0.2794)
				(xy 0.5334 -0.2794) (xy 0.5334 -0.254) (xy 0.635 -0.254) (xy 0.635 0.254) (xy 0.5334 0.254) (xy 0.5334 0.2794)
				(xy -0.508 0.2794) (xy -0.5334 0.2794)
			)
			(stroke
				(width 0)
				(type default)
			)
			(fill no)
			(layer "F.CrtYd")
		)
		(pad "1" smd rect
			(at 0.40005 0 180)
			(size 0.4572 0.508)
			(layers "F.Cu" "F.Mask" "F.Paste")
			(net "P5V_STB_NODE1")
		)
		(pad "2" smd rect
			(at -0.40005 0 180)
			(size 0.4572 0.508)
			(layers "F.Cu" "F.Mask" "F.Paste")
			(net "GND")
		)
	)
	(footprint ""
		(layer "F.Cu")
		(at 102.039166 -135.132064)
		(property "Reference" "R137"
			(at -4.413758 -8.417814 0)
			(unlocked yes)
			(layer "F.SilkS")
			(effects
				(font
					(size 0.7874 0.5842)
					(thickness 0.1524)
				)
				(justify left)
			)
		)
		(property "Value" ""
			(at 0 0 0)
			(layer "F.Fab")
			(effects
				(font
					(size 1.27 1.27)
				)
			)
		)
		(duplicate_pad_numbers_are_jumpers no)
		(fp_line
			(start -0.7874 -0.4064)
			(end 0.7874 -0.4064)
			(stroke
				(width 0.1524)
				(type default)
			)
			(layer "F.SilkS")
		)
		(fp_line
			(start -0.7874 0.4064)
			(end -0.7874 -0.4064)
			(stroke
				(width 0.1524)
				(type default)
			)
			(layer "F.SilkS")
		)
		(fp_line
			(start 0.7874 -0.4064)
			(end 0.7874 0.4064)
			(stroke
				(width 0.1524)
				(type default)
			)
			(layer "F.SilkS")
		)
		(fp_line
			(start 0.7874 0.4064)
			(end -0.7874 0.4064)
			(stroke
				(width 0.1524)
				(type default)
			)
			(layer "F.SilkS")
		)
		(fp_poly
			(pts
				(xy -0.508 0.2794) (xy -0.508 0.2286) (xy -0.635 0.2286) (xy -0.635 -0.254) (xy -0.5334 -0.254)
				(xy -0.5334 -0.2794) (xy 0.5334 -0.2794) (xy 0.5334 -0.254) (xy 0.635 -0.254) (xy 0.635 0.254) (xy 0.5334 0.254)
				(xy 0.5334 0.2794)
			)
			(stroke
				(width 0)
				(type default)
			)
			(fill no)
			(layer "F.CrtYd")
		)
		(pad "1" smd rect
			(at 0.40005 0)
			(size 0.4572 0.508)
			(layers "F.Cu" "F.Mask" "F.Paste")
			(net "SVID_CPU_NODE1_PVCCP_DAT")
		)
		(pad "2" smd rect
			(at -0.40005 0)
			(size 0.4572 0.508)
			(layers "F.Cu" "F.Mask" "F.Paste")
			(net "P1V05_NODE1")
		)
	)
	(footprint ""
		(layer "F.Cu")
		(at 19.72564 -132.360416)
		(property "Reference" "PR24"
			(at 1.524762 -0.23495 0)
			(unlocked yes)
			(layer "F.SilkS")
			(effects
				(font
					(size 0.7874 0.5842)
					(thickness 0.1524)
				)
				(justify left)
			)
		)
		(property "Value" ""
			(at 0 0 0)
			(layer "F.Fab")
			(effects
				(font
					(size 1.27 1.27)
				)
			)
		)
		(duplicate_pad_numbers_are_jumpers no)
		(fp_line
			(start -0.7874 -0.4064)
			(end 0.7874 -0.4064)
			(stroke
				(width 0.1524)
				(type default)
			)
			(layer "F.SilkS")
		)
		(fp_line
			(start -0.7874 0.4064)
			(end -0.7874 -0.4064)
			(stroke
				(width 0.1524)
				(type default)
			)
			(layer "F.SilkS")
		)
		(fp_line
			(start 0.7874 -0.4064)
			(end 0.7874 0.4064)
			(stroke
				(width 0.1524)
				(type default)
			)
			(layer "F.SilkS")
		)
		(fp_line
			(start 0.7874 0.4064)
			(end -0.7874 0.4064)
			(stroke
				(width 0.1524)
				(type default)
			)
			(layer "F.SilkS")
		)
		(fp_poly
			(pts
				(xy -0.508 0.2794) (xy -0.508 0.2286) (xy -0.635 0.2286) (xy -0.635 -0.254) (xy -0.5334 -0.254)
				(xy -0.5334 -0.2794) (xy 0.5334 -0.2794) (xy 0.5334 -0.254) (xy 0.635 -0.254) (xy 0.635 0.254) (xy 0.5334 0.254)
				(xy 0.5334 0.2794)
			)
			(stroke
				(width 0)
				(type default)
			)
			(fill no)
			(layer "F.CrtYd")
		)
		(pad "1" smd rect
			(at 0.40005 0)
			(size 0.4572 0.508)
			(layers "F.Cu" "F.Mask" "F.Paste")
			(net "P3V3_NODE1")
		)
		(pad "2" smd rect
			(at -0.40005 0)
			(size 0.4572 0.508)
			(layers "F.Cu" "F.Mask" "F.Paste")
			(net "PWRGD_NODE1_P1V05_PG")
		)
	)
	(footprint ""
		(layer "F.Cu")
		(at 56.725312 -148.290788 180)
		(property "Reference" "R315"
			(at 1.708912 1.13792 0)
			(unlocked yes)
			(layer "F.SilkS")
			(effects
				(font
					(size 0.7874 0.5842)
					(thickness 0.1524)
				)
			)
		)
		(property "Value" ""
			(at 0 0 180)
			(layer "F.Fab")
			(effects
				(font
					(size 1.27 1.27)
				)
			)
		)
		(duplicate_pad_numbers_are_jumpers no)
		(fp_line
			(start 1.2954 0.5842)
			(end -1.2954 0.5842)
			(stroke
				(width 0.1524)
				(type default)
			)
			(layer "F.SilkS")
		)
		(fp_line
			(start 1.2954 -0.5842)
			(end 1.2954 0.5842)
			(stroke
				(width 0.1524)
				(type default)
			)
			(layer "F.SilkS")
		)
		(fp_line
			(start -1.2954 0.5842)
			(end -1.2954 -0.5842)
			(stroke
				(width 0.1524)
				(type default)
			)
			(layer "F.SilkS")
		)
		(fp_line
			(start -1.2954 -0.5842)
			(end 1.2954 -0.5842)
			(stroke
				(width 0.1524)
				(type default)
			)
			(layer "F.SilkS")
		)
		(fp_poly
			(pts
				(xy 1.143 -0.3556) (xy 1.143 0.3556) (xy 0.8636 0.3556) (xy 0.8636 0.4572) (xy -0.8636 0.4572) (xy -0.8636 0.4318)
				(xy -0.8636 0.3556) (xy -1.143 0.3556) (xy -1.143 -0.3556) (xy -0.8636 -0.3556) (xy -0.8636 -0.4572)
				(xy 0.8636 -0.4572) (xy 0.8636 -0.3556)
			)
			(stroke
				(width 0)
				(type default)
			)
			(fill no)
			(layer "F.CrtYd")
		)
		(pad "1" smd rect
			(at 0.7366 0 270)
			(size 0.7112 0.8128)
			(layers "F.Cu" "F.Mask" "F.Paste")
			(net "GND")
		)
		(pad "2" smd rect
			(at -0.7366 0 270)
			(size 0.7112 0.8128)
			(layers "F.Cu" "F.Mask" "F.Paste")
			(net "BMC_NODE1_DACRSET")
		)
	)
	(footprint ""
		(layer "F.Cu")
		(at 123.93676 -185.205624 -90)
		(property "Reference" "R860"
			(at -4.768088 -0.152908 90)
			(unlocked yes)
			(layer "F.SilkS")
			(effects
				(font
					(size 0.7874 0.5842)
					(thickness 0.1524)
				)
				(justify left)
			)
		)
		(property "Value" ""
			(at 0 0 270)
			(layer "F.Fab")
			(effects
				(font
					(size 1.27 1.27)
				)
			)
		)
		(duplicate_pad_numbers_are_jumpers no)
		(fp_line
			(start -0.7874 0.4064)
			(end -0.7874 -0.4064)
			(stroke
				(width 0.1524)
				(type default)
			)
			(layer "F.SilkS")
		)
		(fp_line
			(start 0.7874 0.4064)
			(end -0.7874 0.4064)
			(stroke
				(width 0.1524)
				(type default)
			)
			(layer "F.SilkS")
		)
		(fp_line
			(start -0.7874 -0.4064)
			(end 0.7874 -0.4064)
			(stroke
				(width 0.1524)
				(type default)
			)
			(layer "F.SilkS")
		)
		(fp_line
			(start 0.7874 -0.4064)
			(end 0.7874 0.4064)
			(stroke
				(width 0.1524)
				(type default)
			)
			(layer "F.SilkS")
		)
		(fp_poly
			(pts
				(xy -0.508 0.2794) (xy -0.508 0.2286) (xy -0.635 0.2286) (xy -0.635 -0.254) (xy -0.5334 -0.254)
				(xy -0.5334 -0.2794) (xy 0.5334 -0.2794) (xy 0.5334 -0.254) (xy 0.635 -0.254) (xy 0.635 0.254) (xy 0.5334 0.254)
				(xy 0.5334 0.2794)
			)
			(stroke
				(width 0)
				(type default)
			)
			(fill no)
			(layer "F.CrtYd")
		)
		(pad "1" smd rect
			(at 0.40005 0 270)
			(size 0.4572 0.508)
			(layers "F.Cu" "F.Mask" "F.Paste")
			(net "T8_NODE1_EN")
		)
		(pad "2" smd rect
			(at -0.40005 0 270)
			(size 0.4572 0.508)
			(layers "F.Cu" "F.Mask" "F.Paste")
			(net "T8_NODE1_EN_R")
		)
	)
	(footprint ""
		(layer "F.Cu")
		(at 66.491358 -8.501888 180)
		(property "Reference" "PC53"
			(at 1.450086 4.286504 0)
			(unlocked yes)
			(layer "F.SilkS")
			(effects
				(font
					(size 0.7874 0.5842)
					(thickness 0.1524)
				)
				(justify left)
			)
		)
		(property "Value" ""
			(at 0 0 180)
			(layer "F.Fab")
			(effects
				(font
					(size 1.27 1.27)
				)
			)
		)
		(duplicate_pad_numbers_are_jumpers no)
		(fp_line
			(start 0.7874 0.4064)
			(end -0.7874 0.4064)
			(stroke
				(width 0.1524)
				(type default)
			)
			(layer "F.SilkS")
		)
		(fp_line
			(start 0.7874 -0.4064)
			(end 0.7874 0.4064)
			(stroke
				(width 0.1524)
				(type default)
			)
			(layer "F.SilkS")
		)
		(fp_line
			(start 0 0.381)
			(end 0 -0.381)
			(stroke
				(width 0.1524)
				(type default)
			)
			(layer "F.SilkS")
		)
		(fp_line
			(start -0.7874 0.4064)
			(end -0.7874 -0.4064)
			(stroke
				(width 0.1524)
				(type default)
			)
			(layer "F.SilkS")
		)
		(fp_line
			(start -0.7874 -0.4064)
			(end 0.7874 -0.4064)
			(stroke
				(width 0.1524)
				(type default)
			)
			(layer "F.SilkS")
		)
		(fp_poly
			(pts
				(xy -0.5334 0.254) (xy -0.635 0.254) (xy -0.635 0.2286) (xy -0.635 -0.254) (xy -0.5334 -0.254) (xy -0.5334 -0.2794)
				(xy 0.5334 -0.2794) (xy 0.5334 -0.254) (xy 0.635 -0.254) (xy 0.635 0.254) (xy 0.5334 0.254) (xy 0.5334 0.2794)
				(xy -0.508 0.2794) (xy -0.5334 0.2794)
			)
			(stroke
				(width 0)
				(type default)
			)
			(fill no)
			(layer "F.CrtYd")
		)
		(pad "1" smd rect
			(at 0.40005 0 180)
			(size 0.4572 0.508)
			(layers "F.Cu" "F.Mask" "F.Paste")
			(net "P3V3_NODE1_FB")
		)
		(pad "2" smd rect
			(at -0.40005 0 180)
			(size 0.4572 0.508)
			(layers "F.Cu" "F.Mask" "F.Paste")
			(net "P3V3_NODE1")
		)
	)
	(footprint ""
		(layer "F.Cu")
		(at 79.558388 -96.661732 90)
		(property "Reference" "R1052"
			(at 3.264408 -0.421894 90)
			(unlocked yes)
			(layer "F.SilkS")
			(effects
				(font
					(size 0.7874 0.5842)
					(thickness 0.1524)
				)
				(justify left)
			)
		)
		(property "Value" ""
			(at 0 0 90)
			(layer "F.Fab")
			(effects
				(font
					(size 1.27 1.27)
				)
			)
		)
		(duplicate_pad_numbers_are_jumpers no)
		(fp_line
			(start 0.7874 -0.4064)
			(end 0.7874 0.4064)
			(stroke
				(width 0.1524)
				(type default)
			)
			(layer "F.SilkS")
		)
		(fp_line
			(start -0.7874 -0.4064)
			(end 0.7874 -0.4064)
			(stroke
				(width 0.1524)
				(type default)
			)
			(layer "F.SilkS")
		)
		(fp_line
			(start 0.7874 0.4064)
			(end -0.7874 0.4064)
			(stroke
				(width 0.1524)
				(type default)
			)
			(layer "F.SilkS")
		)
		(fp_line
			(start -0.7874 0.4064)
			(end -0.7874 -0.4064)
			(stroke
				(width 0.1524)
				(type default)
			)
			(layer "F.SilkS")
		)
		(fp_poly
			(pts
				(xy -0.508 0.2794) (xy -0.508 0.2286) (xy -0.635 0.2286) (xy -0.635 -0.254) (xy -0.5334 -0.254)
				(xy -0.5334 -0.2794) (xy 0.5334 -0.2794) (xy 0.5334 -0.254) (xy 0.635 -0.254) (xy 0.635 0.254) (xy 0.5334 0.254)
				(xy 0.5334 0.2794)
			)
			(stroke
				(width 0)
				(type default)
			)
			(fill no)
			(layer "F.CrtYd")
		)
		(pad "1" smd rect
			(at 0.40005 0 90)
			(size 0.4572 0.508)
			(layers "F.Cu" "F.Mask" "F.Paste")
			(net "CLK_33K_CPU_NODE1_SUSCLK_R")
		)
		(pad "2" smd rect
			(at -0.40005 0 90)
			(size 0.4572 0.508)
			(layers "F.Cu" "F.Mask" "F.Paste")
			(net "CLK_33K_CPU_NODE1_SUSCLK")
		)
	)
	(footprint ""
		(layer "F.Cu")
		(at 48.262286 -114.424714 180)
		(property "Reference" "PC11"
			(at 1.882394 2.665476 0)
			(unlocked yes)
			(layer "F.SilkS")
			(effects
				(font
					(size 0.7874 0.5842)
					(thickness 0.1524)
				)
				(justify left)
			)
		)
		(property "Value" ""
			(at 0 0 180)
			(layer "F.Fab")
			(effects
				(font
					(size 1.27 1.27)
				)
			)
		)
		(duplicate_pad_numbers_are_jumpers no)
		(fp_line
			(start 2.2098 0.9398)
			(end -2.2098 0.9398)
			(stroke
				(width 0.1524)
				(type default)
			)
			(layer "F.SilkS")
		)
		(fp_line
			(start 2.2098 -0.9398)
			(end 2.2098 0.9398)
			(stroke
				(width 0.1524)
				(type default)
			)
			(layer "F.SilkS")
		)
		(fp_line
			(start 0 -0.9398)
			(end 0 0.9398)
			(stroke
				(width 0.1524)
				(type default)
			)
			(layer "F.SilkS")
		)
		(fp_line
			(start -2.2098 0.9398)
			(end -2.2098 -0.9398)
			(stroke
				(width 0.1524)
				(type default)
			)
			(layer "F.SilkS")
		)
		(fp_line
			(start -2.2098 -0.9398)
			(end 2.2098 -0.9398)
			(stroke
				(width 0.1524)
				(type default)
			)
			(layer "F.SilkS")
		)
		(fp_poly
			(pts
				(xy -1.6764 0.889) (xy -1.6764 0.7874) (xy -2.0574 0.7874) (xy -2.0574 -0.7874) (xy -1.6764 -0.7874)
				(xy -1.6764 -0.9398) (xy 1.6764 -0.9398) (xy 1.6764 -0.7874) (xy 2.0574 -0.7874) (xy 2.0574 0.7874)
				(xy 1.6764 0.7874) (xy 1.6764 0.9398) (xy -1.6764 0.9398)
			)
			(stroke
				(width 0)
				(type default)
			)
			(fill no)
			(layer "F.CrtYd")
		)
		(fp_line
			(start 1.700022 0.899922)
			(end -1.700022 0.899922)
			(stroke
				(width 0.1)
				(type default)
			)
			(layer "F.Fab")
		)
		(fp_line
			(start 1.700022 -0.899922)
			(end 1.700022 0.899922)
			(stroke
				(width 0.1)
				(type default)
			)
			(layer "F.Fab")
		)
		(fp_line
			(start -1.700022 0.899922)
			(end -1.700022 -0.899922)
			(stroke
				(width 0.1)
				(type default)
			)
			(layer "F.Fab")
		)
		(fp_line
			(start -1.700022 -0.899922)
			(end 1.700022 -0.899922)
			(stroke
				(width 0.1)
				(type default)
			)
			(layer "F.Fab")
		)
		(pad "1" smd rect
			(at 1.4732 0 180)
			(size 1.1684 1.5748)
			(layers "F.Cu" "F.Mask" "F.Paste")
			(net "P12V_AUX")
		)
		(pad "2" smd rect
			(at -1.4732 0 180)
			(size 1.1684 1.5748)
			(layers "F.Cu" "F.Mask" "F.Paste")
			(net "GND")
		)
	)
	(footprint ""
		(layer "F.Cu")
		(at -73.134728 -265.390884)
		(property "Reference" "H10_SRW"
			(at 1.819148 -1.728978 0)
			(unlocked yes)
			(layer "B.SilkS")
			(effects
				(font
					(size 0.7874 0.5842)
					(thickness 0.1524)
				)
				(justify left mirror)
			)
		)
		(property "Value" ""
			(at 0 0 0)
			(layer "F.Fab")
			(effects
				(font
					(size 1.27 1.27)
				)
			)
		)
		(duplicate_pad_numbers_are_jumpers no)
		(fp_poly
			(pts
				(arc
					(start 0.3302 0)
					(mid -0.3302 0)
					(end 0.3302 0)
				)
			)
			(stroke
				(width 0)
				(type default)
			)
			(fill no)
			(layer "B.CrtYd")
		)
		(pad "1" thru_hole circle
			(at 0 0)
			(size 0.508 0.508)
			(drill 0.254)
			(layers "*.Cu" "*.Mask")
			(remove_unused_layers no)
			(net "Net_219")
			(clearance 0.127)
			(thermal_gap 0.127)
			(padstack
				(mode front_inner_back)
				(layer "Inner"
					(shape circle)
					(size 0.508 0.508)
					(clearance 0.127)
				)
				(layer "B.Cu"
					(shape circle)
					(size 0.6604 0.6604)
					(clearance 0.0508)
				)
			)
		)
	)
	(footprint ""
		(layer "F.Cu")
		(at 152.579578 -69.060822)
		(property "Reference" "R505"
			(at -1.658366 -2.39395 0)
			(unlocked yes)
			(layer "F.SilkS")
			(effects
				(font
					(size 0.7874 0.5842)
					(thickness 0.1524)
				)
				(justify left)
			)
		)
		(property "Value" ""
			(at 0 0 0)
			(layer "F.Fab")
			(effects
				(font
					(size 1.27 1.27)
				)
			)
		)
		(duplicate_pad_numbers_are_jumpers no)
		(fp_line
			(start -0.7874 -0.4064)
			(end 0.7874 -0.4064)
			(stroke
				(width 0.1524)
				(type default)
			)
			(layer "F.SilkS")
		)
		(fp_line
			(start -0.7874 0.4064)
			(end -0.7874 -0.4064)
			(stroke
				(width 0.1524)
				(type default)
			)
			(layer "F.SilkS")
		)
		(fp_line
			(start 0.7874 -0.4064)
			(end 0.7874 0.4064)
			(stroke
				(width 0.1524)
				(type default)
			)
			(layer "F.SilkS")
		)
		(fp_line
			(start 0.7874 0.4064)
			(end -0.7874 0.4064)
			(stroke
				(width 0.1524)
				(type default)
			)
			(layer "F.SilkS")
		)
		(fp_poly
			(pts
				(xy -0.508 0.2794) (xy -0.508 0.2286) (xy -0.635 0.2286) (xy -0.635 -0.254) (xy -0.5334 -0.254)
				(xy -0.5334 -0.2794) (xy 0.5334 -0.2794) (xy 0.5334 -0.254) (xy 0.635 -0.254) (xy 0.635 0.254) (xy 0.5334 0.254)
				(xy 0.5334 0.2794)
			)
			(stroke
				(width 0)
				(type default)
			)
			(fill no)
			(layer "F.CrtYd")
		)
		(pad "1" smd rect
			(at 0.40005 0)
			(size 0.4572 0.508)
			(layers "F.Cu" "F.Mask" "F.Paste")
			(net "GND")
		)
		(pad "2" smd rect
			(at -0.40005 0)
			(size 0.4572 0.508)
			(layers "F.Cu" "F.Mask" "F.Paste")
			(net "SATA_NODE1_XTLOUT")
		)
	)
	(footprint ""
		(layer "F.Cu")
		(at 95.813372 -161.137092)
		(property "Reference" "U105"
			(at 88.933274 71.779892 90)
			(unlocked yes)
			(layer "F.SilkS")
			(effects
				(font
					(size 0.7874 0.5842)
					(thickness 0.1524)
				)
			)
		)
		(property "Value" ""
			(at 0 0 0)
			(layer "F.Fab")
			(effects
				(font
					(size 1.27 1.27)
				)
			)
		)
		(duplicate_pad_numbers_are_jumpers no)
		(fp_line
			(start -1.651 -1.905)
			(end 1.651 -1.905)
			(stroke
				(width 0.1524)
				(type default)
			)
			(layer "F.SilkS")
		)
		(fp_line
			(start -1.651 1.905)
			(end -1.651 -1.905)
			(stroke
				(width 0.1524)
				(type default)
			)
			(layer "F.SilkS")
		)
		(fp_line
			(start 1.651 -1.905)
			(end 1.651 1.905)
			(stroke
				(width 0.1524)
				(type default)
			)
			(layer "F.SilkS")
		)
		(fp_line
			(start 1.651 1.905)
			(end -1.651 1.905)
			(stroke
				(width 0.1524)
				(type default)
			)
			(layer "F.SilkS")
		)
		(fp_poly
			(pts
				(xy -1.524 0.7112) (xy -1.524 1.7526) (xy -0.508 1.7526) (xy -0.508 0.6985) (xy 0.508 0.6985) (xy 0.508 1.7526)
				(xy 1.524 1.7526) (xy 1.524 0.6985) (xy 1.524 -0.6985) (xy 0.508 -0.6985) (xy 0.508 -1.7526) (xy -0.508 -1.7526)
				(xy -0.508 -0.6985) (xy -1.524 -0.6985) (xy -1.524 0.6985)
			)
			(stroke
				(width 0)
				(type default)
			)
			(fill no)
			(layer "F.CrtYd")
		)
		(fp_text user "G"
			(at -1.856994 1.673352 0)
			(unlocked yes)
			(layer "F.SilkS")
			(effects
				(font
					(size 0.635 0.4064)
					(thickness 0.1524)
				)
			)
		)
		(fp_text user "D"
			(at 0.511556 -2.534412 0)
			(unlocked yes)
			(layer "F.SilkS")
			(effects
				(font
					(size 0.635 0.4064)
					(thickness 0.1524)
				)
			)
		)
		(fp_text user "S"
			(at 2.015998 0.473964 0)
			(unlocked yes)
			(layer "F.SilkS")
			(effects
				(font
					(size 0.635 0.4064)
					(thickness 0.1524)
				)
			)
		)
		(pad "D" smd rect
			(at 0 -1.1176)
			(size 1.016 1.27)
			(layers "F.Cu" "F.Mask" "F.Paste")
			(net "N52411040")
		)
		(pad "G" smd rect
			(at -1.016 1.1176)
			(size 1.016 1.27)
			(layers "F.Cu" "F.Mask" "F.Paste")
			(net "N52410998")
		)
		(pad "S" smd rect
			(at 1.016 1.1176)
			(size 1.016 1.27)
			(layers "F.Cu" "F.Mask" "F.Paste")
			(net "GND")
		)
	)
	(footprint ""
		(layer "F.Cu")
		(at 68.353686 -121.044462 -90)
		(property "Reference" "R255"
			(at 6.142736 -6.807708 90)
			(unlocked yes)
			(layer "F.SilkS")
			(effects
				(font
					(size 0.7874 0.5842)
					(thickness 0.1524)
				)
				(justify left)
			)
		)
		(property "Value" ""
			(at 0 0 270)
			(layer "F.Fab")
			(effects
				(font
					(size 1.27 1.27)
				)
			)
		)
		(duplicate_pad_numbers_are_jumpers no)
		(fp_line
			(start -0.7874 0.4064)
			(end -0.7874 -0.4064)
			(stroke
				(width 0.1524)
				(type default)
			)
			(layer "F.SilkS")
		)
		(fp_line
			(start 0.7874 0.4064)
			(end -0.7874 0.4064)
			(stroke
				(width 0.1524)
				(type default)
			)
			(layer "F.SilkS")
		)
		(fp_line
			(start -0.7874 -0.4064)
			(end 0.7874 -0.4064)
			(stroke
				(width 0.1524)
				(type default)
			)
			(layer "F.SilkS")
		)
		(fp_line
			(start 0.7874 -0.4064)
			(end 0.7874 0.4064)
			(stroke
				(width 0.1524)
				(type default)
			)
			(layer "F.SilkS")
		)
		(fp_poly
			(pts
				(xy -0.508 0.2794) (xy -0.508 0.2286) (xy -0.635 0.2286) (xy -0.635 -0.254) (xy -0.5334 -0.254)
				(xy -0.5334 -0.2794) (xy 0.5334 -0.2794) (xy 0.5334 -0.254) (xy 0.635 -0.254) (xy 0.635 0.254) (xy 0.5334 0.254)
				(xy 0.5334 0.2794)
			)
			(stroke
				(width 0)
				(type default)
			)
			(fill no)
			(layer "F.CrtYd")
		)
		(pad "1" smd rect
			(at 0.40005 0 270)
			(size 0.4572 0.508)
			(layers "F.Cu" "F.Mask" "F.Paste")
			(net "IRQ_LVC3_CPU_NODE1_WAKE_L")
		)
		(pad "2" smd rect
			(at -0.40005 0 270)
			(size 0.4572 0.508)
			(layers "F.Cu" "F.Mask" "F.Paste")
			(net "IRQ_LVC3_CPU_NODE1_WAKE_R_L")
		)
	)
	(footprint ""
		(layer "F.Cu")
		(at 21.871178 -160.379156 180)
		(property "Reference" "U137"
			(at 5.163058 8.864092 0)
			(unlocked yes)
			(layer "F.SilkS")
			(effects
				(font
					(size 0.7874 0.5842)
					(thickness 0.1524)
				)
				(justify left)
			)
		)
		(property "Value" ""
			(at 0 0 180)
			(layer "F.Fab")
			(effects
				(font
					(size 1.27 1.27)
				)
			)
		)
		(duplicate_pad_numbers_are_jumpers no)
		(fp_line
			(start 3.564128 7.800086)
			(end -3.564128 7.800086)
			(stroke
				(width 0.1524)
				(type default)
			)
			(layer "F.SilkS")
		)
		(fp_line
			(start 3.564128 -7.800086)
			(end 3.564128 7.800086)
			(stroke
				(width 0.1524)
				(type default)
			)
			(layer "F.SilkS")
		)
		(fp_line
			(start 1.800098 -7.800086)
			(end 3.564128 -7.800086)
			(stroke
				(width 0.1524)
				(type default)
			)
			(layer "F.SilkS")
		)
		(fp_line
			(start 0 -5.999988)
			(end 1.800098 -7.800086)
			(stroke
				(width 0.1524)
				(type default)
			)
			(layer "F.SilkS")
		)
		(fp_line
			(start -1.800098 -7.800086)
			(end 0 -5.999988)
			(stroke
				(width 0.1524)
				(type default)
			)
			(layer "F.SilkS")
		)
		(fp_line
			(start -3.564128 7.800086)
			(end -3.564128 -7.800086)
			(stroke
				(width 0.1524)
				(type default)
			)
			(layer "F.SilkS")
		)
		(fp_line
			(start -3.564128 -7.800086)
			(end -1.800098 -7.800086)
			(stroke
				(width 0.1524)
				(type default)
			)
			(layer "F.SilkS")
		)
		(fp_poly
			(pts
				(xy -6.477 -7.493) (xy -6.477 -6.477) (xy -5.461 -6.985)
			)
			(stroke
				(width 0)
				(type default)
			)
			(fill yes)
			(layer "F.SilkS")
		)
		(fp_poly
			(pts
				(xy -4.249928 7.800086) (xy -4.249928 7.4422) (xy -5.300472 7.4422) (xy -5.300472 -7.4422) (xy -4.249928 -7.4422)
				(xy -4.249928 -7.800086) (xy 4.249928 -7.800086) (xy 4.249928 -7.4422) (xy 5.300472 -7.4422) (xy 5.300472 7.4422)
				(xy 4.249928 7.4422) (xy 4.249928 7.800086)
			)
			(stroke
				(width 0)
				(type default)
			)
			(fill no)
			(layer "F.CrtYd")
		)
		(fp_line
			(start 4.249928 7.800086)
			(end 4.249928 -7.800086)
			(stroke
				(width 0.1)
				(type default)
			)
			(layer "F.Fab")
		)
		(fp_line
			(start 4.249928 -7.800086)
			(end -4.249928 -7.800086)
			(stroke
				(width 0.1)
				(type default)
			)
			(layer "F.Fab")
		)
		(fp_line
			(start -4.249928 7.800086)
			(end 4.249928 7.800086)
			(stroke
				(width 0.1)
				(type default)
			)
			(layer "F.Fab")
		)
		(fp_line
			(start -4.249928 -7.800086)
			(end -4.249928 7.800086)
			(stroke
				(width 0.1)
				(type default)
			)
			(layer "F.Fab")
		)
		(fp_poly
			(pts
				(xy -6.477 -7.493) (xy -6.477 -6.477) (xy -5.461 -6.985)
			)
			(stroke
				(width 0)
				(type default)
			)
			(fill yes)
			(layer "F.Fab")
		)
		(pad "1" smd rect
			(at -4.474972 -6.985 90)
			(size 0.8128 1.5494)
			(layers "F.Cu" "F.Mask" "F.Paste")
			(net "LAN1_MDI0_DP")
		)
		(pad "2" smd rect
			(at -4.474972 -5.715 90)
			(size 0.8128 1.5494)
			(layers "F.Cu" "F.Mask" "F.Paste")
			(net "LAN1_MDI0_DN")
		)
		(pad "3" smd rect
			(at -4.474972 -4.445 90)
			(size 0.8128 1.5494)
			(layers "F.Cu" "F.Mask" "F.Paste")
			(net "P1V9_LAN1")
		)
		(pad "4" smd rect
			(at -4.474972 -3.175 90)
			(size 0.8128 1.5494)
			(layers "F.Cu" "F.Mask" "F.Paste")
			(net "P1V9_LAN1")
		)
		(pad "5" smd rect
			(at -4.474972 -1.905 90)
			(size 0.8128 1.5494)
			(layers "F.Cu" "F.Mask" "F.Paste")
			(net "LAN1_MDI1_DP")
		)
		(pad "6" smd rect
			(at -4.474972 -0.635 90)
			(size 0.8128 1.5494)
			(layers "F.Cu" "F.Mask" "F.Paste")
			(net "LAN1_MDI1_DN")
		)
		(pad "7" smd rect
			(at -4.474972 0.635 90)
			(size 0.8128 1.5494)
			(layers "F.Cu" "F.Mask" "F.Paste")
			(net "LAN1_MDI2_DP")
		)
		(pad "8" smd rect
			(at -4.474972 1.905 90)
			(size 0.8128 1.5494)
			(layers "F.Cu" "F.Mask" "F.Paste")
			(net "LAN1_MDI2_DN")
		)
		(pad "9" smd rect
			(at -4.474972 3.175 90)
			(size 0.8128 1.5494)
			(layers "F.Cu" "F.Mask" "F.Paste")
			(net "P1V9_LAN1")
		)
		(pad "10" smd rect
			(at -4.474972 4.445 90)
			(size 0.8128 1.5494)
			(layers "F.Cu" "F.Mask" "F.Paste")
			(net "P1V9_LAN1")
		)
		(pad "11" smd rect
			(at -4.474972 5.715 90)
			(size 0.8128 1.5494)
			(layers "F.Cu" "F.Mask" "F.Paste")
			(net "LAN1_MDI3_DP")
		)
		(pad "12" smd rect
			(at -4.474972 6.985 90)
			(size 0.8128 1.5494)
			(layers "F.Cu" "F.Mask" "F.Paste")
			(net "LAN1_MDI3_DN")
		)
		(pad "13" smd rect
			(at 4.474972 6.985 90)
			(size 0.8128 1.5494)
			(layers "F.Cu" "F.Mask" "F.Paste")
			(net "LAN1_P4_N")
		)
		(pad "14" smd rect
			(at 4.474972 5.715 90)
			(size 0.8128 1.5494)
			(layers "F.Cu" "F.Mask" "F.Paste")
			(net "LAN1_P4_P")
		)
		(pad "15" smd rect
			(at 4.474972 4.445 90)
			(size 0.8128 1.5494)
			(layers "F.Cu" "F.Mask" "F.Paste")
			(net "LAN1_P4_R")
		)
		(pad "16" smd rect
			(at 4.474972 3.175 90)
			(size 0.8128 1.5494)
			(layers "F.Cu" "F.Mask" "F.Paste")
			(net "LAN1_P3_R")
		)
		(pad "17" smd rect
			(at 4.474972 1.905 90)
			(size 0.8128 1.5494)
			(layers "F.Cu" "F.Mask" "F.Paste")
			(net "LAN1_P3_N")
		)
		(pad "18" smd rect
			(at 4.474972 0.635 90)
			(size 0.8128 1.5494)
			(layers "F.Cu" "F.Mask" "F.Paste")
			(net "LAN1_P3_P")
		)
		(pad "19" smd rect
			(at 4.474972 -0.635 90)
			(size 0.8128 1.5494)
			(layers "F.Cu" "F.Mask" "F.Paste")
			(net "LAN1_P2_N")
		)
		(pad "20" smd rect
			(at 4.474972 -1.905 90)
			(size 0.8128 1.5494)
			(layers "F.Cu" "F.Mask" "F.Paste")
			(net "LAN1_P2_P")
		)
		(pad "21" smd rect
			(at 4.474972 -3.175 90)
			(size 0.8128 1.5494)
			(layers "F.Cu" "F.Mask" "F.Paste")
			(net "LAN1_P2_R")
		)
		(pad "22" smd rect
			(at 4.474972 -4.445 90)
			(size 0.8128 1.5494)
			(layers "F.Cu" "F.Mask" "F.Paste")
			(net "LAN1_P1_R")
		)
		(pad "23" smd rect
			(at 4.474972 -5.715 90)
			(size 0.8128 1.5494)
			(layers "F.Cu" "F.Mask" "F.Paste")
			(net "LAN1_P1_N")
		)
		(pad "24" smd rect
			(at 4.474972 -6.985 90)
			(size 0.8128 1.5494)
			(layers "F.Cu" "F.Mask" "F.Paste")
			(net "LAN1_P1_P")
		)
	)
	(footprint ""
		(layer "F.Cu")
		(at 26.91892 -135.941308 180)
		(property "Reference" "C432"
			(at -0.07112 -1.40716 0)
			(unlocked yes)
			(layer "F.SilkS")
			(effects
				(font
					(size 0.7874 0.5842)
					(thickness 0.1524)
				)
			)
		)
		(property "Value" ""
			(at 0 0 180)
			(layer "F.Fab")
			(effects
				(font
					(size 1.27 1.27)
				)
			)
		)
		(duplicate_pad_numbers_are_jumpers no)
		(fp_line
			(start 1.2954 0.5842)
			(end -1.2954 0.5842)
			(stroke
				(width 0.1524)
				(type default)
			)
			(layer "F.SilkS")
		)
		(fp_line
			(start 1.2954 -0.5842)
			(end 1.2954 0.5842)
			(stroke
				(width 0.1524)
				(type default)
			)
			(layer "F.SilkS")
		)
		(fp_line
			(start 0 -0.5842)
			(end 0 0.5842)
			(stroke
				(width 0.1524)
				(type default)
			)
			(layer "F.SilkS")
		)
		(fp_line
			(start -1.2954 0.5842)
			(end -1.2954 -0.5842)
			(stroke
				(width 0.1524)
				(type default)
			)
			(layer "F.SilkS")
		)
		(fp_line
			(start -1.2954 -0.5842)
			(end 1.2954 -0.5842)
			(stroke
				(width 0.1524)
				(type default)
			)
			(layer "F.SilkS")
		)
		(fp_poly
			(pts
				(xy 0.8636 -0.4572) (xy 0.8636 -0.3556) (xy 1.143 -0.3556) (xy 1.143 0.3556) (xy 0.8636 0.3556)
				(xy 0.8636 0.4572) (xy -0.8636 0.4572) (xy -0.8636 0.3556) (xy -1.143 0.3556) (xy -1.143 -0.3556)
				(xy -0.8636 -0.3556) (xy -0.8636 -0.4572)
			)
			(stroke
				(width 0)
				(type default)
			)
			(fill no)
			(layer "F.CrtYd")
		)
		(fp_line
			(start 0.884936 0.504952)
			(end -0.884936 0.504952)
			(stroke
				(width 0.1)
				(type default)
			)
			(layer "F.Fab")
		)
		(fp_line
			(start 0.884936 -0.504952)
			(end 0.884936 0.504952)
			(stroke
				(width 0.1)
				(type default)
			)
			(layer "F.Fab")
		)
		(fp_line
			(start -0.884936 0.504952)
			(end -0.884936 -0.504952)
			(stroke
				(width 0.1)
				(type default)
			)
			(layer "F.Fab")
		)
		(fp_line
			(start -0.884936 -0.504952)
			(end 0.884936 -0.504952)
			(stroke
				(width 0.1)
				(type default)
			)
			(layer "F.Fab")
		)
		(pad "1" smd rect
			(at 0.7366 0 270)
			(size 0.7112 0.8128)
			(layers "F.Cu" "F.Mask" "F.Paste")
			(net "P1V9_LAN1")
		)
		(pad "2" smd rect
			(at -0.7366 0 270)
			(size 0.7112 0.8128)
			(layers "F.Cu" "F.Mask" "F.Paste")
			(net "GND")
		)
	)
	(footprint ""
		(layer "F.Cu")
		(at 15.284958 -62.089538 -90)
		(property "Reference" "R635"
			(at 0.357886 1.025144 90)
			(unlocked yes)
			(layer "F.SilkS")
			(effects
				(font
					(size 0.7874 0.5842)
					(thickness 0.1524)
				)
				(justify left)
			)
		)
		(property "Value" ""
			(at 0 0 270)
			(layer "F.Fab")
			(effects
				(font
					(size 1.27 1.27)
				)
			)
		)
		(duplicate_pad_numbers_are_jumpers no)
		(fp_line
			(start -0.7874 0.4064)
			(end -0.7874 -0.4064)
			(stroke
				(width 0.1524)
				(type default)
			)
			(layer "F.SilkS")
		)
		(fp_line
			(start 0.7874 0.4064)
			(end -0.7874 0.4064)
			(stroke
				(width 0.1524)
				(type default)
			)
			(layer "F.SilkS")
		)
		(fp_line
			(start -0.7874 -0.4064)
			(end 0.7874 -0.4064)
			(stroke
				(width 0.1524)
				(type default)
			)
			(layer "F.SilkS")
		)
		(fp_line
			(start 0.7874 -0.4064)
			(end 0.7874 0.4064)
			(stroke
				(width 0.1524)
				(type default)
			)
			(layer "F.SilkS")
		)
		(fp_poly
			(pts
				(xy -0.508 0.2794) (xy -0.508 0.2286) (xy -0.635 0.2286) (xy -0.635 -0.254) (xy -0.5334 -0.254)
				(xy -0.5334 -0.2794) (xy 0.5334 -0.2794) (xy 0.5334 -0.254) (xy 0.635 -0.254) (xy 0.635 0.254) (xy 0.5334 0.254)
				(xy 0.5334 0.2794)
			)
			(stroke
				(width 0)
				(type default)
			)
			(fill no)
			(layer "F.CrtYd")
		)
		(pad "1" smd rect
			(at 0.40005 0 270)
			(size 0.4572 0.508)
			(layers "F.Cu" "F.Mask" "F.Paste")
			(net "P5V_CRT")
		)
		(pad "2" smd rect
			(at -0.40005 0 270)
			(size 0.4572 0.508)
			(layers "F.Cu" "F.Mask" "F.Paste")
			(net "I2C_VIDREAR_5V_SCL")
		)
	)
	(footprint ""
		(layer "F.Cu")
		(at 119.138192 -39.93769 180)
		(property "Reference" "R618"
			(at 1.03378 -3.443986 0)
			(unlocked yes)
			(layer "F.SilkS")
			(effects
				(font
					(size 0.7874 0.5842)
					(thickness 0.1524)
				)
				(justify left)
			)
		)
		(property "Value" ""
			(at 0 0 180)
			(layer "F.Fab")
			(effects
				(font
					(size 1.27 1.27)
				)
			)
		)
		(duplicate_pad_numbers_are_jumpers no)
		(fp_line
			(start 0.7874 0.4064)
			(end -0.7874 0.4064)
			(stroke
				(width 0.1524)
				(type default)
			)
			(layer "F.SilkS")
		)
		(fp_line
			(start 0.7874 -0.4064)
			(end 0.7874 0.4064)
			(stroke
				(width 0.1524)
				(type default)
			)
			(layer "F.SilkS")
		)
		(fp_line
			(start -0.7874 0.4064)
			(end -0.7874 -0.4064)
			(stroke
				(width 0.1524)
				(type default)
			)
			(layer "F.SilkS")
		)
		(fp_line
			(start -0.7874 -0.4064)
			(end 0.7874 -0.4064)
			(stroke
				(width 0.1524)
				(type default)
			)
			(layer "F.SilkS")
		)
		(fp_poly
			(pts
				(xy -0.508 0.2794) (xy -0.508 0.2286) (xy -0.635 0.2286) (xy -0.635 -0.254) (xy -0.5334 -0.254)
				(xy -0.5334 -0.2794) (xy 0.5334 -0.2794) (xy 0.5334 -0.254) (xy 0.635 -0.254) (xy 0.635 0.254) (xy 0.5334 0.254)
				(xy 0.5334 0.2794)
			)
			(stroke
				(width 0)
				(type default)
			)
			(fill no)
			(layer "F.CrtYd")
		)
		(pad "1" smd rect
			(at 0.40005 0 180)
			(size 0.4572 0.508)
			(layers "F.Cu" "F.Mask" "F.Paste")
			(net "OSC1_48MHZ")
		)
		(pad "2" smd rect
			(at -0.40005 0 180)
			(size 0.4572 0.508)
			(layers "F.Cu" "F.Mask" "F.Paste")
			(net "SIO_CLKIN")
		)
	)
	(footprint ""
		(layer "F.Cu")
		(at 35.991546 -7.212076 -90)
		(property "Reference" "PC86"
			(at 0.612902 9.233408 90)
			(unlocked yes)
			(layer "F.SilkS")
			(effects
				(font
					(size 0.7874 0.5842)
					(thickness 0.1524)
				)
			)
		)
		(property "Value" ""
			(at 0 0 270)
			(layer "F.Fab")
			(effects
				(font
					(size 1.27 1.27)
				)
			)
		)
		(duplicate_pad_numbers_are_jumpers no)
		(fp_line
			(start -1.2954 0.5842)
			(end -1.2954 -0.5842)
			(stroke
				(width 0.1524)
				(type default)
			)
			(layer "F.SilkS")
		)
		(fp_line
			(start 1.2954 0.5842)
			(end -1.2954 0.5842)
			(stroke
				(width 0.1524)
				(type default)
			)
			(layer "F.SilkS")
		)
		(fp_line
			(start -1.2954 -0.5842)
			(end 1.2954 -0.5842)
			(stroke
				(width 0.1524)
				(type default)
			)
			(layer "F.SilkS")
		)
		(fp_line
			(start 0 -0.5842)
			(end 0 0.5842)
			(stroke
				(width 0.1524)
				(type default)
			)
			(layer "F.SilkS")
		)
		(fp_line
			(start 1.2954 -0.5842)
			(end 1.2954 0.5842)
			(stroke
				(width 0.1524)
				(type default)
			)
			(layer "F.SilkS")
		)
		(fp_poly
			(pts
				(xy 0.8636 -0.4572) (xy 0.8636 -0.3556) (xy 1.143 -0.3556) (xy 1.143 0.3556) (xy 0.8636 0.3556)
				(xy 0.8636 0.4572) (xy -0.8636 0.4572) (xy -0.8636 0.3556) (xy -1.143 0.3556) (xy -1.143 -0.3556)
				(xy -0.8636 -0.3556) (xy -0.8636 -0.4572)
			)
			(stroke
				(width 0)
				(type default)
			)
			(fill no)
			(layer "F.CrtYd")
		)
		(fp_line
			(start -0.884936 0.504952)
			(end -0.884936 -0.504952)
			(stroke
				(width 0.1)
				(type default)
			)
			(layer "F.Fab")
		)
		(fp_line
			(start 0.884936 0.504952)
			(end -0.884936 0.504952)
			(stroke
				(width 0.1)
				(type default)
			)
			(layer "F.Fab")
		)
		(fp_line
			(start -0.884936 -0.504952)
			(end 0.884936 -0.504952)
			(stroke
				(width 0.1)
				(type default)
			)
			(layer "F.Fab")
		)
		(fp_line
			(start 0.884936 -0.504952)
			(end 0.884936 0.504952)
			(stroke
				(width 0.1)
				(type default)
			)
			(layer "F.Fab")
		)
		(pad "1" smd rect
			(at 0.7366 0)
			(size 0.7112 0.8128)
			(layers "F.Cu" "F.Mask" "F.Paste")
			(net "GND")
		)
		(pad "2" smd rect
			(at -0.7366 0)
			(size 0.7112 0.8128)
			(layers "F.Cu" "F.Mask" "F.Paste")
			(net "PV_VDDR_NODE1_VREF")
		)
	)
	(footprint ""
		(layer "F.Cu")
		(at 82.53476 -185.205624 -90)
		(property "Reference" "R895"
			(at -4.198112 1.795272 90)
			(unlocked yes)
			(layer "F.SilkS")
			(effects
				(font
					(size 0.7874 0.5842)
					(thickness 0.1524)
				)
				(justify left)
			)
		)
		(property "Value" ""
			(at 0 0 270)
			(layer "F.Fab")
			(effects
				(font
					(size 1.27 1.27)
				)
			)
		)
		(duplicate_pad_numbers_are_jumpers no)
		(fp_line
			(start -0.7874 0.4064)
			(end -0.7874 -0.4064)
			(stroke
				(width 0.1524)
				(type default)
			)
			(layer "F.SilkS")
		)
		(fp_line
			(start 0.7874 0.4064)
			(end -0.7874 0.4064)
			(stroke
				(width 0.1524)
				(type default)
			)
			(layer "F.SilkS")
		)
		(fp_line
			(start -0.7874 -0.4064)
			(end 0.7874 -0.4064)
			(stroke
				(width 0.1524)
				(type default)
			)
			(layer "F.SilkS")
		)
		(fp_line
			(start 0.7874 -0.4064)
			(end 0.7874 0.4064)
			(stroke
				(width 0.1524)
				(type default)
			)
			(layer "F.SilkS")
		)
		(fp_poly
			(pts
				(xy -0.508 0.2794) (xy -0.508 0.2286) (xy -0.635 0.2286) (xy -0.635 -0.254) (xy -0.5334 -0.254)
				(xy -0.5334 -0.2794) (xy 0.5334 -0.2794) (xy 0.5334 -0.254) (xy 0.635 -0.254) (xy 0.635 0.254) (xy 0.5334 0.254)
				(xy 0.5334 0.2794)
			)
			(stroke
				(width 0)
				(type default)
			)
			(fill no)
			(layer "F.CrtYd")
		)
		(pad "1" smd rect
			(at 0.40005 0 270)
			(size 0.4572 0.508)
			(layers "F.Cu" "F.Mask" "F.Paste")
			(net "T4_NODE1_EN")
		)
		(pad "2" smd rect
			(at -0.40005 0 270)
			(size 0.4572 0.508)
			(layers "F.Cu" "F.Mask" "F.Paste")
			(net "T4_NODE1_EN_R")
		)
	)
	(footprint ""
		(layer "F.Cu")
		(at 37.48786 -164.561012 -90)
		(property "Reference" ""
			(at 0 0 270)
			(layer "F.SilkS")
			(hide yes)
			(effects
				(font
					(size 1.27 1.27)
				)
			)
		)
		(property "Value" ""
			(at 0 0 270)
			(layer "F.Fab")
			(effects
				(font
					(size 1.27 1.27)
				)
			)
		)
		(duplicate_pad_numbers_are_jumpers no)
		(fp_poly
			(pts
				(arc
					(start 0 -1.4986)
					(mid 0 1.4986)
					(end 0 -1.4986)
				)
			)
			(stroke
				(width 0)
				(type default)
			)
			(fill no)
			(layer "F.CrtYd")
		)
		(pad "1" smd circle
			(at 0 0 270)
			(size 0.9906 0.9906)
			(layers "F.Cu" "F.Mask" "F.Paste")
			(net "Net_35")
		)
		(zone
			(layer "F.Cu")
			(hatch none 0.5)
			(connect_pads
				(clearance 0)
			)
			(min_thickness 0.25)
			(keepout
				(tracks not_allowed)
				(vias allowed)
				(pads allowed)
				(copperpour not_allowed)
				(footprints allowed)
			)
			(placement
				(enabled no)
				(sheetname "")
			)
			(fill
				(thermal_gap 0.5)
				(thermal_bridge_width 0.5)
				(island_removal_mode 0)
			)
			(polygon
				(pts
					(arc
						(start 39.11346 -164.561012)
						(mid 35.86226 -164.561012)
						(end 39.11346 -164.561012)
					)
				)
			)
		)
	)
	(footprint ""
		(layer "F.Cu")
		(at 117.20576 -175.426624 90)
		(property "Reference" "R805"
			(at -57.046622 32.819848 90)
			(unlocked yes)
			(layer "F.SilkS")
			(effects
				(font
					(size 0.7874 0.5842)
					(thickness 0.1524)
				)
				(justify left)
			)
		)
		(property "Value" ""
			(at 0 0 90)
			(layer "F.Fab")
			(effects
				(font
					(size 1.27 1.27)
				)
			)
		)
		(duplicate_pad_numbers_are_jumpers no)
		(fp_line
			(start 0.7874 -0.4064)
			(end 0.7874 0.4064)
			(stroke
				(width 0.1524)
				(type default)
			)
			(layer "F.SilkS")
		)
		(fp_line
			(start -0.7874 -0.4064)
			(end 0.7874 -0.4064)
			(stroke
				(width 0.1524)
				(type default)
			)
			(layer "F.SilkS")
		)
		(fp_line
			(start 0.7874 0.4064)
			(end -0.7874 0.4064)
			(stroke
				(width 0.1524)
				(type default)
			)
			(layer "F.SilkS")
		)
		(fp_line
			(start -0.7874 0.4064)
			(end -0.7874 -0.4064)
			(stroke
				(width 0.1524)
				(type default)
			)
			(layer "F.SilkS")
		)
		(fp_poly
			(pts
				(xy -0.508 0.2794) (xy -0.508 0.2286) (xy -0.635 0.2286) (xy -0.635 -0.254) (xy -0.5334 -0.254)
				(xy -0.5334 -0.2794) (xy 0.5334 -0.2794) (xy 0.5334 -0.254) (xy 0.635 -0.254) (xy 0.635 0.254) (xy 0.5334 0.254)
				(xy 0.5334 0.2794)
			)
			(stroke
				(width 0)
				(type default)
			)
			(fill no)
			(layer "F.CrtYd")
		)
		(pad "1" smd rect
			(at 0.40005 0 90)
			(size 0.4572 0.508)
			(layers "F.Cu" "F.Mask" "F.Paste")
			(net "N31341803")
		)
		(pad "2" smd rect
			(at -0.40005 0 90)
			(size 0.4572 0.508)
			(layers "F.Cu" "F.Mask" "F.Paste")
			(net "GND")
		)
	)
	(footprint ""
		(layer "F.Cu")
		(at 122.893328 -158.608014 180)
		(property "Reference" "U118"
			(at 59.338718 -109.210348 90)
			(unlocked yes)
			(layer "F.SilkS")
			(effects
				(font
					(size 0.7874 0.5842)
					(thickness 0.1524)
				)
			)
		)
		(property "Value" ""
			(at 0 0 180)
			(layer "F.Fab")
			(effects
				(font
					(size 1.27 1.27)
				)
			)
		)
		(duplicate_pad_numbers_are_jumpers no)
		(fp_line
			(start 1.651 1.905)
			(end -1.651 1.905)
			(stroke
				(width 0.1524)
				(type default)
			)
			(layer "F.SilkS")
		)
		(fp_line
			(start 1.651 -1.905)
			(end 1.651 1.905)
			(stroke
				(width 0.1524)
				(type default)
			)
			(layer "F.SilkS")
		)
		(fp_line
			(start -1.651 1.905)
			(end -1.651 -1.905)
			(stroke
				(width 0.1524)
				(type default)
			)
			(layer "F.SilkS")
		)
		(fp_line
			(start -1.651 -1.905)
			(end 1.651 -1.905)
			(stroke
				(width 0.1524)
				(type default)
			)
			(layer "F.SilkS")
		)
		(fp_poly
			(pts
				(xy -1.524 0.7112) (xy -1.524 1.7526) (xy -0.508 1.7526) (xy -0.508 0.6985) (xy 0.508 0.6985) (xy 0.508 1.7526)
				(xy 1.524 1.7526) (xy 1.524 0.6985) (xy 1.524 -0.6985) (xy 0.508 -0.6985) (xy 0.508 -1.7526) (xy -0.508 -1.7526)
				(xy -0.508 -0.6985) (xy -1.524 -0.6985) (xy -1.524 0.6985)
			)
			(stroke
				(width 0)
				(type default)
			)
			(fill no)
			(layer "F.CrtYd")
		)
		(fp_text user "S"
			(at 1.938528 1.316736 0)
			(unlocked yes)
			(layer "F.SilkS")
			(effects
				(font
					(size 0.635 0.4064)
					(thickness 0.1524)
				)
			)
		)
		(fp_text user "G"
			(at -0.093472 1.189736 0)
			(unlocked yes)
			(layer "F.SilkS")
			(effects
				(font
					(size 0.635 0.4064)
					(thickness 0.1524)
				)
			)
		)
		(fp_text user "D"
			(at -1.12141 -1.356614 0)
			(unlocked yes)
			(layer "F.SilkS")
			(effects
				(font
					(size 0.635 0.4064)
					(thickness 0.1524)
				)
			)
		)
		(pad "D" smd rect
			(at 0 -1.1176 180)
			(size 1.016 1.27)
			(layers "F.Cu" "F.Mask" "F.Paste")
			(net "I2C_PSU2_SDA")
		)
		(pad "G" smd rect
			(at -1.016 1.1176 180)
			(size 1.016 1.27)
			(layers "F.Cu" "F.Mask" "F.Paste")
			(net "PMBUS2_EN")
		)
		(pad "S" smd rect
			(at 1.016 1.1176 180)
			(size 1.016 1.27)
			(layers "F.Cu" "F.Mask" "F.Paste")
			(net "I2C_PSU2_SDA_MOS")
		)
	)
	(footprint ""
		(layer "F.Cu")
		(at 66.41338 -170.630088)
		(property "Reference" "C617"
			(at -10.195306 131.070096 0)
			(unlocked yes)
			(layer "F.SilkS")
			(effects
				(font
					(size 0.7874 0.5842)
					(thickness 0.1524)
				)
				(justify left)
			)
		)
		(property "Value" ""
			(at 0 0 0)
			(layer "F.Fab")
			(effects
				(font
					(size 1.27 1.27)
				)
			)
		)
		(duplicate_pad_numbers_are_jumpers no)
		(fp_line
			(start -0.7874 -0.4064)
			(end 0.7874 -0.4064)
			(stroke
				(width 0.1524)
				(type default)
			)
			(layer "F.SilkS")
		)
		(fp_line
			(start -0.7874 0.4064)
			(end -0.7874 -0.4064)
			(stroke
				(width 0.1524)
				(type default)
			)
			(layer "F.SilkS")
		)
		(fp_line
			(start 0 0.381)
			(end 0 -0.381)
			(stroke
				(width 0.1524)
				(type default)
			)
			(layer "F.SilkS")
		)
		(fp_line
			(start 0.7874 -0.4064)
			(end 0.7874 0.4064)
			(stroke
				(width 0.1524)
				(type default)
			)
			(layer "F.SilkS")
		)
		(fp_line
			(start 0.7874 0.4064)
			(end -0.7874 0.4064)
			(stroke
				(width 0.1524)
				(type default)
			)
			(layer "F.SilkS")
		)
		(fp_poly
			(pts
				(xy -0.5334 0.254) (xy -0.635 0.254) (xy -0.635 0.2286) (xy -0.635 -0.254) (xy -0.5334 -0.254) (xy -0.5334 -0.2794)
				(xy 0.5334 -0.2794) (xy 0.5334 -0.254) (xy 0.635 -0.254) (xy 0.635 0.254) (xy 0.5334 0.254) (xy 0.5334 0.2794)
				(xy -0.508 0.2794) (xy -0.5334 0.2794)
			)
			(stroke
				(width 0)
				(type default)
			)
			(fill no)
			(layer "F.CrtYd")
		)
		(pad "1" smd rect
			(at 0.40005 0)
			(size 0.4572 0.508)
			(layers "F.Cu" "F.Mask" "F.Paste")
			(net "P3V3_NODE1")
		)
		(pad "2" smd rect
			(at -0.40005 0)
			(size 0.4572 0.508)
			(layers "F.Cu" "F.Mask" "F.Paste")
			(net "GND")
		)
	)
	(footprint ""
		(layer "F.Cu")
		(at 92.819982 -137.581894 90)
		(property "Reference" "C816"
			(at 1.288542 -0.084328 90)
			(unlocked yes)
			(layer "F.SilkS")
			(effects
				(font
					(size 0.7874 0.5842)
					(thickness 0.1524)
				)
				(justify left)
			)
		)
		(property "Value" ""
			(at 0 0 90)
			(layer "F.Fab")
			(effects
				(font
					(size 1.27 1.27)
				)
			)
		)
		(duplicate_pad_numbers_are_jumpers no)
		(fp_line
			(start 0.7874 -0.4064)
			(end 0.7874 0.4064)
			(stroke
				(width 0.1524)
				(type default)
			)
			(layer "F.SilkS")
		)
		(fp_line
			(start -0.7874 -0.4064)
			(end 0.7874 -0.4064)
			(stroke
				(width 0.1524)
				(type default)
			)
			(layer "F.SilkS")
		)
		(fp_line
			(start 0 0.381)
			(end 0 -0.381)
			(stroke
				(width 0.1524)
				(type default)
			)
			(layer "F.SilkS")
		)
		(fp_line
			(start 0.7874 0.4064)
			(end -0.7874 0.4064)
			(stroke
				(width 0.1524)
				(type default)
			)
			(layer "F.SilkS")
		)
		(fp_line
			(start -0.7874 0.4064)
			(end -0.7874 -0.4064)
			(stroke
				(width 0.1524)
				(type default)
			)
			(layer "F.SilkS")
		)
		(fp_poly
			(pts
				(xy -0.5334 0.254) (xy -0.635 0.254) (xy -0.635 0.2286) (xy -0.635 -0.254) (xy -0.5334 -0.254) (xy -0.5334 -0.2794)
				(xy 0.5334 -0.2794) (xy 0.5334 -0.254) (xy 0.635 -0.254) (xy 0.635 0.254) (xy 0.5334 0.254) (xy 0.5334 0.2794)
				(xy -0.508 0.2794) (xy -0.5334 0.2794)
			)
			(stroke
				(width 0)
				(type default)
			)
			(fill no)
			(layer "F.CrtYd")
		)
		(pad "1" smd rect
			(at 0.40005 0 90)
			(size 0.4572 0.508)
			(layers "F.Cu" "F.Mask" "F.Paste")
			(net "GND")
		)
		(pad "2" smd rect
			(at -0.40005 0 90)
			(size 0.4572 0.508)
			(layers "F.Cu" "F.Mask" "F.Paste")
			(net "PWRGD_NODE1_P1V05_SUS_PG")
		)
	)
	(footprint ""
		(layer "F.Cu")
		(at 142.75816 -117.082824 180)
		(property "Reference" "R12"
			(at -1.487424 -0.09906 0)
			(unlocked yes)
			(layer "F.SilkS")
			(effects
				(font
					(size 0.7874 0.5842)
					(thickness 0.1524)
				)
				(justify left)
			)
		)
		(property "Value" ""
			(at 0 0 180)
			(layer "F.Fab")
			(effects
				(font
					(size 1.27 1.27)
				)
			)
		)
		(duplicate_pad_numbers_are_jumpers no)
		(fp_line
			(start 0.7874 0.4064)
			(end -0.7874 0.4064)
			(stroke
				(width 0.1524)
				(type default)
			)
			(layer "F.SilkS")
		)
		(fp_line
			(start 0.7874 -0.4064)
			(end 0.7874 0.4064)
			(stroke
				(width 0.1524)
				(type default)
			)
			(layer "F.SilkS")
		)
		(fp_line
			(start -0.7874 0.4064)
			(end -0.7874 -0.4064)
			(stroke
				(width 0.1524)
				(type default)
			)
			(layer "F.SilkS")
		)
		(fp_line
			(start -0.7874 -0.4064)
			(end 0.7874 -0.4064)
			(stroke
				(width 0.1524)
				(type default)
			)
			(layer "F.SilkS")
		)
		(fp_poly
			(pts
				(xy -0.508 0.2794) (xy -0.508 0.2286) (xy -0.635 0.2286) (xy -0.635 -0.254) (xy -0.5334 -0.254)
				(xy -0.5334 -0.2794) (xy 0.5334 -0.2794) (xy 0.5334 -0.254) (xy 0.635 -0.254) (xy 0.635 0.254) (xy 0.5334 0.254)
				(xy 0.5334 0.2794)
			)
			(stroke
				(width 0)
				(type default)
			)
			(fill no)
			(layer "F.CrtYd")
		)
		(pad "1" smd rect
			(at 0.40005 0 180)
			(size 0.4572 0.508)
			(layers "F.Cu" "F.Mask" "F.Paste")
			(net "SEL_PCI_27M")
		)
		(pad "2" smd rect
			(at -0.40005 0 180)
			(size 0.4572 0.508)
			(layers "F.Cu" "F.Mask" "F.Paste")
			(net "P3V3_CLK_NODE1")
		)
	)
	(footprint ""
		(layer "F.Cu")
		(at 63.832486 -118.783862 90)
		(property "Reference" "R326"
			(at -5.013706 -0.666242 90)
			(unlocked yes)
			(layer "F.SilkS")
			(effects
				(font
					(size 0.7874 0.5842)
					(thickness 0.1524)
				)
				(justify left)
			)
		)
		(property "Value" ""
			(at 0 0 90)
			(layer "F.Fab")
			(effects
				(font
					(size 1.27 1.27)
				)
			)
		)
		(duplicate_pad_numbers_are_jumpers no)
		(fp_line
			(start 0.7874 -0.4064)
			(end 0.7874 0.4064)
			(stroke
				(width 0.1524)
				(type default)
			)
			(layer "F.SilkS")
		)
		(fp_line
			(start -0.7874 -0.4064)
			(end 0.7874 -0.4064)
			(stroke
				(width 0.1524)
				(type default)
			)
			(layer "F.SilkS")
		)
		(fp_line
			(start 0.7874 0.4064)
			(end -0.7874 0.4064)
			(stroke
				(width 0.1524)
				(type default)
			)
			(layer "F.SilkS")
		)
		(fp_line
			(start -0.7874 0.4064)
			(end -0.7874 -0.4064)
			(stroke
				(width 0.1524)
				(type default)
			)
			(layer "F.SilkS")
		)
		(fp_poly
			(pts
				(xy -0.508 0.2794) (xy -0.508 0.2286) (xy -0.635 0.2286) (xy -0.635 -0.254) (xy -0.5334 -0.254)
				(xy -0.5334 -0.2794) (xy 0.5334 -0.2794) (xy 0.5334 -0.254) (xy 0.635 -0.254) (xy 0.635 0.254) (xy 0.5334 0.254)
				(xy 0.5334 0.2794)
			)
			(stroke
				(width 0)
				(type default)
			)
			(fill no)
			(layer "F.CrtYd")
		)
		(pad "1" smd rect
			(at 0.40005 0 90)
			(size 0.4572 0.508)
			(layers "F.Cu" "F.Mask" "F.Paste")
			(net "P3V3_NODE1")
		)
		(pad "2" smd rect
			(at -0.40005 0 90)
			(size 0.4572 0.508)
			(layers "F.Cu" "F.Mask" "F.Paste")
			(net "BMC_ROMA10")
		)
	)
	(footprint ""
		(layer "F.Cu")
		(at 44.516802 -145.829782 -90)
		(property "Reference" "R546"
			(at 0.88646 6.618732 90)
			(unlocked yes)
			(layer "F.SilkS")
			(effects
				(font
					(size 0.7874 0.5842)
					(thickness 0.1524)
				)
				(justify left)
			)
		)
		(property "Value" ""
			(at 0 0 270)
			(layer "F.Fab")
			(effects
				(font
					(size 1.27 1.27)
				)
			)
		)
		(duplicate_pad_numbers_are_jumpers no)
		(fp_line
			(start -0.7874 0.4064)
			(end -0.7874 -0.4064)
			(stroke
				(width 0.1524)
				(type default)
			)
			(layer "F.SilkS")
		)
		(fp_line
			(start 0.7874 0.4064)
			(end -0.7874 0.4064)
			(stroke
				(width 0.1524)
				(type default)
			)
			(layer "F.SilkS")
		)
		(fp_line
			(start -0.7874 -0.4064)
			(end 0.7874 -0.4064)
			(stroke
				(width 0.1524)
				(type default)
			)
			(layer "F.SilkS")
		)
		(fp_line
			(start 0.7874 -0.4064)
			(end 0.7874 0.4064)
			(stroke
				(width 0.1524)
				(type default)
			)
			(layer "F.SilkS")
		)
		(fp_poly
			(pts
				(xy -0.508 0.2794) (xy -0.508 0.2286) (xy -0.635 0.2286) (xy -0.635 -0.254) (xy -0.5334 -0.254)
				(xy -0.5334 -0.2794) (xy 0.5334 -0.2794) (xy 0.5334 -0.254) (xy 0.635 -0.254) (xy 0.635 0.254) (xy 0.5334 0.254)
				(xy 0.5334 0.2794)
			)
			(stroke
				(width 0)
				(type default)
			)
			(fill no)
			(layer "F.CrtYd")
		)
		(pad "1" smd rect
			(at 0.40005 0 270)
			(size 0.4572 0.508)
			(layers "F.Cu" "F.Mask" "F.Paste")
			(net "P3V3_NODE1")
		)
		(pad "2" smd rect
			(at -0.40005 0 270)
			(size 0.4572 0.508)
			(layers "F.Cu" "F.Mask" "F.Paste")
			(net "LAN1_NC_SI_TDX1")
		)
	)
	(footprint ""
		(layer "F.Cu")
		(at 135.36676 -185.205624 90)
		(property "Reference" "C743"
			(at 4.510786 -0.076708 90)
			(unlocked yes)
			(layer "F.SilkS")
			(effects
				(font
					(size 0.7874 0.5842)
					(thickness 0.1524)
				)
				(justify left)
			)
		)
		(property "Value" ""
			(at 0 0 90)
			(layer "F.Fab")
			(effects
				(font
					(size 1.27 1.27)
				)
			)
		)
		(duplicate_pad_numbers_are_jumpers no)
		(fp_line
			(start 0.7874 -0.4064)
			(end 0.7874 0.4064)
			(stroke
				(width 0.1524)
				(type default)
			)
			(layer "F.SilkS")
		)
		(fp_line
			(start -0.7874 -0.4064)
			(end 0.7874 -0.4064)
			(stroke
				(width 0.1524)
				(type default)
			)
			(layer "F.SilkS")
		)
		(fp_line
			(start 0 0.381)
			(end 0 -0.381)
			(stroke
				(width 0.1524)
				(type default)
			)
			(layer "F.SilkS")
		)
		(fp_line
			(start 0.7874 0.4064)
			(end -0.7874 0.4064)
			(stroke
				(width 0.1524)
				(type default)
			)
			(layer "F.SilkS")
		)
		(fp_line
			(start -0.7874 0.4064)
			(end -0.7874 -0.4064)
			(stroke
				(width 0.1524)
				(type default)
			)
			(layer "F.SilkS")
		)
		(fp_poly
			(pts
				(xy -0.5334 0.254) (xy -0.635 0.254) (xy -0.635 0.2286) (xy -0.635 -0.254) (xy -0.5334 -0.254) (xy -0.5334 -0.2794)
				(xy 0.5334 -0.2794) (xy 0.5334 -0.254) (xy 0.635 -0.254) (xy 0.635 0.254) (xy 0.5334 0.254) (xy 0.5334 0.2794)
				(xy -0.508 0.2794) (xy -0.5334 0.2794)
			)
			(stroke
				(width 0)
				(type default)
			)
			(fill no)
			(layer "F.CrtYd")
		)
		(pad "1" smd rect
			(at 0.40005 0 90)
			(size 0.4572 0.508)
			(layers "F.Cu" "F.Mask" "F.Paste")
			(net "UART_T10_NODE1_RXD")
		)
		(pad "2" smd rect
			(at -0.40005 0 90)
			(size 0.4572 0.508)
			(layers "F.Cu" "F.Mask" "F.Paste")
			(net "GND")
		)
	)
	(footprint ""
		(layer "F.Cu")
		(at 68.257166 -96.709992 -90)
		(property "Reference" "R72"
			(at 54.98719 -28.370276 90)
			(unlocked yes)
			(layer "F.SilkS")
			(effects
				(font
					(size 0.7874 0.5842)
					(thickness 0.1524)
				)
				(justify left)
			)
		)
		(property "Value" ""
			(at 0 0 270)
			(layer "F.Fab")
			(effects
				(font
					(size 1.27 1.27)
				)
			)
		)
		(duplicate_pad_numbers_are_jumpers no)
		(fp_line
			(start -0.7874 0.4064)
			(end -0.7874 -0.4064)
			(stroke
				(width 0.1524)
				(type default)
			)
			(layer "F.SilkS")
		)
		(fp_line
			(start 0.7874 0.4064)
			(end -0.7874 0.4064)
			(stroke
				(width 0.1524)
				(type default)
			)
			(layer "F.SilkS")
		)
		(fp_line
			(start -0.7874 -0.4064)
			(end 0.7874 -0.4064)
			(stroke
				(width 0.1524)
				(type default)
			)
			(layer "F.SilkS")
		)
		(fp_line
			(start 0.7874 -0.4064)
			(end 0.7874 0.4064)
			(stroke
				(width 0.1524)
				(type default)
			)
			(layer "F.SilkS")
		)
		(fp_poly
			(pts
				(xy -0.508 0.2794) (xy -0.508 0.2286) (xy -0.635 0.2286) (xy -0.635 -0.254) (xy -0.5334 -0.254)
				(xy -0.5334 -0.2794) (xy 0.5334 -0.2794) (xy 0.5334 -0.254) (xy 0.635 -0.254) (xy 0.635 0.254) (xy 0.5334 0.254)
				(xy 0.5334 0.2794)
			)
			(stroke
				(width 0)
				(type default)
			)
			(fill no)
			(layer "F.CrtYd")
		)
		(pad "1" smd rect
			(at 0.40005 0 270)
			(size 0.4572 0.508)
			(layers "F.Cu" "F.Mask" "F.Paste")
			(net "LPC_CPU_NODE1_R_CLKOUT1")
		)
		(pad "2" smd rect
			(at -0.40005 0 270)
			(size 0.4572 0.508)
			(layers "F.Cu" "F.Mask" "F.Paste")
			(net "LPC_CPU_NODE1_CLKOUT1")
		)
	)
	(footprint ""
		(layer "F.Cu")
		(at 60.352686 -121.044462 -90)
		(property "Reference" "R318"
			(at 4.642612 -8.379968 90)
			(unlocked yes)
			(layer "F.SilkS")
			(effects
				(font
					(size 0.7874 0.5842)
					(thickness 0.1524)
				)
				(justify left)
			)
		)
		(property "Value" ""
			(at 0 0 270)
			(layer "F.Fab")
			(effects
				(font
					(size 1.27 1.27)
				)
			)
		)
		(duplicate_pad_numbers_are_jumpers no)
		(fp_line
			(start -0.7874 0.4064)
			(end -0.7874 -0.4064)
			(stroke
				(width 0.1524)
				(type default)
			)
			(layer "F.SilkS")
		)
		(fp_line
			(start 0.7874 0.4064)
			(end -0.7874 0.4064)
			(stroke
				(width 0.1524)
				(type default)
			)
			(layer "F.SilkS")
		)
		(fp_line
			(start -0.7874 -0.4064)
			(end 0.7874 -0.4064)
			(stroke
				(width 0.1524)
				(type default)
			)
			(layer "F.SilkS")
		)
		(fp_line
			(start 0.7874 -0.4064)
			(end 0.7874 0.4064)
			(stroke
				(width 0.1524)
				(type default)
			)
			(layer "F.SilkS")
		)
		(fp_poly
			(pts
				(xy -0.508 0.2794) (xy -0.508 0.2286) (xy -0.635 0.2286) (xy -0.635 -0.254) (xy -0.5334 -0.254)
				(xy -0.5334 -0.2794) (xy 0.5334 -0.2794) (xy 0.5334 -0.254) (xy 0.635 -0.254) (xy 0.635 0.254) (xy 0.5334 0.254)
				(xy 0.5334 0.2794)
			)
			(stroke
				(width 0)
				(type default)
			)
			(fill no)
			(layer "F.CrtYd")
		)
		(pad "1" smd rect
			(at 0.40005 0 270)
			(size 0.4572 0.508)
			(layers "F.Cu" "F.Mask" "F.Paste")
			(net "P3V3_NODE1")
		)
		(pad "2" smd rect
			(at -0.40005 0 270)
			(size 0.4572 0.508)
			(layers "F.Cu" "F.Mask" "F.Paste")
			(net "BMC_ROMA2")
		)
	)
	(footprint ""
		(layer "F.Cu")
		(at 146.913346 -150.244048 90)
		(property "Reference" "R303"
			(at -4.65455 0.049276 90)
			(unlocked yes)
			(layer "F.SilkS")
			(effects
				(font
					(size 0.7874 0.5842)
					(thickness 0.1524)
				)
				(justify left)
			)
		)
		(property "Value" ""
			(at 0 0 90)
			(layer "F.Fab")
			(effects
				(font
					(size 1.27 1.27)
				)
			)
		)
		(duplicate_pad_numbers_are_jumpers no)
		(fp_line
			(start 0.7874 -0.4064)
			(end 0.7874 0.4064)
			(stroke
				(width 0.1524)
				(type default)
			)
			(layer "F.SilkS")
		)
		(fp_line
			(start -0.7874 -0.4064)
			(end 0.7874 -0.4064)
			(stroke
				(width 0.1524)
				(type default)
			)
			(layer "F.SilkS")
		)
		(fp_line
			(start 0.7874 0.4064)
			(end -0.7874 0.4064)
			(stroke
				(width 0.1524)
				(type default)
			)
			(layer "F.SilkS")
		)
		(fp_line
			(start -0.7874 0.4064)
			(end -0.7874 -0.4064)
			(stroke
				(width 0.1524)
				(type default)
			)
			(layer "F.SilkS")
		)
		(fp_poly
			(pts
				(xy -0.508 0.2794) (xy -0.508 0.2286) (xy -0.635 0.2286) (xy -0.635 -0.254) (xy -0.5334 -0.254)
				(xy -0.5334 -0.2794) (xy 0.5334 -0.2794) (xy 0.5334 -0.254) (xy 0.635 -0.254) (xy 0.635 0.254) (xy 0.5334 0.254)
				(xy 0.5334 0.2794)
			)
			(stroke
				(width 0)
				(type default)
			)
			(fill no)
			(layer "F.CrtYd")
		)
		(pad "1" smd rect
			(at 0.40005 0 90)
			(size 0.4572 0.508)
			(layers "F.Cu" "F.Mask" "F.Paste")
			(net "PCIE_SW_EEPROM_DAT")
		)
		(pad "2" smd rect
			(at -0.40005 0 90)
			(size 0.4572 0.508)
			(layers "F.Cu" "F.Mask" "F.Paste")
			(net "P3V3_NODE1")
		)
	)
	(footprint ""
		(layer "F.Cu")
		(at 81.374996 -74.733912 90)
		(property "Reference" "R103"
			(at -16.266414 1.877568 90)
			(unlocked yes)
			(layer "F.SilkS")
			(effects
				(font
					(size 0.7874 0.5842)
					(thickness 0.1524)
				)
				(justify left)
			)
		)
		(property "Value" ""
			(at 0 0 90)
			(layer "F.Fab")
			(effects
				(font
					(size 1.27 1.27)
				)
			)
		)
		(duplicate_pad_numbers_are_jumpers no)
		(fp_line
			(start 0.7874 -0.4064)
			(end 0.7874 0.4064)
			(stroke
				(width 0.1524)
				(type default)
			)
			(layer "F.SilkS")
		)
		(fp_line
			(start -0.7874 -0.4064)
			(end 0.7874 -0.4064)
			(stroke
				(width 0.1524)
				(type default)
			)
			(layer "F.SilkS")
		)
		(fp_line
			(start 0.7874 0.4064)
			(end -0.7874 0.4064)
			(stroke
				(width 0.1524)
				(type default)
			)
			(layer "F.SilkS")
		)
		(fp_line
			(start -0.7874 0.4064)
			(end -0.7874 -0.4064)
			(stroke
				(width 0.1524)
				(type default)
			)
			(layer "F.SilkS")
		)
		(fp_poly
			(pts
				(xy -0.508 0.2794) (xy -0.508 0.2286) (xy -0.635 0.2286) (xy -0.635 -0.254) (xy -0.5334 -0.254)
				(xy -0.5334 -0.2794) (xy 0.5334 -0.2794) (xy 0.5334 -0.254) (xy 0.635 -0.254) (xy 0.635 0.254) (xy 0.5334 0.254)
				(xy 0.5334 0.2794)
			)
			(stroke
				(width 0)
				(type default)
			)
			(fill no)
			(layer "F.CrtYd")
		)
		(pad "1" smd rect
			(at 0.40005 0 90)
			(size 0.4572 0.508)
			(layers "F.Cu" "F.Mask" "F.Paste")
			(net "P1V05_NODE1")
		)
		(pad "2" smd rect
			(at -0.40005 0 90)
			(size 0.4572 0.508)
			(layers "F.Cu" "F.Mask" "F.Paste")
			(net "A_CPU_NODE1_AE64_PU")
		)
	)
	(footprint ""
		(layer "F.Cu")
		(at 78.823058 -154.740356 180)
		(property "Reference" "PU1"
			(at -2.442972 -1.271016 90)
			(unlocked yes)
			(layer "F.SilkS")
			(effects
				(font
					(size 0.7874 0.5842)
					(thickness 0.1524)
				)
				(justify left)
			)
		)
		(property "Value" ""
			(at 0 0 180)
			(layer "F.Fab")
			(effects
				(font
					(size 1.27 1.27)
				)
			)
		)
		(duplicate_pad_numbers_are_jumpers no)
		(fp_line
			(start 2.055622 0.25019)
			(end 2.563622 0.25019)
			(stroke
				(width 0.1524)
				(type default)
			)
			(layer "F.SilkS")
		)
		(fp_line
			(start 1.575054 1.575054)
			(end 1.575054 1.143)
			(stroke
				(width 0.1524)
				(type default)
			)
			(layer "F.SilkS")
		)
		(fp_line
			(start 1.575054 -1.0668)
			(end 1.575054 -1.575054)
			(stroke
				(width 0.1524)
				(type default)
			)
			(layer "F.SilkS")
		)
		(fp_line
			(start 1.575054 -1.575054)
			(end 1.0414 -1.575054)
			(stroke
				(width 0.1524)
				(type default)
			)
			(layer "F.SilkS")
		)
		(fp_line
			(start 1.0414 1.575054)
			(end 1.575054 1.575054)
			(stroke
				(width 0.1524)
				(type default)
			)
			(layer "F.SilkS")
		)
		(fp_line
			(start -0.255778 -2.350262)
			(end -0.255778 -2.045462)
			(stroke
				(width 0.1524)
				(type default)
			)
			(layer "F.SilkS")
		)
		(fp_line
			(start -0.750062 2.043938)
			(end -0.750062 2.348738)
			(stroke
				(width 0.1524)
				(type default)
			)
			(layer "F.SilkS")
		)
		(fp_line
			(start -1.0668 -1.575054)
			(end -1.575054 -1.575054)
			(stroke
				(width 0.1524)
				(type default)
			)
			(layer "F.SilkS")
		)
		(fp_line
			(start -1.575054 1.575054)
			(end -1.0922 1.575054)
			(stroke
				(width 0.1524)
				(type default)
			)
			(layer "F.SilkS")
		)
		(fp_line
			(start -1.575054 1.0922)
			(end -1.575054 1.575054)
			(stroke
				(width 0.1524)
				(type default)
			)
			(layer "F.SilkS")
		)
		(fp_line
			(start -1.575054 -1.575054)
			(end -1.575054 -1.0414)
			(stroke
				(width 0.1524)
				(type default)
			)
			(layer "F.SilkS")
		)
		(fp_poly
			(pts
				(xy -1.729232 -1.368552) (xy -2.266442 -2.443226) (xy -2.803906 -1.905762)
			)
			(stroke
				(width 0)
				(type default)
			)
			(fill yes)
			(layer "F.SilkS")
		)
		(fp_poly
			(pts
				(xy -1.575054 1.575054) (xy -0.9398 1.575054) (xy -0.9398 1.9558) (xy 0.9398 1.9558) (xy 0.9398 1.575054)
				(xy 1.575054 1.575054) (xy 1.575054 0.9398) (xy 1.9558 0.9398) (xy 1.9558 -0.9398) (xy 1.575054 -0.9398)
				(xy 1.575054 -1.575054) (xy 0.9398 -1.575054) (xy 0.9398 -1.9558) (xy -0.9398 -1.9558) (xy -0.9398 -1.575054)
				(xy -1.575054 -1.575054) (xy -1.575054 -0.9398) (xy -1.9558 -0.9398) (xy -1.9558 0.9398) (xy -1.575054 0.9398)
			)
			(stroke
				(width 0)
				(type default)
			)
			(fill no)
			(layer "F.CrtYd")
		)
		(fp_line
			(start 2.055622 0.25019)
			(end 2.563622 0.25019)
			(stroke
				(width 0.1)
				(type default)
			)
			(layer "F.Fab")
		)
		(fp_line
			(start 1.575054 1.575054)
			(end -1.575054 1.575054)
			(stroke
				(width 0.1)
				(type default)
			)
			(layer "F.Fab")
		)
		(fp_line
			(start 1.575054 -1.575054)
			(end 1.575054 1.575054)
			(stroke
				(width 0.1)
				(type default)
			)
			(layer "F.Fab")
		)
		(fp_line
			(start -0.255778 -2.350262)
			(end -0.255778 -2.045462)
			(stroke
				(width 0.1)
				(type default)
			)
			(layer "F.Fab")
		)
		(fp_line
			(start -0.750062 2.043938)
			(end -0.750062 2.348738)
			(stroke
				(width 0.1)
				(type default)
			)
			(layer "F.Fab")
		)
		(fp_line
			(start -1.575054 1.575054)
			(end -1.575054 -1.575054)
			(stroke
				(width 0.1)
				(type default)
			)
			(layer "F.Fab")
		)
		(fp_line
			(start -1.575054 -1.575054)
			(end 1.575054 -1.575054)
			(stroke
				(width 0.1)
				(type default)
			)
			(layer "F.Fab")
		)
		(fp_poly
			(pts
				(xy -2.100072 -0.750062) (xy -3.240024 -1.130046) (xy -3.240024 -0.370078)
			)
			(stroke
				(width 0)
				(type default)
			)
			(fill yes)
			(layer "F.Fab")
		)
		(fp_text user "9"
			(at 2.078736 1.508506 0)
			(unlocked yes)
			(layer "F.SilkS")
			(effects
				(font
					(size 0.635 0.4064)
					(thickness 0.1524)
				)
				(justify left)
			)
		)
		(fp_text user "12"
			(at 2.001012 -0.81788 270)
			(unlocked yes)
			(layer "F.SilkS")
			(effects
				(font
					(size 0.635 0.4064)
					(thickness 0.1524)
				)
				(justify left)
			)
		)
		(fp_text user "16"
			(at -0.981456 -1.984502 0)
			(unlocked yes)
			(layer "F.SilkS")
			(effects
				(font
					(size 0.635 0.4064)
					(thickness 0.1524)
				)
				(justify left)
			)
		)
		(fp_text user "5"
			(at -1.280922 2.128774 270)
			(unlocked yes)
			(layer "F.SilkS")
			(effects
				(font
					(size 0.635 0.4064)
					(thickness 0.1524)
				)
				(justify left)
			)
		)
		(fp_text user "9"
			(at 1.767586 1.584325 180)
			(unlocked yes)
			(layer "F.Fab")
			(effects
				(font
					(size 0.78994 0.579882)
					(thickness 0.000001)
				)
				(justify left)
			)
		)
		(fp_text user "12"
			(at 1.708912 -1.514475 180)
			(unlocked yes)
			(layer "F.Fab")
			(effects
				(font
					(size 0.78994 0.579882)
					(thickness 0.000001)
				)
				(justify left)
			)
		)
		(fp_text user "5"
			(at -1.737868 2.295525 180)
			(unlocked yes)
			(layer "F.Fab")
			(effects
				(font
					(size 0.78994 0.579882)
					(thickness 0.000001)
				)
				(justify left)
			)
		)
		(fp_text user "16"
			(at -2.457958 -2.225675 180)
			(unlocked yes)
			(layer "F.Fab")
			(effects
				(font
					(size 0.78994 0.579882)
					(thickness 0.000001)
				)
				(justify left)
			)
		)
		(pad "1" smd rect
			(at -1.474978 -0.750062 270)
			(size 0.254 0.8382)
			(layers "F.Cu" "F.Mask" "F.Paste")
			(net "P5V_STB_NODE1_FB")
		)
		(pad "2" smd rect
			(at -1.474978 -0.249936 270)
			(size 0.254 0.8382)
			(layers "F.Cu" "F.Mask" "F.Paste")
			(net "P5V_STB_NODE1_VREG5")
		)
		(pad "3" smd rect
			(at -1.474978 0.249936 270)
			(size 0.254 0.8382)
			(layers "F.Cu" "F.Mask" "F.Paste")
			(net "P5V_STB_NODE1_SS")
		)
		(pad "4" smd rect
			(at -1.474978 0.750062 270)
			(size 0.254 0.8382)
			(layers "F.Cu" "F.Mask" "F.Paste")
			(net "GND")
		)
		(pad "5" smd rect
			(at -0.750062 1.474978 180)
			(size 0.254 0.8382)
			(layers "F.Cu" "F.Mask" "F.Paste")
			(net "PWRGD_NODE1_P5V_STB_PG")
		)
		(pad "6" smd rect
			(at -0.249936 1.474978 180)
			(size 0.254 0.8382)
			(layers "F.Cu" "F.Mask" "F.Paste")
			(net "P5V_STB_NODE1_EN_P")
		)
		(pad "7" smd rect
			(at 0.249936 1.474978 180)
			(size 0.254 0.8382)
			(layers "F.Cu" "F.Mask" "F.Paste")
			(net "GND")
		)
		(pad "8" smd rect
			(at 0.750062 1.474978 180)
			(size 0.254 0.8382)
			(layers "F.Cu" "F.Mask" "F.Paste")
			(net "GND")
		)
		(pad "9" smd rect
			(at 1.474978 0.750062 270)
			(size 0.254 0.8382)
			(layers "F.Cu" "F.Mask" "F.Paste")
			(net "SW_P5V_STB_NODE1_PH")
		)
		(pad "10" smd rect
			(at 1.474978 0.249936 270)
			(size 0.254 0.8382)
			(layers "F.Cu" "F.Mask" "F.Paste")
			(net "SW_P5V_STB_NODE1_PH")
		)
		(pad "11" smd rect
			(at 1.474978 -0.249936 270)
			(size 0.254 0.8382)
			(layers "F.Cu" "F.Mask" "F.Paste")
			(net "SW_P5V_STB_NODE1_PH")
		)
		(pad "12" smd rect
			(at 1.474978 -0.750062 270)
			(size 0.254 0.8382)
			(layers "F.Cu" "F.Mask" "F.Paste")
			(net "SW_P5V_STB_NODE1_BT")
		)
		(pad "13" smd rect
			(at 0.750062 -1.474978 180)
			(size 0.254 0.8382)
			(layers "F.Cu" "F.Mask" "F.Paste")
			(net "P12V_AUX")
		)
		(pad "14" smd rect
			(at 0.249936 -1.474978 180)
			(size 0.254 0.8382)
			(layers "F.Cu" "F.Mask" "F.Paste")
			(net "P12V_AUX")
		)
		(pad "15" smd rect
			(at -0.249936 -1.474978 180)
			(size 0.254 0.8382)
			(layers "F.Cu" "F.Mask" "F.Paste")
			(net "P12V_AUX")
		)
		(pad "16" smd rect
			(at -0.750062 -1.474978 180)
			(size 0.254 0.8382)
			(layers "F.Cu" "F.Mask" "F.Paste")
			(net "P5V_STB_NODE1")
		)
		(pad "TH" smd rect
			(at 0 0 270)
			(size 1.7018 1.7018)
			(layers "F.Cu" "F.Mask" "F.Paste")
			(net "GND")
		)
		(zone
			(layer "F.Cu")
			(hatch none 0.5)
			(connect_pads
				(clearance 0)
			)
			(min_thickness 0.25)
			(keepout
				(tracks not_allowed)
				(vias allowed)
				(pads allowed)
				(copperpour not_allowed)
				(footprints allowed)
			)
			(placement
				(enabled no)
				(sheetname "")
			)
			(fill
				(thermal_gap 0.5)
				(thermal_bridge_width 0.5)
				(island_removal_mode 0)
			)
			(polygon
				(pts
					(xy 79.813658 -153.749756) (xy 77.832458 -153.749756) (xy 77.832458 -155.730956) (xy 77.885798 -155.730956)
					(xy 77.908658 -155.640278) (xy 77.908658 -153.825956) (xy 79.737458 -153.825956) (xy 79.737458 -155.629356)
					(xy 79.813658 -155.629356)
				)
			)
		)
		(zone
			(layer "F.Cu")
			(hatch none 0.5)
			(connect_pads
				(clearance 0)
			)
			(min_thickness 0.25)
			(keepout
				(tracks allowed)
				(vias not_allowed)
				(pads allowed)
				(copperpour not_allowed)
				(footprints allowed)
			)
			(placement
				(enabled no)
				(sheetname "")
			)
			(fill
				(thermal_gap 0.5)
				(thermal_bridge_width 0.5)
				(island_removal_mode 0)
			)
			(polygon
				(pts
					(xy 79.813658 -153.749756) (xy 77.832458 -153.749756) (xy 77.832458 -155.730956) (xy 79.813658 -155.730956)
					(xy 79.813658 -155.654756) (xy 77.908658 -155.654756) (xy 77.908658 -153.825956) (xy 79.737458 -153.825956)
					(xy 79.737458 -155.629356) (xy 79.813658 -155.629356)
				)
			)
		)
	)
	(footprint ""
		(layer "F.Cu")
		(at 149.947122 -165.95979 180)
		(property "Reference" "R1158"
			(at 0.244094 1.953006 0)
			(unlocked yes)
			(layer "F.SilkS")
			(effects
				(font
					(size 0.635 0.4064)
					(thickness 0.1524)
				)
				(justify left)
			)
		)
		(property "Value" ""
			(at 0 0 180)
			(layer "F.Fab")
			(effects
				(font
					(size 1.27 1.27)
				)
			)
		)
		(duplicate_pad_numbers_are_jumpers no)
		(fp_line
			(start 0.7874 0.4064)
			(end -0.7874 0.4064)
			(stroke
				(width 0.1524)
				(type default)
			)
			(layer "F.SilkS")
		)
		(fp_line
			(start 0.7874 -0.4064)
			(end 0.7874 0.4064)
			(stroke
				(width 0.1524)
				(type default)
			)
			(layer "F.SilkS")
		)
		(fp_line
			(start -0.7874 0.4064)
			(end -0.7874 -0.4064)
			(stroke
				(width 0.1524)
				(type default)
			)
			(layer "F.SilkS")
		)
		(fp_line
			(start -0.7874 -0.4064)
			(end 0.7874 -0.4064)
			(stroke
				(width 0.1524)
				(type default)
			)
			(layer "F.SilkS")
		)
		(fp_poly
			(pts
				(xy -0.508 0.2794) (xy -0.508 0.2286) (xy -0.635 0.2286) (xy -0.635 -0.254) (xy -0.5334 -0.254)
				(xy -0.5334 -0.2794) (xy 0.5334 -0.2794) (xy 0.5334 -0.254) (xy 0.635 -0.254) (xy 0.635 0.254) (xy 0.5334 0.254)
				(xy 0.5334 0.2794)
			)
			(stroke
				(width 0)
				(type default)
			)
			(fill no)
			(layer "F.CrtYd")
		)
		(pad "1" smd rect
			(at 0.40005 0 180)
			(size 0.4572 0.508)
			(layers "F.Cu" "F.Mask" "F.Paste")
			(net "UART_RTS_P3_N")
		)
		(pad "2" smd rect
			(at -0.40005 0 180)
			(size 0.4572 0.508)
			(layers "F.Cu" "F.Mask" "F.Paste")
			(net "GND")
		)
	)
	(footprint ""
		(layer "F.Cu")
		(at 155.257246 -161.2138 90)
		(property "Reference" "R590"
			(at -7.98703 19.88947 90)
			(unlocked yes)
			(layer "F.SilkS")
			(effects
				(font
					(size 0.7874 0.5842)
					(thickness 0.1524)
				)
				(justify left)
			)
		)
		(property "Value" ""
			(at 0 0 90)
			(layer "F.Fab")
			(effects
				(font
					(size 1.27 1.27)
				)
			)
		)
		(duplicate_pad_numbers_are_jumpers no)
		(fp_line
			(start 0.7874 -0.4064)
			(end 0.7874 0.4064)
			(stroke
				(width 0.1524)
				(type default)
			)
			(layer "F.SilkS")
		)
		(fp_line
			(start -0.7874 -0.4064)
			(end 0.7874 -0.4064)
			(stroke
				(width 0.1524)
				(type default)
			)
			(layer "F.SilkS")
		)
		(fp_line
			(start 0.7874 0.4064)
			(end -0.7874 0.4064)
			(stroke
				(width 0.1524)
				(type default)
			)
			(layer "F.SilkS")
		)
		(fp_line
			(start -0.7874 0.4064)
			(end -0.7874 -0.4064)
			(stroke
				(width 0.1524)
				(type default)
			)
			(layer "F.SilkS")
		)
		(fp_poly
			(pts
				(xy -0.508 0.2794) (xy -0.508 0.2286) (xy -0.635 0.2286) (xy -0.635 -0.254) (xy -0.5334 -0.254)
				(xy -0.5334 -0.2794) (xy 0.5334 -0.2794) (xy 0.5334 -0.254) (xy 0.635 -0.254) (xy 0.635 0.254) (xy 0.5334 0.254)
				(xy 0.5334 0.2794)
			)
			(stroke
				(width 0)
				(type default)
			)
			(fill no)
			(layer "F.CrtYd")
		)
		(pad "1" smd rect
			(at 0.40005 0 90)
			(size 0.4572 0.508)
			(layers "F.Cu" "F.Mask" "F.Paste")
			(net "FM_CPLD_NODE1_CPU_RESET_L")
		)
		(pad "2" smd rect
			(at -0.40005 0 90)
			(size 0.4572 0.508)
			(layers "F.Cu" "F.Mask" "F.Paste")
			(net "PLT_RST_LAN2_N")
		)
	)
	(footprint ""
		(layer "F.Cu")
		(at 39.266368 -6.550914 90)
		(property "Reference" "PR37"
			(at -1.42494 -9.37895 90)
			(unlocked yes)
			(layer "F.SilkS")
			(effects
				(font
					(size 0.7874 0.5842)
					(thickness 0.1524)
				)
				(justify left)
			)
		)
		(property "Value" ""
			(at 0 0 90)
			(layer "F.Fab")
			(effects
				(font
					(size 1.27 1.27)
				)
			)
		)
		(duplicate_pad_numbers_are_jumpers no)
		(fp_line
			(start 0.7874 -0.4064)
			(end 0.7874 0.4064)
			(stroke
				(width 0.1524)
				(type default)
			)
			(layer "F.SilkS")
		)
		(fp_line
			(start -0.7874 -0.4064)
			(end 0.7874 -0.4064)
			(stroke
				(width 0.1524)
				(type default)
			)
			(layer "F.SilkS")
		)
		(fp_line
			(start 0.7874 0.4064)
			(end -0.7874 0.4064)
			(stroke
				(width 0.1524)
				(type default)
			)
			(layer "F.SilkS")
		)
		(fp_line
			(start -0.7874 0.4064)
			(end -0.7874 -0.4064)
			(stroke
				(width 0.1524)
				(type default)
			)
			(layer "F.SilkS")
		)
		(fp_poly
			(pts
				(xy -0.508 0.2794) (xy -0.508 0.2286) (xy -0.635 0.2286) (xy -0.635 -0.254) (xy -0.5334 -0.254)
				(xy -0.5334 -0.2794) (xy 0.5334 -0.2794) (xy 0.5334 -0.254) (xy 0.635 -0.254) (xy 0.635 0.254) (xy 0.5334 0.254)
				(xy 0.5334 0.2794)
			)
			(stroke
				(width 0)
				(type default)
			)
			(fill no)
			(layer "F.CrtYd")
		)
		(pad "1" smd rect
			(at 0.40005 0 90)
			(size 0.4572 0.508)
			(layers "F.Cu" "F.Mask" "F.Paste")
			(net "PV_VDDR_NODE1_VID1")
		)
		(pad "2" smd rect
			(at -0.40005 0 90)
			(size 0.4572 0.508)
			(layers "F.Cu" "F.Mask" "F.Paste")
			(net "GND")
		)
	)
	(footprint ""
		(layer "F.Cu")
		(at 15.286228 -63.887096 -90)
		(property "Reference" "R636"
			(at -1.893824 -0.494538 90)
			(unlocked yes)
			(layer "F.SilkS")
			(effects
				(font
					(size 0.635 0.4064)
					(thickness 0.1524)
				)
				(justify left)
			)
		)
		(property "Value" ""
			(at 0 0 270)
			(layer "F.Fab")
			(effects
				(font
					(size 1.27 1.27)
				)
			)
		)
		(duplicate_pad_numbers_are_jumpers no)
		(fp_line
			(start -0.7874 0.4064)
			(end -0.7874 -0.4064)
			(stroke
				(width 0.1524)
				(type default)
			)
			(layer "F.SilkS")
		)
		(fp_line
			(start 0.7874 0.4064)
			(end -0.7874 0.4064)
			(stroke
				(width 0.1524)
				(type default)
			)
			(layer "F.SilkS")
		)
		(fp_line
			(start -0.7874 -0.4064)
			(end 0.7874 -0.4064)
			(stroke
				(width 0.1524)
				(type default)
			)
			(layer "F.SilkS")
		)
		(fp_line
			(start 0.7874 -0.4064)
			(end 0.7874 0.4064)
			(stroke
				(width 0.1524)
				(type default)
			)
			(layer "F.SilkS")
		)
		(fp_poly
			(pts
				(xy -0.508 0.2794) (xy -0.508 0.2286) (xy -0.635 0.2286) (xy -0.635 -0.254) (xy -0.5334 -0.254)
				(xy -0.5334 -0.2794) (xy 0.5334 -0.2794) (xy 0.5334 -0.254) (xy 0.635 -0.254) (xy 0.635 0.254) (xy 0.5334 0.254)
				(xy 0.5334 0.2794)
			)
			(stroke
				(width 0)
				(type default)
			)
			(fill no)
			(layer "F.CrtYd")
		)
		(pad "1" smd rect
			(at 0.40005 0 270)
			(size 0.4572 0.508)
			(layers "F.Cu" "F.Mask" "F.Paste")
			(net "I2C_VIDREAR_5V_SCL")
		)
		(pad "2" smd rect
			(at -0.40005 0 270)
			(size 0.4572 0.508)
			(layers "F.Cu" "F.Mask" "F.Paste")
			(net "CRT_DDCCLK")
		)
	)
	(footprint ""
		(layer "F.Cu")
		(at 80.540352 -143.002762)
		(property "Reference" "C835"
			(at -1.578864 1.173988 90)
			(unlocked yes)
			(layer "F.SilkS")
			(effects
				(font
					(size 0.7874 0.5842)
					(thickness 0.1524)
				)
				(justify left)
			)
		)
		(property "Value" ""
			(at 0 0 0)
			(layer "F.Fab")
			(effects
				(font
					(size 1.27 1.27)
				)
			)
		)
		(duplicate_pad_numbers_are_jumpers no)
		(fp_line
			(start -0.7874 -0.4064)
			(end 0.7874 -0.4064)
			(stroke
				(width 0.1524)
				(type default)
			)
			(layer "F.SilkS")
		)
		(fp_line
			(start -0.7874 0.4064)
			(end -0.7874 -0.4064)
			(stroke
				(width 0.1524)
				(type default)
			)
			(layer "F.SilkS")
		)
		(fp_line
			(start 0 0.381)
			(end 0 -0.381)
			(stroke
				(width 0.1524)
				(type default)
			)
			(layer "F.SilkS")
		)
		(fp_line
			(start 0.7874 -0.4064)
			(end 0.7874 0.4064)
			(stroke
				(width 0.1524)
				(type default)
			)
			(layer "F.SilkS")
		)
		(fp_line
			(start 0.7874 0.4064)
			(end -0.7874 0.4064)
			(stroke
				(width 0.1524)
				(type default)
			)
			(layer "F.SilkS")
		)
		(fp_poly
			(pts
				(xy -0.5334 0.254) (xy -0.635 0.254) (xy -0.635 0.2286) (xy -0.635 -0.254) (xy -0.5334 -0.254) (xy -0.5334 -0.2794)
				(xy 0.5334 -0.2794) (xy 0.5334 -0.254) (xy 0.635 -0.254) (xy 0.635 0.254) (xy 0.5334 0.254) (xy 0.5334 0.2794)
				(xy -0.508 0.2794) (xy -0.5334 0.2794)
			)
			(stroke
				(width 0)
				(type default)
			)
			(fill no)
			(layer "F.CrtYd")
		)
		(pad "1" smd rect
			(at 0.40005 0)
			(size 0.4572 0.508)
			(layers "F.Cu" "F.Mask" "F.Paste")
			(net "P5V_STB_NODE1")
		)
		(pad "2" smd rect
			(at -0.40005 0)
			(size 0.4572 0.508)
			(layers "F.Cu" "F.Mask" "F.Paste")
			(net "GND")
		)
	)
	(footprint ""
		(layer "F.Cu")
		(at 51.16576 -178.804824 180)
		(property "Reference" "U96"
			(at 3.339084 -132.66293 90)
			(unlocked yes)
			(layer "F.SilkS")
			(effects
				(font
					(size 0.7874 0.5842)
					(thickness 0.1524)
				)
			)
		)
		(property "Value" ""
			(at 0 0 180)
			(layer "F.Fab")
			(effects
				(font
					(size 1.27 1.27)
				)
			)
		)
		(duplicate_pad_numbers_are_jumpers no)
		(fp_line
			(start 1.651 1.905)
			(end -1.651 1.905)
			(stroke
				(width 0.1524)
				(type default)
			)
			(layer "F.SilkS")
		)
		(fp_line
			(start 1.651 -1.905)
			(end 1.651 1.905)
			(stroke
				(width 0.1524)
				(type default)
			)
			(layer "F.SilkS")
		)
		(fp_line
			(start -1.651 1.905)
			(end -1.651 -1.905)
			(stroke
				(width 0.1524)
				(type default)
			)
			(layer "F.SilkS")
		)
		(fp_line
			(start -1.651 -1.905)
			(end 1.651 -1.905)
			(stroke
				(width 0.1524)
				(type default)
			)
			(layer "F.SilkS")
		)
		(fp_poly
			(pts
				(xy -1.524 0.7112) (xy -1.524 1.7526) (xy -0.508 1.7526) (xy -0.508 0.6985) (xy 0.508 0.6985) (xy 0.508 1.7526)
				(xy 1.524 1.7526) (xy 1.524 0.6985) (xy 1.524 -0.6985) (xy 0.508 -0.6985) (xy 0.508 -1.7526) (xy -0.508 -1.7526)
				(xy -0.508 -0.6985) (xy -1.524 -0.6985) (xy -1.524 0.6985)
			)
			(stroke
				(width 0)
				(type default)
			)
			(fill no)
			(layer "F.CrtYd")
		)
		(fp_text user "S"
			(at 0.667258 2.328418 90)
			(unlocked yes)
			(layer "F.SilkS")
			(effects
				(font
					(size 0.635 0.4064)
					(thickness 0.1524)
				)
			)
		)
		(fp_text user "D"
			(at -0.360426 -2.460244 0)
			(unlocked yes)
			(layer "F.SilkS")
			(effects
				(font
					(size 0.635 0.4064)
					(thickness 0.1524)
				)
			)
		)
		(fp_text user "G"
			(at -1.618742 2.201418 90)
			(unlocked yes)
			(layer "F.SilkS")
			(effects
				(font
					(size 0.635 0.4064)
					(thickness 0.1524)
				)
			)
		)
		(pad "D" smd rect
			(at 0 -1.1176 180)
			(size 1.016 1.27)
			(layers "F.Cu" "F.Mask" "F.Paste")
			(net "PSU_DC_OK_N")
		)
		(pad "G" smd rect
			(at -1.016 1.1176 180)
			(size 1.016 1.27)
			(layers "F.Cu" "F.Mask" "F.Paste")
			(net "PSU5_DC_OK_R_BUF")
		)
		(pad "S" smd rect
			(at 1.016 1.1176 180)
			(size 1.016 1.27)
			(layers "F.Cu" "F.Mask" "F.Paste")
			(net "GND")
		)
	)
	(footprint ""
		(layer "F.Cu")
		(at 158.50616 -88.218772 -90)
		(property "Reference" "U33"
			(at -3.226816 0.69977 0)
			(unlocked yes)
			(layer "F.SilkS")
			(effects
				(font
					(size 0.7874 0.5842)
					(thickness 0.1524)
				)
				(justify left)
			)
		)
		(property "Value" ""
			(at 0 0 270)
			(layer "F.Fab")
			(effects
				(font
					(size 1.27 1.27)
				)
			)
		)
		(duplicate_pad_numbers_are_jumpers no)
		(fp_line
			(start -2.5146 1.4224)
			(end -2.5146 0.4572)
			(stroke
				(width 0.1524)
				(type default)
			)
			(layer "F.SilkS")
		)
		(fp_line
			(start 2.5146 1.4224)
			(end -2.5146 1.4224)
			(stroke
				(width 0.1524)
				(type default)
			)
			(layer "F.SilkS")
		)
		(fp_line
			(start -2.5146 0.4572)
			(end -2.0574 0)
			(stroke
				(width 0.1524)
				(type default)
			)
			(layer "F.SilkS")
		)
		(fp_line
			(start -2.0574 0)
			(end -2.5146 -0.4572)
			(stroke
				(width 0.1524)
				(type default)
			)
			(layer "F.SilkS")
		)
		(fp_line
			(start -2.5146 -0.4572)
			(end -2.5146 -1.4224)
			(stroke
				(width 0.1524)
				(type default)
			)
			(layer "F.SilkS")
		)
		(fp_line
			(start -2.5146 -1.4224)
			(end 2.5146 -1.4224)
			(stroke
				(width 0.1524)
				(type default)
			)
			(layer "F.SilkS")
		)
		(fp_line
			(start 2.5146 -1.4224)
			(end 2.5146 1.4224)
			(stroke
				(width 0.1524)
				(type default)
			)
			(layer "F.SilkS")
		)
		(fp_circle
			(center -1.905 0.889)
			(end -1.905 0.635)
			(stroke
				(width 0.1524)
				(type default)
			)
			(fill no)
			(layer "F.SilkS")
		)
		(fp_poly
			(pts
				(xy -2.1844 3.5052) (xy -2.1844 2.0066) (xy -2.5146 2.0066) (xy -2.5146 -2.0066) (xy -2.1844 -2.0066)
				(xy -2.1844 -3.5052) (xy 2.1844 -3.5052) (xy 2.1844 -2.0066) (xy 2.5146 -2.0066) (xy 2.5146 2.0066)
				(xy 2.1844 2.0066) (xy 2.1844 3.5052)
			)
			(stroke
				(width 0)
				(type default)
			)
			(fill no)
			(layer "F.CrtYd")
		)
		(pad "1" smd rect
			(at -1.905 2.6416 270)
			(size 0.5588 1.7272)
			(layers "F.Cu" "F.Mask" "F.Paste")
			(net "SPI_USB_NODE1_CSB_N")
		)
		(pad "2" smd rect
			(at -0.635 2.6416 270)
			(size 0.5588 1.7272)
			(layers "F.Cu" "F.Mask" "F.Paste")
			(net "SPI_USB_NODE1_SI_R")
		)
		(pad "3" smd rect
			(at 0.635 2.6416 270)
			(size 0.5588 1.7272)
			(layers "F.Cu" "F.Mask" "F.Paste")
			(net "SPI_USB_NODE1_WP_L")
		)
		(pad "4" smd rect
			(at 1.905 2.6416 270)
			(size 0.5588 1.7272)
			(layers "F.Cu" "F.Mask" "F.Paste")
			(net "GND")
		)
		(pad "5" smd rect
			(at 1.905 -2.6416 270)
			(size 0.5588 1.7272)
			(layers "F.Cu" "F.Mask" "F.Paste")
			(net "SPI_USB_NODE1_SO")
		)
		(pad "6" smd rect
			(at 0.635 -2.6416 270)
			(size 0.5588 1.7272)
			(layers "F.Cu" "F.Mask" "F.Paste")
			(net "SPI_USB_NODE1_CLK")
		)
		(pad "7" smd rect
			(at -0.635 -2.6416 270)
			(size 0.5588 1.7272)
			(layers "F.Cu" "F.Mask" "F.Paste")
			(net "SPI_USB_NODE1_HOLD_L")
		)
		(pad "8" smd rect
			(at -1.905 -2.6416 270)
			(size 0.5588 1.7272)
			(layers "F.Cu" "F.Mask" "F.Paste")
			(net "P3V3_NODE1")
		)
	)
	(footprint ""
		(layer "F.Cu")
		(at 4.725162 -155.788106 -90)
		(property "Reference" "R1310"
			(at -0.313436 -0.719328 0)
			(unlocked yes)
			(layer "F.SilkS")
			(effects
				(font
					(size 0.7874 0.5842)
					(thickness 0.1524)
				)
				(justify left)
			)
		)
		(property "Value" ""
			(at 0 0 270)
			(layer "F.Fab")
			(effects
				(font
					(size 1.27 1.27)
				)
			)
		)
		(duplicate_pad_numbers_are_jumpers no)
		(fp_line
			(start -0.7874 0.4064)
			(end -0.7874 -0.4064)
			(stroke
				(width 0.1524)
				(type default)
			)
			(layer "F.SilkS")
		)
		(fp_line
			(start 0.7874 0.4064)
			(end -0.7874 0.4064)
			(stroke
				(width 0.1524)
				(type default)
			)
			(layer "F.SilkS")
		)
		(fp_line
			(start -0.7874 -0.4064)
			(end 0.7874 -0.4064)
			(stroke
				(width 0.1524)
				(type default)
			)
			(layer "F.SilkS")
		)
		(fp_line
			(start 0.7874 -0.4064)
			(end 0.7874 0.4064)
			(stroke
				(width 0.1524)
				(type default)
			)
			(layer "F.SilkS")
		)
		(fp_poly
			(pts
				(xy -0.508 0.2794) (xy -0.508 0.2286) (xy -0.635 0.2286) (xy -0.635 -0.254) (xy -0.5334 -0.254)
				(xy -0.5334 -0.2794) (xy 0.5334 -0.2794) (xy 0.5334 -0.254) (xy 0.635 -0.254) (xy 0.635 0.254) (xy 0.5334 0.254)
				(xy 0.5334 0.2794)
			)
			(stroke
				(width 0)
				(type default)
			)
			(fill no)
			(layer "F.CrtYd")
		)
		(pad "1" smd rect
			(at 0.40005 0 270)
			(size 0.4572 0.508)
			(layers "F.Cu" "F.Mask" "F.Paste")
			(net "P3V3_NODE1")
		)
		(pad "2" smd rect
			(at -0.40005 0 270)
			(size 0.4572 0.508)
			(layers "F.Cu" "F.Mask" "F.Paste")
			(net "UART_RI_P5_LS_N")
		)
	)
	(footprint ""
		(layer "F.Cu")
		(at 23.736554 -100.067872 180)
		(property "Reference" "U134"
			(at 1.318514 4.418076 0)
			(unlocked yes)
			(layer "F.SilkS")
			(effects
				(font
					(size 0.7874 0.5842)
					(thickness 0.1524)
				)
				(justify left)
			)
		)
		(property "Value" ""
			(at 0 0 180)
			(layer "F.Fab")
			(effects
				(font
					(size 1.27 1.27)
				)
			)
		)
		(duplicate_pad_numbers_are_jumpers no)
		(fp_line
			(start 2.5146 1.4224)
			(end -2.5146 1.4224)
			(stroke
				(width 0.1524)
				(type default)
			)
			(layer "F.SilkS")
		)
		(fp_line
			(start 2.5146 -1.4224)
			(end 2.5146 1.4224)
			(stroke
				(width 0.1524)
				(type default)
			)
			(layer "F.SilkS")
		)
		(fp_line
			(start -2.0574 0)
			(end -2.5146 -0.4572)
			(stroke
				(width 0.1524)
				(type default)
			)
			(layer "F.SilkS")
		)
		(fp_line
			(start -2.5146 1.4224)
			(end -2.5146 0.4572)
			(stroke
				(width 0.1524)
				(type default)
			)
			(layer "F.SilkS")
		)
		(fp_line
			(start -2.5146 0.4572)
			(end -2.0574 0)
			(stroke
				(width 0.1524)
				(type default)
			)
			(layer "F.SilkS")
		)
		(fp_line
			(start -2.5146 -0.4572)
			(end -2.5146 -1.4224)
			(stroke
				(width 0.1524)
				(type default)
			)
			(layer "F.SilkS")
		)
		(fp_line
			(start -2.5146 -1.4224)
			(end 2.5146 -1.4224)
			(stroke
				(width 0.1524)
				(type default)
			)
			(layer "F.SilkS")
		)
		(fp_circle
			(center -1.905 0.889)
			(end -2.159 0.889)
			(stroke
				(width 0.1524)
				(type default)
			)
			(fill no)
			(layer "F.SilkS")
		)
		(fp_poly
			(pts
				(xy -2.1844 3.5052) (xy -2.1844 2.0066) (xy -2.5146 2.0066) (xy -2.5146 -2.0066) (xy -2.1844 -2.0066)
				(xy -2.1844 -3.5052) (xy 2.1844 -3.5052) (xy 2.1844 -2.0066) (xy 2.5146 -2.0066) (xy 2.5146 2.0066)
				(xy 2.1844 2.0066) (xy 2.1844 3.5052)
			)
			(stroke
				(width 0)
				(type default)
			)
			(fill no)
			(layer "F.CrtYd")
		)
		(pad "1" smd rect
			(at -1.905 2.6416 180)
			(size 0.5588 1.7272)
			(layers "F.Cu" "F.Mask" "F.Paste")
			(net "FRU_SYS_A0")
		)
		(pad "2" smd rect
			(at -0.635 2.6416 180)
			(size 0.5588 1.7272)
			(layers "F.Cu" "F.Mask" "F.Paste")
			(net "FRU_SYS_A1")
		)
		(pad "3" smd rect
			(at 0.635 2.6416 180)
			(size 0.5588 1.7272)
			(layers "F.Cu" "F.Mask" "F.Paste")
			(net "FRU_SYS_A2")
		)
		(pad "4" smd rect
			(at 1.905 2.6416 180)
			(size 0.5588 1.7272)
			(layers "F.Cu" "F.Mask" "F.Paste")
			(net "GND")
		)
		(pad "5" smd rect
			(at 1.905 -2.6416 180)
			(size 0.5588 1.7272)
			(layers "F.Cu" "F.Mask" "F.Paste")
			(net "SMB_MUX_CPU_ICS_NODE1_DAT")
		)
		(pad "6" smd rect
			(at 0.635 -2.6416 180)
			(size 0.5588 1.7272)
			(layers "F.Cu" "F.Mask" "F.Paste")
			(net "SMB_MUX_CPU_ICS_NODE1_CLK")
		)
		(pad "7" smd rect
			(at -0.635 -2.6416 180)
			(size 0.5588 1.7272)
			(layers "F.Cu" "F.Mask" "F.Paste")
			(net "N43448372")
		)
		(pad "8" smd rect
			(at -1.905 -2.6416 180)
			(size 0.5588 1.7272)
			(layers "F.Cu" "F.Mask" "F.Paste")
			(net "P3V3_NODE1")
		)
	)
	(footprint ""
		(layer "F.Cu")
		(at 47.215298 -176.247298)
		(property "Reference" "R1012"
			(at -0.007366 132.939282 0)
			(unlocked yes)
			(layer "F.SilkS")
			(effects
				(font
					(size 0.7874 0.5842)
					(thickness 0.1524)
				)
				(justify left)
			)
		)
		(property "Value" ""
			(at 0 0 0)
			(layer "F.Fab")
			(effects
				(font
					(size 1.27 1.27)
				)
			)
		)
		(duplicate_pad_numbers_are_jumpers no)
		(fp_line
			(start -0.7874 -0.4064)
			(end 0.7874 -0.4064)
			(stroke
				(width 0.1524)
				(type default)
			)
			(layer "F.SilkS")
		)
		(fp_line
			(start -0.7874 0.4064)
			(end -0.7874 -0.4064)
			(stroke
				(width 0.1524)
				(type default)
			)
			(layer "F.SilkS")
		)
		(fp_line
			(start 0.7874 -0.4064)
			(end 0.7874 0.4064)
			(stroke
				(width 0.1524)
				(type default)
			)
			(layer "F.SilkS")
		)
		(fp_line
			(start 0.7874 0.4064)
			(end -0.7874 0.4064)
			(stroke
				(width 0.1524)
				(type default)
			)
			(layer "F.SilkS")
		)
		(fp_poly
			(pts
				(xy -0.508 0.2794) (xy -0.508 0.2286) (xy -0.635 0.2286) (xy -0.635 -0.254) (xy -0.5334 -0.254)
				(xy -0.5334 -0.2794) (xy 0.5334 -0.2794) (xy 0.5334 -0.254) (xy 0.635 -0.254) (xy 0.635 0.254) (xy 0.5334 0.254)
				(xy 0.5334 0.2794)
			)
			(stroke
				(width 0)
				(type default)
			)
			(fill no)
			(layer "F.CrtYd")
		)
		(pad "1" smd rect
			(at 0.40005 0)
			(size 0.4572 0.508)
			(layers "F.Cu" "F.Mask" "F.Paste")
			(net "PSU_DC_OK_N")
		)
		(pad "2" smd rect
			(at -0.40005 0)
			(size 0.4572 0.508)
			(layers "F.Cu" "F.Mask" "F.Paste")
			(net "P12V_PDB")
		)
	)
	(footprint ""
		(layer "F.Cu")
		(at 77.96276 -188.126624 -90)
		(property "Reference" "R932"
			(at -4.548886 1.495298 90)
			(unlocked yes)
			(layer "F.SilkS")
			(effects
				(font
					(size 0.7874 0.5842)
					(thickness 0.1524)
				)
				(justify left)
			)
		)
		(property "Value" ""
			(at 0 0 270)
			(layer "F.Fab")
			(effects
				(font
					(size 1.27 1.27)
				)
			)
		)
		(duplicate_pad_numbers_are_jumpers no)
		(fp_line
			(start -0.7874 0.4064)
			(end -0.7874 -0.4064)
			(stroke
				(width 0.1524)
				(type default)
			)
			(layer "F.SilkS")
		)
		(fp_line
			(start 0.7874 0.4064)
			(end -0.7874 0.4064)
			(stroke
				(width 0.1524)
				(type default)
			)
			(layer "F.SilkS")
		)
		(fp_line
			(start -0.7874 -0.4064)
			(end 0.7874 -0.4064)
			(stroke
				(width 0.1524)
				(type default)
			)
			(layer "F.SilkS")
		)
		(fp_line
			(start 0.7874 -0.4064)
			(end 0.7874 0.4064)
			(stroke
				(width 0.1524)
				(type default)
			)
			(layer "F.SilkS")
		)
		(fp_poly
			(pts
				(xy -0.508 0.2794) (xy -0.508 0.2286) (xy -0.635 0.2286) (xy -0.635 -0.254) (xy -0.5334 -0.254)
				(xy -0.5334 -0.2794) (xy 0.5334 -0.2794) (xy 0.5334 -0.254) (xy 0.635 -0.254) (xy 0.635 0.254) (xy 0.5334 0.254)
				(xy 0.5334 0.2794)
			)
			(stroke
				(width 0)
				(type default)
			)
			(fill no)
			(layer "F.CrtYd")
		)
		(pad "1" smd rect
			(at 0.40005 0 270)
			(size 0.4572 0.508)
			(layers "F.Cu" "F.Mask" "F.Paste")
			(net "UART_T4_NODE1_RXD")
		)
		(pad "2" smd rect
			(at -0.40005 0 270)
			(size 0.4572 0.508)
			(layers "F.Cu" "F.Mask" "F.Paste")
			(net "UART_T4_NODE1_RXD_R")
		)
	)
	(footprint ""
		(layer "F.Cu")
		(at 117.435376 -128.387348 -90)
		(property "Reference" "PR49"
			(at 1.917192 -2.019554 90)
			(unlocked yes)
			(layer "F.SilkS")
			(effects
				(font
					(size 0.7874 0.5842)
					(thickness 0.1524)
				)
				(justify left)
			)
		)
		(property "Value" ""
			(at 0 0 270)
			(layer "F.Fab")
			(effects
				(font
					(size 1.27 1.27)
				)
			)
		)
		(duplicate_pad_numbers_are_jumpers no)
		(fp_line
			(start -2.2098 0.9398)
			(end -2.2098 -0.9398)
			(stroke
				(width 0.1524)
				(type default)
			)
			(layer "F.SilkS")
		)
		(fp_line
			(start 2.2098 0.9398)
			(end -2.2098 0.9398)
			(stroke
				(width 0.1524)
				(type default)
			)
			(layer "F.SilkS")
		)
		(fp_line
			(start -2.2098 -0.9398)
			(end 2.2098 -0.9398)
			(stroke
				(width 0.1524)
				(type default)
			)
			(layer "F.SilkS")
		)
		(fp_line
			(start 2.2098 -0.9398)
			(end 2.2098 0.9398)
			(stroke
				(width 0.1524)
				(type default)
			)
			(layer "F.SilkS")
		)
		(fp_poly
			(pts
				(xy 2.0574 0.8382) (xy 2.0574 -0.8382) (xy 2.0574 -0.9398) (xy -2.0574 -0.9398) (xy -2.0574 -0.8382)
				(xy -2.0574 0.8382) (xy -2.0574 0.9398) (xy 2.0574 0.9398)
			)
			(stroke
				(width 0)
				(type default)
			)
			(fill no)
			(layer "F.CrtYd")
		)
		(pad "1" smd rect
			(at 1.4732 0 270)
			(size 1.1684 1.5748)
			(layers "F.Cu" "F.Mask" "F.Paste")
			(net "SW_VR_PVCCP_NODE1_VIN_FLT")
		)
		(pad "2" smd rect
			(at -1.4732 0 270)
			(size 1.1684 1.5748)
			(layers "F.Cu" "F.Mask" "F.Paste")
			(net "P12V_AUX")
		)
	)
	(footprint ""
		(layer "F.Cu")
		(at 184.2516 -188.4172 -90)
		(property "Reference" "R1296"
			(at -1.1176 -0.28067 90)
			(unlocked yes)
			(layer "F.SilkS")
			(effects
				(font
					(size 0.7874 0.5842)
					(thickness 0.1524)
				)
				(justify left)
			)
		)
		(property "Value" ""
			(at 0 0 270)
			(layer "F.Fab")
			(effects
				(font
					(size 1.27 1.27)
				)
			)
		)
		(duplicate_pad_numbers_are_jumpers no)
		(fp_line
			(start -0.7874 0.4064)
			(end -0.7874 -0.4064)
			(stroke
				(width 0.1524)
				(type default)
			)
			(layer "F.SilkS")
		)
		(fp_line
			(start 0.7874 0.4064)
			(end -0.7874 0.4064)
			(stroke
				(width 0.1524)
				(type default)
			)
			(layer "F.SilkS")
		)
		(fp_line
			(start -0.7874 -0.4064)
			(end 0.7874 -0.4064)
			(stroke
				(width 0.1524)
				(type default)
			)
			(layer "F.SilkS")
		)
		(fp_line
			(start 0.7874 -0.4064)
			(end 0.7874 0.4064)
			(stroke
				(width 0.1524)
				(type default)
			)
			(layer "F.SilkS")
		)
		(fp_poly
			(pts
				(xy -0.508 0.2794) (xy -0.508 0.2286) (xy -0.635 0.2286) (xy -0.635 -0.254) (xy -0.5334 -0.254)
				(xy -0.5334 -0.2794) (xy 0.5334 -0.2794) (xy 0.5334 -0.254) (xy 0.635 -0.254) (xy 0.635 0.254) (xy 0.5334 0.254)
				(xy 0.5334 0.2794)
			)
			(stroke
				(width 0)
				(type default)
			)
			(fill no)
			(layer "F.CrtYd")
		)
		(pad "1" smd rect
			(at 0.40005 0 270)
			(size 0.4572 0.508)
			(layers "F.Cu" "F.Mask" "F.Paste")
			(net "POWER_SW1_PWR_CTR_12V")
		)
		(pad "2" smd rect
			(at -0.40005 0 270)
			(size 0.4572 0.508)
			(layers "F.Cu" "F.Mask" "F.Paste")
			(net "POWER_SW1_PWR_CTR_12V_R")
		)
	)
	(footprint ""
		(layer "F.Cu")
		(at 107.134152 -129.483358 90)
		(property "Reference" "PC88"
			(at -3.252978 -7.426706 90)
			(unlocked yes)
			(layer "F.SilkS")
			(effects
				(font
					(size 0.7874 0.5842)
					(thickness 0.1524)
				)
			)
		)
		(property "Value" ""
			(at 0 0 90)
			(layer "F.Fab")
			(effects
				(font
					(size 1.27 1.27)
				)
			)
		)
		(duplicate_pad_numbers_are_jumpers no)
		(fp_line
			(start 1.2954 -0.5842)
			(end 1.2954 0.5842)
			(stroke
				(width 0.1524)
				(type default)
			)
			(layer "F.SilkS")
		)
		(fp_line
			(start 0 -0.5842)
			(end 0 0.5842)
			(stroke
				(width 0.1524)
				(type default)
			)
			(layer "F.SilkS")
		)
		(fp_line
			(start -1.2954 -0.5842)
			(end 1.2954 -0.5842)
			(stroke
				(width 0.1524)
				(type default)
			)
			(layer "F.SilkS")
		)
		(fp_line
			(start 1.2954 0.5842)
			(end -1.2954 0.5842)
			(stroke
				(width 0.1524)
				(type default)
			)
			(layer "F.SilkS")
		)
		(fp_line
			(start -1.2954 0.5842)
			(end -1.2954 -0.5842)
			(stroke
				(width 0.1524)
				(type default)
			)
			(layer "F.SilkS")
		)
		(fp_poly
			(pts
				(xy 0.8636 -0.4572) (xy 0.8636 -0.3556) (xy 1.143 -0.3556) (xy 1.143 0.3556) (xy 0.8636 0.3556)
				(xy 0.8636 0.4572) (xy -0.8636 0.4572) (xy -0.8636 0.3556) (xy -1.143 0.3556) (xy -1.143 -0.3556)
				(xy -0.8636 -0.3556) (xy -0.8636 -0.4572)
			)
			(stroke
				(width 0)
				(type default)
			)
			(fill no)
			(layer "F.CrtYd")
		)
		(fp_line
			(start 0.884936 -0.504952)
			(end 0.884936 0.504952)
			(stroke
				(width 0.1)
				(type default)
			)
			(layer "F.Fab")
		)
		(fp_line
			(start -0.884936 -0.504952)
			(end 0.884936 -0.504952)
			(stroke
				(width 0.1)
				(type default)
			)
			(layer "F.Fab")
		)
		(fp_line
			(start 0.884936 0.504952)
			(end -0.884936 0.504952)
			(stroke
				(width 0.1)
				(type default)
			)
			(layer "F.Fab")
		)
		(fp_line
			(start -0.884936 0.504952)
			(end -0.884936 -0.504952)
			(stroke
				(width 0.1)
				(type default)
			)
			(layer "F.Fab")
		)
		(pad "1" smd rect
			(at 0.7366 0 180)
			(size 0.7112 0.8128)
			(layers "F.Cu" "F.Mask" "F.Paste")
			(net "VR_PVCCP_NODE1_PVCC")
		)
		(pad "2" smd rect
			(at -0.7366 0 180)
			(size 0.7112 0.8128)
			(layers "F.Cu" "F.Mask" "F.Paste")
			(net "GND")
		)
	)
	(footprint ""
		(layer "F.Cu")
		(at 28.85948 -101.538786 90)
		(property "Reference" "C817"
			(at -1.358138 1.33858 0)
			(unlocked yes)
			(layer "F.SilkS")
			(effects
				(font
					(size 0.7874 0.5842)
					(thickness 0.1524)
				)
				(justify left)
			)
		)
		(property "Value" ""
			(at 0 0 90)
			(layer "F.Fab")
			(effects
				(font
					(size 1.27 1.27)
				)
			)
		)
		(duplicate_pad_numbers_are_jumpers no)
		(fp_line
			(start 0.7874 -0.4064)
			(end 0.7874 0.4064)
			(stroke
				(width 0.1524)
				(type default)
			)
			(layer "F.SilkS")
		)
		(fp_line
			(start -0.7874 -0.4064)
			(end 0.7874 -0.4064)
			(stroke
				(width 0.1524)
				(type default)
			)
			(layer "F.SilkS")
		)
		(fp_line
			(start 0 0.381)
			(end 0 -0.381)
			(stroke
				(width 0.1524)
				(type default)
			)
			(layer "F.SilkS")
		)
		(fp_line
			(start 0.7874 0.4064)
			(end -0.7874 0.4064)
			(stroke
				(width 0.1524)
				(type default)
			)
			(layer "F.SilkS")
		)
		(fp_line
			(start -0.7874 0.4064)
			(end -0.7874 -0.4064)
			(stroke
				(width 0.1524)
				(type default)
			)
			(layer "F.SilkS")
		)
		(fp_poly
			(pts
				(xy -0.5334 0.254) (xy -0.635 0.254) (xy -0.635 0.2286) (xy -0.635 -0.254) (xy -0.5334 -0.254) (xy -0.5334 -0.2794)
				(xy 0.5334 -0.2794) (xy 0.5334 -0.254) (xy 0.635 -0.254) (xy 0.635 0.254) (xy 0.5334 0.254) (xy 0.5334 0.2794)
				(xy -0.508 0.2794) (xy -0.5334 0.2794)
			)
			(stroke
				(width 0)
				(type default)
			)
			(fill no)
			(layer "F.CrtYd")
		)
		(pad "1" smd rect
			(at 0.40005 0 90)
			(size 0.4572 0.508)
			(layers "F.Cu" "F.Mask" "F.Paste")
			(net "P5V_STB_NODE1")
		)
		(pad "2" smd rect
			(at -0.40005 0 90)
			(size 0.4572 0.508)
			(layers "F.Cu" "F.Mask" "F.Paste")
			(net "GND")
		)
	)
	(footprint ""
		(layer "F.Cu")
		(at 61.470286 -118.910862 90)
		(property "Reference" "R322"
			(at -5.140706 0.65024 90)
			(unlocked yes)
			(layer "F.SilkS")
			(effects
				(font
					(size 0.7874 0.5842)
					(thickness 0.1524)
				)
				(justify left)
			)
		)
		(property "Value" ""
			(at 0 0 90)
			(layer "F.Fab")
			(effects
				(font
					(size 1.27 1.27)
				)
			)
		)
		(duplicate_pad_numbers_are_jumpers no)
		(fp_line
			(start 0.7874 -0.4064)
			(end 0.7874 0.4064)
			(stroke
				(width 0.1524)
				(type default)
			)
			(layer "F.SilkS")
		)
		(fp_line
			(start -0.7874 -0.4064)
			(end 0.7874 -0.4064)
			(stroke
				(width 0.1524)
				(type default)
			)
			(layer "F.SilkS")
		)
		(fp_line
			(start 0.7874 0.4064)
			(end -0.7874 0.4064)
			(stroke
				(width 0.1524)
				(type default)
			)
			(layer "F.SilkS")
		)
		(fp_line
			(start -0.7874 0.4064)
			(end -0.7874 -0.4064)
			(stroke
				(width 0.1524)
				(type default)
			)
			(layer "F.SilkS")
		)
		(fp_poly
			(pts
				(xy -0.508 0.2794) (xy -0.508 0.2286) (xy -0.635 0.2286) (xy -0.635 -0.254) (xy -0.5334 -0.254)
				(xy -0.5334 -0.2794) (xy 0.5334 -0.2794) (xy 0.5334 -0.254) (xy 0.635 -0.254) (xy 0.635 0.254) (xy 0.5334 0.254)
				(xy 0.5334 0.2794)
			)
			(stroke
				(width 0)
				(type default)
			)
			(fill no)
			(layer "F.CrtYd")
		)
		(pad "1" smd rect
			(at 0.40005 0 90)
			(size 0.4572 0.508)
			(layers "F.Cu" "F.Mask" "F.Paste")
			(net "P3V3_NODE1")
		)
		(pad "2" smd rect
			(at -0.40005 0 90)
			(size 0.4572 0.508)
			(layers "F.Cu" "F.Mask" "F.Paste")
			(net "BMC_ROMA6")
		)
	)
	(footprint ""
		(layer "F.Cu")
		(at 139.000992 -25.802844 -90)
		(property "Reference" "C493"
			(at 10.72261 -4.28625 90)
			(unlocked yes)
			(layer "F.SilkS")
			(effects
				(font
					(size 0.7874 0.5842)
					(thickness 0.1524)
				)
				(justify left)
			)
		)
		(property "Value" ""
			(at 0 0 270)
			(layer "F.Fab")
			(effects
				(font
					(size 1.27 1.27)
				)
			)
		)
		(duplicate_pad_numbers_are_jumpers no)
		(fp_line
			(start -0.7874 0.4064)
			(end -0.7874 -0.4064)
			(stroke
				(width 0.1524)
				(type default)
			)
			(layer "F.SilkS")
		)
		(fp_line
			(start 0.7874 0.4064)
			(end -0.7874 0.4064)
			(stroke
				(width 0.1524)
				(type default)
			)
			(layer "F.SilkS")
		)
		(fp_line
			(start 0 0.381)
			(end 0 -0.381)
			(stroke
				(width 0.1524)
				(type default)
			)
			(layer "F.SilkS")
		)
		(fp_line
			(start -0.7874 -0.4064)
			(end 0.7874 -0.4064)
			(stroke
				(width 0.1524)
				(type default)
			)
			(layer "F.SilkS")
		)
		(fp_line
			(start 0.7874 -0.4064)
			(end 0.7874 0.4064)
			(stroke
				(width 0.1524)
				(type default)
			)
			(layer "F.SilkS")
		)
		(fp_poly
			(pts
				(xy -0.5334 0.254) (xy -0.635 0.254) (xy -0.635 0.2286) (xy -0.635 -0.254) (xy -0.5334 -0.254) (xy -0.5334 -0.2794)
				(xy 0.5334 -0.2794) (xy 0.5334 -0.254) (xy 0.635 -0.254) (xy 0.635 0.254) (xy 0.5334 0.254) (xy 0.5334 0.2794)
				(xy -0.508 0.2794) (xy -0.5334 0.2794)
			)
			(stroke
				(width 0)
				(type default)
			)
			(fill no)
			(layer "F.CrtYd")
		)
		(pad "1" smd rect
			(at 0.40005 0 270)
			(size 0.4572 0.508)
			(layers "F.Cu" "F.Mask" "F.Paste")
			(net "P5V_NODE1")
		)
		(pad "2" smd rect
			(at -0.40005 0 270)
			(size 0.4572 0.508)
			(layers "F.Cu" "F.Mask" "F.Paste")
			(net "GND")
		)
	)
	(footprint ""
		(layer "F.Cu")
		(at 90.80754 -175.418496 180)
		(property "Reference" "C909"
			(at -85.979 -76.25969 0)
			(unlocked yes)
			(layer "F.SilkS")
			(effects
				(font
					(size 0.7874 0.5842)
					(thickness 0.1524)
				)
				(justify left)
			)
		)
		(property "Value" ""
			(at 0 0 180)
			(layer "F.Fab")
			(effects
				(font
					(size 1.27 1.27)
				)
			)
		)
		(duplicate_pad_numbers_are_jumpers no)
		(fp_line
			(start 0.7874 0.4064)
			(end -0.7874 0.4064)
			(stroke
				(width 0.1524)
				(type default)
			)
			(layer "F.SilkS")
		)
		(fp_line
			(start 0.7874 -0.4064)
			(end 0.7874 0.4064)
			(stroke
				(width 0.1524)
				(type default)
			)
			(layer "F.SilkS")
		)
		(fp_line
			(start 0 0.381)
			(end 0 -0.381)
			(stroke
				(width 0.1524)
				(type default)
			)
			(layer "F.SilkS")
		)
		(fp_line
			(start -0.7874 0.4064)
			(end -0.7874 -0.4064)
			(stroke
				(width 0.1524)
				(type default)
			)
			(layer "F.SilkS")
		)
		(fp_line
			(start -0.7874 -0.4064)
			(end 0.7874 -0.4064)
			(stroke
				(width 0.1524)
				(type default)
			)
			(layer "F.SilkS")
		)
		(fp_poly
			(pts
				(xy -0.5334 0.254) (xy -0.635 0.254) (xy -0.635 0.2286) (xy -0.635 -0.254) (xy -0.5334 -0.254) (xy -0.5334 -0.2794)
				(xy 0.5334 -0.2794) (xy 0.5334 -0.254) (xy 0.635 -0.254) (xy 0.635 0.254) (xy 0.5334 0.254) (xy 0.5334 0.2794)
				(xy -0.508 0.2794) (xy -0.5334 0.2794)
			)
			(stroke
				(width 0)
				(type default)
			)
			(fill no)
			(layer "F.CrtYd")
		)
		(pad "1" smd rect
			(at 0.40005 0 180)
			(size 0.4572 0.508)
			(layers "F.Cu" "F.Mask" "F.Paste")
			(net "P3V3_NODE1")
		)
		(pad "2" smd rect
			(at -0.40005 0 180)
			(size 0.4572 0.508)
			(layers "F.Cu" "F.Mask" "F.Paste")
			(net "GND")
		)
	)
	(footprint ""
		(layer "F.Cu")
		(at 96.719644 -131.158488 90)
		(property "Reference" "C809"
			(at 0.149352 1.641602 90)
			(unlocked yes)
			(layer "F.SilkS")
			(effects
				(font
					(size 0.7874 0.5842)
					(thickness 0.1524)
				)
				(justify left)
			)
		)
		(property "Value" ""
			(at 0 0 90)
			(layer "F.Fab")
			(effects
				(font
					(size 1.27 1.27)
				)
			)
		)
		(duplicate_pad_numbers_are_jumpers no)
		(fp_line
			(start 0.7874 -0.4064)
			(end 0.7874 0.4064)
			(stroke
				(width 0.1524)
				(type default)
			)
			(layer "F.SilkS")
		)
		(fp_line
			(start -0.7874 -0.4064)
			(end 0.7874 -0.4064)
			(stroke
				(width 0.1524)
				(type default)
			)
			(layer "F.SilkS")
		)
		(fp_line
			(start 0 0.381)
			(end 0 -0.381)
			(stroke
				(width 0.1524)
				(type default)
			)
			(layer "F.SilkS")
		)
		(fp_line
			(start 0.7874 0.4064)
			(end -0.7874 0.4064)
			(stroke
				(width 0.1524)
				(type default)
			)
			(layer "F.SilkS")
		)
		(fp_line
			(start -0.7874 0.4064)
			(end -0.7874 -0.4064)
			(stroke
				(width 0.1524)
				(type default)
			)
			(layer "F.SilkS")
		)
		(fp_poly
			(pts
				(xy -0.5334 0.254) (xy -0.635 0.254) (xy -0.635 0.2286) (xy -0.635 -0.254) (xy -0.5334 -0.254) (xy -0.5334 -0.2794)
				(xy 0.5334 -0.2794) (xy 0.5334 -0.254) (xy 0.635 -0.254) (xy 0.635 0.254) (xy 0.5334 0.254) (xy 0.5334 0.2794)
				(xy -0.508 0.2794) (xy -0.5334 0.2794)
			)
			(stroke
				(width 0)
				(type default)
			)
			(fill no)
			(layer "F.CrtYd")
		)
		(pad "1" smd rect
			(at 0.40005 0 90)
			(size 0.4572 0.508)
			(layers "F.Cu" "F.Mask" "F.Paste")
			(net "P5V_STB_NODE1")
		)
		(pad "2" smd rect
			(at -0.40005 0 90)
			(size 0.4572 0.508)
			(layers "F.Cu" "F.Mask" "F.Paste")
			(net "GND")
		)
	)
	(footprint ""
		(layer "F.Cu")
		(at 148.193252 -137.31875 180)
		(property "Reference" "R1229"
			(at -0.949706 0.089154 0)
			(unlocked yes)
			(layer "F.SilkS")
			(effects
				(font
					(size 0.635 0.4064)
					(thickness 0.1524)
				)
				(justify left)
			)
		)
		(property "Value" ""
			(at 0 0 180)
			(layer "F.Fab")
			(effects
				(font
					(size 1.27 1.27)
				)
			)
		)
		(duplicate_pad_numbers_are_jumpers no)
		(fp_line
			(start 0.7874 0.4064)
			(end -0.7874 0.4064)
			(stroke
				(width 0.1524)
				(type default)
			)
			(layer "F.SilkS")
		)
		(fp_line
			(start 0.7874 -0.4064)
			(end 0.7874 0.4064)
			(stroke
				(width 0.1524)
				(type default)
			)
			(layer "F.SilkS")
		)
		(fp_line
			(start -0.7874 0.4064)
			(end -0.7874 -0.4064)
			(stroke
				(width 0.1524)
				(type default)
			)
			(layer "F.SilkS")
		)
		(fp_line
			(start -0.7874 -0.4064)
			(end 0.7874 -0.4064)
			(stroke
				(width 0.1524)
				(type default)
			)
			(layer "F.SilkS")
		)
		(fp_poly
			(pts
				(xy -0.508 0.2794) (xy -0.508 0.2286) (xy -0.635 0.2286) (xy -0.635 -0.254) (xy -0.5334 -0.254)
				(xy -0.5334 -0.2794) (xy 0.5334 -0.2794) (xy 0.5334 -0.254) (xy 0.635 -0.254) (xy 0.635 0.254) (xy 0.5334 0.254)
				(xy 0.5334 0.2794)
			)
			(stroke
				(width 0)
				(type default)
			)
			(fill no)
			(layer "F.CrtYd")
		)
		(pad "1" smd rect
			(at 0.40005 0 180)
			(size 0.4572 0.508)
			(layers "F.Cu" "F.Mask" "F.Paste")
			(net "PCIE_SW_PRSNT2")
		)
		(pad "2" smd rect
			(at -0.40005 0 180)
			(size 0.4572 0.508)
			(layers "F.Cu" "F.Mask" "F.Paste")
			(net "GND")
		)
	)
	(footprint ""
		(layer "F.Cu")
		(at 51.03114 -166.43985 90)
		(property "Reference" "R561"
			(at -130.36804 -3.432048 90)
			(unlocked yes)
			(layer "F.SilkS")
			(effects
				(font
					(size 0.7874 0.5842)
					(thickness 0.1524)
				)
				(justify left)
			)
		)
		(property "Value" ""
			(at 0 0 90)
			(layer "F.Fab")
			(effects
				(font
					(size 1.27 1.27)
				)
			)
		)
		(duplicate_pad_numbers_are_jumpers no)
		(fp_line
			(start 0.7874 -0.4064)
			(end 0.7874 0.4064)
			(stroke
				(width 0.1524)
				(type default)
			)
			(layer "F.SilkS")
		)
		(fp_line
			(start -0.7874 -0.4064)
			(end 0.7874 -0.4064)
			(stroke
				(width 0.1524)
				(type default)
			)
			(layer "F.SilkS")
		)
		(fp_line
			(start 0.7874 0.4064)
			(end -0.7874 0.4064)
			(stroke
				(width 0.1524)
				(type default)
			)
			(layer "F.SilkS")
		)
		(fp_line
			(start -0.7874 0.4064)
			(end -0.7874 -0.4064)
			(stroke
				(width 0.1524)
				(type default)
			)
			(layer "F.SilkS")
		)
		(fp_poly
			(pts
				(xy -0.508 0.2794) (xy -0.508 0.2286) (xy -0.635 0.2286) (xy -0.635 -0.254) (xy -0.5334 -0.254)
				(xy -0.5334 -0.2794) (xy 0.5334 -0.2794) (xy 0.5334 -0.254) (xy 0.635 -0.254) (xy 0.635 0.254) (xy 0.5334 0.254)
				(xy 0.5334 0.2794)
			)
			(stroke
				(width 0)
				(type default)
			)
			(fill no)
			(layer "F.CrtYd")
		)
		(pad "1" smd rect
			(at 0.40005 0 90)
			(size 0.4572 0.508)
			(layers "F.Cu" "F.Mask" "F.Paste")
			(net "PCH_I2C_ALERT_N")
		)
		(pad "2" smd rect
			(at -0.40005 0 90)
			(size 0.4572 0.508)
			(layers "F.Cu" "F.Mask" "F.Paste")
			(net "SMB_LAN1_ALT_N")
		)
	)
	(footprint ""
		(layer "F.Cu")
		(at 22.537166 -137.846308)
		(property "Reference" "C430"
			(at -2.122424 3.178048 0)
			(unlocked yes)
			(layer "F.SilkS")
			(effects
				(font
					(size 0.7874 0.5842)
					(thickness 0.1524)
				)
				(justify left)
			)
		)
		(property "Value" ""
			(at 0 0 0)
			(layer "F.Fab")
			(effects
				(font
					(size 1.27 1.27)
				)
			)
		)
		(duplicate_pad_numbers_are_jumpers no)
		(fp_line
			(start -1.905 -0.8636)
			(end 1.905 -0.8636)
			(stroke
				(width 0.1524)
				(type default)
			)
			(layer "F.SilkS")
		)
		(fp_line
			(start -1.905 0.8636)
			(end -1.905 -0.8636)
			(stroke
				(width 0.1524)
				(type default)
			)
			(layer "F.SilkS")
		)
		(fp_line
			(start 0 0.8382)
			(end 0 -0.8382)
			(stroke
				(width 0.1524)
				(type default)
			)
			(layer "F.SilkS")
		)
		(fp_line
			(start 1.905 -0.8636)
			(end 1.905 0.8636)
			(stroke
				(width 0.1524)
				(type default)
			)
			(layer "F.SilkS")
		)
		(fp_line
			(start 1.905 0.8636)
			(end -1.905 0.8636)
			(stroke
				(width 0.1524)
				(type default)
			)
			(layer "F.SilkS")
		)
		(fp_rect
			(start -1.524 0.7366)
			(end 1.524 -0.7366)
			(stroke
				(width 0)
				(type default)
			)
			(fill no)
			(layer "F.CrtYd")
		)
		(pad "1" smd rect
			(at 0.94996 0)
			(size 1.1176 1.3716)
			(layers "F.Cu" "F.Mask" "F.Paste")
			(net "P1V9_LAN1")
		)
		(pad "2" smd rect
			(at -0.94996 0)
			(size 1.1176 1.3716)
			(layers "F.Cu" "F.Mask" "F.Paste")
			(net "GND")
		)
	)
	(footprint ""
		(layer "F.Cu")
		(at 93.963236 -82.994246 90)
		(property "Reference" "Q42"
			(at -2.537206 0.170942 0)
			(unlocked yes)
			(layer "F.SilkS")
			(effects
				(font
					(size 0.7874 0.5842)
					(thickness 0.1524)
				)
				(justify left)
			)
		)
		(property "Value" ""
			(at 0 0 90)
			(layer "F.Fab")
			(effects
				(font
					(size 1.27 1.27)
				)
			)
		)
		(duplicate_pad_numbers_are_jumpers no)
		(fp_line
			(start 2.584196 -0.5842)
			(end 2.584196 2.48412)
			(stroke
				(width 0.1524)
				(type default)
			)
			(layer "F.SilkS")
		)
		(fp_line
			(start -0.5842 -0.5842)
			(end 2.584196 -0.5842)
			(stroke
				(width 0.1524)
				(type default)
			)
			(layer "F.SilkS")
		)
		(fp_line
			(start 2.584196 2.48412)
			(end -0.5842 2.48412)
			(stroke
				(width 0.1524)
				(type default)
			)
			(layer "F.SilkS")
		)
		(fp_line
			(start -0.5842 2.48412)
			(end -0.5842 -0.5842)
			(stroke
				(width 0.1524)
				(type default)
			)
			(layer "F.SilkS")
		)
		(fp_poly
			(pts
				(xy -0.508 -0.4572) (xy 0.299974 -0.4572) (xy 0.299974 -0.54991) (xy 1.700022 -0.54991) (xy 1.700022 0.49276)
				(xy 2.507996 0.49276) (xy 2.507996 1.40716) (xy 1.700022 1.40716) (xy 1.700022 2.450084) (xy 0.299974 2.450084)
				(xy 0.299974 2.35712) (xy -0.508 2.35712)
			)
			(stroke
				(width 0)
				(type default)
			)
			(fill no)
			(layer "F.CrtYd")
		)
		(fp_line
			(start 1.700022 -0.54991)
			(end 1.700022 2.450084)
			(stroke
				(width 0.1)
				(type default)
			)
			(layer "F.Fab")
		)
		(fp_line
			(start 0.299974 -0.54991)
			(end 1.700022 -0.54991)
			(stroke
				(width 0.1)
				(type default)
			)
			(layer "F.Fab")
		)
		(fp_line
			(start 1.700022 2.450084)
			(end 0.299974 2.450084)
			(stroke
				(width 0.1)
				(type default)
			)
			(layer "F.Fab")
		)
		(fp_line
			(start 0.299974 2.450084)
			(end 0.299974 -0.54991)
			(stroke
				(width 0.1)
				(type default)
			)
			(layer "F.Fab")
		)
		(fp_text user "C"
			(at 2.57683 -1.116838 0)
			(unlocked yes)
			(layer "F.SilkS")
			(effects
				(font
					(size 0.635 0.4064)
					(thickness 0.1524)
				)
				(justify left)
			)
		)
		(fp_text user "B"
			(at -1.238758 0.435864 0)
			(unlocked yes)
			(layer "F.SilkS")
			(effects
				(font
					(size 0.635 0.4064)
					(thickness 0.1524)
				)
				(justify left)
			)
		)
		(fp_text user "E"
			(at -1.247394 1.912366 0)
			(unlocked yes)
			(layer "F.SilkS")
			(effects
				(font
					(size 0.635 0.4064)
					(thickness 0.1524)
				)
				(justify left)
			)
		)
		(fp_text user "B"
			(at -1.5494 0.00127 90)
			(unlocked yes)
			(layer "F.Fab")
			(effects
				(font
					(size 0.7874 0.5842)
					(thickness 0.000001)
				)
				(justify left)
			)
		)
		(fp_text user "C"
			(at 2.8702 0.99187 90)
			(unlocked yes)
			(layer "F.Fab")
			(effects
				(font
					(size 0.7874 0.5842)
					(thickness 0.000001)
				)
				(justify left)
			)
		)
		(fp_text user "E"
			(at -1.5748 1.95707 90)
			(unlocked yes)
			(layer "F.Fab")
			(effects
				(font
					(size 0.7874 0.5842)
					(thickness 0.000001)
				)
				(justify left)
			)
		)
		(pad "B" smd rect
			(at 0 0 180)
			(size 0.8128 0.9144)
			(layers "F.Cu" "F.Mask" "F.Paste")
			(net "N45787194")
		)
		(pad "C" smd rect
			(at 1.999996 0.94996 180)
			(size 0.8128 0.9144)
			(layers "F.Cu" "F.Mask" "F.Paste")
			(net "CPU_NODE1_PROCHOT_N")
		)
		(pad "E" smd rect
			(at 0 1.89992 180)
			(size 0.8128 0.9144)
			(layers "F.Cu" "F.Mask" "F.Paste")
			(net "H_CPU_NODE1_PROCHOT_L")
		)
	)
	(footprint ""
		(layer "F.Cu")
		(at 153.526998 -142.88643 -90)
		(property "Reference" "R566"
			(at -1.382014 -0.556514 90)
			(unlocked yes)
			(layer "F.SilkS")
			(effects
				(font
					(size 0.635 0.4064)
					(thickness 0.1524)
				)
				(justify left)
			)
		)
		(property "Value" ""
			(at 0 0 270)
			(layer "F.Fab")
			(effects
				(font
					(size 1.27 1.27)
				)
			)
		)
		(duplicate_pad_numbers_are_jumpers no)
		(fp_line
			(start -0.7874 0.4064)
			(end -0.7874 -0.4064)
			(stroke
				(width 0.1524)
				(type default)
			)
			(layer "F.SilkS")
		)
		(fp_line
			(start 0.7874 0.4064)
			(end -0.7874 0.4064)
			(stroke
				(width 0.1524)
				(type default)
			)
			(layer "F.SilkS")
		)
		(fp_line
			(start -0.7874 -0.4064)
			(end 0.7874 -0.4064)
			(stroke
				(width 0.1524)
				(type default)
			)
			(layer "F.SilkS")
		)
		(fp_line
			(start 0.7874 -0.4064)
			(end 0.7874 0.4064)
			(stroke
				(width 0.1524)
				(type default)
			)
			(layer "F.SilkS")
		)
		(fp_poly
			(pts
				(xy -0.508 0.2794) (xy -0.508 0.2286) (xy -0.635 0.2286) (xy -0.635 -0.254) (xy -0.5334 -0.254)
				(xy -0.5334 -0.2794) (xy 0.5334 -0.2794) (xy 0.5334 -0.254) (xy 0.635 -0.254) (xy 0.635 0.254) (xy 0.5334 0.254)
				(xy 0.5334 0.2794)
			)
			(stroke
				(width 0)
				(type default)
			)
			(fill no)
			(layer "F.CrtYd")
		)
		(pad "1" smd rect
			(at 0.40005 0 270)
			(size 0.4572 0.508)
			(layers "F.Cu" "F.Mask" "F.Paste")
			(net "P3V3_NODE1")
		)
		(pad "2" smd rect
			(at -0.40005 0 270)
			(size 0.4572 0.508)
			(layers "F.Cu" "F.Mask" "F.Paste")
			(net "SMB_LAN2_DAT")
		)
	)
	(footprint ""
		(layer "F.Cu")
		(at 34.474404 -12.03198)
		(property "Reference" "PR34"
			(at -10.784078 -0.04826 0)
			(unlocked yes)
			(layer "F.SilkS")
			(effects
				(font
					(size 0.7874 0.5842)
					(thickness 0.1524)
				)
				(justify left)
			)
		)
		(property "Value" ""
			(at 0 0 0)
			(layer "F.Fab")
			(effects
				(font
					(size 1.27 1.27)
				)
			)
		)
		(duplicate_pad_numbers_are_jumpers no)
		(fp_line
			(start -0.7874 -0.4064)
			(end 0.7874 -0.4064)
			(stroke
				(width 0.1524)
				(type default)
			)
			(layer "F.SilkS")
		)
		(fp_line
			(start -0.7874 0.4064)
			(end -0.7874 -0.4064)
			(stroke
				(width 0.1524)
				(type default)
			)
			(layer "F.SilkS")
		)
		(fp_line
			(start 0.7874 -0.4064)
			(end 0.7874 0.4064)
			(stroke
				(width 0.1524)
				(type default)
			)
			(layer "F.SilkS")
		)
		(fp_line
			(start 0.7874 0.4064)
			(end -0.7874 0.4064)
			(stroke
				(width 0.1524)
				(type default)
			)
			(layer "F.SilkS")
		)
		(fp_poly
			(pts
				(xy -0.508 0.2794) (xy -0.508 0.2286) (xy -0.635 0.2286) (xy -0.635 -0.254) (xy -0.5334 -0.254)
				(xy -0.5334 -0.2794) (xy 0.5334 -0.2794) (xy 0.5334 -0.254) (xy 0.635 -0.254) (xy 0.635 0.254) (xy 0.5334 0.254)
				(xy 0.5334 0.2794)
			)
			(stroke
				(width 0)
				(type default)
			)
			(fill no)
			(layer "F.CrtYd")
		)
		(pad "1" smd rect
			(at 0.40005 0)
			(size 0.4572 0.508)
			(layers "F.Cu" "F.Mask" "F.Paste")
			(net "VSENSE_PV_VDDR_NODE1_N")
		)
		(pad "2" smd rect
			(at -0.40005 0)
			(size 0.4572 0.508)
			(layers "F.Cu" "F.Mask" "F.Paste")
			(net "GND")
		)
	)
	(footprint ""
		(layer "F.Cu")
		(at 141.530578 -59.916822 90)
		(property "Reference" "U30"
			(at 10.669016 3.15341 0)
			(unlocked yes)
			(layer "F.SilkS")
			(effects
				(font
					(size 0.7874 0.5842)
					(thickness 0.1524)
				)
				(justify left)
			)
		)
		(property "Value" ""
			(at 0 0 90)
			(layer "F.Fab")
			(effects
				(font
					(size 1.27 1.27)
				)
			)
		)
		(duplicate_pad_numbers_are_jumpers no)
		(fp_line
			(start 7.244334 -2.660904)
			(end 7.244334 -1.644904)
			(stroke
				(width 0.1524)
				(type default)
			)
			(layer "F.SilkS")
		)
		(fp_line
			(start 3.258312 -2.6543)
			(end 3.258312 -1.6383)
			(stroke
				(width 0.1524)
				(type default)
			)
			(layer "F.SilkS")
		)
		(fp_line
			(start 1.248918 -2.168906)
			(end 1.248918 -1.660906)
			(stroke
				(width 0.1524)
				(type default)
			)
			(layer "F.SilkS")
		)
		(fp_line
			(start 5.221478 -2.135886)
			(end 5.221478 -1.627886)
			(stroke
				(width 0.1524)
				(type default)
			)
			(layer "F.SilkS")
		)
		(fp_line
			(start 8.941308 -0.899922)
			(end 8.257032 -0.899922)
			(stroke
				(width 0.1524)
				(type default)
			)
			(layer "F.SilkS")
		)
		(fp_line
			(start 0.625348 -0.899922)
			(end -0.058928 -0.899922)
			(stroke
				(width 0.1524)
				(type default)
			)
			(layer "F.SilkS")
		)
		(fp_line
			(start -0.058928 -0.899922)
			(end -0.058928 -0.2159)
			(stroke
				(width 0.1524)
				(type default)
			)
			(layer "F.SilkS")
		)
		(fp_line
			(start 8.941308 -0.2159)
			(end 8.941308 -0.899922)
			(stroke
				(width 0.1524)
				(type default)
			)
			(layer "F.SilkS")
		)
		(fp_line
			(start 9.686036 0.81534)
			(end 10.194036 0.81534)
			(stroke
				(width 0.1524)
				(type default)
			)
			(layer "F.SilkS")
		)
		(fp_line
			(start -1.324102 1.601724)
			(end -0.816102 1.601724)
			(stroke
				(width 0.1524)
				(type default)
			)
			(layer "F.SilkS")
		)
		(fp_line
			(start 9.703054 2.798318)
			(end 10.719054 2.798318)
			(stroke
				(width 0.1524)
				(type default)
			)
			(layer "F.SilkS")
		)
		(fp_line
			(start -1.789684 3.598164)
			(end -0.773684 3.598164)
			(stroke
				(width 0.1524)
				(type default)
			)
			(layer "F.SilkS")
		)
		(fp_line
			(start 9.712452 4.807712)
			(end 10.220452 4.807712)
			(stroke
				(width 0.1524)
				(type default)
			)
			(layer "F.SilkS")
		)
		(fp_line
			(start -1.310894 5.59435)
			(end -0.802894 5.59435)
			(stroke
				(width 0.1524)
				(type default)
			)
			(layer "F.SilkS")
		)
		(fp_line
			(start 9.689846 6.797548)
			(end 10.705846 6.797548)
			(stroke
				(width 0.1524)
				(type default)
			)
			(layer "F.SilkS")
		)
		(fp_line
			(start -0.058928 7.415784)
			(end -0.058928 8.10006)
			(stroke
				(width 0.1524)
				(type default)
			)
			(layer "F.SilkS")
		)
		(fp_line
			(start 8.941308 8.10006)
			(end 8.941308 7.415784)
			(stroke
				(width 0.1524)
				(type default)
			)
			(layer "F.SilkS")
		)
		(fp_line
			(start 8.257032 8.10006)
			(end 8.941308 8.10006)
			(stroke
				(width 0.1524)
				(type default)
			)
			(layer "F.SilkS")
		)
		(fp_line
			(start -0.058928 8.10006)
			(end 0.625348 8.10006)
			(stroke
				(width 0.1524)
				(type default)
			)
			(layer "F.SilkS")
		)
		(fp_line
			(start 4.844796 8.814816)
			(end 4.844796 9.830816)
			(stroke
				(width 0.1524)
				(type default)
			)
			(layer "F.SilkS")
		)
		(fp_line
			(start 6.861048 8.817356)
			(end 6.861048 9.325356)
			(stroke
				(width 0.1524)
				(type default)
			)
			(layer "F.SilkS")
		)
		(fp_line
			(start 2.841752 8.824214)
			(end 2.841752 9.332214)
			(stroke
				(width 0.1524)
				(type default)
			)
			(layer "F.SilkS")
		)
		(fp_line
			(start 0.832358 8.847582)
			(end 0.832358 9.863582)
			(stroke
				(width 0.1524)
				(type default)
			)
			(layer "F.SilkS")
		)
		(fp_poly
			(pts
				(xy -0.79375 -1.728978) (xy -1.512062 -1.010666) (xy -0.434594 -0.65151)
			)
			(stroke
				(width 0)
				(type default)
			)
			(fill yes)
			(layer "F.SilkS")
		)
		(fp_poly
			(pts
				(xy 0.701548 8.650732) (xy 0.701548 8.10006) (xy -0.058928 8.10006) (xy -0.058928 7.339584) (xy -0.6096 7.339584)
				(xy -0.6096 -0.1397) (xy -0.058928 -0.1397) (xy -0.058928 -0.899922) (xy 0.701548 -0.899922) (xy 0.701548 -1.450848)
				(xy 8.180832 -1.450848) (xy 8.180832 -0.899922) (xy 8.941308 -0.899922) (xy 8.941308 -0.1397) (xy 9.49198 -0.1397)
				(xy 9.49198 7.339584) (xy 8.941308 7.339584) (xy 8.941308 8.10006) (xy 8.180832 8.10006) (xy 8.180832 8.650732)
			)
			(stroke
				(width 0)
				(type default)
			)
			(fill no)
			(layer "F.CrtYd")
		)
		(fp_line
			(start 7.244334 -2.660904)
			(end 7.244334 -1.644904)
			(stroke
				(width 0.1)
				(type default)
			)
			(layer "F.Fab")
		)
		(fp_line
			(start 3.258312 -2.6543)
			(end 3.258312 -1.6383)
			(stroke
				(width 0.1)
				(type default)
			)
			(layer "F.Fab")
		)
		(fp_line
			(start 1.248918 -2.168906)
			(end 1.248918 -1.660906)
			(stroke
				(width 0.1)
				(type default)
			)
			(layer "F.Fab")
		)
		(fp_line
			(start 5.221478 -2.135886)
			(end 5.221478 -1.627886)
			(stroke
				(width 0.1)
				(type default)
			)
			(layer "F.Fab")
		)
		(fp_line
			(start 8.941308 -0.899922)
			(end -0.058928 -0.899922)
			(stroke
				(width 0.1)
				(type default)
			)
			(layer "F.Fab")
		)
		(fp_line
			(start -0.058928 -0.899922)
			(end -0.058928 8.10006)
			(stroke
				(width 0.1)
				(type default)
			)
			(layer "F.Fab")
		)
		(fp_line
			(start 9.686036 0.81534)
			(end 10.194036 0.81534)
			(stroke
				(width 0.1)
				(type default)
			)
			(layer "F.Fab")
		)
		(fp_line
			(start -1.324102 1.601724)
			(end -0.816102 1.601724)
			(stroke
				(width 0.1)
				(type default)
			)
			(layer "F.Fab")
		)
		(fp_line
			(start 9.703054 2.798318)
			(end 10.719054 2.798318)
			(stroke
				(width 0.1)
				(type default)
			)
			(layer "F.Fab")
		)
		(fp_line
			(start -1.789684 3.598164)
			(end -0.773684 3.598164)
			(stroke
				(width 0.1)
				(type default)
			)
			(layer "F.Fab")
		)
		(fp_line
			(start 9.712452 4.807712)
			(end 10.220452 4.807712)
			(stroke
				(width 0.1)
				(type default)
			)
			(layer "F.Fab")
		)
		(fp_line
			(start -1.310894 5.59435)
			(end -0.802894 5.59435)
			(stroke
				(width 0.1)
				(type default)
			)
			(layer "F.Fab")
		)
		(fp_line
			(start 9.689846 6.797548)
			(end 10.705846 6.797548)
			(stroke
				(width 0.1)
				(type default)
			)
			(layer "F.Fab")
		)
		(fp_line
			(start 8.941308 8.10006)
			(end 8.941308 -0.899922)
			(stroke
				(width 0.1)
				(type default)
			)
			(layer "F.Fab")
		)
		(fp_line
			(start -0.058928 8.10006)
			(end 8.941308 8.10006)
			(stroke
				(width 0.1)
				(type default)
			)
			(layer "F.Fab")
		)
		(fp_line
			(start 4.844796 8.814816)
			(end 4.844796 9.830816)
			(stroke
				(width 0.1)
				(type default)
			)
			(layer "F.Fab")
		)
		(fp_line
			(start 6.861048 8.817356)
			(end 6.861048 9.325356)
			(stroke
				(width 0.1)
				(type default)
			)
			(layer "F.Fab")
		)
		(fp_line
			(start 2.841752 8.824214)
			(end 2.841752 9.332214)
			(stroke
				(width 0.1)
				(type default)
			)
			(layer "F.Fab")
		)
		(fp_line
			(start 0.832358 8.847582)
			(end 0.832358 9.863582)
			(stroke
				(width 0.1)
				(type default)
			)
			(layer "F.Fab")
		)
		(fp_poly
			(pts
				(xy -1.804162 -0.505968) (xy -1.804162 0.510032) (xy -0.788162 0.002032)
			)
			(stroke
				(width 0)
				(type default)
			)
			(fill yes)
			(layer "F.Fab")
		)
		(fp_text user "58"
			(at 8.54964 -1.569974 0)
			(unlocked yes)
			(layer "F.SilkS")
			(effects
				(font
					(size 0.635 0.4064)
					(thickness 0.1524)
				)
			)
		)
		(fp_text user "76"
			(at 0.198882 -1.55448 0)
			(unlocked yes)
			(layer "F.SilkS")
			(effects
				(font
					(size 0.635 0.4064)
					(thickness 0.1524)
				)
			)
		)
		(fp_text user "57"
			(at 9.424924 -0.676148 0)
			(unlocked yes)
			(layer "F.SilkS")
			(effects
				(font
					(size 0.635 0.4064)
					(thickness 0.1524)
				)
			)
		)
		(fp_text user "1"
			(at -0.62103 -0.448818 0)
			(unlocked yes)
			(layer "F.SilkS")
			(effects
				(font
					(size 0.635 0.4064)
					(thickness 0.1524)
				)
			)
		)
		(fp_text user "19"
			(at -0.676402 7.842504 0)
			(unlocked yes)
			(layer "F.SilkS")
			(effects
				(font
					(size 0.635 0.4064)
					(thickness 0.1524)
				)
			)
		)
		(fp_text user "39"
			(at 9.439656 7.870444 0)
			(unlocked yes)
			(layer "F.SilkS")
			(effects
				(font
					(size 0.635 0.4064)
					(thickness 0.1524)
				)
			)
		)
		(fp_text user "38"
			(at 8.58266 8.782304 0)
			(unlocked yes)
			(layer "F.SilkS")
			(effects
				(font
					(size 0.635 0.4064)
					(thickness 0.1524)
				)
			)
		)
		(fp_text user "20"
			(at 0.208026 8.782304 0)
			(unlocked yes)
			(layer "F.SilkS")
			(effects
				(font
					(size 0.635 0.4064)
					(thickness 0.1524)
				)
			)
		)
		(fp_text user "58"
			(at 8.771382 -1.513078 90)
			(unlocked yes)
			(layer "F.Fab")
			(effects
				(font
					(size 0.635 0.4064)
					(thickness 0.000001)
				)
			)
		)
		(fp_text user "76"
			(at 0.072136 -1.43383 90)
			(unlocked yes)
			(layer "F.Fab")
			(effects
				(font
					(size 0.635 0.4064)
					(thickness 0.000001)
				)
			)
		)
		(fp_text user "57"
			(at 9.682226 -0.744982 180)
			(unlocked yes)
			(layer "F.Fab")
			(effects
				(font
					(size 0.635 0.4064)
					(thickness 0.000001)
				)
			)
		)
		(fp_text user "1"
			(at -0.5969 -0.559816 180)
			(unlocked yes)
			(layer "F.Fab")
			(effects
				(font
					(size 0.635 0.4064)
					(thickness 0.000001)
				)
			)
		)
		(fp_text user "39"
			(at 9.715246 7.901432 180)
			(unlocked yes)
			(layer "F.Fab")
			(effects
				(font
					(size 0.635 0.4064)
					(thickness 0.000001)
				)
			)
		)
		(fp_text user "19"
			(at -0.742188 7.960868 180)
			(unlocked yes)
			(layer "F.Fab")
			(effects
				(font
					(size 0.635 0.4064)
					(thickness 0.000001)
				)
			)
		)
		(fp_text user "38"
			(at 8.824214 8.759444 90)
			(unlocked yes)
			(layer "F.Fab")
			(effects
				(font
					(size 0.635 0.4064)
					(thickness 0.000001)
				)
			)
		)
		(fp_text user "20"
			(at 0.118364 8.792464 90)
			(unlocked yes)
			(layer "F.Fab")
			(effects
				(font
					(size 0.635 0.4064)
					(thickness 0.000001)
				)
			)
		)
		(pad "1" smd rect
			(at 0 0 180)
			(size 0.1778 1.1176)
			(layers "F.Cu" "F.Mask" "F.Paste")
			(net "Net_1786")
		)
		(pad "2" smd rect
			(at 0 0.40005 180)
			(size 0.1778 1.1176)
			(layers "F.Cu" "F.Mask" "F.Paste")
			(net "Net_1793")
		)
		(pad "3" smd rect
			(at 0 0.8001 180)
			(size 0.1778 1.1176)
			(layers "F.Cu" "F.Mask" "F.Paste")
			(net "Net_1794")
		)
		(pad "4" smd rect
			(at 0 1.199896 180)
			(size 0.1778 1.1176)
			(layers "F.Cu" "F.Mask" "F.Paste")
			(net "Net_1795")
		)
		(pad "5" smd rect
			(at 0 1.599946 180)
			(size 0.1778 1.1176)
			(layers "F.Cu" "F.Mask" "F.Paste")
			(net "P1V0_SATA")
		)
		(pad "6" smd rect
			(at 0 1.999996 180)
			(size 0.1778 1.1176)
			(layers "F.Cu" "F.Mask" "F.Paste")
			(net "Net_1800")
		)
		(pad "7" smd rect
			(at 0 2.400046 180)
			(size 0.1778 1.1176)
			(layers "F.Cu" "F.Mask" "F.Paste")
			(net "Net_1810")
		)
		(pad "8" smd rect
			(at 0 2.800096 180)
			(size 0.1778 1.1176)
			(layers "F.Cu" "F.Mask" "F.Paste")
			(net "Net_1814")
		)
		(pad "9" smd rect
			(at 0 3.199892 180)
			(size 0.1778 1.1176)
			(layers "F.Cu" "F.Mask" "F.Paste")
			(net "P3V3_NODE1")
		)
		(pad "10" smd rect
			(at 0 3.599942 180)
			(size 0.1778 1.1176)
			(layers "F.Cu" "F.Mask" "F.Paste")
			(net "Net_1787")
		)
		(pad "11" smd rect
			(at 0 3.999992 180)
			(size 0.1778 1.1176)
			(layers "F.Cu" "F.Mask" "F.Paste")
			(net "Net_1788")
		)
		(pad "12" smd rect
			(at 0 4.400042 180)
			(size 0.1778 1.1176)
			(layers "F.Cu" "F.Mask" "F.Paste")
			(net "Net_1789")
		)
		(pad "13" smd rect
			(at 0 4.800092 180)
			(size 0.1778 1.1176)
			(layers "F.Cu" "F.Mask" "F.Paste")
			(net "P1V0_SATA")
		)
		(pad "14" smd rect
			(at 0 5.199888 180)
			(size 0.1778 1.1176)
			(layers "F.Cu" "F.Mask" "F.Paste")
			(net "Net_1790")
		)
		(pad "15" smd rect
			(at 0 5.599938 180)
			(size 0.1778 1.1176)
			(layers "F.Cu" "F.Mask" "F.Paste")
			(net "Net_1791")
		)
		(pad "16" smd rect
			(at 0 5.999988 180)
			(size 0.1778 1.1176)
			(layers "F.Cu" "F.Mask" "F.Paste")
			(net "Net_1792")
		)
		(pad "17" smd rect
			(at 0 6.400038 180)
			(size 0.1778 1.1176)
			(layers "F.Cu" "F.Mask" "F.Paste")
			(net "SATA_NODE1_GPIO3")
		)
		(pad "18" smd rect
			(at 0 6.800088 180)
			(size 0.1778 1.1176)
			(layers "F.Cu" "F.Mask" "F.Paste")
			(net "PU_SATA_NODE1_GPIO4")
		)
		(pad "19" smd rect
			(at 0 7.199884 180)
			(size 0.1778 1.1176)
			(layers "F.Cu" "F.Mask" "F.Paste")
			(net "SATA_NODE1_GPIO5")
		)
		(pad "20" smd rect
			(at 0.841248 8.041132 90)
			(size 0.1778 1.1176)
			(layers "F.Cu" "F.Mask" "F.Paste")
			(net "NODE1_USB_TESTMODE")
		)
		(pad "21" smd rect
			(at 1.241298 8.041132 90)
			(size 0.1778 1.1176)
			(layers "F.Cu" "F.Mask" "F.Paste")
			(net "P1V0_SATA")
		)
		(pad "22" smd rect
			(at 1.641094 8.041132 90)
			(size 0.1778 1.1176)
			(layers "F.Cu" "F.Mask" "F.Paste")
			(net "TP_SATA_NODE1")
		)
		(pad "23" smd rect
			(at 2.041144 8.041132 90)
			(size 0.1778 1.1176)
			(layers "F.Cu" "F.Mask" "F.Paste")
			(net "Net_1816")
		)
		(pad "24" smd rect
			(at 2.441194 8.041132 90)
			(size 0.1778 1.1176)
			(layers "F.Cu" "F.Mask" "F.Paste")
			(net "Net_1815")
		)
		(pad "25" smd rect
			(at 2.841244 8.041132 90)
			(size 0.1778 1.1176)
			(layers "F.Cu" "F.Mask" "F.Paste")
			(net "P1V8_SATA_VAA2_1_NODE1")
		)
		(pad "26" smd rect
			(at 3.241294 8.041132 90)
			(size 0.1778 1.1176)
			(layers "F.Cu" "F.Mask" "F.Paste")
			(net "Net_1817")
		)
		(pad "27" smd rect
			(at 3.64109 8.041132 90)
			(size 0.1778 1.1176)
			(layers "F.Cu" "F.Mask" "F.Paste")
			(net "Net_1818")
		)
		(pad "28" smd rect
			(at 4.04114 8.041132 90)
			(size 0.1778 1.1176)
			(layers "F.Cu" "F.Mask" "F.Paste")
			(net "GND")
		)
		(pad "29" smd rect
			(at 4.44119 8.041132 90)
			(size 0.1778 1.1176)
			(layers "F.Cu" "F.Mask" "F.Paste")
			(net "SATA_A_NODE1_RX_P0")
		)
		(pad "30" smd rect
			(at 4.84124 8.041132 90)
			(size 0.1778 1.1176)
			(layers "F.Cu" "F.Mask" "F.Paste")
			(net "SATA_A_NODE1_RX_N0")
		)
		(pad "31" smd rect
			(at 5.24129 8.041132 90)
			(size 0.1778 1.1176)
			(layers "F.Cu" "F.Mask" "F.Paste")
			(net "P1V8_SATA_VAA2_0_NODE1")
		)
		(pad "32" smd rect
			(at 5.641086 8.041132 90)
			(size 0.1778 1.1176)
			(layers "F.Cu" "F.Mask" "F.Paste")
			(net "SATA_A_NODE1_TX_N0")
		)
		(pad "33" smd rect
			(at 6.041136 8.041132 90)
			(size 0.1778 1.1176)
			(layers "F.Cu" "F.Mask" "F.Paste")
			(net "SATA_A_NODE1_TX_P0")
		)
		(pad "34" smd rect
			(at 6.441186 8.041132 90)
			(size 0.1778 1.1176)
			(layers "F.Cu" "F.Mask" "F.Paste")
			(net "P1V8_SATA_VAA1_NODE1")
		)
		(pad "35" smd rect
			(at 6.841236 8.041132 90)
			(size 0.1778 1.1176)
			(layers "F.Cu" "F.Mask" "F.Paste")
			(net "CLK_25M_SATA_NODE1")
		)
		(pad "36" smd rect
			(at 7.241286 8.041132 90)
			(size 0.1778 1.1176)
			(layers "F.Cu" "F.Mask" "F.Paste")
			(net "SATA_NODE1_XTLOUT")
		)
		(pad "37" smd rect
			(at 7.641082 8.041132 90)
			(size 0.1778 1.1176)
			(layers "F.Cu" "F.Mask" "F.Paste")
			(net "SATA_NODE1_ISET")
		)
		(pad "38" smd rect
			(at 8.041132 8.041132 90)
			(size 0.1778 1.1176)
			(layers "F.Cu" "F.Mask" "F.Paste")
			(net "SATA_VCONT_NODE1")
		)
		(pad "39" smd rect
			(at 8.88238 7.199884 180)
			(size 0.1778 1.1176)
			(layers "F.Cu" "F.Mask" "F.Paste")
			(net "P2E_CPU_SATA_NODE1_RX_C_DN")
		)
		(pad "40" smd rect
			(at 8.88238 6.800088 180)
			(size 0.1778 1.1176)
			(layers "F.Cu" "F.Mask" "F.Paste")
			(net "P2E_CPU_SATA_NODE1_RX_C_DP")
		)
		(pad "41" smd rect
			(at 8.88238 6.400038 180)
			(size 0.1778 1.1176)
			(layers "F.Cu" "F.Mask" "F.Paste")
			(net "P1V8_SATA_AVDD_NODE1")
		)
		(pad "42" smd rect
			(at 8.88238 5.999988 180)
			(size 0.1778 1.1176)
			(layers "F.Cu" "F.Mask" "F.Paste")
			(net "P1V8_SATA_AVDD_NODE1")
		)
		(pad "43" smd rect
			(at 8.88238 5.599938 180)
			(size 0.1778 1.1176)
			(layers "F.Cu" "F.Mask" "F.Paste")
			(net "P2E_CPU_SATA_NODE1_TX_DN")
		)
		(pad "44" smd rect
			(at 8.88238 5.199888 180)
			(size 0.1778 1.1176)
			(layers "F.Cu" "F.Mask" "F.Paste")
			(net "P2E_CPU_SATA_NODE1_TX_DP")
		)
		(pad "45" smd rect
			(at 8.88238 4.800092 180)
			(size 0.1778 1.1176)
			(layers "F.Cu" "F.Mask" "F.Paste")
			(net "CLK_100M_SATA_NODE1_DP")
		)
		(pad "46" smd rect
			(at 8.88238 4.400042 180)
			(size 0.1778 1.1176)
			(layers "F.Cu" "F.Mask" "F.Paste")
			(net "CLK_100M_SATA_NODE1_DN")
		)
		(pad "47" smd rect
			(at 8.88238 3.999992 180)
			(size 0.1778 1.1176)
			(layers "F.Cu" "F.Mask" "F.Paste")
			(net "SATA_SPI_DO_NODE1_R")
		)
		(pad "48" smd rect
			(at 8.88238 3.599942 180)
			(size 0.1778 1.1176)
			(layers "F.Cu" "F.Mask" "F.Paste")
			(net "SATA_SPI_CS_NODE1_R")
		)
		(pad "49" smd rect
			(at 8.88238 3.199892 180)
			(size 0.1778 1.1176)
			(layers "F.Cu" "F.Mask" "F.Paste")
			(net "SATA_SPI_DI_NODE1")
		)
		(pad "50" smd rect
			(at 8.88238 2.800096 180)
			(size 0.1778 1.1176)
			(layers "F.Cu" "F.Mask" "F.Paste")
			(net "SATA_SPI_CLK_NODE1_R")
		)
		(pad "51" smd rect
			(at 8.88238 2.400046 180)
			(size 0.1778 1.1176)
			(layers "F.Cu" "F.Mask" "F.Paste")
			(net "P1V0_SATA")
		)
		(pad "52" smd rect
			(at 8.88238 1.999996 180)
			(size 0.1778 1.1176)
			(layers "F.Cu" "F.Mask" "F.Paste")
			(net "IRQ_LVC3_SATA_NODE1_WAKE_L")
		)
		(pad "53" smd rect
			(at 8.88238 1.599946 180)
			(size 0.1778 1.1176)
			(layers "F.Cu" "F.Mask" "F.Paste")
			(net "FM_CPLD_NODE1_SATA_PERST_L")
		)
		(pad "54" smd rect
			(at 8.88238 1.199896 180)
			(size 0.1778 1.1176)
			(layers "F.Cu" "F.Mask" "F.Paste")
			(net "LED_SATA_NODE1_GPIO0")
		)
		(pad "55" smd rect
			(at 8.88238 0.8001 180)
			(size 0.1778 1.1176)
			(layers "F.Cu" "F.Mask" "F.Paste")
			(net "Net_1796")
		)
		(pad "56" smd rect
			(at 8.88238 0.40005 180)
			(size 0.1778 1.1176)
			(layers "F.Cu" "F.Mask" "F.Paste")
			(net "Net_1797")
		)
		(pad "57" smd rect
			(at 8.88238 0 180)
			(size 0.1778 1.1176)
			(layers "F.Cu" "F.Mask" "F.Paste")
			(net "P3V3_NODE1")
		)
		(pad "58" smd rect
			(at 8.041132 -0.841248 90)
			(size 0.1778 1.1176)
			(layers "F.Cu" "F.Mask" "F.Paste")
			(net "Net_1798")
		)
		(pad "59" smd rect
			(at 7.641082 -0.841248 90)
			(size 0.1778 1.1176)
			(layers "F.Cu" "F.Mask" "F.Paste")
			(net "Net_1799")
		)
		(pad "60" smd rect
			(at 7.241286 -0.841248 90)
			(size 0.1778 1.1176)
			(layers "F.Cu" "F.Mask" "F.Paste")
			(net "Net_1801")
		)
		(pad "61" smd rect
			(at 6.841236 -0.841248 90)
			(size 0.1778 1.1176)
			(layers "F.Cu" "F.Mask" "F.Paste")
			(net "Net_1802")
		)
		(pad "62" smd rect
			(at 6.441186 -0.841248 90)
			(size 0.1778 1.1176)
			(layers "F.Cu" "F.Mask" "F.Paste")
			(net "Net_1803")
		)
		(pad "63" smd rect
			(at 6.041136 -0.841248 90)
			(size 0.1778 1.1176)
			(layers "F.Cu" "F.Mask" "F.Paste")
			(net "Net_1804")
		)
		(pad "64" smd rect
			(at 5.641086 -0.841248 90)
			(size 0.1778 1.1176)
			(layers "F.Cu" "F.Mask" "F.Paste")
			(net "P1V0_SATA")
		)
		(pad "65" smd rect
			(at 5.24129 -0.841248 90)
			(size 0.1778 1.1176)
			(layers "F.Cu" "F.Mask" "F.Paste")
			(net "Net_1805")
		)
		(pad "66" smd rect
			(at 4.84124 -0.841248 90)
			(size 0.1778 1.1176)
			(layers "F.Cu" "F.Mask" "F.Paste")
			(net "Net_1806")
		)
		(pad "67" smd rect
			(at 4.44119 -0.841248 90)
			(size 0.1778 1.1176)
			(layers "F.Cu" "F.Mask" "F.Paste")
			(net "Net_1807")
		)
		(pad "68" smd rect
			(at 4.04114 -0.841248 90)
			(size 0.1778 1.1176)
			(layers "F.Cu" "F.Mask" "F.Paste")
			(net "Net_1808")
		)
		(pad "69" smd rect
			(at 3.64109 -0.841248 90)
			(size 0.1778 1.1176)
			(layers "F.Cu" "F.Mask" "F.Paste")
			(net "Net_1809")
		)
		(pad "70" smd rect
			(at 3.241294 -0.841248 90)
			(size 0.1778 1.1176)
			(layers "F.Cu" "F.Mask" "F.Paste")
			(net "Net_1811")
		)
		(pad "71" smd rect
			(at 2.841244 -0.841248 90)
			(size 0.1778 1.1176)
			(layers "F.Cu" "F.Mask" "F.Paste")
			(net "P1V0_SATA")
		)
		(pad "72" smd rect
			(at 2.441194 -0.841248 90)
			(size 0.1778 1.1176)
			(layers "F.Cu" "F.Mask" "F.Paste")
			(net "Net_1812")
		)
		(pad "73" smd rect
			(at 2.041144 -0.841248 90)
			(size 0.1778 1.1176)
			(layers "F.Cu" "F.Mask" "F.Paste")
			(net "P3V3_NODE1")
		)
		(pad "74" smd rect
			(at 1.641094 -0.841248 90)
			(size 0.1778 1.1176)
			(layers "F.Cu" "F.Mask" "F.Paste")
			(net "SATA_NODE1_GPIO1")
		)
		(pad "75" smd rect
			(at 1.241298 -0.841248 90)
			(size 0.1778 1.1176)
			(layers "F.Cu" "F.Mask" "F.Paste")
			(net "SATA_NODE1_GPIO2")
		)
		(pad "76" smd rect
			(at 0.841248 -0.841248 90)
			(size 0.1778 1.1176)
			(layers "F.Cu" "F.Mask" "F.Paste")
			(net "Net_1813")
		)
		(pad "TH" smd rect
			(at 4.44119 3.599942 90)
			(size 3.9624 3.9624)
			(layers "F.Cu" "F.Mask" "F.Paste")
			(net "GND")
		)
		(zone
			(layer "F.Cu")
			(hatch none 0.5)
			(connect_pads
				(clearance 0)
			)
			(min_thickness 0.25)
			(keepout
				(tracks not_allowed)
				(vias allowed)
				(pads allowed)
				(copperpour not_allowed)
				(footprints allowed)
			)
			(placement
				(enabled no)
				(sheetname "")
			)
			(fill
				(thermal_gap 0.5)
				(thermal_bridge_width 0.5)
				(island_removal_mode 0)
			)
			(polygon
				(pts
					(xy 148.93671 -60.551822) (xy 143.100552 -60.551822) (xy 143.100552 -62.300612) (xy 147.18792 -62.300612)
					(xy 147.18792 -66.415412) (xy 143.07312 -66.415412) (xy 143.07312 -60.551822) (xy 141.32433 -60.551822)
					(xy 141.32433 -68.164202) (xy 148.93671 -68.164202)
				)
			)
		)
		(zone
			(layer "F.Cu")
			(hatch none 0.5)
			(connect_pads
				(clearance 0)
			)
			(min_thickness 0.25)
			(keepout
				(tracks allowed)
				(vias not_allowed)
				(pads allowed)
				(copperpour not_allowed)
				(footprints allowed)
			)
			(placement
				(enabled no)
				(sheetname "")
			)
			(fill
				(thermal_gap 0.5)
				(thermal_bridge_width 0.5)
				(island_removal_mode 0)
			)
			(polygon
				(pts
					(xy 148.93671 -60.551822) (xy 143.100552 -60.551822) (xy 143.100552 -62.300612) (xy 147.18792 -62.300612)
					(xy 147.18792 -66.415412) (xy 143.07312 -66.415412) (xy 143.07312 -60.551822) (xy 141.32433 -60.551822)
					(xy 141.32433 -68.164202) (xy 148.93671 -68.164202)
				)
			)
		)
	)
	(footprint ""
		(layer "F.Cu")
		(at 176.267364 -132.622798 -90)
		(property "Reference" "R1131"
			(at 2.232152 -12.395454 90)
			(unlocked yes)
			(layer "F.SilkS")
			(effects
				(font
					(size 0.7874 0.5842)
					(thickness 0.1524)
				)
				(justify left)
			)
		)
		(property "Value" ""
			(at 0 0 270)
			(layer "F.Fab")
			(effects
				(font
					(size 1.27 1.27)
				)
			)
		)
		(duplicate_pad_numbers_are_jumpers no)
		(fp_line
			(start -0.7874 0.4064)
			(end -0.7874 -0.4064)
			(stroke
				(width 0.1524)
				(type default)
			)
			(layer "F.SilkS")
		)
		(fp_line
			(start 0.7874 0.4064)
			(end -0.7874 0.4064)
			(stroke
				(width 0.1524)
				(type default)
			)
			(layer "F.SilkS")
		)
		(fp_line
			(start -0.7874 -0.4064)
			(end 0.7874 -0.4064)
			(stroke
				(width 0.1524)
				(type default)
			)
			(layer "F.SilkS")
		)
		(fp_line
			(start 0.7874 -0.4064)
			(end 0.7874 0.4064)
			(stroke
				(width 0.1524)
				(type default)
			)
			(layer "F.SilkS")
		)
		(fp_poly
			(pts
				(xy -0.508 0.2794) (xy -0.508 0.2286) (xy -0.635 0.2286) (xy -0.635 -0.254) (xy -0.5334 -0.254)
				(xy -0.5334 -0.2794) (xy 0.5334 -0.2794) (xy 0.5334 -0.254) (xy 0.635 -0.254) (xy 0.635 0.254) (xy 0.5334 0.254)
				(xy 0.5334 0.2794)
			)
			(stroke
				(width 0)
				(type default)
			)
			(fill no)
			(layer "F.CrtYd")
		)
		(pad "1" smd rect
			(at 0.40005 0 270)
			(size 0.4572 0.508)
			(layers "F.Cu" "F.Mask" "F.Paste")
			(net "CPLD_CPU_THRMTRIP_N")
		)
		(pad "2" smd rect
			(at -0.40005 0 270)
			(size 0.4572 0.508)
			(layers "F.Cu" "F.Mask" "F.Paste")
			(net "P3V3_STB_NODE1")
		)
	)
	(footprint ""
		(layer "F.Cu")
		(at 34.990786 -175.4505 90)
		(property "Reference" "R106"
			(at -10.50671 -3.513836 90)
			(unlocked yes)
			(layer "F.SilkS")
			(effects
				(font
					(size 0.7874 0.5842)
					(thickness 0.1524)
				)
				(justify left)
			)
		)
		(property "Value" ""
			(at 0 0 90)
			(layer "F.Fab")
			(effects
				(font
					(size 1.27 1.27)
				)
			)
		)
		(duplicate_pad_numbers_are_jumpers no)
		(fp_line
			(start 0.7874 -0.4064)
			(end 0.7874 0.4064)
			(stroke
				(width 0.1524)
				(type default)
			)
			(layer "F.SilkS")
		)
		(fp_line
			(start -0.7874 -0.4064)
			(end 0.7874 -0.4064)
			(stroke
				(width 0.1524)
				(type default)
			)
			(layer "F.SilkS")
		)
		(fp_line
			(start 0.7874 0.4064)
			(end -0.7874 0.4064)
			(stroke
				(width 0.1524)
				(type default)
			)
			(layer "F.SilkS")
		)
		(fp_line
			(start -0.7874 0.4064)
			(end -0.7874 -0.4064)
			(stroke
				(width 0.1524)
				(type default)
			)
			(layer "F.SilkS")
		)
		(fp_poly
			(pts
				(xy -0.508 0.2794) (xy -0.508 0.2286) (xy -0.635 0.2286) (xy -0.635 -0.254) (xy -0.5334 -0.254)
				(xy -0.5334 -0.2794) (xy 0.5334 -0.2794) (xy 0.5334 -0.254) (xy 0.635 -0.254) (xy 0.635 0.254) (xy 0.5334 0.254)
				(xy 0.5334 0.2794)
			)
			(stroke
				(width 0)
				(type default)
			)
			(fill no)
			(layer "F.CrtYd")
		)
		(pad "1" smd rect
			(at 0.40005 0 90)
			(size 0.4572 0.508)
			(layers "F.Cu" "F.Mask" "F.Paste")
			(net "SMB_BMC_NODE1_HSC_ALERT_R_L")
		)
		(pad "2" smd rect
			(at -0.40005 0 90)
			(size 0.4572 0.508)
			(layers "F.Cu" "F.Mask" "F.Paste")
			(net "SMB_BMC_NODE1_HSC_ALERT_L")
		)
	)
	(footprint ""
		(layer "F.Cu")
		(at 56.884062 -118.971568 -90)
		(property "Reference" "R344"
			(at 5.201412 -1.117092 90)
			(unlocked yes)
			(layer "F.SilkS")
			(effects
				(font
					(size 0.7874 0.5842)
					(thickness 0.1524)
				)
				(justify left)
			)
		)
		(property "Value" ""
			(at 0 0 270)
			(layer "F.Fab")
			(effects
				(font
					(size 1.27 1.27)
				)
			)
		)
		(duplicate_pad_numbers_are_jumpers no)
		(fp_line
			(start -0.7874 0.4064)
			(end -0.7874 -0.4064)
			(stroke
				(width 0.1524)
				(type default)
			)
			(layer "F.SilkS")
		)
		(fp_line
			(start 0.7874 0.4064)
			(end -0.7874 0.4064)
			(stroke
				(width 0.1524)
				(type default)
			)
			(layer "F.SilkS")
		)
		(fp_line
			(start -0.7874 -0.4064)
			(end 0.7874 -0.4064)
			(stroke
				(width 0.1524)
				(type default)
			)
			(layer "F.SilkS")
		)
		(fp_line
			(start 0.7874 -0.4064)
			(end 0.7874 0.4064)
			(stroke
				(width 0.1524)
				(type default)
			)
			(layer "F.SilkS")
		)
		(fp_poly
			(pts
				(xy -0.508 0.2794) (xy -0.508 0.2286) (xy -0.635 0.2286) (xy -0.635 -0.254) (xy -0.5334 -0.254)
				(xy -0.5334 -0.2794) (xy 0.5334 -0.2794) (xy 0.5334 -0.254) (xy 0.635 -0.254) (xy 0.635 0.254) (xy 0.5334 0.254)
				(xy 0.5334 0.2794)
			)
			(stroke
				(width 0)
				(type default)
			)
			(fill no)
			(layer "F.CrtYd")
		)
		(pad "1" smd rect
			(at 0.40005 0 270)
			(size 0.4572 0.508)
			(layers "F.Cu" "F.Mask" "F.Paste")
			(net "P3V3_NODE1")
		)
		(pad "2" smd rect
			(at -0.40005 0 270)
			(size 0.4572 0.508)
			(layers "F.Cu" "F.Mask" "F.Paste")
			(net "BMC_ROMD4")
		)
	)
	(footprint ""
		(layer "F.Cu")
		(at 114.13109 -63.348616 180)
		(property "Reference" "C183"
			(at -1.060196 -1.891792 0)
			(unlocked yes)
			(layer "F.SilkS")
			(effects
				(font
					(size 0.7874 0.5842)
					(thickness 0.1524)
				)
				(justify left)
			)
		)
		(property "Value" ""
			(at 0 0 180)
			(layer "F.Fab")
			(effects
				(font
					(size 1.27 1.27)
				)
			)
		)
		(duplicate_pad_numbers_are_jumpers no)
		(fp_line
			(start 0.7874 0.4064)
			(end -0.7874 0.4064)
			(stroke
				(width 0.1524)
				(type default)
			)
			(layer "F.SilkS")
		)
		(fp_line
			(start 0.7874 -0.4064)
			(end 0.7874 0.4064)
			(stroke
				(width 0.1524)
				(type default)
			)
			(layer "F.SilkS")
		)
		(fp_line
			(start 0 0.381)
			(end 0 -0.381)
			(stroke
				(width 0.1524)
				(type default)
			)
			(layer "F.SilkS")
		)
		(fp_line
			(start -0.7874 0.4064)
			(end -0.7874 -0.4064)
			(stroke
				(width 0.1524)
				(type default)
			)
			(layer "F.SilkS")
		)
		(fp_line
			(start -0.7874 -0.4064)
			(end 0.7874 -0.4064)
			(stroke
				(width 0.1524)
				(type default)
			)
			(layer "F.SilkS")
		)
		(fp_poly
			(pts
				(xy -0.5334 0.254) (xy -0.635 0.254) (xy -0.635 0.2286) (xy -0.635 -0.254) (xy -0.5334 -0.254) (xy -0.5334 -0.2794)
				(xy 0.5334 -0.2794) (xy 0.5334 -0.254) (xy 0.635 -0.254) (xy 0.635 0.254) (xy 0.5334 0.254) (xy 0.5334 0.2794)
				(xy -0.508 0.2794) (xy -0.5334 0.2794)
			)
			(stroke
				(width 0)
				(type default)
			)
			(fill no)
			(layer "F.CrtYd")
		)
		(pad "1" smd rect
			(at 0.40005 0 180)
			(size 0.4572 0.508)
			(layers "F.Cu" "F.Mask" "F.Paste")
			(net "RST_NODE1_CPU_XDP_RSTIN_L")
		)
		(pad "2" smd rect
			(at -0.40005 0 180)
			(size 0.4572 0.508)
			(layers "F.Cu" "F.Mask" "F.Paste")
			(net "GND")
		)
	)
	(footprint ""
		(layer "F.Cu")
		(at 81.06029 -151.304498 90)
		(property "Reference" "R1083"
			(at -2.23393 -0.85979 0)
			(unlocked yes)
			(layer "F.SilkS")
			(effects
				(font
					(size 0.7874 0.5842)
					(thickness 0.1524)
				)
				(justify left)
			)
		)
		(property "Value" ""
			(at 0 0 90)
			(layer "F.Fab")
			(effects
				(font
					(size 1.27 1.27)
				)
			)
		)
		(duplicate_pad_numbers_are_jumpers no)
		(fp_line
			(start 0.7874 -0.4064)
			(end 0.7874 0.4064)
			(stroke
				(width 0.1524)
				(type default)
			)
			(layer "F.SilkS")
		)
		(fp_line
			(start -0.7874 -0.4064)
			(end 0.7874 -0.4064)
			(stroke
				(width 0.1524)
				(type default)
			)
			(layer "F.SilkS")
		)
		(fp_line
			(start 0.7874 0.4064)
			(end -0.7874 0.4064)
			(stroke
				(width 0.1524)
				(type default)
			)
			(layer "F.SilkS")
		)
		(fp_line
			(start -0.7874 0.4064)
			(end -0.7874 -0.4064)
			(stroke
				(width 0.1524)
				(type default)
			)
			(layer "F.SilkS")
		)
		(fp_poly
			(pts
				(xy -0.508 0.2794) (xy -0.508 0.2286) (xy -0.635 0.2286) (xy -0.635 -0.254) (xy -0.5334 -0.254)
				(xy -0.5334 -0.2794) (xy 0.5334 -0.2794) (xy 0.5334 -0.254) (xy 0.635 -0.254) (xy 0.635 0.254) (xy 0.5334 0.254)
				(xy 0.5334 0.2794)
			)
			(stroke
				(width 0)
				(type default)
			)
			(fill no)
			(layer "F.CrtYd")
		)
		(pad "1" smd rect
			(at 0.40005 0 90)
			(size 0.4572 0.508)
			(layers "F.Cu" "F.Mask" "F.Paste")
			(net "P5V_STB_NODE1_EN")
		)
		(pad "2" smd rect
			(at -0.40005 0 90)
			(size 0.4572 0.508)
			(layers "F.Cu" "F.Mask" "F.Paste")
			(net "GND")
		)
	)
	(footprint ""
		(layer "F.Cu")
		(at 106.170476 -169.932858 180)
		(property "Reference" "R761"
			(at -1.206754 -0.161798 0)
			(unlocked yes)
			(layer "F.SilkS")
			(effects
				(font
					(size 0.7874 0.5842)
					(thickness 0.1524)
				)
				(justify left)
			)
		)
		(property "Value" ""
			(at 0 0 180)
			(layer "F.Fab")
			(effects
				(font
					(size 1.27 1.27)
				)
			)
		)
		(duplicate_pad_numbers_are_jumpers no)
		(fp_line
			(start 0.7874 0.4064)
			(end -0.7874 0.4064)
			(stroke
				(width 0.1524)
				(type default)
			)
			(layer "F.SilkS")
		)
		(fp_line
			(start 0.7874 -0.4064)
			(end 0.7874 0.4064)
			(stroke
				(width 0.1524)
				(type default)
			)
			(layer "F.SilkS")
		)
		(fp_line
			(start -0.7874 0.4064)
			(end -0.7874 -0.4064)
			(stroke
				(width 0.1524)
				(type default)
			)
			(layer "F.SilkS")
		)
		(fp_line
			(start -0.7874 -0.4064)
			(end 0.7874 -0.4064)
			(stroke
				(width 0.1524)
				(type default)
			)
			(layer "F.SilkS")
		)
		(fp_poly
			(pts
				(xy -0.508 0.2794) (xy -0.508 0.2286) (xy -0.635 0.2286) (xy -0.635 -0.254) (xy -0.5334 -0.254)
				(xy -0.5334 -0.2794) (xy 0.5334 -0.2794) (xy 0.5334 -0.254) (xy 0.635 -0.254) (xy 0.635 0.254) (xy 0.5334 0.254)
				(xy 0.5334 0.2794)
			)
			(stroke
				(width 0)
				(type default)
			)
			(fill no)
			(layer "F.CrtYd")
		)
		(pad "1" smd rect
			(at 0.40005 0 180)
			(size 0.4572 0.508)
			(layers "F.Cu" "F.Mask" "F.Paste")
			(net "FAN4_TACH_IN")
		)
		(pad "2" smd rect
			(at -0.40005 0 180)
			(size 0.4572 0.508)
			(layers "F.Cu" "F.Mask" "F.Paste")
			(net "FAN4_TACH")
		)
	)
	(footprint ""
		(layer "F.Cu")
		(at 64.628522 -158.423864)
		(property "Reference" "PC132"
			(at -32.07639 -3.594354 0)
			(unlocked yes)
			(layer "F.SilkS")
			(effects
				(font
					(size 0.7874 0.5842)
					(thickness 0.1524)
				)
				(justify left)
			)
		)
		(property "Value" ""
			(at 0 0 0)
			(layer "F.Fab")
			(effects
				(font
					(size 1.27 1.27)
				)
			)
		)
		(duplicate_pad_numbers_are_jumpers no)
		(fp_line
			(start -1.905 -0.8636)
			(end 1.905 -0.8636)
			(stroke
				(width 0.1524)
				(type default)
			)
			(layer "F.SilkS")
		)
		(fp_line
			(start -1.905 0.8636)
			(end -1.905 -0.8636)
			(stroke
				(width 0.1524)
				(type default)
			)
			(layer "F.SilkS")
		)
		(fp_line
			(start 0 0.8382)
			(end 0 -0.8382)
			(stroke
				(width 0.1524)
				(type default)
			)
			(layer "F.SilkS")
		)
		(fp_line
			(start 1.905 -0.8636)
			(end 1.905 0.8636)
			(stroke
				(width 0.1524)
				(type default)
			)
			(layer "F.SilkS")
		)
		(fp_line
			(start 1.905 0.8636)
			(end -1.905 0.8636)
			(stroke
				(width 0.1524)
				(type default)
			)
			(layer "F.SilkS")
		)
		(fp_rect
			(start -1.524 0.7366)
			(end 1.524 -0.7366)
			(stroke
				(width 0)
				(type default)
			)
			(fill no)
			(layer "F.CrtYd")
		)
		(pad "1" smd rect
			(at 0.94996 0)
			(size 1.1176 1.3716)
			(layers "F.Cu" "F.Mask" "F.Paste")
			(net "P5V_STB_NODE1")
		)
		(pad "2" smd rect
			(at -0.94996 0)
			(size 1.1176 1.3716)
			(layers "F.Cu" "F.Mask" "F.Paste")
			(net "GND")
		)
	)
	(footprint ""
		(layer "F.Cu")
		(at 184.3786 -183.8452)
		(property "Reference" "R1319"
			(at 9.398 17.01927 0)
			(unlocked yes)
			(layer "F.SilkS")
			(effects
				(font
					(size 0.7874 0.5842)
					(thickness 0.1524)
				)
				(justify left)
			)
		)
		(property "Value" ""
			(at 0 0 0)
			(layer "F.Fab")
			(effects
				(font
					(size 1.27 1.27)
				)
			)
		)
		(duplicate_pad_numbers_are_jumpers no)
		(fp_line
			(start -0.7874 -0.4064)
			(end 0.7874 -0.4064)
			(stroke
				(width 0.1524)
				(type default)
			)
			(layer "F.SilkS")
		)
		(fp_line
			(start -0.7874 0.4064)
			(end -0.7874 -0.4064)
			(stroke
				(width 0.1524)
				(type default)
			)
			(layer "F.SilkS")
		)
		(fp_line
			(start 0.7874 -0.4064)
			(end 0.7874 0.4064)
			(stroke
				(width 0.1524)
				(type default)
			)
			(layer "F.SilkS")
		)
		(fp_line
			(start 0.7874 0.4064)
			(end -0.7874 0.4064)
			(stroke
				(width 0.1524)
				(type default)
			)
			(layer "F.SilkS")
		)
		(fp_poly
			(pts
				(xy -0.508 0.2794) (xy -0.508 0.2286) (xy -0.635 0.2286) (xy -0.635 -0.254) (xy -0.5334 -0.254)
				(xy -0.5334 -0.2794) (xy 0.5334 -0.2794) (xy 0.5334 -0.254) (xy 0.635 -0.254) (xy 0.635 0.254) (xy 0.5334 0.254)
				(xy 0.5334 0.2794)
			)
			(stroke
				(width 0)
				(type default)
			)
			(fill no)
			(layer "F.CrtYd")
		)
		(pad "1" smd rect
			(at 0.40005 0)
			(size 0.4572 0.508)
			(layers "F.Cu" "F.Mask" "F.Paste")
			(net "POWER_SW3_PWR_CTR_12V")
		)
		(pad "2" smd rect
			(at -0.40005 0)
			(size 0.4572 0.508)
			(layers "F.Cu" "F.Mask" "F.Paste")
			(net "POWER_SW3_PWR_CTR_12V_R")
		)
	)
	(footprint ""
		(layer "F.Cu")
		(at 82.7278 -85.439504 -90)
		(property "Reference" "C25"
			(at 17.558512 -1.900174 90)
			(unlocked yes)
			(layer "F.SilkS")
			(effects
				(font
					(size 0.7874 0.5842)
					(thickness 0.1524)
				)
				(justify left)
			)
		)
		(property "Value" ""
			(at 0 0 270)
			(layer "F.Fab")
			(effects
				(font
					(size 1.27 1.27)
				)
			)
		)
		(duplicate_pad_numbers_are_jumpers no)
		(fp_line
			(start -0.7874 0.4064)
			(end -0.7874 -0.4064)
			(stroke
				(width 0.1524)
				(type default)
			)
			(layer "F.SilkS")
		)
		(fp_line
			(start 0.7874 0.4064)
			(end -0.7874 0.4064)
			(stroke
				(width 0.1524)
				(type default)
			)
			(layer "F.SilkS")
		)
		(fp_line
			(start 0 0.381)
			(end 0 -0.381)
			(stroke
				(width 0.1524)
				(type default)
			)
			(layer "F.SilkS")
		)
		(fp_line
			(start -0.7874 -0.4064)
			(end 0.7874 -0.4064)
			(stroke
				(width 0.1524)
				(type default)
			)
			(layer "F.SilkS")
		)
		(fp_line
			(start 0.7874 -0.4064)
			(end 0.7874 0.4064)
			(stroke
				(width 0.1524)
				(type default)
			)
			(layer "F.SilkS")
		)
		(fp_poly
			(pts
				(xy -0.5334 0.254) (xy -0.635 0.254) (xy -0.635 0.2286) (xy -0.635 -0.254) (xy -0.5334 -0.254) (xy -0.5334 -0.2794)
				(xy 0.5334 -0.2794) (xy 0.5334 -0.254) (xy 0.635 -0.254) (xy 0.635 0.254) (xy 0.5334 0.254) (xy 0.5334 0.2794)
				(xy -0.508 0.2794) (xy -0.5334 0.2794)
			)
			(stroke
				(width 0)
				(type default)
			)
			(fill no)
			(layer "F.CrtYd")
		)
		(pad "1" smd rect
			(at 0.40005 0 270)
			(size 0.4572 0.508)
			(layers "F.Cu" "F.Mask" "F.Paste")
			(net "XTAL_CPU_NODE1_X2PAD")
		)
		(pad "2" smd rect
			(at -0.40005 0 270)
			(size 0.4572 0.508)
			(layers "F.Cu" "F.Mask" "F.Paste")
			(net "GND")
		)
	)
	(footprint ""
		(layer "F.Cu")
		(at 94.451932 -170.219624)
		(property "Reference" "R756"
			(at 86.67369 74.174096 0)
			(unlocked yes)
			(layer "F.SilkS")
			(effects
				(font
					(size 0.7874 0.5842)
					(thickness 0.1524)
				)
				(justify left)
			)
		)
		(property "Value" ""
			(at 0 0 0)
			(layer "F.Fab")
			(effects
				(font
					(size 1.27 1.27)
				)
			)
		)
		(duplicate_pad_numbers_are_jumpers no)
		(fp_line
			(start -0.7874 -0.4064)
			(end 0.7874 -0.4064)
			(stroke
				(width 0.1524)
				(type default)
			)
			(layer "F.SilkS")
		)
		(fp_line
			(start -0.7874 0.4064)
			(end -0.7874 -0.4064)
			(stroke
				(width 0.1524)
				(type default)
			)
			(layer "F.SilkS")
		)
		(fp_line
			(start 0.7874 -0.4064)
			(end 0.7874 0.4064)
			(stroke
				(width 0.1524)
				(type default)
			)
			(layer "F.SilkS")
		)
		(fp_line
			(start 0.7874 0.4064)
			(end -0.7874 0.4064)
			(stroke
				(width 0.1524)
				(type default)
			)
			(layer "F.SilkS")
		)
		(fp_poly
			(pts
				(xy -0.508 0.2794) (xy -0.508 0.2286) (xy -0.635 0.2286) (xy -0.635 -0.254) (xy -0.5334 -0.254)
				(xy -0.5334 -0.2794) (xy 0.5334 -0.2794) (xy 0.5334 -0.254) (xy 0.635 -0.254) (xy 0.635 0.254) (xy 0.5334 0.254)
				(xy 0.5334 0.2794)
			)
			(stroke
				(width 0)
				(type default)
			)
			(fill no)
			(layer "F.CrtYd")
		)
		(pad "1" smd rect
			(at 0.40005 0)
			(size 0.4572 0.508)
			(layers "F.Cu" "F.Mask" "F.Paste")
			(net "FAN1_TACH_IN")
		)
		(pad "2" smd rect
			(at -0.40005 0)
			(size 0.4572 0.508)
			(layers "F.Cu" "F.Mask" "F.Paste")
			(net "FAN1_TACH")
		)
	)
	(footprint ""
		(layer "F.Cu")
		(at 55.10276 -188.126624 90)
		(property "Reference" "C589"
			(at 4.548886 0.349758 90)
			(unlocked yes)
			(layer "F.SilkS")
			(effects
				(font
					(size 0.7874 0.5842)
					(thickness 0.1524)
				)
				(justify left)
			)
		)
		(property "Value" ""
			(at 0 0 90)
			(layer "F.Fab")
			(effects
				(font
					(size 1.27 1.27)
				)
			)
		)
		(duplicate_pad_numbers_are_jumpers no)
		(fp_line
			(start 0.7874 -0.4064)
			(end 0.7874 0.4064)
			(stroke
				(width 0.1524)
				(type default)
			)
			(layer "F.SilkS")
		)
		(fp_line
			(start -0.7874 -0.4064)
			(end 0.7874 -0.4064)
			(stroke
				(width 0.1524)
				(type default)
			)
			(layer "F.SilkS")
		)
		(fp_line
			(start 0 0.381)
			(end 0 -0.381)
			(stroke
				(width 0.1524)
				(type default)
			)
			(layer "F.SilkS")
		)
		(fp_line
			(start 0.7874 0.4064)
			(end -0.7874 0.4064)
			(stroke
				(width 0.1524)
				(type default)
			)
			(layer "F.SilkS")
		)
		(fp_line
			(start -0.7874 0.4064)
			(end -0.7874 -0.4064)
			(stroke
				(width 0.1524)
				(type default)
			)
			(layer "F.SilkS")
		)
		(fp_poly
			(pts
				(xy -0.5334 0.254) (xy -0.635 0.254) (xy -0.635 0.2286) (xy -0.635 -0.254) (xy -0.5334 -0.254) (xy -0.5334 -0.2794)
				(xy 0.5334 -0.2794) (xy 0.5334 -0.254) (xy 0.635 -0.254) (xy 0.635 0.254) (xy 0.5334 0.254) (xy 0.5334 0.2794)
				(xy -0.508 0.2794) (xy -0.5334 0.2794)
			)
			(stroke
				(width 0)
				(type default)
			)
			(fill no)
			(layer "F.CrtYd")
		)
		(pad "1" smd rect
			(at 0.40005 0 90)
			(size 0.4572 0.508)
			(layers "F.Cu" "F.Mask" "F.Paste")
			(net "I2C_PSU1_R_SCL")
		)
		(pad "2" smd rect
			(at -0.40005 0 90)
			(size 0.4572 0.508)
			(layers "F.Cu" "F.Mask" "F.Paste")
			(net "GND")
		)
	)
	(footprint ""
		(layer "F.Cu")
		(at 18.78584 -140.454888)
		(property "Reference" "C393"
			(at -5.1054 0.08382 0)
			(unlocked yes)
			(layer "F.SilkS")
			(effects
				(font
					(size 0.7874 0.5842)
					(thickness 0.1524)
				)
				(justify left)
			)
		)
		(property "Value" ""
			(at 0 0 0)
			(layer "F.Fab")
			(effects
				(font
					(size 1.27 1.27)
				)
			)
		)
		(duplicate_pad_numbers_are_jumpers no)
		(fp_line
			(start -1.905 -0.8636)
			(end 1.905 -0.8636)
			(stroke
				(width 0.1524)
				(type default)
			)
			(layer "F.SilkS")
		)
		(fp_line
			(start -1.905 0.8636)
			(end -1.905 -0.8636)
			(stroke
				(width 0.1524)
				(type default)
			)
			(layer "F.SilkS")
		)
		(fp_line
			(start 0 0.8382)
			(end 0 -0.8382)
			(stroke
				(width 0.1524)
				(type default)
			)
			(layer "F.SilkS")
		)
		(fp_line
			(start 1.905 -0.8636)
			(end 1.905 0.8636)
			(stroke
				(width 0.1524)
				(type default)
			)
			(layer "F.SilkS")
		)
		(fp_line
			(start 1.905 0.8636)
			(end -1.905 0.8636)
			(stroke
				(width 0.1524)
				(type default)
			)
			(layer "F.SilkS")
		)
		(fp_rect
			(start -1.524 0.7366)
			(end 1.524 -0.7366)
			(stroke
				(width 0)
				(type default)
			)
			(fill no)
			(layer "F.CrtYd")
		)
		(pad "1" smd rect
			(at 0.94996 0)
			(size 1.1176 1.3716)
			(layers "F.Cu" "F.Mask" "F.Paste")
			(net "P3V3_NODE1")
		)
		(pad "2" smd rect
			(at -0.94996 0)
			(size 1.1176 1.3716)
			(layers "F.Cu" "F.Mask" "F.Paste")
			(net "GND")
		)
	)
	(footprint ""
		(layer "F.Cu")
		(at 156.828998 -142.93723 -90)
		(property "Reference" "R571"
			(at -1.23063 -0.30607 90)
			(unlocked yes)
			(layer "F.SilkS")
			(effects
				(font
					(size 0.7874 0.5842)
					(thickness 0.1524)
				)
				(justify left)
			)
		)
		(property "Value" ""
			(at 0 0 270)
			(layer "F.Fab")
			(effects
				(font
					(size 1.27 1.27)
				)
			)
		)
		(duplicate_pad_numbers_are_jumpers no)
		(fp_line
			(start -0.7874 0.4064)
			(end -0.7874 -0.4064)
			(stroke
				(width 0.1524)
				(type default)
			)
			(layer "F.SilkS")
		)
		(fp_line
			(start 0.7874 0.4064)
			(end -0.7874 0.4064)
			(stroke
				(width 0.1524)
				(type default)
			)
			(layer "F.SilkS")
		)
		(fp_line
			(start -0.7874 -0.4064)
			(end 0.7874 -0.4064)
			(stroke
				(width 0.1524)
				(type default)
			)
			(layer "F.SilkS")
		)
		(fp_line
			(start 0.7874 -0.4064)
			(end 0.7874 0.4064)
			(stroke
				(width 0.1524)
				(type default)
			)
			(layer "F.SilkS")
		)
		(fp_poly
			(pts
				(xy -0.508 0.2794) (xy -0.508 0.2286) (xy -0.635 0.2286) (xy -0.635 -0.254) (xy -0.5334 -0.254)
				(xy -0.5334 -0.2794) (xy 0.5334 -0.2794) (xy 0.5334 -0.254) (xy 0.635 -0.254) (xy 0.635 0.254) (xy 0.5334 0.254)
				(xy 0.5334 0.2794)
			)
			(stroke
				(width 0)
				(type default)
			)
			(fill no)
			(layer "F.CrtYd")
		)
		(pad "1" smd rect
			(at 0.40005 0 270)
			(size 0.4572 0.508)
			(layers "F.Cu" "F.Mask" "F.Paste")
			(net "P3V3_NODE1")
		)
		(pad "2" smd rect
			(at -0.40005 0 270)
			(size 0.4572 0.508)
			(layers "F.Cu" "F.Mask" "F.Paste")
			(net "LAN2_AUX_PWR")
		)
	)
	(footprint ""
		(layer "F.Cu")
		(at 35.268662 -184.193942)
		(property "Reference" "C777"
			(at -1.557274 -5.586222 0)
			(unlocked yes)
			(layer "F.SilkS")
			(effects
				(font
					(size 0.7874 0.5842)
					(thickness 0.1524)
				)
				(justify left)
			)
		)
		(property "Value" ""
			(at 0 0 0)
			(layer "F.Fab")
			(effects
				(font
					(size 1.27 1.27)
				)
			)
		)
		(duplicate_pad_numbers_are_jumpers no)
		(fp_line
			(start -0.7874 -0.4064)
			(end 0.7874 -0.4064)
			(stroke
				(width 0.1524)
				(type default)
			)
			(layer "F.SilkS")
		)
		(fp_line
			(start -0.7874 0.4064)
			(end -0.7874 -0.4064)
			(stroke
				(width 0.1524)
				(type default)
			)
			(layer "F.SilkS")
		)
		(fp_line
			(start 0 0.381)
			(end 0 -0.381)
			(stroke
				(width 0.1524)
				(type default)
			)
			(layer "F.SilkS")
		)
		(fp_line
			(start 0.7874 -0.4064)
			(end 0.7874 0.4064)
			(stroke
				(width 0.1524)
				(type default)
			)
			(layer "F.SilkS")
		)
		(fp_line
			(start 0.7874 0.4064)
			(end -0.7874 0.4064)
			(stroke
				(width 0.1524)
				(type default)
			)
			(layer "F.SilkS")
		)
		(fp_poly
			(pts
				(xy -0.5334 0.254) (xy -0.635 0.254) (xy -0.635 0.2286) (xy -0.635 -0.254) (xy -0.5334 -0.254) (xy -0.5334 -0.2794)
				(xy 0.5334 -0.2794) (xy 0.5334 -0.254) (xy 0.635 -0.254) (xy 0.635 0.254) (xy 0.5334 0.254) (xy 0.5334 0.2794)
				(xy -0.508 0.2794) (xy -0.5334 0.2794)
			)
			(stroke
				(width 0)
				(type default)
			)
			(fill no)
			(layer "F.CrtYd")
		)
		(pad "1" smd rect
			(at 0.40005 0)
			(size 0.4572 0.508)
			(layers "F.Cu" "F.Mask" "F.Paste")
			(net "P12V_PDB")
		)
		(pad "2" smd rect
			(at -0.40005 0)
			(size 0.4572 0.508)
			(layers "F.Cu" "F.Mask" "F.Paste")
			(net "GND")
		)
	)
	(footprint ""
		(layer "F.Cu")
		(at 133.08076 -185.205624 90)
		(property "Reference" "C749"
			(at 4.510786 -0.278638 90)
			(unlocked yes)
			(layer "F.SilkS")
			(effects
				(font
					(size 0.7874 0.5842)
					(thickness 0.1524)
				)
				(justify left)
			)
		)
		(property "Value" ""
			(at 0 0 90)
			(layer "F.Fab")
			(effects
				(font
					(size 1.27 1.27)
				)
			)
		)
		(duplicate_pad_numbers_are_jumpers no)
		(fp_line
			(start 0.7874 -0.4064)
			(end 0.7874 0.4064)
			(stroke
				(width 0.1524)
				(type default)
			)
			(layer "F.SilkS")
		)
		(fp_line
			(start -0.7874 -0.4064)
			(end 0.7874 -0.4064)
			(stroke
				(width 0.1524)
				(type default)
			)
			(layer "F.SilkS")
		)
		(fp_line
			(start 0 0.381)
			(end 0 -0.381)
			(stroke
				(width 0.1524)
				(type default)
			)
			(layer "F.SilkS")
		)
		(fp_line
			(start 0.7874 0.4064)
			(end -0.7874 0.4064)
			(stroke
				(width 0.1524)
				(type default)
			)
			(layer "F.SilkS")
		)
		(fp_line
			(start -0.7874 0.4064)
			(end -0.7874 -0.4064)
			(stroke
				(width 0.1524)
				(type default)
			)
			(layer "F.SilkS")
		)
		(fp_poly
			(pts
				(xy -0.5334 0.254) (xy -0.635 0.254) (xy -0.635 0.2286) (xy -0.635 -0.254) (xy -0.5334 -0.254) (xy -0.5334 -0.2794)
				(xy 0.5334 -0.2794) (xy 0.5334 -0.254) (xy 0.635 -0.254) (xy 0.635 0.254) (xy 0.5334 0.254) (xy 0.5334 0.2794)
				(xy -0.508 0.2794) (xy -0.5334 0.2794)
			)
			(stroke
				(width 0)
				(type default)
			)
			(fill no)
			(layer "F.CrtYd")
		)
		(pad "1" smd rect
			(at 0.40005 0 90)
			(size 0.4572 0.508)
			(layers "F.Cu" "F.Mask" "F.Paste")
			(net "UART_T10_NODE2_RXD")
		)
		(pad "2" smd rect
			(at -0.40005 0 90)
			(size 0.4572 0.508)
			(layers "F.Cu" "F.Mask" "F.Paste")
			(net "GND")
		)
	)
	(footprint ""
		(layer "F.Cu")
		(at 143.345916 -72.314308 -90)
		(property "Reference" "R513"
			(at 1.013714 -1.270254 90)
			(unlocked yes)
			(layer "F.SilkS")
			(effects
				(font
					(size 0.7874 0.5842)
					(thickness 0.1524)
				)
				(justify left)
			)
		)
		(property "Value" ""
			(at 0 0 270)
			(layer "F.Fab")
			(effects
				(font
					(size 1.27 1.27)
				)
			)
		)
		(duplicate_pad_numbers_are_jumpers no)
		(fp_line
			(start -0.7874 0.4064)
			(end -0.7874 -0.4064)
			(stroke
				(width 0.1524)
				(type default)
			)
			(layer "F.SilkS")
		)
		(fp_line
			(start 0.7874 0.4064)
			(end -0.7874 0.4064)
			(stroke
				(width 0.1524)
				(type default)
			)
			(layer "F.SilkS")
		)
		(fp_line
			(start -0.7874 -0.4064)
			(end 0.7874 -0.4064)
			(stroke
				(width 0.1524)
				(type default)
			)
			(layer "F.SilkS")
		)
		(fp_line
			(start 0.7874 -0.4064)
			(end 0.7874 0.4064)
			(stroke
				(width 0.1524)
				(type default)
			)
			(layer "F.SilkS")
		)
		(fp_poly
			(pts
				(xy -0.508 0.2794) (xy -0.508 0.2286) (xy -0.635 0.2286) (xy -0.635 -0.254) (xy -0.5334 -0.254)
				(xy -0.5334 -0.2794) (xy 0.5334 -0.2794) (xy 0.5334 -0.254) (xy 0.635 -0.254) (xy 0.635 0.254) (xy 0.5334 0.254)
				(xy 0.5334 0.2794)
			)
			(stroke
				(width 0)
				(type default)
			)
			(fill no)
			(layer "F.CrtYd")
		)
		(pad "1" smd rect
			(at 0.40005 0 270)
			(size 0.4572 0.508)
			(layers "F.Cu" "F.Mask" "F.Paste")
			(net "IRQ_LVC3_SATA_NODE1_WAKE_L")
		)
		(pad "2" smd rect
			(at -0.40005 0 270)
			(size 0.4572 0.508)
			(layers "F.Cu" "F.Mask" "F.Paste")
			(net "IRQ_LVC3_CPU_NODE1_WAKE_L")
		)
	)
	(footprint ""
		(layer "F.Cu")
		(at 114.621818 -136.67359)
		(property "Reference" "PC110"
			(at 3.165602 -4.479798 0)
			(unlocked yes)
			(layer "F.SilkS")
			(effects
				(font
					(size 0.635 0.4064)
					(thickness 0.1524)
				)
				(justify left)
			)
		)
		(property "Value" ""
			(at 0 0 0)
			(layer "F.Fab")
			(effects
				(font
					(size 1.27 1.27)
				)
			)
		)
		(duplicate_pad_numbers_are_jumpers no)
		(fp_line
			(start -0.7874 -0.4064)
			(end 0.7874 -0.4064)
			(stroke
				(width 0.1524)
				(type default)
			)
			(layer "F.SilkS")
		)
		(fp_line
			(start -0.7874 0.4064)
			(end -0.7874 -0.4064)
			(stroke
				(width 0.1524)
				(type default)
			)
			(layer "F.SilkS")
		)
		(fp_line
			(start 0 0.381)
			(end 0 -0.381)
			(stroke
				(width 0.1524)
				(type default)
			)
			(layer "F.SilkS")
		)
		(fp_line
			(start 0.7874 -0.4064)
			(end 0.7874 0.4064)
			(stroke
				(width 0.1524)
				(type default)
			)
			(layer "F.SilkS")
		)
		(fp_line
			(start 0.7874 0.4064)
			(end -0.7874 0.4064)
			(stroke
				(width 0.1524)
				(type default)
			)
			(layer "F.SilkS")
		)
		(fp_poly
			(pts
				(xy -0.5334 0.254) (xy -0.635 0.254) (xy -0.635 0.2286) (xy -0.635 -0.254) (xy -0.5334 -0.254) (xy -0.5334 -0.2794)
				(xy 0.5334 -0.2794) (xy 0.5334 -0.254) (xy 0.635 -0.254) (xy 0.635 0.254) (xy 0.5334 0.254) (xy 0.5334 0.2794)
				(xy -0.508 0.2794) (xy -0.5334 0.2794)
			)
			(stroke
				(width 0)
				(type default)
			)
			(fill no)
			(layer "F.CrtYd")
		)
		(pad "1" smd rect
			(at 0.40005 0)
			(size 0.4572 0.508)
			(layers "F.Cu" "F.Mask" "F.Paste")
			(net "AGND_PVCCP_NODE1")
		)
		(pad "2" smd rect
			(at -0.40005 0)
			(size 0.4572 0.508)
			(layers "F.Cu" "F.Mask" "F.Paste")
			(net "VR_PVCCP_NODE1_FB")
		)
	)
	(footprint ""
		(layer "F.Cu")
		(at 80.907128 -140.255752)
		(property "Reference" "C839"
			(at -2.426208 3.661918 0)
			(unlocked yes)
			(layer "F.SilkS")
			(effects
				(font
					(size 0.635 0.4064)
					(thickness 0.1524)
				)
				(justify left)
			)
		)
		(property "Value" ""
			(at 0 0 0)
			(layer "F.Fab")
			(effects
				(font
					(size 1.27 1.27)
				)
			)
		)
		(duplicate_pad_numbers_are_jumpers no)
		(fp_line
			(start -0.7874 -0.4064)
			(end 0.7874 -0.4064)
			(stroke
				(width 0.1524)
				(type default)
			)
			(layer "F.SilkS")
		)
		(fp_line
			(start -0.7874 0.4064)
			(end -0.7874 -0.4064)
			(stroke
				(width 0.1524)
				(type default)
			)
			(layer "F.SilkS")
		)
		(fp_line
			(start 0 0.381)
			(end 0 -0.381)
			(stroke
				(width 0.1524)
				(type default)
			)
			(layer "F.SilkS")
		)
		(fp_line
			(start 0.7874 -0.4064)
			(end 0.7874 0.4064)
			(stroke
				(width 0.1524)
				(type default)
			)
			(layer "F.SilkS")
		)
		(fp_line
			(start 0.7874 0.4064)
			(end -0.7874 0.4064)
			(stroke
				(width 0.1524)
				(type default)
			)
			(layer "F.SilkS")
		)
		(fp_poly
			(pts
				(xy -0.5334 0.254) (xy -0.635 0.254) (xy -0.635 0.2286) (xy -0.635 -0.254) (xy -0.5334 -0.254) (xy -0.5334 -0.2794)
				(xy 0.5334 -0.2794) (xy 0.5334 -0.254) (xy 0.635 -0.254) (xy 0.635 0.254) (xy 0.5334 0.254) (xy 0.5334 0.2794)
				(xy -0.508 0.2794) (xy -0.5334 0.2794)
			)
			(stroke
				(width 0)
				(type default)
			)
			(fill no)
			(layer "F.CrtYd")
		)
		(pad "1" smd rect
			(at 0.40005 0)
			(size 0.4572 0.508)
			(layers "F.Cu" "F.Mask" "F.Paste")
			(net "P1V26_BMC_NODE1")
		)
		(pad "2" smd rect
			(at -0.40005 0)
			(size 0.4572 0.508)
			(layers "F.Cu" "F.Mask" "F.Paste")
			(net "GND")
		)
	)
	(footprint ""
		(layer "F.Cu")
		(at 125.735588 -180.487828 180)
		(property "Reference" "R722"
			(at -1.39446 0.675132 0)
			(unlocked yes)
			(layer "F.SilkS")
			(effects
				(font
					(size 0.7874 0.5842)
					(thickness 0.1524)
				)
				(justify left)
			)
		)
		(property "Value" ""
			(at 0 0 180)
			(layer "F.Fab")
			(effects
				(font
					(size 1.27 1.27)
				)
			)
		)
		(duplicate_pad_numbers_are_jumpers no)
		(fp_line
			(start 0.7874 0.4064)
			(end -0.7874 0.4064)
			(stroke
				(width 0.1524)
				(type default)
			)
			(layer "F.SilkS")
		)
		(fp_line
			(start 0.7874 -0.4064)
			(end 0.7874 0.4064)
			(stroke
				(width 0.1524)
				(type default)
			)
			(layer "F.SilkS")
		)
		(fp_line
			(start -0.7874 0.4064)
			(end -0.7874 -0.4064)
			(stroke
				(width 0.1524)
				(type default)
			)
			(layer "F.SilkS")
		)
		(fp_line
			(start -0.7874 -0.4064)
			(end 0.7874 -0.4064)
			(stroke
				(width 0.1524)
				(type default)
			)
			(layer "F.SilkS")
		)
		(fp_poly
			(pts
				(xy -0.508 0.2794) (xy -0.508 0.2286) (xy -0.635 0.2286) (xy -0.635 -0.254) (xy -0.5334 -0.254)
				(xy -0.5334 -0.2794) (xy 0.5334 -0.2794) (xy 0.5334 -0.254) (xy 0.635 -0.254) (xy 0.635 0.254) (xy 0.5334 0.254)
				(xy 0.5334 0.2794)
			)
			(stroke
				(width 0)
				(type default)
			)
			(fill no)
			(layer "F.CrtYd")
		)
		(pad "1" smd rect
			(at 0.40005 0 180)
			(size 0.4572 0.508)
			(layers "F.Cu" "F.Mask" "F.Paste")
			(net "T7_NODE3_EN")
		)
		(pad "2" smd rect
			(at -0.40005 0 180)
			(size 0.4572 0.508)
			(layers "F.Cu" "F.Mask" "F.Paste")
			(net "P5V_NODE1")
		)
	)
	(footprint ""
		(layer "F.Cu")
		(at 79.91856 -80.683608 -90)
		(property "Reference" "C70"
			(at 17.592294 -1.189482 90)
			(unlocked yes)
			(layer "F.SilkS")
			(effects
				(font
					(size 0.7874 0.5842)
					(thickness 0.1524)
				)
				(justify left)
			)
		)
		(property "Value" ""
			(at 0 0 270)
			(layer "F.Fab")
			(effects
				(font
					(size 1.27 1.27)
				)
			)
		)
		(duplicate_pad_numbers_are_jumpers no)
		(fp_line
			(start -0.7874 0.4064)
			(end -0.7874 -0.4064)
			(stroke
				(width 0.1524)
				(type default)
			)
			(layer "F.SilkS")
		)
		(fp_line
			(start 0.7874 0.4064)
			(end -0.7874 0.4064)
			(stroke
				(width 0.1524)
				(type default)
			)
			(layer "F.SilkS")
		)
		(fp_line
			(start 0 0.381)
			(end 0 -0.381)
			(stroke
				(width 0.1524)
				(type default)
			)
			(layer "F.SilkS")
		)
		(fp_line
			(start -0.7874 -0.4064)
			(end 0.7874 -0.4064)
			(stroke
				(width 0.1524)
				(type default)
			)
			(layer "F.SilkS")
		)
		(fp_line
			(start 0.7874 -0.4064)
			(end 0.7874 0.4064)
			(stroke
				(width 0.1524)
				(type default)
			)
			(layer "F.SilkS")
		)
		(fp_poly
			(pts
				(xy -0.5334 0.254) (xy -0.635 0.254) (xy -0.635 0.2286) (xy -0.635 -0.254) (xy -0.5334 -0.254) (xy -0.5334 -0.2794)
				(xy 0.5334 -0.2794) (xy 0.5334 -0.254) (xy 0.635 -0.254) (xy 0.635 0.254) (xy 0.5334 0.254) (xy 0.5334 0.2794)
				(xy -0.508 0.2794) (xy -0.5334 0.2794)
			)
			(stroke
				(width 0)
				(type default)
			)
			(fill no)
			(layer "F.CrtYd")
		)
		(pad "1" smd rect
			(at 0.40005 0 270)
			(size 0.4572 0.508)
			(layers "F.Cu" "F.Mask" "F.Paste")
			(net "PV_VCCP_NODE1")
		)
		(pad "2" smd rect
			(at -0.40005 0 270)
			(size 0.4572 0.508)
			(layers "F.Cu" "F.Mask" "F.Paste")
			(net "GND")
		)
	)
	(footprint ""
		(layer "F.Cu")
		(at 74.53376 -188.126624 90)
		(property "Reference" "C704"
			(at 4.548886 -1.165098 90)
			(unlocked yes)
			(layer "F.SilkS")
			(effects
				(font
					(size 0.7874 0.5842)
					(thickness 0.1524)
				)
				(justify left)
			)
		)
		(property "Value" ""
			(at 0 0 90)
			(layer "F.Fab")
			(effects
				(font
					(size 1.27 1.27)
				)
			)
		)
		(duplicate_pad_numbers_are_jumpers no)
		(fp_line
			(start 0.7874 -0.4064)
			(end 0.7874 0.4064)
			(stroke
				(width 0.1524)
				(type default)
			)
			(layer "F.SilkS")
		)
		(fp_line
			(start -0.7874 -0.4064)
			(end 0.7874 -0.4064)
			(stroke
				(width 0.1524)
				(type default)
			)
			(layer "F.SilkS")
		)
		(fp_line
			(start 0 0.381)
			(end 0 -0.381)
			(stroke
				(width 0.1524)
				(type default)
			)
			(layer "F.SilkS")
		)
		(fp_line
			(start 0.7874 0.4064)
			(end -0.7874 0.4064)
			(stroke
				(width 0.1524)
				(type default)
			)
			(layer "F.SilkS")
		)
		(fp_line
			(start -0.7874 0.4064)
			(end -0.7874 -0.4064)
			(stroke
				(width 0.1524)
				(type default)
			)
			(layer "F.SilkS")
		)
		(fp_poly
			(pts
				(xy -0.5334 0.254) (xy -0.635 0.254) (xy -0.635 0.2286) (xy -0.635 -0.254) (xy -0.5334 -0.254) (xy -0.5334 -0.2794)
				(xy 0.5334 -0.2794) (xy 0.5334 -0.254) (xy 0.635 -0.254) (xy 0.635 0.254) (xy 0.5334 0.254) (xy 0.5334 0.2794)
				(xy -0.508 0.2794) (xy -0.5334 0.2794)
			)
			(stroke
				(width 0)
				(type default)
			)
			(fill no)
			(layer "F.CrtYd")
		)
		(pad "1" smd rect
			(at 0.40005 0 90)
			(size 0.4572 0.508)
			(layers "F.Cu" "F.Mask" "F.Paste")
			(net "UART_T4_NODE2_TXD_R")
		)
		(pad "2" smd rect
			(at -0.40005 0 90)
			(size 0.4572 0.508)
			(layers "F.Cu" "F.Mask" "F.Paste")
			(net "GND")
		)
	)
	(footprint ""
		(layer "F.Cu")
		(at 79.99476 -182.411624 -90)
		(property "Reference" "C585"
			(at 1.297178 1.584198 90)
			(unlocked yes)
			(layer "F.SilkS")
			(effects
				(font
					(size 0.7874 0.5842)
					(thickness 0.1524)
				)
				(justify left)
			)
		)
		(property "Value" ""
			(at 0 0 270)
			(layer "F.Fab")
			(effects
				(font
					(size 1.27 1.27)
				)
			)
		)
		(duplicate_pad_numbers_are_jumpers no)
		(fp_line
			(start -0.7874 0.4064)
			(end -0.7874 -0.4064)
			(stroke
				(width 0.1524)
				(type default)
			)
			(layer "F.SilkS")
		)
		(fp_line
			(start 0.7874 0.4064)
			(end -0.7874 0.4064)
			(stroke
				(width 0.1524)
				(type default)
			)
			(layer "F.SilkS")
		)
		(fp_line
			(start 0 0.381)
			(end 0 -0.381)
			(stroke
				(width 0.1524)
				(type default)
			)
			(layer "F.SilkS")
		)
		(fp_line
			(start -0.7874 -0.4064)
			(end 0.7874 -0.4064)
			(stroke
				(width 0.1524)
				(type default)
			)
			(layer "F.SilkS")
		)
		(fp_line
			(start 0.7874 -0.4064)
			(end 0.7874 0.4064)
			(stroke
				(width 0.1524)
				(type default)
			)
			(layer "F.SilkS")
		)
		(fp_poly
			(pts
				(xy -0.5334 0.254) (xy -0.635 0.254) (xy -0.635 0.2286) (xy -0.635 -0.254) (xy -0.5334 -0.254) (xy -0.5334 -0.2794)
				(xy 0.5334 -0.2794) (xy 0.5334 -0.254) (xy 0.635 -0.254) (xy 0.635 0.254) (xy 0.5334 0.254) (xy 0.5334 0.2794)
				(xy -0.508 0.2794) (xy -0.5334 0.2794)
			)
			(stroke
				(width 0)
				(type default)
			)
			(fill no)
			(layer "F.CrtYd")
		)
		(pad "1" smd rect
			(at 0.40005 0 270)
			(size 0.4572 0.508)
			(layers "F.Cu" "F.Mask" "F.Paste")
			(net "P3V3_NODE1")
		)
		(pad "2" smd rect
			(at -0.40005 0 270)
			(size 0.4572 0.508)
			(layers "F.Cu" "F.Mask" "F.Paste")
			(net "GND")
		)
	)
	(footprint ""
		(layer "F.Cu")
		(at 151.732234 -8.585962 180)
		(property "Reference" "J26"
			(at 1.646682 3.350768 0)
			(unlocked yes)
			(layer "F.SilkS")
			(effects
				(font
					(size 0.7874 0.5842)
					(thickness 0.1524)
				)
				(justify left)
			)
		)
		(property "Value" ""
			(at 0 0 180)
			(layer "F.Fab")
			(effects
				(font
					(size 1.27 1.27)
				)
			)
		)
		(duplicate_pad_numbers_are_jumpers no)
		(fp_line
			(start 6.599936 2.640076)
			(end -6.599936 2.640076)
			(stroke
				(width 0.1524)
				(type default)
			)
			(layer "F.SilkS")
		)
		(fp_line
			(start 6.599936 -2.640076)
			(end 6.599936 2.640076)
			(stroke
				(width 0.1524)
				(type default)
			)
			(layer "F.SilkS")
		)
		(fp_line
			(start -6.599936 2.640076)
			(end -6.599936 -2.640076)
			(stroke
				(width 0.1524)
				(type default)
			)
			(layer "F.SilkS")
		)
		(fp_line
			(start -6.599936 -2.640076)
			(end 6.599936 -2.640076)
			(stroke
				(width 0.1524)
				(type default)
			)
			(layer "F.SilkS")
		)
		(fp_poly
			(pts
				(xy -5.196586 3.444494) (xy -5.958586 5.349494) (xy -4.434586 5.349494)
			)
			(stroke
				(width 0)
				(type default)
			)
			(fill yes)
			(layer "F.SilkS")
		)
		(fp_poly
			(pts
				(xy -5.969 -2.159) (xy 5.969 -2.159) (xy 5.969 2.159) (xy -5.969 2.159)
			)
			(stroke
				(width 0)
				(type default)
			)
			(fill no)
			(layer "B.CrtYd")
		)
		(fp_poly
			(pts
				(xy -6.599936 2.640076) (xy 6.599936 2.640076) (xy 6.599936 -2.640076) (xy -6.599936 -2.640076)
			)
			(stroke
				(width 0)
				(type default)
			)
			(fill no)
			(layer "F.CrtYd")
		)
		(fp_line
			(start 6.599936 2.640076)
			(end -6.599936 2.640076)
			(stroke
				(width 0.1)
				(type default)
			)
			(layer "F.Fab")
		)
		(fp_line
			(start 6.599936 -2.640076)
			(end 6.599936 2.640076)
			(stroke
				(width 0.1)
				(type default)
			)
			(layer "F.Fab")
		)
		(fp_line
			(start -6.599936 2.640076)
			(end -6.599936 -2.640076)
			(stroke
				(width 0.1)
				(type default)
			)
			(layer "F.Fab")
		)
		(fp_line
			(start -6.599936 -2.640076)
			(end 6.599936 -2.640076)
			(stroke
				(width 0.1)
				(type default)
			)
			(layer "F.Fab")
		)
		(fp_poly
			(pts
				(xy -7.4295 1.27) (xy -9.3345 0.508) (xy -9.3345 2.032)
			)
			(stroke
				(width 0)
				(type default)
			)
			(fill yes)
			(layer "F.Fab")
		)
		(fp_text user "9"
			(at 7.405624 2.211324 0)
			(unlocked yes)
			(layer "F.SilkS")
			(effects
				(font
					(size 0.7874 0.5842)
					(thickness 0.1524)
				)
				(justify left)
			)
		)
		(fp_text user "10"
			(at 6.613144 -3.49377 0)
			(unlocked yes)
			(layer "F.SilkS")
			(effects
				(font
					(size 0.7874 0.5842)
					(thickness 0.1524)
				)
				(justify left)
			)
		)
		(fp_text user "2"
			(at -5.792216 -3.447796 0)
			(unlocked yes)
			(layer "F.SilkS")
			(effects
				(font
					(size 0.7874 0.5842)
					(thickness 0.1524)
				)
				(justify left)
			)
		)
		(fp_text user "1"
			(at -6.914896 2.450084 0)
			(unlocked yes)
			(layer "F.SilkS")
			(effects
				(font
					(size 0.7874 0.5842)
					(thickness 0.1524)
				)
				(justify left)
			)
		)
		(fp_text user "9"
			(at 6.305042 1.09982 0)
			(unlocked yes)
			(layer "B.SilkS")
			(effects
				(font
					(size 0.7874 0.5842)
					(thickness 0.1524)
				)
				(justify left mirror)
			)
		)
		(fp_text user "10"
			(at 6.142482 -1.373632 0)
			(unlocked yes)
			(layer "B.SilkS")
			(effects
				(font
					(size 0.7874 0.5842)
					(thickness 0.1524)
				)
				(justify left mirror)
			)
		)
		(fp_text user "1"
			(at -6.679438 1.100074 0)
			(unlocked yes)
			(layer "B.SilkS")
			(effects
				(font
					(size 0.7874 0.5842)
					(thickness 0.1524)
				)
				(justify left mirror)
			)
		)
		(fp_text user "2"
			(at -6.679438 -1.275842 0)
			(unlocked yes)
			(layer "B.SilkS")
			(effects
				(font
					(size 0.7874 0.5842)
					(thickness 0.1524)
				)
				(justify left mirror)
			)
		)
		(fp_text user "10"
			(at 7.5438 -1.361948 180)
			(unlocked yes)
			(layer "B.Fab")
			(effects
				(font
					(size 0.7874 0.5842)
					(thickness 0.000001)
				)
				(justify left mirror)
			)
		)
		(fp_text user "9"
			(at 7.1501 1.178052 180)
			(unlocked yes)
			(layer "B.Fab")
			(effects
				(font
					(size 0.7874 0.5842)
					(thickness 0.000001)
				)
				(justify left mirror)
			)
		)
		(fp_text user "1"
			(at -6.1849 1.178052 180)
			(unlocked yes)
			(layer "B.Fab")
			(effects
				(font
					(size 0.7874 0.5842)
					(thickness 0.000001)
				)
				(justify left mirror)
			)
		)
		(fp_text user "2"
			(at -6.1849 -1.361948 180)
			(unlocked yes)
			(layer "B.Fab")
			(effects
				(font
					(size 0.7874 0.5842)
					(thickness 0.000001)
				)
				(justify left mirror)
			)
		)
		(fp_text user "9"
			(at 6.9469 1.178052 180)
			(unlocked yes)
			(layer "F.Fab")
			(effects
				(font
					(size 0.7874 0.5842)
					(thickness 0.000001)
				)
				(justify left)
			)
		)
		(fp_text user "10"
			(at 6.5532 -1.361948 180)
			(unlocked yes)
			(layer "F.Fab")
			(effects
				(font
					(size 0.7874 0.5842)
					(thickness 0.000001)
				)
				(justify left)
			)
		)
		(fp_text user "1"
			(at -7.5311 1.178052 180)
			(unlocked yes)
			(layer "F.Fab")
			(effects
				(font
					(size 0.7874 0.5842)
					(thickness 0.000001)
				)
				(justify left)
			)
		)
		(fp_text user "2"
			(at -7.5311 -1.361948 180)
			(unlocked yes)
			(layer "F.Fab")
			(effects
				(font
					(size 0.7874 0.5842)
					(thickness 0.000001)
				)
				(justify left)
			)
		)
		(pad "1" thru_hole rect
			(at -5.08 1.27 270)
			(size 1.6764 1.6764)
			(drill 1.1684)
			(layers "*.Cu" "*.Mask")
			(remove_unused_layers no)
			(net "JTAG_CPLD2_TCK")
			(clearance 0)
			(padstack
				(mode front_inner_back)
				(layer "Inner"
					(shape circle)
					(size 1.6764 1.6764)
					(clearance 0)
				)
				(layer "B.Cu"
					(shape rect)
					(size 1.6764 1.6764)
					(clearance 0)
				)
			)
		)
		(pad "2" thru_hole circle
			(at -5.08 -1.27 270)
			(size 1.6764 1.6764)
			(drill 1.1684)
			(layers "*.Cu" "*.Mask")
			(remove_unused_layers no)
			(net "GND")
			(clearance 0)
		)
		(pad "3" thru_hole circle
			(at -2.54 1.27 270)
			(size 1.6764 1.6764)
			(drill 1.1684)
			(layers "*.Cu" "*.Mask")
			(remove_unused_layers no)
			(net "JTAG_CPLD2_TDO")
			(clearance 0)
		)
		(pad "4" thru_hole circle
			(at -2.54 -1.27 270)
			(size 1.6764 1.6764)
			(drill 1.1684)
			(layers "*.Cu" "*.Mask")
			(remove_unused_layers no)
			(net "P3V3_NODE1")
			(clearance 0)
		)
		(pad "5" thru_hole circle
			(at 0 1.27 270)
			(size 1.6764 1.6764)
			(drill 1.1684)
			(layers "*.Cu" "*.Mask")
			(remove_unused_layers no)
			(net "JTAG_CPLD2_TMS")
			(clearance 0)
		)
		(pad "6" thru_hole circle
			(at 0 -1.27 270)
			(size 1.6764 1.6764)
			(drill 1.1684)
			(layers "*.Cu" "*.Mask")
			(remove_unused_layers no)
			(net "Net_2262")
			(clearance 0)
		)
		(pad "7" thru_hole circle
			(at 2.54 1.27 270)
			(size 1.6764 1.6764)
			(drill 1.1684)
			(layers "*.Cu" "*.Mask")
			(remove_unused_layers no)
			(net "Net_2261")
			(clearance 0)
		)
		(pad "8" thru_hole circle
			(at 2.54 -1.27 270)
			(size 1.6764 1.6764)
			(drill 1.1684)
			(layers "*.Cu" "*.Mask")
			(remove_unused_layers no)
			(net "Net_2260")
			(clearance 0)
		)
		(pad "9" thru_hole circle
			(at 5.08 1.27 270)
			(size 1.6764 1.6764)
			(drill 1.1684)
			(layers "*.Cu" "*.Mask")
			(remove_unused_layers no)
			(net "JTAG_CPLD2_TDI")
			(clearance 0)
		)
		(pad "10" thru_hole circle
			(at 5.08 -1.27 270)
			(size 1.6764 1.6764)
			(drill 1.1684)
			(layers "*.Cu" "*.Mask")
			(remove_unused_layers no)
			(net "GND")
			(clearance 0)
		)
	)
	(footprint ""
		(layer "F.Cu")
		(at 137.52576 -171.108624 -90)
		(property "Reference" "U129"
			(at -6.558534 12.007088 0)
			(unlocked yes)
			(layer "F.SilkS")
			(effects
				(font
					(size 0.7874 0.5842)
					(thickness 0.1524)
				)
				(justify left)
			)
		)
		(property "Value" ""
			(at 0 0 270)
			(layer "F.Fab")
			(effects
				(font
					(size 1.27 1.27)
				)
			)
		)
		(duplicate_pad_numbers_are_jumpers no)
		(fp_line
			(start -4.0386 8.8646)
			(end -4.0386 11.9634)
			(stroke
				(width 0.1524)
				(type default)
			)
			(layer "F.SilkS")
		)
		(fp_line
			(start -1.4986 8.8392)
			(end -1.4986 10.1092)
			(stroke
				(width 0.1524)
				(type default)
			)
			(layer "F.SilkS")
		)
		(fp_line
			(start 1.016 8.7376)
			(end 1.016 9.01954)
			(stroke
				(width 0.1524)
				(type default)
			)
			(layer "F.SilkS")
		)
		(fp_line
			(start 3.5052 8.7376)
			(end 3.5052 10.0076)
			(stroke
				(width 0.1524)
				(type default)
			)
			(layer "F.SilkS")
		)
		(fp_line
			(start -6.2992 6.2992)
			(end -6.2992 -5.969)
			(stroke
				(width 0.1524)
				(type default)
			)
			(layer "F.SilkS")
		)
		(fp_line
			(start 6.2992 6.2992)
			(end -6.2992 6.2992)
			(stroke
				(width 0.1524)
				(type default)
			)
			(layer "F.SilkS")
		)
		(fp_line
			(start -8.7376 6.0198)
			(end -10.0076 6.0198)
			(stroke
				(width 0.1524)
				(type default)
			)
			(layer "F.SilkS")
		)
		(fp_line
			(start -8.7376 3.5052)
			(end -11.4808 3.5052)
			(stroke
				(width 0.1524)
				(type default)
			)
			(layer "F.SilkS")
		)
		(fp_line
			(start 9.850882 1.4986)
			(end 8.7376 1.4986)
			(stroke
				(width 0.1524)
				(type default)
			)
			(layer "F.SilkS")
		)
		(fp_line
			(start -8.763 1.0414)
			(end -10.033 1.0414)
			(stroke
				(width 0.1524)
				(type default)
			)
			(layer "F.SilkS")
		)
		(fp_line
			(start 9.9568 -0.9906)
			(end 8.6868 -0.9906)
			(stroke
				(width 0.1524)
				(type default)
			)
			(layer "F.SilkS")
		)
		(fp_line
			(start -8.7376 -1.4986)
			(end -11.4808 -1.4986)
			(stroke
				(width 0.1524)
				(type default)
			)
			(layer "F.SilkS")
		)
		(fp_line
			(start -8.7122 -4.0132)
			(end -9.9822 -4.0132)
			(stroke
				(width 0.1524)
				(type default)
			)
			(layer "F.SilkS")
		)
		(fp_line
			(start -6.2992 -5.969)
			(end -5.969 -6.2992)
			(stroke
				(width 0.1524)
				(type default)
			)
			(layer "F.SilkS")
		)
		(fp_line
			(start 9.9822 -6.0198)
			(end 8.7122 -6.0198)
			(stroke
				(width 0.1524)
				(type default)
			)
			(layer "F.SilkS")
		)
		(fp_line
			(start -5.969 -6.2992)
			(end 6.2992 -6.2992)
			(stroke
				(width 0.1524)
				(type default)
			)
			(layer "F.SilkS")
		)
		(fp_line
			(start 6.2992 -6.2992)
			(end 6.2992 6.2992)
			(stroke
				(width 0.1524)
				(type default)
			)
			(layer "F.SilkS")
		)
		(fp_line
			(start -3.4798 -9.9568)
			(end -3.4798 -8.6868)
			(stroke
				(width 0.1524)
				(type default)
			)
			(layer "F.SilkS")
		)
		(fp_line
			(start 1.4732 -9.9822)
			(end 1.4732 -8.7122)
			(stroke
				(width 0.1524)
				(type default)
			)
			(layer "F.SilkS")
		)
		(fp_line
			(start -0.9906 -10.032492)
			(end -0.9906 -8.6868)
			(stroke
				(width 0.1524)
				(type default)
			)
			(layer "F.SilkS")
		)
		(fp_line
			(start -6.0198 -11.811)
			(end -6.0198 -8.7122)
			(stroke
				(width 0.1524)
				(type default)
			)
			(layer "F.SilkS")
		)
		(fp_poly
			(pts
				(xy -8.721344 -6.537706) (xy -9.152382 -7.18439) (xy -9.349994 -6.986778)
			)
			(stroke
				(width 0)
				(type default)
			)
			(fill yes)
			(layer "F.SilkS")
		)
		(fp_poly
			(pts
				(xy -6.1468 8.509) (xy -6.1468 7.2644) (xy -7.2644 7.2644) (xy -7.2644 6.1468) (xy -8.509 6.1468)
				(xy -8.509 -6.1468) (xy -7.2644 -6.1468) (xy -7.2644 -7.2644) (xy -6.1468 -7.2644) (xy -6.1468 -8.509)
				(xy 6.1468 -8.509) (xy 6.1468 -7.2644) (xy 7.2644 -7.2644) (xy 7.2644 -6.1468) (xy 8.509 -6.1468)
				(xy 8.509 6.1468) (xy 7.2644 6.1468) (xy 7.2644 7.2644) (xy 6.1468 7.2644) (xy 6.1468 8.509)
			)
			(stroke
				(width 0)
				(type default)
			)
			(fill no)
			(layer "F.CrtYd")
		)
		(fp_text user "50"
			(at 6.722364 8.270494 0)
			(unlocked yes)
			(layer "F.SilkS")
			(effects
				(font
					(size 0.635 0.4064)
					(thickness 0.1524)
				)
				(justify left)
			)
		)
		(fp_text user "26"
			(at -6.587744 8.199882 0)
			(unlocked yes)
			(layer "F.SilkS")
			(effects
				(font
					(size 0.635 0.4064)
					(thickness 0.1524)
				)
				(justify left)
			)
		)
		(fp_text user "25"
			(at -7.757922 7.315454 0)
			(unlocked yes)
			(layer "F.SilkS")
			(effects
				(font
					(size 0.635 0.4064)
					(thickness 0.1524)
				)
				(justify left)
			)
		)
		(fp_text user "51"
			(at 7.406132 7.176008 0)
			(unlocked yes)
			(layer "F.SilkS")
			(effects
				(font
					(size 0.635 0.4064)
					(thickness 0.1524)
				)
				(justify left)
			)
		)
		(fp_text user "75"
			(at 8.08482 -6.477 0)
			(unlocked yes)
			(layer "F.SilkS")
			(effects
				(font
					(size 0.635 0.4064)
					(thickness 0.1524)
				)
				(justify left)
			)
		)
		(fp_text user "1"
			(at -8.292846 -6.574536 0)
			(unlocked yes)
			(layer "F.SilkS")
			(effects
				(font
					(size 0.7874 0.5842)
					(thickness 0.1524)
				)
				(justify left)
			)
		)
		(fp_text user "100"
			(at -6.757924 -7.056628 0)
			(unlocked yes)
			(layer "F.SilkS")
			(effects
				(font
					(size 0.7874 0.5842)
					(thickness 0.1524)
				)
				(justify left)
			)
		)
		(fp_text user "76"
			(at 6.263132 -8.825992 0)
			(unlocked yes)
			(layer "F.SilkS")
			(effects
				(font
					(size 0.635 0.4064)
					(thickness 0.1524)
				)
				(justify left)
			)
		)
		(pad "1" smd rect
			(at -7.750048 -5.999988)
			(size 0.2794 1.4986)
			(layers "F.Cu" "F.Mask" "F.Paste")
			(net "CPLD_UART_DTR_P3_N")
		)
		(pad "2" smd rect
			(at -7.750048 -5.500116)
			(size 0.2794 1.4986)
			(layers "F.Cu" "F.Mask" "F.Paste")
			(net "UART_SW_S0_N")
		)
		(pad "3" smd rect
			(at -7.750048 -4.99999)
			(size 0.2794 1.4986)
			(layers "F.Cu" "F.Mask" "F.Paste")
			(net "UART_SW_S1_N")
		)
		(pad "4" smd rect
			(at -7.750048 -4.500118)
			(size 0.2794 1.4986)
			(layers "F.Cu" "F.Mask" "F.Paste")
			(net "UART_SW_S2_N")
		)
		(pad "5" smd rect
			(at -7.750048 -3.999992)
			(size 0.2794 1.4986)
			(layers "F.Cu" "F.Mask" "F.Paste")
			(net "UART_SW_S3_N")
		)
		(pad "6" smd rect
			(at -7.750048 -3.50012)
			(size 0.2794 1.4986)
			(layers "F.Cu" "F.Mask" "F.Paste")
			(net "UART_SW_S4_N")
		)
		(pad "7" smd rect
			(at -7.750048 -2.999994)
			(size 0.2794 1.4986)
			(layers "F.Cu" "F.Mask" "F.Paste")
			(net "UART_SW_S5_N")
		)
		(pad "8" smd rect
			(at -7.750048 -2.500122)
			(size 0.2794 1.4986)
			(layers "F.Cu" "F.Mask" "F.Paste")
			(net "UART3_RESET_N")
		)
		(pad "9" smd rect
			(at -7.750048 -1.999996)
			(size 0.2794 1.4986)
			(layers "F.Cu" "F.Mask" "F.Paste")
			(net "P3V3_NODE1")
		)
		(pad "10" smd rect
			(at -7.750048 -1.500124)
			(size 0.2794 1.4986)
			(layers "F.Cu" "F.Mask" "F.Paste")
			(net "GND")
		)
		(pad "11" smd rect
			(at -7.750048 -0.999998)
			(size 0.2794 1.4986)
			(layers "F.Cu" "F.Mask" "F.Paste")
			(net "GND")
		)
		(pad "12" smd rect
			(at -7.750048 -0.499872)
			(size 0.2794 1.4986)
			(layers "F.Cu" "F.Mask" "F.Paste")
			(net "CPLD_WDT3")
		)
		(pad "13" smd rect
			(at -7.750048 0)
			(size 0.2794 1.4986)
			(layers "F.Cu" "F.Mask" "F.Paste")
			(net "P3V3_NODE1")
		)
		(pad "14" smd rect
			(at -7.750048 0.499872)
			(size 0.2794 1.4986)
			(layers "F.Cu" "F.Mask" "F.Paste")
			(net "CPU_RSV_1")
		)
		(pad "15" smd rect
			(at -7.750048 0.999998)
			(size 0.2794 1.4986)
			(layers "F.Cu" "F.Mask" "F.Paste")
			(net "UART_TX_P4")
		)
		(pad "16" smd rect
			(at -7.750048 1.500124)
			(size 0.2794 1.4986)
			(layers "F.Cu" "F.Mask" "F.Paste")
			(net "UART_RX_P4")
		)
		(pad "17" smd rect
			(at -7.750048 1.999996)
			(size 0.2794 1.4986)
			(layers "F.Cu" "F.Mask" "F.Paste")
			(net "UART_DTR_P3_N")
		)
		(pad "18" smd rect
			(at -7.750048 2.500122)
			(size 0.2794 1.4986)
			(layers "F.Cu" "F.Mask" "F.Paste")
			(net "UART_TX_P3")
		)
		(pad "19" smd rect
			(at -7.750048 2.999994)
			(size 0.2794 1.4986)
			(layers "F.Cu" "F.Mask" "F.Paste")
			(net "UART_RX_P3")
		)
		(pad "20" smd rect
			(at -7.750048 3.50012)
			(size 0.2794 1.4986)
			(layers "F.Cu" "F.Mask" "F.Paste")
			(net "UART_CMC_TX_P")
		)
		(pad "21" smd rect
			(at -7.750048 3.999992)
			(size 0.2794 1.4986)
			(layers "F.Cu" "F.Mask" "F.Paste")
			(net "UART_CMC_RX_P")
		)
		(pad "22" smd rect
			(at -7.750048 4.500118)
			(size 0.2794 1.4986)
			(layers "F.Cu" "F.Mask" "F.Paste")
			(net "JTAG_CPLD3_TMS")
		)
		(pad "23" smd rect
			(at -7.750048 4.99999)
			(size 0.2794 1.4986)
			(layers "F.Cu" "F.Mask" "F.Paste")
			(net "JTAG_CPLD3_TDI")
		)
		(pad "24" smd rect
			(at -7.750048 5.500116)
			(size 0.2794 1.4986)
			(layers "F.Cu" "F.Mask" "F.Paste")
			(net "JTAG_CPLD3_TCK")
		)
		(pad "25" smd rect
			(at -7.750048 5.999988)
			(size 0.2794 1.4986)
			(layers "F.Cu" "F.Mask" "F.Paste")
			(net "JTAG_CPLD3_TDO")
		)
		(pad "26" smd rect
			(at -5.999988 7.750048 270)
			(size 0.2794 1.4986)
			(layers "F.Cu" "F.Mask" "F.Paste")
			(net "UART_T7_NODE1_TXD")
		)
		(pad "27" smd rect
			(at -5.500116 7.750048 270)
			(size 0.2794 1.4986)
			(layers "F.Cu" "F.Mask" "F.Paste")
			(net "UART_T7_NODE1_RXD")
		)
		(pad "28" smd rect
			(at -4.99999 7.750048 270)
			(size 0.2794 1.4986)
			(layers "F.Cu" "F.Mask" "F.Paste")
			(net "UART_T7_NODE2_TXD")
		)
		(pad "29" smd rect
			(at -4.500118 7.750048 270)
			(size 0.2794 1.4986)
			(layers "F.Cu" "F.Mask" "F.Paste")
			(net "UART_T7_NODE2_RXD")
		)
		(pad "30" smd rect
			(at -3.999992 7.750048 270)
			(size 0.2794 1.4986)
			(layers "F.Cu" "F.Mask" "F.Paste")
			(net "CPLD_EXT_RST_N")
		)
		(pad "31" smd rect
			(at -3.50012 7.750048 270)
			(size 0.2794 1.4986)
			(layers "F.Cu" "F.Mask" "F.Paste")
			(net "P3V3_NODE1")
		)
		(pad "32" smd rect
			(at -2.999994 7.750048 270)
			(size 0.2794 1.4986)
			(layers "F.Cu" "F.Mask" "F.Paste")
			(net "GND")
		)
		(pad "33" smd rect
			(at -2.500122 7.750048 270)
			(size 0.2794 1.4986)
			(layers "F.Cu" "F.Mask" "F.Paste")
			(net "UART_T7_NODE3_TXD")
		)
		(pad "34" smd rect
			(at -1.999996 7.750048 270)
			(size 0.2794 1.4986)
			(layers "F.Cu" "F.Mask" "F.Paste")
			(net "UART_T7_NODE3_RXD")
		)
		(pad "35" smd rect
			(at -1.500124 7.750048 270)
			(size 0.2794 1.4986)
			(layers "F.Cu" "F.Mask" "F.Paste")
			(net "UART_T7_NODE4_TXD")
		)
		(pad "36" smd rect
			(at -0.999998 7.750048 270)
			(size 0.2794 1.4986)
			(layers "F.Cu" "F.Mask" "F.Paste")
			(net "UART_T7_NODE4_RXD")
		)
		(pad "37" smd rect
			(at -0.499872 7.750048 270)
			(size 0.2794 1.4986)
			(layers "F.Cu" "F.Mask" "F.Paste")
			(net "UART_T8_NODE1_TXD")
		)
		(pad "38" smd rect
			(at 0 7.750048 270)
			(size 0.2794 1.4986)
			(layers "F.Cu" "F.Mask" "F.Paste")
			(net "UART_T8_NODE1_RXD")
		)
		(pad "39" smd rect
			(at 0.499872 7.750048 270)
			(size 0.2794 1.4986)
			(layers "F.Cu" "F.Mask" "F.Paste")
			(net "UART_T8_NODE2_TXD")
		)
		(pad "40" smd rect
			(at 0.999998 7.750048 270)
			(size 0.2794 1.4986)
			(layers "F.Cu" "F.Mask" "F.Paste")
			(net "UART_T8_NODE2_RXD")
		)
		(pad "41" smd rect
			(at 1.500124 7.750048 270)
			(size 0.2794 1.4986)
			(layers "F.Cu" "F.Mask" "F.Paste")
			(net "UART_T8_NODE3_TXD")
		)
		(pad "42" smd rect
			(at 1.999996 7.750048 270)
			(size 0.2794 1.4986)
			(layers "F.Cu" "F.Mask" "F.Paste")
			(net "UART_T8_NODE3_RXD")
		)
		(pad "43" smd rect
			(at 2.500122 7.750048 270)
			(size 0.2794 1.4986)
			(layers "F.Cu" "F.Mask" "F.Paste")
			(net "CPLD_WDT1")
		)
		(pad "44" smd rect
			(at 2.999994 7.750048 270)
			(size 0.2794 1.4986)
			(layers "F.Cu" "F.Mask" "F.Paste")
			(net "CPLD_WDT2")
		)
		(pad "45" smd rect
			(at 3.50012 7.750048 270)
			(size 0.2794 1.4986)
			(layers "F.Cu" "F.Mask" "F.Paste")
			(net "P3V3_NODE1")
		)
		(pad "46" smd rect
			(at 3.999992 7.750048 270)
			(size 0.2794 1.4986)
			(layers "F.Cu" "F.Mask" "F.Paste")
			(net "GND")
		)
		(pad "47" smd rect
			(at 4.500118 7.750048 270)
			(size 0.2794 1.4986)
			(layers "F.Cu" "F.Mask" "F.Paste")
			(net "UART_T8_NODE4_TXD")
		)
		(pad "48" smd rect
			(at 4.99999 7.750048 270)
			(size 0.2794 1.4986)
			(layers "F.Cu" "F.Mask" "F.Paste")
			(net "UART_T8_NODE4_RXD")
		)
		(pad "49" smd rect
			(at 5.500116 7.750048 270)
			(size 0.2794 1.4986)
			(layers "F.Cu" "F.Mask" "F.Paste")
			(net "CPLD3_RSV1")
		)
		(pad "50" smd rect
			(at 5.999988 7.750048 270)
			(size 0.2794 1.4986)
			(layers "F.Cu" "F.Mask" "F.Paste")
			(net "CPLD3_RSV2")
		)
		(pad "51" smd rect
			(at 7.750048 5.999988)
			(size 0.2794 1.4986)
			(layers "F.Cu" "F.Mask" "F.Paste")
			(net "CPLD3_RSV3")
		)
		(pad "52" smd rect
			(at 7.750048 5.500116)
			(size 0.2794 1.4986)
			(layers "F.Cu" "F.Mask" "F.Paste")
			(net "UART_T9_NODE1_TXD")
		)
		(pad "53" smd rect
			(at 7.750048 4.99999)
			(size 0.2794 1.4986)
			(layers "F.Cu" "F.Mask" "F.Paste")
			(net "UART_T9_NODE1_RXD")
		)
		(pad "54" smd rect
			(at 7.750048 4.500118)
			(size 0.2794 1.4986)
			(layers "F.Cu" "F.Mask" "F.Paste")
			(net "UART_T9_NODE2_TXD")
		)
		(pad "55" smd rect
			(at 7.750048 3.999992)
			(size 0.2794 1.4986)
			(layers "F.Cu" "F.Mask" "F.Paste")
			(net "UART_T9_NODE2_RXD")
		)
		(pad "56" smd rect
			(at 7.750048 3.50012)
			(size 0.2794 1.4986)
			(layers "F.Cu" "F.Mask" "F.Paste")
			(net "UART_T9_NODE3_TXD")
		)
		(pad "57" smd rect
			(at 7.750048 2.999994)
			(size 0.2794 1.4986)
			(layers "F.Cu" "F.Mask" "F.Paste")
			(net "UART_T9_NODE3_RXD")
		)
		(pad "58" smd rect
			(at 7.750048 2.500122)
			(size 0.2794 1.4986)
			(layers "F.Cu" "F.Mask" "F.Paste")
			(net "TACKOVER_EN_N")
		)
		(pad "59" smd rect
			(at 7.750048 1.999996)
			(size 0.2794 1.4986)
			(layers "F.Cu" "F.Mask" "F.Paste")
			(net "P3V3_NODE1")
		)
		(pad "60" smd rect
			(at 7.750048 1.500124)
			(size 0.2794 1.4986)
			(layers "F.Cu" "F.Mask" "F.Paste")
			(net "GND")
		)
		(pad "61" smd rect
			(at 7.750048 0.999998)
			(size 0.2794 1.4986)
			(layers "F.Cu" "F.Mask" "F.Paste")
			(net "CMC_CPU_RST_N")
		)
		(pad "62" smd rect
			(at 7.750048 0.499872)
			(size 0.2794 1.4986)
			(layers "F.Cu" "F.Mask" "F.Paste")
			(net "UART_RI_P3_BUFFER_N")
		)
		(pad "63" smd rect
			(at 7.750048 0)
			(size 0.2794 1.4986)
			(layers "F.Cu" "F.Mask" "F.Paste")
			(net "P3V3_NODE1")
		)
		(pad "64" smd rect
			(at 7.750048 -0.499872)
			(size 0.2794 1.4986)
			(layers "F.Cu" "F.Mask" "F.Paste")
			(net "CLK_33K_CPLD23")
		)
		(pad "65" smd rect
			(at 7.750048 -0.999998)
			(size 0.2794 1.4986)
			(layers "F.Cu" "F.Mask" "F.Paste")
			(net "GND")
		)
		(pad "66" smd rect
			(at 7.750048 -1.500124)
			(size 0.2794 1.4986)
			(layers "F.Cu" "F.Mask" "F.Paste")
			(net "UART_T9_NODE4_TXD")
		)
		(pad "67" smd rect
			(at 7.750048 -1.999996)
			(size 0.2794 1.4986)
			(layers "F.Cu" "F.Mask" "F.Paste")
			(net "UART_T9_NODE4_RXD")
		)
		(pad "68" smd rect
			(at 7.750048 -2.500122)
			(size 0.2794 1.4986)
			(layers "F.Cu" "F.Mask" "F.Paste")
			(net "UART_T10_NODE1_TXD")
		)
		(pad "69" smd rect
			(at 7.750048 -2.999994)
			(size 0.2794 1.4986)
			(layers "F.Cu" "F.Mask" "F.Paste")
			(net "UART_T10_NODE1_RXD")
		)
		(pad "70" smd rect
			(at 7.750048 -3.50012)
			(size 0.2794 1.4986)
			(layers "F.Cu" "F.Mask" "F.Paste")
			(net "UART_T10_NODE2_TXD")
		)
		(pad "71" smd rect
			(at 7.750048 -3.999992)
			(size 0.2794 1.4986)
			(layers "F.Cu" "F.Mask" "F.Paste")
			(net "UART_T10_NODE2_RXD")
		)
		(pad "72" smd rect
			(at 7.750048 -4.500118)
			(size 0.2794 1.4986)
			(layers "F.Cu" "F.Mask" "F.Paste")
			(net "UART_T10_NODE3_TXD")
		)
		(pad "73" smd rect
			(at 7.750048 -4.99999)
			(size 0.2794 1.4986)
			(layers "F.Cu" "F.Mask" "F.Paste")
			(net "UART_T10_NODE3_RXD")
		)
		(pad "74" smd rect
			(at 7.750048 -5.500116)
			(size 0.2794 1.4986)
			(layers "F.Cu" "F.Mask" "F.Paste")
			(net "UART_T10_NODE4_TXD")
		)
		(pad "75" smd rect
			(at 7.750048 -5.999988)
			(size 0.2794 1.4986)
			(layers "F.Cu" "F.Mask" "F.Paste")
			(net "UART_T10_NODE4_RXD")
		)
		(pad "76" smd rect
			(at 5.999988 -7.750048 270)
			(size 0.2794 1.4986)
			(layers "F.Cu" "F.Mask" "F.Paste")
			(net "UART_T11_NODE1_TXD")
		)
		(pad "77" smd rect
			(at 5.500116 -7.750048 270)
			(size 0.2794 1.4986)
			(layers "F.Cu" "F.Mask" "F.Paste")
			(net "UART_T11_NODE1_RXD")
		)
		(pad "78" smd rect
			(at 4.99999 -7.750048 270)
			(size 0.2794 1.4986)
			(layers "F.Cu" "F.Mask" "F.Paste")
			(net "UART_RTS_P3_N")
		)
		(pad "79" smd rect
			(at 4.500118 -7.750048 270)
			(size 0.2794 1.4986)
			(layers "F.Cu" "F.Mask" "F.Paste")
			(net "GND")
		)
		(pad "80" smd rect
			(at 3.999992 -7.750048 270)
			(size 0.2794 1.4986)
			(layers "F.Cu" "F.Mask" "F.Paste")
			(net "P3V3_NODE1")
		)
		(pad "81" smd rect
			(at 3.50012 -7.750048 270)
			(size 0.2794 1.4986)
			(layers "F.Cu" "F.Mask" "F.Paste")
			(net "UART_T11_NODE2_TXD")
		)
		(pad "82" smd rect
			(at 2.999994 -7.750048 270)
			(size 0.2794 1.4986)
			(layers "F.Cu" "F.Mask" "F.Paste")
			(net "UART_T11_NODE2_RXD")
		)
		(pad "83" smd rect
			(at 2.500122 -7.750048 270)
			(size 0.2794 1.4986)
			(layers "F.Cu" "F.Mask" "F.Paste")
			(net "UART_T11_NODE3_TXD")
		)
		(pad "84" smd rect
			(at 1.999996 -7.750048 270)
			(size 0.2794 1.4986)
			(layers "F.Cu" "F.Mask" "F.Paste")
			(net "UART_T11_NODE3_RXD")
		)
		(pad "85" smd rect
			(at 1.500124 -7.750048 270)
			(size 0.2794 1.4986)
			(layers "F.Cu" "F.Mask" "F.Paste")
			(net "UART_T11_NODE4_TXD")
		)
		(pad "86" smd rect
			(at 0.999998 -7.750048 270)
			(size 0.2794 1.4986)
			(layers "F.Cu" "F.Mask" "F.Paste")
			(net "UART_T11_NODE4_RXD")
		)
		(pad "87" smd rect
			(at 0.499872 -7.750048 270)
			(size 0.2794 1.4986)
			(layers "F.Cu" "F.Mask" "F.Paste")
			(net "UART_T12_NODE1_TXD")
		)
		(pad "88" smd rect
			(at 0 -7.750048 270)
			(size 0.2794 1.4986)
			(layers "F.Cu" "F.Mask" "F.Paste")
			(net "UART_T12_NODE1_RXD")
		)
		(pad "89" smd rect
			(at -0.499872 -7.750048 270)
			(size 0.2794 1.4986)
			(layers "F.Cu" "F.Mask" "F.Paste")
			(net "UART_T12_NODE2_TXD")
		)
		(pad "90" smd rect
			(at -0.999998 -7.750048 270)
			(size 0.2794 1.4986)
			(layers "F.Cu" "F.Mask" "F.Paste")
			(net "UART_T12_NODE2_RXD")
		)
		(pad "91" smd rect
			(at -1.500124 -7.750048 270)
			(size 0.2794 1.4986)
			(layers "F.Cu" "F.Mask" "F.Paste")
			(net "UART_T12_NODE3_TXD")
		)
		(pad "92" smd rect
			(at -1.999996 -7.750048 270)
			(size 0.2794 1.4986)
			(layers "F.Cu" "F.Mask" "F.Paste")
			(net "UART_T12_NODE3_RXD")
		)
		(pad "93" smd rect
			(at -2.500122 -7.750048 270)
			(size 0.2794 1.4986)
			(layers "F.Cu" "F.Mask" "F.Paste")
			(net "GND")
		)
		(pad "94" smd rect
			(at -2.999994 -7.750048 270)
			(size 0.2794 1.4986)
			(layers "F.Cu" "F.Mask" "F.Paste")
			(net "P3V3_NODE1")
		)
		(pad "95" smd rect
			(at -3.50012 -7.750048 270)
			(size 0.2794 1.4986)
			(layers "F.Cu" "F.Mask" "F.Paste")
			(net "UART_T12_NODE4_TXD")
		)
		(pad "96" smd rect
			(at -3.999992 -7.750048 270)
			(size 0.2794 1.4986)
			(layers "F.Cu" "F.Mask" "F.Paste")
			(net "UART_T12_NODE4_RXD")
		)
		(pad "97" smd rect
			(at -4.500118 -7.750048 270)
			(size 0.2794 1.4986)
			(layers "F.Cu" "F.Mask" "F.Paste")
			(net "CPLD_UART_RTS_P3_N")
		)
		(pad "98" smd rect
			(at -4.99999 -7.750048 270)
			(size 0.2794 1.4986)
			(layers "F.Cu" "F.Mask" "F.Paste")
			(net "CPLD_UART_RI_P3_N")
		)
		(pad "99" smd rect
			(at -5.500116 -7.750048 270)
			(size 0.2794 1.4986)
			(layers "F.Cu" "F.Mask" "F.Paste")
			(net "CPLD_UART_RX_P3")
		)
		(pad "100" smd rect
			(at -5.999988 -7.750048 270)
			(size 0.2794 1.4986)
			(layers "F.Cu" "F.Mask" "F.Paste")
			(net "CPLD_UART_TX_P3")
		)
	)
	(footprint ""
		(layer "F.Cu")
		(at 144.51076 -188.126624 90)
		(property "Reference" "C759"
			(at 5.519674 -0.903732 90)
			(unlocked yes)
			(layer "F.SilkS")
			(effects
				(font
					(size 0.7874 0.5842)
					(thickness 0.1524)
				)
				(justify left)
			)
		)
		(property "Value" ""
			(at 0 0 90)
			(layer "F.Fab")
			(effects
				(font
					(size 1.27 1.27)
				)
			)
		)
		(duplicate_pad_numbers_are_jumpers no)
		(fp_line
			(start 0.7874 -0.4064)
			(end 0.7874 0.4064)
			(stroke
				(width 0.1524)
				(type default)
			)
			(layer "F.SilkS")
		)
		(fp_line
			(start -0.7874 -0.4064)
			(end 0.7874 -0.4064)
			(stroke
				(width 0.1524)
				(type default)
			)
			(layer "F.SilkS")
		)
		(fp_line
			(start 0 0.381)
			(end 0 -0.381)
			(stroke
				(width 0.1524)
				(type default)
			)
			(layer "F.SilkS")
		)
		(fp_line
			(start 0.7874 0.4064)
			(end -0.7874 0.4064)
			(stroke
				(width 0.1524)
				(type default)
			)
			(layer "F.SilkS")
		)
		(fp_line
			(start -0.7874 0.4064)
			(end -0.7874 -0.4064)
			(stroke
				(width 0.1524)
				(type default)
			)
			(layer "F.SilkS")
		)
		(fp_poly
			(pts
				(xy -0.5334 0.254) (xy -0.635 0.254) (xy -0.635 0.2286) (xy -0.635 -0.254) (xy -0.5334 -0.254) (xy -0.5334 -0.2794)
				(xy 0.5334 -0.2794) (xy 0.5334 -0.254) (xy 0.635 -0.254) (xy 0.635 0.254) (xy 0.5334 0.254) (xy 0.5334 0.2794)
				(xy -0.508 0.2794) (xy -0.5334 0.2794)
			)
			(stroke
				(width 0)
				(type default)
			)
			(fill no)
			(layer "F.CrtYd")
		)
		(pad "1" smd rect
			(at 0.40005 0 90)
			(size 0.4572 0.508)
			(layers "F.Cu" "F.Mask" "F.Paste")
			(net "UART_T12_NODE3_TXD_R")
		)
		(pad "2" smd rect
			(at -0.40005 0 90)
			(size 0.4572 0.508)
			(layers "F.Cu" "F.Mask" "F.Paste")
			(net "GND")
		)
	)
	(footprint ""
		(layer "F.Cu")
		(at 94.451932 -171.250356)
		(property "Reference" "R758"
			(at 86.67369 74.174096 0)
			(unlocked yes)
			(layer "F.SilkS")
			(effects
				(font
					(size 0.7874 0.5842)
					(thickness 0.1524)
				)
				(justify left)
			)
		)
		(property "Value" ""
			(at 0 0 0)
			(layer "F.Fab")
			(effects
				(font
					(size 1.27 1.27)
				)
			)
		)
		(duplicate_pad_numbers_are_jumpers no)
		(fp_line
			(start -0.7874 -0.4064)
			(end 0.7874 -0.4064)
			(stroke
				(width 0.1524)
				(type default)
			)
			(layer "F.SilkS")
		)
		(fp_line
			(start -0.7874 0.4064)
			(end -0.7874 -0.4064)
			(stroke
				(width 0.1524)
				(type default)
			)
			(layer "F.SilkS")
		)
		(fp_line
			(start 0.7874 -0.4064)
			(end 0.7874 0.4064)
			(stroke
				(width 0.1524)
				(type default)
			)
			(layer "F.SilkS")
		)
		(fp_line
			(start 0.7874 0.4064)
			(end -0.7874 0.4064)
			(stroke
				(width 0.1524)
				(type default)
			)
			(layer "F.SilkS")
		)
		(fp_poly
			(pts
				(xy -0.508 0.2794) (xy -0.508 0.2286) (xy -0.635 0.2286) (xy -0.635 -0.254) (xy -0.5334 -0.254)
				(xy -0.5334 -0.2794) (xy 0.5334 -0.2794) (xy 0.5334 -0.254) (xy 0.635 -0.254) (xy 0.635 0.254) (xy 0.5334 0.254)
				(xy 0.5334 0.2794)
			)
			(stroke
				(width 0)
				(type default)
			)
			(fill no)
			(layer "F.CrtYd")
		)
		(pad "1" smd rect
			(at 0.40005 0)
			(size 0.4572 0.508)
			(layers "F.Cu" "F.Mask" "F.Paste")
			(net "FAN3_TACH_IN")
		)
		(pad "2" smd rect
			(at -0.40005 0)
			(size 0.4572 0.508)
			(layers "F.Cu" "F.Mask" "F.Paste")
			(net "FAN3_TACH")
		)
	)
	(footprint ""
		(layer "F.Cu")
		(at 66.53276 -188.126624 90)
		(property "Reference" "C640"
			(at 4.548886 -0.4445 90)
			(unlocked yes)
			(layer "F.SilkS")
			(effects
				(font
					(size 0.7874 0.5842)
					(thickness 0.1524)
				)
				(justify left)
			)
		)
		(property "Value" ""
			(at 0 0 90)
			(layer "F.Fab")
			(effects
				(font
					(size 1.27 1.27)
				)
			)
		)
		(duplicate_pad_numbers_are_jumpers no)
		(fp_line
			(start 0.7874 -0.4064)
			(end 0.7874 0.4064)
			(stroke
				(width 0.1524)
				(type default)
			)
			(layer "F.SilkS")
		)
		(fp_line
			(start -0.7874 -0.4064)
			(end 0.7874 -0.4064)
			(stroke
				(width 0.1524)
				(type default)
			)
			(layer "F.SilkS")
		)
		(fp_line
			(start 0 0.381)
			(end 0 -0.381)
			(stroke
				(width 0.1524)
				(type default)
			)
			(layer "F.SilkS")
		)
		(fp_line
			(start 0.7874 0.4064)
			(end -0.7874 0.4064)
			(stroke
				(width 0.1524)
				(type default)
			)
			(layer "F.SilkS")
		)
		(fp_line
			(start -0.7874 0.4064)
			(end -0.7874 -0.4064)
			(stroke
				(width 0.1524)
				(type default)
			)
			(layer "F.SilkS")
		)
		(fp_poly
			(pts
				(xy -0.5334 0.254) (xy -0.635 0.254) (xy -0.635 0.2286) (xy -0.635 -0.254) (xy -0.5334 -0.254) (xy -0.5334 -0.2794)
				(xy 0.5334 -0.2794) (xy 0.5334 -0.254) (xy 0.635 -0.254) (xy 0.635 0.254) (xy 0.5334 0.254) (xy 0.5334 0.2794)
				(xy -0.508 0.2794) (xy -0.5334 0.2794)
			)
			(stroke
				(width 0)
				(type default)
			)
			(fill no)
			(layer "F.CrtYd")
		)
		(pad "1" smd rect
			(at 0.40005 0 90)
			(size 0.4572 0.508)
			(layers "F.Cu" "F.Mask" "F.Paste")
			(net "T2_NODE3_EN_R")
		)
		(pad "2" smd rect
			(at -0.40005 0 90)
			(size 0.4572 0.508)
			(layers "F.Cu" "F.Mask" "F.Paste")
			(net "GND")
		)
	)
	(footprint ""
		(layer "F.Cu")
		(at 88.12276 -188.126624 90)
		(property "Reference" "C711"
			(at 4.548886 -1.93802 90)
			(unlocked yes)
			(layer "F.SilkS")
			(effects
				(font
					(size 0.7874 0.5842)
					(thickness 0.1524)
				)
				(justify left)
			)
		)
		(property "Value" ""
			(at 0 0 90)
			(layer "F.Fab")
			(effects
				(font
					(size 1.27 1.27)
				)
			)
		)
		(duplicate_pad_numbers_are_jumpers no)
		(fp_line
			(start 0.7874 -0.4064)
			(end 0.7874 0.4064)
			(stroke
				(width 0.1524)
				(type default)
			)
			(layer "F.SilkS")
		)
		(fp_line
			(start -0.7874 -0.4064)
			(end 0.7874 -0.4064)
			(stroke
				(width 0.1524)
				(type default)
			)
			(layer "F.SilkS")
		)
		(fp_line
			(start 0 0.381)
			(end 0 -0.381)
			(stroke
				(width 0.1524)
				(type default)
			)
			(layer "F.SilkS")
		)
		(fp_line
			(start 0.7874 0.4064)
			(end -0.7874 0.4064)
			(stroke
				(width 0.1524)
				(type default)
			)
			(layer "F.SilkS")
		)
		(fp_line
			(start -0.7874 0.4064)
			(end -0.7874 -0.4064)
			(stroke
				(width 0.1524)
				(type default)
			)
			(layer "F.SilkS")
		)
		(fp_poly
			(pts
				(xy -0.5334 0.254) (xy -0.635 0.254) (xy -0.635 0.2286) (xy -0.635 -0.254) (xy -0.5334 -0.254) (xy -0.5334 -0.2794)
				(xy 0.5334 -0.2794) (xy 0.5334 -0.254) (xy 0.635 -0.254) (xy 0.635 0.254) (xy 0.5334 0.254) (xy 0.5334 0.2794)
				(xy -0.508 0.2794) (xy -0.5334 0.2794)
			)
			(stroke
				(width 0)
				(type default)
			)
			(fill no)
			(layer "F.CrtYd")
		)
		(pad "1" smd rect
			(at 0.40005 0 90)
			(size 0.4572 0.508)
			(layers "F.Cu" "F.Mask" "F.Paste")
			(net "UART_T6_NODE3_TXD_R")
		)
		(pad "2" smd rect
			(at -0.40005 0 90)
			(size 0.4572 0.508)
			(layers "F.Cu" "F.Mask" "F.Paste")
			(net "GND")
		)
	)
	(footprint ""
		(layer "F.Cu")
		(at 43.233086 -134.963662)
		(property "Reference" "U15"
			(at -7.777734 -0.440436 90)
			(unlocked yes)
			(layer "F.SilkS")
			(effects
				(font
					(size 0.7874 0.5842)
					(thickness 0.1524)
				)
				(justify left)
			)
		)
		(property "Value" ""
			(at 0 0 0)
			(layer "F.Fab")
			(effects
				(font
					(size 1.27 1.27)
				)
			)
		)
		(duplicate_pad_numbers_are_jumpers no)
		(fp_line
			(start -6.999986 -9.700006)
			(end 6.599936 -9.700006)
			(stroke
				(width 0.1524)
				(type default)
			)
			(layer "F.SilkS")
		)
		(fp_line
			(start -6.999986 9.700006)
			(end -6.999986 -9.700006)
			(stroke
				(width 0.1524)
				(type default)
			)
			(layer "F.SilkS")
		)
		(fp_line
			(start -3.999992 -6.700012)
			(end 3.599942 -6.700012)
			(stroke
				(width 0.1524)
				(type default)
			)
			(layer "F.SilkS")
		)
		(fp_line
			(start -3.999992 6.700012)
			(end -3.999992 -6.700012)
			(stroke
				(width 0.1524)
				(type default)
			)
			(layer "F.SilkS")
		)
		(fp_line
			(start 3.599942 -6.700012)
			(end 3.599942 6.700012)
			(stroke
				(width 0.1524)
				(type default)
			)
			(layer "F.SilkS")
		)
		(fp_line
			(start 3.599942 6.700012)
			(end -3.999992 6.700012)
			(stroke
				(width 0.1524)
				(type default)
			)
			(layer "F.SilkS")
		)
		(fp_line
			(start 6.599936 -9.700006)
			(end 6.599936 -2.22758)
			(stroke
				(width 0.1524)
				(type default)
			)
			(layer "F.SilkS")
		)
		(fp_line
			(start 6.599936 -1.46558)
			(end 6.599936 3.23342)
			(stroke
				(width 0.1524)
				(type default)
			)
			(layer "F.SilkS")
		)
		(fp_line
			(start 6.599936 4.88442)
			(end 6.599936 9.700006)
			(stroke
				(width 0.1524)
				(type default)
			)
			(layer "F.SilkS")
		)
		(fp_line
			(start 6.599936 9.700006)
			(end -6.999986 9.700006)
			(stroke
				(width 0.1524)
				(type default)
			)
			(layer "F.SilkS")
		)
		(fp_poly
			(pts
				(xy -6.98119 -9.7536) (xy -3.19405 -9.7536) (xy -3.19405 -9.70534) (xy -4.44119 -8.4582) (xy -2.76352 -6.78053)
				(xy -2.78765 -6.7564) (xy -4.00939 -6.7564) (xy -4.00939 -5.5626) (xy -4.04749 -5.5245) (xy -5.71119 -7.1882)
				(xy -6.95579 -5.9436) (xy -6.98119 -5.969)
			)
			(stroke
				(width 0)
				(type default)
			)
			(fill yes)
			(layer "F.SilkS")
		)
		(fp_rect
			(start -3.999992 6.700012)
			(end 3.599942 -6.700012)
			(stroke
				(width 0)
				(type default)
			)
			(fill no)
			(layer "F.CrtYd")
		)
		(fp_line
			(start -3.999992 -6.700012)
			(end 3.599942 -6.700012)
			(stroke
				(width 0.1)
				(type default)
			)
			(layer "F.Fab")
		)
		(fp_line
			(start -3.999992 6.700012)
			(end -3.999992 -6.700012)
			(stroke
				(width 0.1)
				(type default)
			)
			(layer "F.Fab")
		)
		(fp_line
			(start 3.599942 -6.700012)
			(end 3.599942 6.700012)
			(stroke
				(width 0.1)
				(type default)
			)
			(layer "F.Fab")
		)
		(fp_line
			(start 3.599942 6.700012)
			(end -3.999992 6.700012)
			(stroke
				(width 0.1)
				(type default)
			)
			(layer "F.Fab")
		)
		(fp_text user "G"
			(at -6.331204 0.359156 0)
			(unlocked yes)
			(layer "F.SilkS")
			(effects
				(font
					(size 0.7874 0.5842)
					(thickness 0.1524)
				)
				(justify left)
			)
		)
		(fp_text user "J"
			(at -6.331204 1.959102 0)
			(unlocked yes)
			(layer "F.SilkS")
			(effects
				(font
					(size 0.7874 0.5842)
					(thickness 0.1524)
				)
				(justify left)
			)
		)
		(fp_text user "L"
			(at -6.331204 3.559302 0)
			(unlocked yes)
			(layer "F.SilkS")
			(effects
				(font
					(size 0.7874 0.5842)
					(thickness 0.1524)
				)
				(justify left)
			)
		)
		(fp_text user "N"
			(at -6.331204 5.159248 0)
			(unlocked yes)
			(layer "F.SilkS")
			(effects
				(font
					(size 0.7874 0.5842)
					(thickness 0.1524)
				)
				(justify left)
			)
		)
		(fp_text user "R"
			(at -6.331204 6.759194 0)
			(unlocked yes)
			(layer "F.SilkS")
			(effects
				(font
					(size 0.7874 0.5842)
					(thickness 0.1524)
				)
				(justify left)
			)
		)
		(fp_text user "A"
			(at -6.077204 -6.091936 0)
			(unlocked yes)
			(layer "F.SilkS")
			(effects
				(font
					(size 0.7874 0.5842)
					(thickness 0.1524)
				)
				(justify left)
			)
		)
		(fp_text user "E"
			(at -6.077204 -2.89179 0)
			(unlocked yes)
			(layer "F.SilkS")
			(effects
				(font
					(size 0.7874 0.5842)
					(thickness 0.1524)
				)
				(justify left)
			)
		)
		(fp_text user "C"
			(at -6.037834 -4.99491 0)
			(unlocked yes)
			(layer "F.SilkS")
			(effects
				(font
					(size 0.7874 0.5842)
					(thickness 0.1524)
				)
				(justify left)
			)
		)
		(fp_text user "T"
			(at -5.011928 6.299708 0)
			(unlocked yes)
			(layer "F.SilkS")
			(effects
				(font
					(size 0.7874 0.5842)
					(thickness 0.1524)
				)
				(justify left)
			)
		)
		(fp_text user "H"
			(at -5.004054 -0.237744 0)
			(unlocked yes)
			(layer "F.SilkS")
			(effects
				(font
					(size 0.7874 0.5842)
					(thickness 0.1524)
				)
				(justify left)
			)
		)
		(fp_text user "K"
			(at -5.004054 1.362202 0)
			(unlocked yes)
			(layer "F.SilkS")
			(effects
				(font
					(size 0.7874 0.5842)
					(thickness 0.1524)
				)
				(justify left)
			)
		)
		(fp_text user "M"
			(at -5.004054 2.962148 0)
			(unlocked yes)
			(layer "F.SilkS")
			(effects
				(font
					(size 0.7874 0.5842)
					(thickness 0.1524)
				)
				(justify left)
			)
		)
		(fp_text user "P"
			(at -5.004054 4.562094 0)
			(unlocked yes)
			(layer "F.SilkS")
			(effects
				(font
					(size 0.7874 0.5842)
					(thickness 0.1524)
				)
				(justify left)
			)
		)
		(fp_text user "B"
			(at -4.877054 -5.291836 0)
			(unlocked yes)
			(layer "F.SilkS")
			(effects
				(font
					(size 0.7874 0.5842)
					(thickness 0.1524)
				)
				(justify left)
			)
		)
		(fp_text user "D"
			(at -4.877054 -3.69189 0)
			(unlocked yes)
			(layer "F.SilkS")
			(effects
				(font
					(size 0.7874 0.5842)
					(thickness 0.1524)
				)
				(justify left)
			)
		)
		(fp_text user "F"
			(at -4.877054 -2.091944 0)
			(unlocked yes)
			(layer "F.SilkS")
			(effects
				(font
					(size 0.7874 0.5842)
					(thickness 0.1524)
				)
				(justify left)
			)
		)
		(fp_text user "1"
			(at -3.491992 -8.600694 0)
			(unlocked yes)
			(layer "F.SilkS")
			(effects
				(font
					(size 0.7874 0.5842)
					(thickness 0.1524)
				)
				(justify left)
			)
		)
		(fp_text user "2"
			(at -2.692146 -7.457694 0)
			(unlocked yes)
			(layer "F.SilkS")
			(effects
				(font
					(size 0.7874 0.5842)
					(thickness 0.1524)
				)
				(justify left)
			)
		)
		(fp_text user "3"
			(at -1.892046 -8.600694 0)
			(unlocked yes)
			(layer "F.SilkS")
			(effects
				(font
					(size 0.7874 0.5842)
					(thickness 0.1524)
				)
				(justify left)
			)
		)
		(fp_text user "4"
			(at -1.0922 -7.457694 0)
			(unlocked yes)
			(layer "F.SilkS")
			(effects
				(font
					(size 0.7874 0.5842)
					(thickness 0.1524)
				)
				(justify left)
			)
		)
		(fp_text user "5"
			(at -0.2921 -8.600694 0)
			(unlocked yes)
			(layer "F.SilkS")
			(effects
				(font
					(size 0.7874 0.5842)
					(thickness 0.1524)
				)
				(justify left)
			)
		)
		(fp_text user "6"
			(at 0.508 -7.457694 0)
			(unlocked yes)
			(layer "F.SilkS")
			(effects
				(font
					(size 0.7874 0.5842)
					(thickness 0.1524)
				)
				(justify left)
			)
		)
		(fp_text user "7"
			(at 1.307846 -8.600694 0)
			(unlocked yes)
			(layer "F.SilkS")
			(effects
				(font
					(size 0.7874 0.5842)
					(thickness 0.1524)
				)
				(justify left)
			)
		)
		(fp_text user "8"
			(at 2.107946 -7.457694 0)
			(unlocked yes)
			(layer "F.SilkS")
			(effects
				(font
					(size 0.7874 0.5842)
					(thickness 0.1524)
				)
				(justify left)
			)
		)
		(fp_text user "9"
			(at 2.907792 -8.600694 0)
			(unlocked yes)
			(layer "F.SilkS")
			(effects
				(font
					(size 0.7874 0.5842)
					(thickness 0.1524)
				)
				(justify left)
			)
		)
		(fp_text user "A"
			(at -6.077204 -6.091936 0)
			(unlocked yes)
			(layer "F.Fab")
			(effects
				(font
					(size 0.7874 0.5842)
					(thickness 0.000001)
				)
				(justify left)
			)
		)
		(fp_text user "T"
			(at -4.884928 6.045708 0)
			(unlocked yes)
			(layer "F.Fab")
			(effects
				(font
					(size 0.7874 0.5842)
					(thickness 0.000001)
				)
				(justify left)
			)
		)
		(fp_text user "1"
			(at -3.491992 -8.473694 0)
			(unlocked yes)
			(layer "F.Fab")
			(effects
				(font
					(size 0.7874 0.5842)
					(thickness 0.000001)
				)
				(justify left)
			)
		)
		(fp_text user "9"
			(at 2.907792 -8.473694 0)
			(unlocked yes)
			(layer "F.Fab")
			(effects
				(font
					(size 0.7874 0.5842)
					(thickness 0.000001)
				)
				(justify left)
			)
		)
		(pad "A1" smd circle
			(at -3.199892 -5.999988)
			(size 0.3683 0.3683)
			(layers "F.Cu" "F.Mask" "F.Paste")
			(net "P1V538_BMC_NODE1")
		)
		(pad "A2" smd circle
			(at -2.400046 -5.999988)
			(size 0.3683 0.3683)
			(layers "F.Cu" "F.Mask" "F.Paste")
			(net "BMC_NODE1_DDR_D15")
		)
		(pad "A3" smd circle
			(at -1.599946 -5.999988)
			(size 0.3683 0.3683)
			(layers "F.Cu" "F.Mask" "F.Paste")
			(net "BMC_NODE1_DDR_D14")
		)
		(pad "A7" smd circle
			(at 1.599946 -5.999988)
			(size 0.3683 0.3683)
			(layers "F.Cu" "F.Mask" "F.Paste")
			(net "BMC_NODE1_DDR_D10")
		)
		(pad "A8" smd circle
			(at 2.400046 -5.999988)
			(size 0.3683 0.3683)
			(layers "F.Cu" "F.Mask" "F.Paste")
			(net "P1V538_BMC_NODE1")
		)
		(pad "A9" smd circle
			(at 3.199892 -5.999988)
			(size 0.3683 0.3683)
			(layers "F.Cu" "F.Mask" "F.Paste")
			(net "GND")
		)
		(pad "B1" smd circle
			(at -3.199892 -5.199888)
			(size 0.3683 0.3683)
			(layers "F.Cu" "F.Mask" "F.Paste")
			(net "GND")
		)
		(pad "B2" smd circle
			(at -2.400046 -5.199888)
			(size 0.3683 0.3683)
			(layers "F.Cu" "F.Mask" "F.Paste")
			(net "P1V538_BMC_NODE1")
		)
		(pad "B3" smd circle
			(at -1.599946 -5.199888)
			(size 0.3683 0.3683)
			(layers "F.Cu" "F.Mask" "F.Paste")
			(net "GND")
		)
		(pad "B7" smd circle
			(at 1.599946 -5.199888)
			(size 0.3683 0.3683)
			(layers "F.Cu" "F.Mask" "F.Paste")
			(net "BMC_NODE1_DDR_DQS1_DN")
		)
		(pad "B8" smd circle
			(at 2.400046 -5.199888)
			(size 0.3683 0.3683)
			(layers "F.Cu" "F.Mask" "F.Paste")
			(net "BMC_NODE1_DDR_D9")
		)
		(pad "B9" smd circle
			(at 3.199892 -5.199888)
			(size 0.3683 0.3683)
			(layers "F.Cu" "F.Mask" "F.Paste")
			(net "GND")
		)
		(pad "C1" smd circle
			(at -3.199892 -4.400042)
			(size 0.3683 0.3683)
			(layers "F.Cu" "F.Mask" "F.Paste")
			(net "P1V538_BMC_NODE1")
		)
		(pad "C2" smd circle
			(at -2.400046 -4.400042)
			(size 0.3683 0.3683)
			(layers "F.Cu" "F.Mask" "F.Paste")
			(net "BMC_NODE1_DDR_D12")
		)
		(pad "C3" smd circle
			(at -1.599946 -4.400042)
			(size 0.3683 0.3683)
			(layers "F.Cu" "F.Mask" "F.Paste")
			(net "BMC_NODE1_DDR_D11")
		)
		(pad "C7" smd circle
			(at 1.599946 -4.400042)
			(size 0.3683 0.3683)
			(layers "F.Cu" "F.Mask" "F.Paste")
			(net "BMC_NODE1_DDR_DQS1_DP")
		)
		(pad "C8" smd circle
			(at 2.400046 -4.400042)
			(size 0.3683 0.3683)
			(layers "F.Cu" "F.Mask" "F.Paste")
			(net "BMC_NODE1_DDR_D13")
		)
		(pad "C9" smd circle
			(at 3.199892 -4.400042)
			(size 0.3683 0.3683)
			(layers "F.Cu" "F.Mask" "F.Paste")
			(net "P1V538_BMC_NODE1")
		)
		(pad "D1" smd circle
			(at -3.199892 -3.599942)
			(size 0.3683 0.3683)
			(layers "F.Cu" "F.Mask" "F.Paste")
			(net "GND")
		)
		(pad "D2" smd circle
			(at -2.400046 -3.599942)
			(size 0.3683 0.3683)
			(layers "F.Cu" "F.Mask" "F.Paste")
			(net "P1V538_BMC_NODE1")
		)
		(pad "D3" smd circle
			(at -1.599946 -3.599942)
			(size 0.3683 0.3683)
			(layers "F.Cu" "F.Mask" "F.Paste")
			(net "BMC_NODE1_DDR_DM1")
		)
		(pad "D7" smd circle
			(at 1.599946 -3.599942)
			(size 0.3683 0.3683)
			(layers "F.Cu" "F.Mask" "F.Paste")
			(net "BMC_NODE1_DDR_D8")
		)
		(pad "D8" smd circle
			(at 2.400046 -3.599942)
			(size 0.3683 0.3683)
			(layers "F.Cu" "F.Mask" "F.Paste")
			(net "GND")
		)
		(pad "D9" smd circle
			(at 3.199892 -3.599942)
			(size 0.3683 0.3683)
			(layers "F.Cu" "F.Mask" "F.Paste")
			(net "P1V538_BMC_NODE1")
		)
		(pad "E1" smd circle
			(at -3.199892 -2.800096)
			(size 0.3683 0.3683)
			(layers "F.Cu" "F.Mask" "F.Paste")
			(net "GND")
		)
		(pad "E2" smd circle
			(at -2.400046 -2.800096)
			(size 0.3683 0.3683)
			(layers "F.Cu" "F.Mask" "F.Paste")
			(net "GND")
		)
		(pad "E3" smd circle
			(at -1.599946 -2.800096)
			(size 0.3683 0.3683)
			(layers "F.Cu" "F.Mask" "F.Paste")
			(net "BMC_NODE1_DDR_D7")
		)
		(pad "E7" smd circle
			(at 1.599946 -2.800096)
			(size 0.3683 0.3683)
			(layers "F.Cu" "F.Mask" "F.Paste")
			(net "BMC_NODE1_DDR_DM0")
		)
		(pad "E8" smd circle
			(at 2.400046 -2.800096)
			(size 0.3683 0.3683)
			(layers "F.Cu" "F.Mask" "F.Paste")
			(net "GND")
		)
		(pad "E9" smd circle
			(at 3.199892 -2.800096)
			(size 0.3683 0.3683)
			(layers "F.Cu" "F.Mask" "F.Paste")
			(net "P1V538_BMC_NODE1")
		)
		(pad "F1" smd circle
			(at -3.199892 -1.999996)
			(size 0.3683 0.3683)
			(layers "F.Cu" "F.Mask" "F.Paste")
			(net "P1V538_BMC_NODE1")
		)
		(pad "F2" smd circle
			(at -2.400046 -1.999996)
			(size 0.3683 0.3683)
			(layers "F.Cu" "F.Mask" "F.Paste")
			(net "BMC_NODE1_DDR_D4")
		)
		(pad "F3" smd circle
			(at -1.599946 -1.999996)
			(size 0.3683 0.3683)
			(layers "F.Cu" "F.Mask" "F.Paste")
			(net "BMC_NODE1_DDR_DQS0_DP")
		)
		(pad "F7" smd circle
			(at 1.599946 -1.999996)
			(size 0.3683 0.3683)
			(layers "F.Cu" "F.Mask" "F.Paste")
			(net "BMC_NODE1_DDR_D3")
		)
		(pad "F8" smd circle
			(at 2.400046 -1.999996)
			(size 0.3683 0.3683)
			(layers "F.Cu" "F.Mask" "F.Paste")
			(net "BMC_NODE1_DDR_D2")
		)
		(pad "F9" smd circle
			(at 3.199892 -1.999996)
			(size 0.3683 0.3683)
			(layers "F.Cu" "F.Mask" "F.Paste")
			(net "GND")
		)
		(pad "G1" smd circle
			(at -3.199892 -1.199896)
			(size 0.3683 0.3683)
			(layers "F.Cu" "F.Mask" "F.Paste")
			(net "GND")
		)
		(pad "G2" smd circle
			(at -2.400046 -1.199896)
			(size 0.3683 0.3683)
			(layers "F.Cu" "F.Mask" "F.Paste")
			(net "BMC_NODE1_DDR_D5")
		)
		(pad "G3" smd circle
			(at -1.599946 -1.199896)
			(size 0.3683 0.3683)
			(layers "F.Cu" "F.Mask" "F.Paste")
			(net "BMC_NODE1_DDR_DQS0_DN")
		)
		(pad "G7" smd circle
			(at 1.599946 -1.199896)
			(size 0.3683 0.3683)
			(layers "F.Cu" "F.Mask" "F.Paste")
			(net "P1V538_BMC_NODE1")
		)
		(pad "G8" smd circle
			(at 2.400046 -1.199896)
			(size 0.3683 0.3683)
			(layers "F.Cu" "F.Mask" "F.Paste")
			(net "GND")
		)
		(pad "G9" smd circle
			(at 3.199892 -1.199896)
			(size 0.3683 0.3683)
			(layers "F.Cu" "F.Mask" "F.Paste")
			(net "GND")
		)
		(pad "H1" smd circle
			(at -3.199892 -0.40005)
			(size 0.3683 0.3683)
			(layers "F.Cu" "F.Mask" "F.Paste")
			(net "P0V75_BMC_VTTREF_NODE1")
		)
		(pad "H2" smd circle
			(at -2.400046 -0.40005)
			(size 0.3683 0.3683)
			(layers "F.Cu" "F.Mask" "F.Paste")
			(net "P1V538_BMC_NODE1")
		)
		(pad "H3" smd circle
			(at -1.599946 -0.40005)
			(size 0.3683 0.3683)
			(layers "F.Cu" "F.Mask" "F.Paste")
			(net "BMC_NODE1_DDR_D1")
		)
		(pad "H7" smd circle
			(at 1.599946 -0.40005)
			(size 0.3683 0.3683)
			(layers "F.Cu" "F.Mask" "F.Paste")
			(net "BMC_NODE1_DDR_D0")
		)
		(pad "H8" smd circle
			(at 2.400046 -0.40005)
			(size 0.3683 0.3683)
			(layers "F.Cu" "F.Mask" "F.Paste")
			(net "BMC_NODE1_DDR_D6")
		)
		(pad "H9" smd circle
			(at 3.199892 -0.40005)
			(size 0.3683 0.3683)
			(layers "F.Cu" "F.Mask" "F.Paste")
			(net "P1V538_BMC_NODE1")
		)
		(pad "J1" smd circle
			(at -3.199892 0.40005)
			(size 0.3683 0.3683)
			(layers "F.Cu" "F.Mask" "F.Paste")
			(net "TP_BMC_NODE1_DDR3_ODT_1NC")
		)
		(pad "J2" smd circle
			(at -2.400046 0.40005)
			(size 0.3683 0.3683)
			(layers "F.Cu" "F.Mask" "F.Paste")
			(net "GND")
		)
		(pad "J3" smd circle
			(at -1.599946 0.40005)
			(size 0.3683 0.3683)
			(layers "F.Cu" "F.Mask" "F.Paste")
			(net "BMC_NODE1_DDR_RAS_L")
		)
		(pad "J7" smd circle
			(at 1.599946 0.40005)
			(size 0.3683 0.3683)
			(layers "F.Cu" "F.Mask" "F.Paste")
			(net "BMC_NODE1_DDR_CLK_DP")
		)
		(pad "J8" smd circle
			(at 2.400046 0.40005)
			(size 0.3683 0.3683)
			(layers "F.Cu" "F.Mask" "F.Paste")
			(net "GND")
		)
		(pad "J9" smd circle
			(at 3.199892 0.40005)
			(size 0.3683 0.3683)
			(layers "F.Cu" "F.Mask" "F.Paste")
			(net "TP_BMC_NODE1_DDR3_CE1_NC1")
		)
		(pad "K1" smd circle
			(at -3.199892 1.199896)
			(size 0.3683 0.3683)
			(layers "F.Cu" "F.Mask" "F.Paste")
			(net "BMC_NODE1_DDR_ODT")
		)
		(pad "K2" smd circle
			(at -2.400046 1.199896)
			(size 0.3683 0.3683)
			(layers "F.Cu" "F.Mask" "F.Paste")
			(net "P1V538_BMC_NODE1")
		)
		(pad "K3" smd circle
			(at -1.599946 1.199896)
			(size 0.3683 0.3683)
			(layers "F.Cu" "F.Mask" "F.Paste")
			(net "BMC_NODE1_DDR_CAS_L")
		)
		(pad "K7" smd circle
			(at 1.599946 1.199896)
			(size 0.3683 0.3683)
			(layers "F.Cu" "F.Mask" "F.Paste")
			(net "BMC_NODE1_DDR_CLK_DN")
		)
		(pad "K8" smd circle
			(at 2.400046 1.199896)
			(size 0.3683 0.3683)
			(layers "F.Cu" "F.Mask" "F.Paste")
			(net "P1V538_BMC_NODE1")
		)
		(pad "K9" smd circle
			(at 3.199892 1.199896)
			(size 0.3683 0.3683)
			(layers "F.Cu" "F.Mask" "F.Paste")
			(net "BMC_NODE1_DDR_CKE")
		)
		(pad "L1" smd circle
			(at -3.199892 1.999996)
			(size 0.3683 0.3683)
			(layers "F.Cu" "F.Mask" "F.Paste")
			(net "TP_BMC_NODE1_DDR3_CS1_L")
		)
		(pad "L2" smd circle
			(at -2.400046 1.999996)
			(size 0.3683 0.3683)
			(layers "F.Cu" "F.Mask" "F.Paste")
			(net "BMC_NODE1_DDR_CS_L")
		)
		(pad "L3" smd circle
			(at -1.599946 1.999996)
			(size 0.3683 0.3683)
			(layers "F.Cu" "F.Mask" "F.Paste")
			(net "BMC_NODE1_DDR_WE_L")
		)
		(pad "L7" smd circle
			(at 1.599946 1.999996)
			(size 0.3683 0.3683)
			(layers "F.Cu" "F.Mask" "F.Paste")
			(net "BMC_NODE1_DDR_MA10")
		)
		(pad "L8" smd circle
			(at 2.400046 1.999996)
			(size 0.3683 0.3683)
			(layers "F.Cu" "F.Mask" "F.Paste")
			(net "BMC_NODE1_DDR3_ZQ")
		)
		(pad "L9" smd circle
			(at 3.199892 1.999996)
			(size 0.3683 0.3683)
			(layers "F.Cu" "F.Mask" "F.Paste")
			(net "TP_BMC_NODE1_DDR3_ZQ1")
		)
		(pad "M1" smd circle
			(at -3.199892 2.800096)
			(size 0.3683 0.3683)
			(layers "F.Cu" "F.Mask" "F.Paste")
			(net "GND")
		)
		(pad "M2" smd circle
			(at -2.400046 2.800096)
			(size 0.3683 0.3683)
			(layers "F.Cu" "F.Mask" "F.Paste")
			(net "BMC_NODE1_DDR_BA0")
		)
		(pad "M3" smd circle
			(at -1.599946 2.800096)
			(size 0.3683 0.3683)
			(layers "F.Cu" "F.Mask" "F.Paste")
			(net "BMC_NODE1_DDR_BA2")
		)
		(pad "M7" smd circle
			(at 1.599946 2.800096)
			(size 0.3683 0.3683)
			(layers "F.Cu" "F.Mask" "F.Paste")
			(net "TP_BMC_NODE1_DDR3_MA15")
		)
		(pad "M8" smd circle
			(at 2.400046 2.800096)
			(size 0.3683 0.3683)
			(layers "F.Cu" "F.Mask" "F.Paste")
			(net "P0V75_BMC_VTTREF_NODE1")
		)
		(pad "M9" smd circle
			(at 3.199892 2.800096)
			(size 0.3683 0.3683)
			(layers "F.Cu" "F.Mask" "F.Paste")
			(net "GND")
		)
		(pad "N1" smd circle
			(at -3.199892 3.599942)
			(size 0.3683 0.3683)
			(layers "F.Cu" "F.Mask" "F.Paste")
			(net "P1V538_BMC_NODE1")
		)
		(pad "N2" smd circle
			(at -2.400046 3.599942)
			(size 0.3683 0.3683)
			(layers "F.Cu" "F.Mask" "F.Paste")
			(net "BMC_NODE1_DDR_MA3")
		)
		(pad "N3" smd circle
			(at -1.599946 3.599942)
			(size 0.3683 0.3683)
			(layers "F.Cu" "F.Mask" "F.Paste")
			(net "BMC_NODE1_DDR_MA0")
		)
		(pad "N7" smd circle
			(at 1.599946 3.599942)
			(size 0.3683 0.3683)
			(layers "F.Cu" "F.Mask" "F.Paste")
			(net "BMC_NODE1_DDR_MA12")
		)
		(pad "N8" smd circle
			(at 2.400046 3.599942)
			(size 0.3683 0.3683)
			(layers "F.Cu" "F.Mask" "F.Paste")
			(net "BMC_NODE1_DDR_BA1")
		)
		(pad "N9" smd circle
			(at 3.199892 3.599942)
			(size 0.3683 0.3683)
			(layers "F.Cu" "F.Mask" "F.Paste")
			(net "P1V538_BMC_NODE1")
		)
		(pad "P1" smd circle
			(at -3.199892 4.400042)
			(size 0.3683 0.3683)
			(layers "F.Cu" "F.Mask" "F.Paste")
			(net "GND")
		)
		(pad "P2" smd circle
			(at -2.400046 4.400042)
			(size 0.3683 0.3683)
			(layers "F.Cu" "F.Mask" "F.Paste")
			(net "BMC_NODE1_DDR_MA5")
		)
		(pad "P3" smd circle
			(at -1.599946 4.400042)
			(size 0.3683 0.3683)
			(layers "F.Cu" "F.Mask" "F.Paste")
			(net "BMC_NODE1_DDR_MA2")
		)
		(pad "P7" smd circle
			(at 1.599946 4.400042)
			(size 0.3683 0.3683)
			(layers "F.Cu" "F.Mask" "F.Paste")
			(net "BMC_NODE1_DDR_MA1")
		)
		(pad "P8" smd circle
			(at 2.400046 4.400042)
			(size 0.3683 0.3683)
			(layers "F.Cu" "F.Mask" "F.Paste")
			(net "BMC_NODE1_DDR_MA4")
		)
		(pad "P9" smd circle
			(at 3.199892 4.400042)
			(size 0.3683 0.3683)
			(layers "F.Cu" "F.Mask" "F.Paste")
			(net "GND")
		)
		(pad "R1" smd circle
			(at -3.199892 5.199888)
			(size 0.3683 0.3683)
			(layers "F.Cu" "F.Mask" "F.Paste")
			(net "P1V538_BMC_NODE1")
		)
		(pad "R2" smd circle
			(at -2.400046 5.199888)
			(size 0.3683 0.3683)
			(layers "F.Cu" "F.Mask" "F.Paste")
			(net "BMC_NODE1_DDR_MA7")
		)
		(pad "R3" smd circle
			(at -1.599946 5.199888)
			(size 0.3683 0.3683)
			(layers "F.Cu" "F.Mask" "F.Paste")
			(net "BMC_NODE1_DDR_MA9")
		)
		(pad "R7" smd circle
			(at 1.599946 5.199888)
			(size 0.3683 0.3683)
			(layers "F.Cu" "F.Mask" "F.Paste")
			(net "BMC_NODE1_DDR_MA11")
		)
		(pad "R8" smd circle
			(at 2.400046 5.199888)
			(size 0.3683 0.3683)
			(layers "F.Cu" "F.Mask" "F.Paste")
			(net "BMC_NODE1_DDR_MA6")
		)
		(pad "R9" smd circle
			(at 3.199892 5.199888)
			(size 0.3683 0.3683)
			(layers "F.Cu" "F.Mask" "F.Paste")
			(net "P1V538_BMC_NODE1")
		)
		(pad "T1" smd circle
			(at -3.199892 5.999988)
			(size 0.3683 0.3683)
			(layers "F.Cu" "F.Mask" "F.Paste")
			(net "GND")
		)
		(pad "T2" smd circle
			(at -2.400046 5.999988)
			(size 0.3683 0.3683)
			(layers "F.Cu" "F.Mask" "F.Paste")
			(net "BMC_NODE1_DDR_RST_L")
		)
		(pad "T3" smd circle
			(at -1.599946 5.999988)
			(size 0.3683 0.3683)
			(layers "F.Cu" "F.Mask" "F.Paste")
			(net "BMC_NODE1_DDR_MA13")
		)
		(pad "T7" smd circle
			(at 1.599946 5.999988)
			(size 0.3683 0.3683)
			(layers "F.Cu" "F.Mask" "F.Paste")
			(net "BMC_NODE1_DDR_MA14")
		)
		(pad "T8" smd circle
			(at 2.400046 5.999988)
			(size 0.3683 0.3683)
			(layers "F.Cu" "F.Mask" "F.Paste")
			(net "BMC_NODE1_DDR_MA8")
		)
		(pad "T9" smd circle
			(at 3.199892 5.999988)
			(size 0.3683 0.3683)
			(layers "F.Cu" "F.Mask" "F.Paste")
			(net "GND")
		)
	)
	(footprint ""
		(layer "F.Cu")
		(at 35.669728 -81.036922)
		(property "Reference" "R41"
			(at -4.58851 -0.106934 0)
			(unlocked yes)
			(layer "F.SilkS")
			(effects
				(font
					(size 0.7874 0.5842)
					(thickness 0.1524)
				)
				(justify left)
			)
		)
		(property "Value" ""
			(at 0 0 0)
			(layer "F.Fab")
			(effects
				(font
					(size 1.27 1.27)
				)
			)
		)
		(duplicate_pad_numbers_are_jumpers no)
		(fp_line
			(start -0.7874 -0.4064)
			(end 0.7874 -0.4064)
			(stroke
				(width 0.1524)
				(type default)
			)
			(layer "F.SilkS")
		)
		(fp_line
			(start -0.7874 0.4064)
			(end -0.7874 -0.4064)
			(stroke
				(width 0.1524)
				(type default)
			)
			(layer "F.SilkS")
		)
		(fp_line
			(start 0.7874 -0.4064)
			(end 0.7874 0.4064)
			(stroke
				(width 0.1524)
				(type default)
			)
			(layer "F.SilkS")
		)
		(fp_line
			(start 0.7874 0.4064)
			(end -0.7874 0.4064)
			(stroke
				(width 0.1524)
				(type default)
			)
			(layer "F.SilkS")
		)
		(fp_poly
			(pts
				(xy -0.508 0.2794) (xy -0.508 0.2286) (xy -0.635 0.2286) (xy -0.635 -0.254) (xy -0.5334 -0.254)
				(xy -0.5334 -0.2794) (xy 0.5334 -0.2794) (xy 0.5334 -0.254) (xy 0.635 -0.254) (xy 0.635 0.254) (xy 0.5334 0.254)
				(xy 0.5334 0.2794)
			)
			(stroke
				(width 0)
				(type default)
			)
			(fill no)
			(layer "F.CrtYd")
		)
		(pad "1" smd rect
			(at 0.40005 0)
			(size 0.4572 0.508)
			(layers "F.Cu" "F.Mask" "F.Paste")
			(net "PD_CPU_NODE1_W1")
		)
		(pad "2" smd rect
			(at -0.40005 0)
			(size 0.4572 0.508)
			(layers "F.Cu" "F.Mask" "F.Paste")
			(net "GND")
		)
	)
	(footprint ""
		(layer "F.Cu")
		(at 13.894562 -29.850334 90)
		(property "Reference" "C545"
			(at -1.276604 -0.944118 90)
			(unlocked yes)
			(layer "F.SilkS")
			(effects
				(font
					(size 0.7874 0.5842)
					(thickness 0.1524)
				)
				(justify left)
			)
		)
		(property "Value" ""
			(at 0 0 90)
			(layer "F.Fab")
			(effects
				(font
					(size 1.27 1.27)
				)
			)
		)
		(duplicate_pad_numbers_are_jumpers no)
		(fp_line
			(start 0.7874 -0.4064)
			(end 0.7874 0.4064)
			(stroke
				(width 0.1524)
				(type default)
			)
			(layer "F.SilkS")
		)
		(fp_line
			(start -0.7874 -0.4064)
			(end 0.7874 -0.4064)
			(stroke
				(width 0.1524)
				(type default)
			)
			(layer "F.SilkS")
		)
		(fp_line
			(start 0 0.381)
			(end 0 -0.381)
			(stroke
				(width 0.1524)
				(type default)
			)
			(layer "F.SilkS")
		)
		(fp_line
			(start 0.7874 0.4064)
			(end -0.7874 0.4064)
			(stroke
				(width 0.1524)
				(type default)
			)
			(layer "F.SilkS")
		)
		(fp_line
			(start -0.7874 0.4064)
			(end -0.7874 -0.4064)
			(stroke
				(width 0.1524)
				(type default)
			)
			(layer "F.SilkS")
		)
		(fp_poly
			(pts
				(xy -0.5334 0.254) (xy -0.635 0.254) (xy -0.635 0.2286) (xy -0.635 -0.254) (xy -0.5334 -0.254) (xy -0.5334 -0.2794)
				(xy 0.5334 -0.2794) (xy 0.5334 -0.254) (xy 0.635 -0.254) (xy 0.635 0.254) (xy 0.5334 0.254) (xy 0.5334 0.2794)
				(xy -0.508 0.2794) (xy -0.5334 0.2794)
			)
			(stroke
				(width 0)
				(type default)
			)
			(fill no)
			(layer "F.CrtYd")
		)
		(pad "1" smd rect
			(at 0.40005 0 90)
			(size 0.4572 0.508)
			(layers "F.Cu" "F.Mask" "F.Paste")
			(net "GND")
		)
		(pad "2" smd rect
			(at -0.40005 0 90)
			(size 0.4572 0.508)
			(layers "F.Cu" "F.Mask" "F.Paste")
			(net "N54251541")
		)
	)
	(footprint ""
		(layer "F.Cu")
		(at 30.58287 -130.513074)
		(property "Reference" "PR17"
			(at -1.295654 -3.38074 0)
			(unlocked yes)
			(layer "F.SilkS")
			(effects
				(font
					(size 0.7874 0.5842)
					(thickness 0.1524)
				)
				(justify left)
			)
		)
		(property "Value" ""
			(at 0 0 0)
			(layer "F.Fab")
			(effects
				(font
					(size 1.27 1.27)
				)
			)
		)
		(duplicate_pad_numbers_are_jumpers no)
		(fp_line
			(start -0.7874 -0.4064)
			(end 0.7874 -0.4064)
			(stroke
				(width 0.1524)
				(type default)
			)
			(layer "F.SilkS")
		)
		(fp_line
			(start -0.7874 0.4064)
			(end -0.7874 -0.4064)
			(stroke
				(width 0.1524)
				(type default)
			)
			(layer "F.SilkS")
		)
		(fp_line
			(start 0.7874 -0.4064)
			(end 0.7874 0.4064)
			(stroke
				(width 0.1524)
				(type default)
			)
			(layer "F.SilkS")
		)
		(fp_line
			(start 0.7874 0.4064)
			(end -0.7874 0.4064)
			(stroke
				(width 0.1524)
				(type default)
			)
			(layer "F.SilkS")
		)
		(fp_poly
			(pts
				(xy -0.508 0.2794) (xy -0.508 0.2286) (xy -0.635 0.2286) (xy -0.635 -0.254) (xy -0.5334 -0.254)
				(xy -0.5334 -0.2794) (xy 0.5334 -0.2794) (xy 0.5334 -0.254) (xy 0.635 -0.254) (xy 0.635 0.254) (xy 0.5334 0.254)
				(xy 0.5334 0.2794)
			)
			(stroke
				(width 0)
				(type default)
			)
			(fill no)
			(layer "F.CrtYd")
		)
		(pad "1" smd rect
			(at 0.40005 0)
			(size 0.4572 0.508)
			(layers "F.Cu" "F.Mask" "F.Paste")
			(net "GND")
		)
		(pad "2" smd rect
			(at -0.40005 0)
			(size 0.4572 0.508)
			(layers "F.Cu" "F.Mask" "F.Paste")
			(net "P1V538_BMC_NODE1_ADJ")
		)
	)
	(footprint ""
		(layer "F.Cu")
		(at 70.1548 -100.254562 180)
		(property "Reference" "R1092"
			(at 1.197102 3.21691 0)
			(unlocked yes)
			(layer "F.SilkS")
			(effects
				(font
					(size 0.7874 0.5842)
					(thickness 0.1524)
				)
				(justify left)
			)
		)
		(property "Value" ""
			(at 0 0 180)
			(layer "F.Fab")
			(effects
				(font
					(size 1.27 1.27)
				)
			)
		)
		(duplicate_pad_numbers_are_jumpers no)
		(fp_line
			(start 0.7874 0.4064)
			(end -0.7874 0.4064)
			(stroke
				(width 0.1524)
				(type default)
			)
			(layer "F.SilkS")
		)
		(fp_line
			(start 0.7874 -0.4064)
			(end 0.7874 0.4064)
			(stroke
				(width 0.1524)
				(type default)
			)
			(layer "F.SilkS")
		)
		(fp_line
			(start -0.7874 0.4064)
			(end -0.7874 -0.4064)
			(stroke
				(width 0.1524)
				(type default)
			)
			(layer "F.SilkS")
		)
		(fp_line
			(start -0.7874 -0.4064)
			(end 0.7874 -0.4064)
			(stroke
				(width 0.1524)
				(type default)
			)
			(layer "F.SilkS")
		)
		(fp_poly
			(pts
				(xy -0.508 0.2794) (xy -0.508 0.2286) (xy -0.635 0.2286) (xy -0.635 -0.254) (xy -0.5334 -0.254)
				(xy -0.5334 -0.2794) (xy 0.5334 -0.2794) (xy 0.5334 -0.254) (xy 0.635 -0.254) (xy 0.635 0.254) (xy 0.5334 0.254)
				(xy 0.5334 0.2794)
			)
			(stroke
				(width 0)
				(type default)
			)
			(fill no)
			(layer "F.CrtYd")
		)
		(pad "1" smd rect
			(at 0.40005 0 180)
			(size 0.4572 0.508)
			(layers "F.Cu" "F.Mask" "F.Paste")
			(net "FM_CPLD_NODE1_P1V8_SUS_EN_G")
		)
		(pad "2" smd rect
			(at -0.40005 0 180)
			(size 0.4572 0.508)
			(layers "F.Cu" "F.Mask" "F.Paste")
			(net "P3V3_STB_NODE1")
		)
	)
	(footprint ""
		(layer "F.Cu")
		(at 109.163866 -128.859026)
		(property "Reference" "PC96"
			(at -8.975852 3.389122 0)
			(unlocked yes)
			(layer "F.SilkS")
			(effects
				(font
					(size 0.7874 0.5842)
					(thickness 0.1524)
				)
				(justify left)
			)
		)
		(property "Value" ""
			(at 0 0 0)
			(layer "F.Fab")
			(effects
				(font
					(size 1.27 1.27)
				)
			)
		)
		(duplicate_pad_numbers_are_jumpers no)
		(fp_line
			(start -0.7874 -0.4064)
			(end 0.7874 -0.4064)
			(stroke
				(width 0.1524)
				(type default)
			)
			(layer "F.SilkS")
		)
		(fp_line
			(start -0.7874 0.4064)
			(end -0.7874 -0.4064)
			(stroke
				(width 0.1524)
				(type default)
			)
			(layer "F.SilkS")
		)
		(fp_line
			(start 0 0.381)
			(end 0 -0.381)
			(stroke
				(width 0.1524)
				(type default)
			)
			(layer "F.SilkS")
		)
		(fp_line
			(start 0.7874 -0.4064)
			(end 0.7874 0.4064)
			(stroke
				(width 0.1524)
				(type default)
			)
			(layer "F.SilkS")
		)
		(fp_line
			(start 0.7874 0.4064)
			(end -0.7874 0.4064)
			(stroke
				(width 0.1524)
				(type default)
			)
			(layer "F.SilkS")
		)
		(fp_poly
			(pts
				(xy -0.5334 0.254) (xy -0.635 0.254) (xy -0.635 0.2286) (xy -0.635 -0.254) (xy -0.5334 -0.254) (xy -0.5334 -0.2794)
				(xy 0.5334 -0.2794) (xy 0.5334 -0.254) (xy 0.635 -0.254) (xy 0.635 0.254) (xy 0.5334 0.254) (xy 0.5334 0.2794)
				(xy -0.508 0.2794) (xy -0.5334 0.2794)
			)
			(stroke
				(width 0)
				(type default)
			)
			(fill no)
			(layer "F.CrtYd")
		)
		(pad "1" smd rect
			(at 0.40005 0)
			(size 0.4572 0.508)
			(layers "F.Cu" "F.Mask" "F.Paste")
			(net "VR_PVCCP_NODE1_BOOT1")
		)
		(pad "2" smd rect
			(at -0.40005 0)
			(size 0.4572 0.508)
			(layers "F.Cu" "F.Mask" "F.Paste")
			(net "VR_PVCCP_NODE1_PHASE1")
		)
	)
	(footprint ""
		(layer "F.Cu")
		(at 56.191912 -100.35921 -90)
		(property "Reference" "R196"
			(at -1.014222 -0.04064 90)
			(unlocked yes)
			(layer "F.SilkS")
			(effects
				(font
					(size 0.7874 0.5842)
					(thickness 0.1524)
				)
				(justify left)
			)
		)
		(property "Value" ""
			(at 0 0 270)
			(layer "F.Fab")
			(effects
				(font
					(size 1.27 1.27)
				)
			)
		)
		(duplicate_pad_numbers_are_jumpers no)
		(fp_line
			(start -0.7874 0.4064)
			(end -0.7874 -0.4064)
			(stroke
				(width 0.1524)
				(type default)
			)
			(layer "F.SilkS")
		)
		(fp_line
			(start 0.7874 0.4064)
			(end -0.7874 0.4064)
			(stroke
				(width 0.1524)
				(type default)
			)
			(layer "F.SilkS")
		)
		(fp_line
			(start -0.7874 -0.4064)
			(end 0.7874 -0.4064)
			(stroke
				(width 0.1524)
				(type default)
			)
			(layer "F.SilkS")
		)
		(fp_line
			(start 0.7874 -0.4064)
			(end 0.7874 0.4064)
			(stroke
				(width 0.1524)
				(type default)
			)
			(layer "F.SilkS")
		)
		(fp_poly
			(pts
				(xy -0.508 0.2794) (xy -0.508 0.2286) (xy -0.635 0.2286) (xy -0.635 -0.254) (xy -0.5334 -0.254)
				(xy -0.5334 -0.2794) (xy 0.5334 -0.2794) (xy 0.5334 -0.254) (xy 0.635 -0.254) (xy 0.635 0.254) (xy 0.5334 0.254)
				(xy 0.5334 0.2794)
			)
			(stroke
				(width 0)
				(type default)
			)
			(fill no)
			(layer "F.CrtYd")
		)
		(pad "1" smd rect
			(at 0.40005 0 270)
			(size 0.4572 0.508)
			(layers "F.Cu" "F.Mask" "F.Paste")
			(net "P3V3_NODE1")
		)
		(pad "2" smd rect
			(at -0.40005 0 270)
			(size 0.4572 0.508)
			(layers "F.Cu" "F.Mask" "F.Paste")
			(net "PU_EMC1428_NODE1_TRIP")
		)
	)
	(footprint ""
		(layer "F.Cu")
		(at 126.64694 -165.259004 180)
		(property "Reference" "R679"
			(at 1.356868 4.558792 0)
			(unlocked yes)
			(layer "F.SilkS")
			(effects
				(font
					(size 0.7874 0.5842)
					(thickness 0.1524)
				)
				(justify left)
			)
		)
		(property "Value" ""
			(at 0 0 180)
			(layer "F.Fab")
			(effects
				(font
					(size 1.27 1.27)
				)
			)
		)
		(duplicate_pad_numbers_are_jumpers no)
		(fp_line
			(start 0.7874 0.4064)
			(end -0.7874 0.4064)
			(stroke
				(width 0.1524)
				(type default)
			)
			(layer "F.SilkS")
		)
		(fp_line
			(start 0.7874 -0.4064)
			(end 0.7874 0.4064)
			(stroke
				(width 0.1524)
				(type default)
			)
			(layer "F.SilkS")
		)
		(fp_line
			(start -0.7874 0.4064)
			(end -0.7874 -0.4064)
			(stroke
				(width 0.1524)
				(type default)
			)
			(layer "F.SilkS")
		)
		(fp_line
			(start -0.7874 -0.4064)
			(end 0.7874 -0.4064)
			(stroke
				(width 0.1524)
				(type default)
			)
			(layer "F.SilkS")
		)
		(fp_poly
			(pts
				(xy -0.508 0.2794) (xy -0.508 0.2286) (xy -0.635 0.2286) (xy -0.635 -0.254) (xy -0.5334 -0.254)
				(xy -0.5334 -0.2794) (xy 0.5334 -0.2794) (xy 0.5334 -0.254) (xy 0.635 -0.254) (xy 0.635 0.254) (xy 0.5334 0.254)
				(xy 0.5334 0.2794)
			)
			(stroke
				(width 0)
				(type default)
			)
			(fill no)
			(layer "F.CrtYd")
		)
		(pad "1" smd rect
			(at 0.40005 0 180)
			(size 0.4572 0.508)
			(layers "F.Cu" "F.Mask" "F.Paste")
			(net "CPLD123_RSV1")
		)
		(pad "2" smd rect
			(at -0.40005 0 180)
			(size 0.4572 0.508)
			(layers "F.Cu" "F.Mask" "F.Paste")
			(net "CPLD3_RSV1")
		)
	)
	(footprint ""
		(layer "F.Cu")
		(at 48.24476 -188.126624 90)
		(property "Reference" "R851"
			(at 4.548886 0.205232 90)
			(unlocked yes)
			(layer "F.SilkS")
			(effects
				(font
					(size 0.7874 0.5842)
					(thickness 0.1524)
				)
				(justify left)
			)
		)
		(property "Value" ""
			(at 0 0 90)
			(layer "F.Fab")
			(effects
				(font
					(size 1.27 1.27)
				)
			)
		)
		(duplicate_pad_numbers_are_jumpers no)
		(fp_line
			(start 0.7874 -0.4064)
			(end 0.7874 0.4064)
			(stroke
				(width 0.1524)
				(type default)
			)
			(layer "F.SilkS")
		)
		(fp_line
			(start -0.7874 -0.4064)
			(end 0.7874 -0.4064)
			(stroke
				(width 0.1524)
				(type default)
			)
			(layer "F.SilkS")
		)
		(fp_line
			(start 0.7874 0.4064)
			(end -0.7874 0.4064)
			(stroke
				(width 0.1524)
				(type default)
			)
			(layer "F.SilkS")
		)
		(fp_line
			(start -0.7874 0.4064)
			(end -0.7874 -0.4064)
			(stroke
				(width 0.1524)
				(type default)
			)
			(layer "F.SilkS")
		)
		(fp_poly
			(pts
				(xy -0.508 0.2794) (xy -0.508 0.2286) (xy -0.635 0.2286) (xy -0.635 -0.254) (xy -0.5334 -0.254)
				(xy -0.5334 -0.2794) (xy 0.5334 -0.2794) (xy 0.5334 -0.254) (xy 0.635 -0.254) (xy 0.635 0.254) (xy 0.5334 0.254)
				(xy 0.5334 0.2794)
			)
			(stroke
				(width 0)
				(type default)
			)
			(fill no)
			(layer "F.CrtYd")
		)
		(pad "1" smd rect
			(at 0.40005 0 90)
			(size 0.4572 0.508)
			(layers "F.Cu" "F.Mask" "F.Paste")
			(net "PSU5_AC_OK_R")
		)
		(pad "2" smd rect
			(at -0.40005 0 90)
			(size 0.4572 0.508)
			(layers "F.Cu" "F.Mask" "F.Paste")
			(net "GND")
		)
	)
	(footprint ""
		(layer "F.Cu")
		(at 137.730992 -25.421844 -90)
		(property "Reference" "C491"
			(at 8.86841 -4.51993 90)
			(unlocked yes)
			(layer "F.SilkS")
			(effects
				(font
					(size 0.7874 0.5842)
					(thickness 0.1524)
				)
			)
		)
		(property "Value" ""
			(at 0 0 270)
			(layer "F.Fab")
			(effects
				(font
					(size 1.27 1.27)
				)
			)
		)
		(duplicate_pad_numbers_are_jumpers no)
		(fp_line
			(start -1.2954 0.5842)
			(end -1.2954 -0.5842)
			(stroke
				(width 0.1524)
				(type default)
			)
			(layer "F.SilkS")
		)
		(fp_line
			(start 1.2954 0.5842)
			(end -1.2954 0.5842)
			(stroke
				(width 0.1524)
				(type default)
			)
			(layer "F.SilkS")
		)
		(fp_line
			(start -1.2954 -0.5842)
			(end 1.2954 -0.5842)
			(stroke
				(width 0.1524)
				(type default)
			)
			(layer "F.SilkS")
		)
		(fp_line
			(start 0 -0.5842)
			(end 0 0.5842)
			(stroke
				(width 0.1524)
				(type default)
			)
			(layer "F.SilkS")
		)
		(fp_line
			(start 1.2954 -0.5842)
			(end 1.2954 0.5842)
			(stroke
				(width 0.1524)
				(type default)
			)
			(layer "F.SilkS")
		)
		(fp_poly
			(pts
				(xy 0.8636 -0.4572) (xy 0.8636 -0.3556) (xy 1.143 -0.3556) (xy 1.143 0.3556) (xy 0.8636 0.3556)
				(xy 0.8636 0.4572) (xy -0.8636 0.4572) (xy -0.8636 0.3556) (xy -1.143 0.3556) (xy -1.143 -0.3556)
				(xy -0.8636 -0.3556) (xy -0.8636 -0.4572)
			)
			(stroke
				(width 0)
				(type default)
			)
			(fill no)
			(layer "F.CrtYd")
		)
		(fp_line
			(start -0.884936 0.504952)
			(end -0.884936 -0.504952)
			(stroke
				(width 0.1)
				(type default)
			)
			(layer "F.Fab")
		)
		(fp_line
			(start 0.884936 0.504952)
			(end -0.884936 0.504952)
			(stroke
				(width 0.1)
				(type default)
			)
			(layer "F.Fab")
		)
		(fp_line
			(start -0.884936 -0.504952)
			(end 0.884936 -0.504952)
			(stroke
				(width 0.1)
				(type default)
			)
			(layer "F.Fab")
		)
		(fp_line
			(start 0.884936 -0.504952)
			(end 0.884936 0.504952)
			(stroke
				(width 0.1)
				(type default)
			)
			(layer "F.Fab")
		)
		(pad "1" smd rect
			(at 0.7366 0)
			(size 0.7112 0.8128)
			(layers "F.Cu" "F.Mask" "F.Paste")
			(net "P5V_NODE1")
		)
		(pad "2" smd rect
			(at -0.7366 0)
			(size 0.7112 0.8128)
			(layers "F.Cu" "F.Mask" "F.Paste")
			(net "GND")
		)
	)
	(footprint ""
		(layer "F.Cu")
		(at 106.426508 -177.969926 180)
		(property "Reference" "R751"
			(at 0.555498 3.196844 0)
			(unlocked yes)
			(layer "F.SilkS")
			(effects
				(font
					(size 0.7874 0.5842)
					(thickness 0.1524)
				)
				(justify left)
			)
		)
		(property "Value" ""
			(at 0 0 180)
			(layer "F.Fab")
			(effects
				(font
					(size 1.27 1.27)
				)
			)
		)
		(duplicate_pad_numbers_are_jumpers no)
		(fp_line
			(start 0.7874 0.4064)
			(end -0.7874 0.4064)
			(stroke
				(width 0.1524)
				(type default)
			)
			(layer "F.SilkS")
		)
		(fp_line
			(start 0.7874 -0.4064)
			(end 0.7874 0.4064)
			(stroke
				(width 0.1524)
				(type default)
			)
			(layer "F.SilkS")
		)
		(fp_line
			(start -0.7874 0.4064)
			(end -0.7874 -0.4064)
			(stroke
				(width 0.1524)
				(type default)
			)
			(layer "F.SilkS")
		)
		(fp_line
			(start -0.7874 -0.4064)
			(end 0.7874 -0.4064)
			(stroke
				(width 0.1524)
				(type default)
			)
			(layer "F.SilkS")
		)
		(fp_poly
			(pts
				(xy -0.508 0.2794) (xy -0.508 0.2286) (xy -0.635 0.2286) (xy -0.635 -0.254) (xy -0.5334 -0.254)
				(xy -0.5334 -0.2794) (xy 0.5334 -0.2794) (xy 0.5334 -0.254) (xy 0.635 -0.254) (xy 0.635 0.254) (xy 0.5334 0.254)
				(xy 0.5334 0.2794)
			)
			(stroke
				(width 0)
				(type default)
			)
			(fill no)
			(layer "F.CrtYd")
		)
		(pad "1" smd rect
			(at 0.40005 0 180)
			(size 0.4572 0.508)
			(layers "F.Cu" "F.Mask" "F.Paste")
			(net "N21700943")
		)
		(pad "2" smd rect
			(at -0.40005 0 180)
			(size 0.4572 0.508)
			(layers "F.Cu" "F.Mask" "F.Paste")
			(net "GND")
		)
	)
	(footprint ""
		(layer "F.Cu")
		(at 93.532452 -131.560062 90)
		(property "Reference" "R1104"
			(at -2.83718 -0.924306 90)
			(unlocked yes)
			(layer "F.SilkS")
			(effects
				(font
					(size 0.7874 0.5842)
					(thickness 0.1524)
				)
				(justify left)
			)
		)
		(property "Value" ""
			(at 0 0 90)
			(layer "F.Fab")
			(effects
				(font
					(size 1.27 1.27)
				)
			)
		)
		(duplicate_pad_numbers_are_jumpers no)
		(fp_line
			(start 0.7874 -0.4064)
			(end 0.7874 0.4064)
			(stroke
				(width 0.1524)
				(type default)
			)
			(layer "F.SilkS")
		)
		(fp_line
			(start -0.7874 -0.4064)
			(end 0.7874 -0.4064)
			(stroke
				(width 0.1524)
				(type default)
			)
			(layer "F.SilkS")
		)
		(fp_line
			(start 0.7874 0.4064)
			(end -0.7874 0.4064)
			(stroke
				(width 0.1524)
				(type default)
			)
			(layer "F.SilkS")
		)
		(fp_line
			(start -0.7874 0.4064)
			(end -0.7874 -0.4064)
			(stroke
				(width 0.1524)
				(type default)
			)
			(layer "F.SilkS")
		)
		(fp_poly
			(pts
				(xy -0.508 0.2794) (xy -0.508 0.2286) (xy -0.635 0.2286) (xy -0.635 -0.254) (xy -0.5334 -0.254)
				(xy -0.5334 -0.2794) (xy 0.5334 -0.2794) (xy 0.5334 -0.254) (xy 0.635 -0.254) (xy 0.635 0.254) (xy 0.5334 0.254)
				(xy 0.5334 0.2794)
			)
			(stroke
				(width 0)
				(type default)
			)
			(fill no)
			(layer "F.CrtYd")
		)
		(pad "1" smd rect
			(at 0.40005 0 90)
			(size 0.4572 0.508)
			(layers "F.Cu" "F.Mask" "F.Paste")
			(net "GND")
		)
		(pad "2" smd rect
			(at -0.40005 0 90)
			(size 0.4572 0.508)
			(layers "F.Cu" "F.Mask" "F.Paste")
			(net "FM_CPLD_NODE1_P1V05_SUS_EN")
		)
	)
	(footprint ""
		(layer "F.Cu")
		(at 133.674612 -158.79953)
		(property "Reference" "U127"
			(at -62.464442 109.000798 90)
			(unlocked yes)
			(layer "F.SilkS")
			(effects
				(font
					(size 0.7874 0.5842)
					(thickness 0.1524)
				)
			)
		)
		(property "Value" ""
			(at 0 0 0)
			(layer "F.Fab")
			(effects
				(font
					(size 1.27 1.27)
				)
			)
		)
		(duplicate_pad_numbers_are_jumpers no)
		(fp_line
			(start -1.651 -1.905)
			(end 1.651 -1.905)
			(stroke
				(width 0.1524)
				(type default)
			)
			(layer "F.SilkS")
		)
		(fp_line
			(start -1.651 1.905)
			(end -1.651 -1.905)
			(stroke
				(width 0.1524)
				(type default)
			)
			(layer "F.SilkS")
		)
		(fp_line
			(start 1.651 -1.905)
			(end 1.651 1.905)
			(stroke
				(width 0.1524)
				(type default)
			)
			(layer "F.SilkS")
		)
		(fp_line
			(start 1.651 1.905)
			(end -1.651 1.905)
			(stroke
				(width 0.1524)
				(type default)
			)
			(layer "F.SilkS")
		)
		(fp_poly
			(pts
				(xy -1.524 0.7112) (xy -1.524 1.7526) (xy -0.508 1.7526) (xy -0.508 0.6985) (xy 0.508 0.6985) (xy 0.508 1.7526)
				(xy 1.524 1.7526) (xy 1.524 0.6985) (xy 1.524 -0.6985) (xy 0.508 -0.6985) (xy 0.508 -1.7526) (xy -0.508 -1.7526)
				(xy -0.508 -0.6985) (xy -1.524 -0.6985) (xy -1.524 0.6985)
			)
			(stroke
				(width 0)
				(type default)
			)
			(fill no)
			(layer "F.CrtYd")
		)
		(fp_text user "G"
			(at -2.350008 2.76733 0)
			(unlocked yes)
			(layer "F.SilkS")
			(effects
				(font
					(size 0.635 0.4064)
					(thickness 0.1524)
				)
			)
		)
		(fp_text user "D"
			(at 0.254762 -2.4765 0)
			(unlocked yes)
			(layer "F.SilkS")
			(effects
				(font
					(size 0.635 0.4064)
					(thickness 0.1524)
				)
			)
		)
		(fp_text user "S"
			(at 0.869696 2.623566 0)
			(unlocked yes)
			(layer "F.SilkS")
			(effects
				(font
					(size 0.635 0.4064)
					(thickness 0.1524)
				)
			)
		)
		(pad "D" smd rect
			(at 0 -1.1176)
			(size 1.016 1.27)
			(layers "F.Cu" "F.Mask" "F.Paste")
			(net "I2C_PSU3_SDA")
		)
		(pad "G" smd rect
			(at -1.016 1.1176)
			(size 1.016 1.27)
			(layers "F.Cu" "F.Mask" "F.Paste")
			(net "PMBUS3_EN")
		)
		(pad "S" smd rect
			(at 1.016 1.1176)
			(size 1.016 1.27)
			(layers "F.Cu" "F.Mask" "F.Paste")
			(net "I2C_PSU3_SDA_MOS")
		)
	)
	(footprint ""
		(layer "F.Cu")
		(at 166.28364 -188.19749 -90)
		(property "Reference" "R844"
			(at -0.95631 -0.24003 90)
			(unlocked yes)
			(layer "F.SilkS")
			(effects
				(font
					(size 0.7874 0.5842)
					(thickness 0.1524)
				)
				(justify left)
			)
		)
		(property "Value" ""
			(at 0 0 270)
			(layer "F.Fab")
			(effects
				(font
					(size 1.27 1.27)
				)
			)
		)
		(duplicate_pad_numbers_are_jumpers no)
		(fp_line
			(start -0.7874 0.4064)
			(end -0.7874 -0.4064)
			(stroke
				(width 0.1524)
				(type default)
			)
			(layer "F.SilkS")
		)
		(fp_line
			(start 0.7874 0.4064)
			(end -0.7874 0.4064)
			(stroke
				(width 0.1524)
				(type default)
			)
			(layer "F.SilkS")
		)
		(fp_line
			(start -0.7874 -0.4064)
			(end 0.7874 -0.4064)
			(stroke
				(width 0.1524)
				(type default)
			)
			(layer "F.SilkS")
		)
		(fp_line
			(start 0.7874 -0.4064)
			(end 0.7874 0.4064)
			(stroke
				(width 0.1524)
				(type default)
			)
			(layer "F.SilkS")
		)
		(fp_poly
			(pts
				(xy -0.508 0.2794) (xy -0.508 0.2286) (xy -0.635 0.2286) (xy -0.635 -0.254) (xy -0.5334 -0.254)
				(xy -0.5334 -0.2794) (xy 0.5334 -0.2794) (xy 0.5334 -0.254) (xy 0.635 -0.254) (xy 0.635 0.254) (xy 0.5334 0.254)
				(xy 0.5334 0.2794)
			)
			(stroke
				(width 0)
				(type default)
			)
			(fill no)
			(layer "F.CrtYd")
		)
		(pad "1" smd rect
			(at 0.40005 0 270)
			(size 0.4572 0.508)
			(layers "F.Cu" "F.Mask" "F.Paste")
			(net "I2C_PDB_SDA")
		)
		(pad "2" smd rect
			(at -0.40005 0 270)
			(size 0.4572 0.508)
			(layers "F.Cu" "F.Mask" "F.Paste")
			(net "I2C_PDB_R_SDA")
		)
	)
	(footprint ""
		(layer "F.Cu")
		(at 129.100834 -65.553336 90)
		(property "Reference" "U31"
			(at 3.312414 -2.070862 0)
			(unlocked yes)
			(layer "F.SilkS")
			(effects
				(font
					(size 0.7874 0.5842)
					(thickness 0.1524)
				)
				(justify left)
			)
		)
		(property "Value" ""
			(at 0 0 90)
			(layer "F.Fab")
			(effects
				(font
					(size 1.27 1.27)
				)
			)
		)
		(duplicate_pad_numbers_are_jumpers no)
		(fp_line
			(start 2.690114 -2.599944)
			(end 2.690114 2.599944)
			(stroke
				(width 0.1524)
				(type default)
			)
			(layer "F.SilkS")
		)
		(fp_line
			(start -2.690114 -2.599944)
			(end 2.690114 -2.599944)
			(stroke
				(width 0.1524)
				(type default)
			)
			(layer "F.SilkS")
		)
		(fp_line
			(start -2.690114 -0.40005)
			(end -2.690114 -2.599944)
			(stroke
				(width 0.1524)
				(type default)
			)
			(layer "F.SilkS")
		)
		(fp_line
			(start -1.905 0)
			(end -2.690114 -0.40005)
			(stroke
				(width 0.1524)
				(type default)
			)
			(layer "F.SilkS")
		)
		(fp_line
			(start -2.690114 0.40005)
			(end -1.905 0)
			(stroke
				(width 0.1524)
				(type default)
			)
			(layer "F.SilkS")
		)
		(fp_line
			(start 2.690114 2.599944)
			(end -2.690114 2.599944)
			(stroke
				(width 0.1524)
				(type default)
			)
			(layer "F.SilkS")
		)
		(fp_line
			(start -2.690114 2.599944)
			(end -2.690114 0.40005)
			(stroke
				(width 0.1524)
				(type default)
			)
			(layer "F.SilkS")
		)
		(fp_circle
			(center -1.9304 2.0066)
			(end -1.9304 2.2606)
			(stroke
				(width 0.1524)
				(type default)
			)
			(fill no)
			(layer "F.SilkS")
		)
		(fp_poly
			(pts
				(xy -2.1844 4.4958) (xy -2.1844 2.5908) (xy -2.6924 2.5908) (xy -2.6924 -2.5908) (xy -2.1844 -2.5908)
				(xy -2.1844 -4.4958) (xy 2.1844 -4.4958) (xy 2.1844 -2.5908) (xy 2.667 -2.5908) (xy 2.667 2.5908)
				(xy 2.1844 2.5908) (xy 2.1844 4.4958)
			)
			(stroke
				(width 0)
				(type default)
			)
			(fill no)
			(layer "F.CrtYd")
		)
		(pad "1" smd rect
			(at -1.905 3.636518 90)
			(size 0.5588 1.7272)
			(layers "F.Cu" "F.Mask" "F.Paste")
			(net "SATA_SPI_CS_NODE1")
		)
		(pad "2" smd rect
			(at -0.635 3.636518 90)
			(size 0.5588 1.7272)
			(layers "F.Cu" "F.Mask" "F.Paste")
			(net "SATA_SPI_DI_NODE1_R")
		)
		(pad "3" smd rect
			(at 0.635 3.636518 90)
			(size 0.5588 1.7272)
			(layers "F.Cu" "F.Mask" "F.Paste")
			(net "N21116716")
		)
		(pad "4" smd rect
			(at 1.905 3.636518 90)
			(size 0.5588 1.7272)
			(layers "F.Cu" "F.Mask" "F.Paste")
			(net "GND")
		)
		(pad "5" smd rect
			(at 1.905 -3.636518 90)
			(size 0.5588 1.7272)
			(layers "F.Cu" "F.Mask" "F.Paste")
			(net "SATA_SPI_DO_NODE1")
		)
		(pad "6" smd rect
			(at 0.635 -3.636518 90)
			(size 0.5588 1.7272)
			(layers "F.Cu" "F.Mask" "F.Paste")
			(net "SATA_SPI_CLK_NODE1")
		)
		(pad "7" smd rect
			(at -0.635 -3.636518 90)
			(size 0.5588 1.7272)
			(layers "F.Cu" "F.Mask" "F.Paste")
			(net "N21116716")
		)
		(pad "8" smd rect
			(at -1.905 -3.636518 90)
			(size 0.5588 1.7272)
			(layers "F.Cu" "F.Mask" "F.Paste")
			(net "P3V3_NODE1")
		)
	)
	(footprint ""
		(layer "F.Cu")
		(at 54.72176 -178.804824 180)
		(property "Reference" "U98"
			(at 5.879084 -132.66293 90)
			(unlocked yes)
			(layer "F.SilkS")
			(effects
				(font
					(size 0.7874 0.5842)
					(thickness 0.1524)
				)
			)
		)
		(property "Value" ""
			(at 0 0 180)
			(layer "F.Fab")
			(effects
				(font
					(size 1.27 1.27)
				)
			)
		)
		(duplicate_pad_numbers_are_jumpers no)
		(fp_line
			(start 1.651 1.905)
			(end -1.651 1.905)
			(stroke
				(width 0.1524)
				(type default)
			)
			(layer "F.SilkS")
		)
		(fp_line
			(start 1.651 -1.905)
			(end 1.651 1.905)
			(stroke
				(width 0.1524)
				(type default)
			)
			(layer "F.SilkS")
		)
		(fp_line
			(start -1.651 1.905)
			(end -1.651 -1.905)
			(stroke
				(width 0.1524)
				(type default)
			)
			(layer "F.SilkS")
		)
		(fp_line
			(start -1.651 -1.905)
			(end 1.651 -1.905)
			(stroke
				(width 0.1524)
				(type default)
			)
			(layer "F.SilkS")
		)
		(fp_poly
			(pts
				(xy -1.524 0.7112) (xy -1.524 1.7526) (xy -0.508 1.7526) (xy -0.508 0.6985) (xy 0.508 0.6985) (xy 0.508 1.7526)
				(xy 1.524 1.7526) (xy 1.524 0.6985) (xy 1.524 -0.6985) (xy 0.508 -0.6985) (xy 0.508 -1.7526) (xy -0.508 -1.7526)
				(xy -0.508 -0.6985) (xy -1.524 -0.6985) (xy -1.524 0.6985)
			)
			(stroke
				(width 0)
				(type default)
			)
			(fill no)
			(layer "F.CrtYd")
		)
		(fp_text user "S"
			(at 0.032258 2.201418 90)
			(unlocked yes)
			(layer "F.SilkS")
			(effects
				(font
					(size 0.635 0.4064)
					(thickness 0.1524)
				)
			)
		)
		(fp_text user "D"
			(at -0.185674 -2.48793 0)
			(unlocked yes)
			(layer "F.SilkS")
			(effects
				(font
					(size 0.635 0.4064)
					(thickness 0.1524)
				)
			)
		)
		(fp_text user "G"
			(at -1.905 2.69875 0)
			(unlocked yes)
			(layer "F.SilkS")
			(effects
				(font
					(size 0.635 0.4064)
					(thickness 0.1524)
				)
			)
		)
		(pad "D" smd rect
			(at 0 -1.1176 180)
			(size 1.016 1.27)
			(layers "F.Cu" "F.Mask" "F.Paste")
			(net "PSU_DC_OK_N")
		)
		(pad "G" smd rect
			(at -1.016 1.1176 180)
			(size 1.016 1.27)
			(layers "F.Cu" "F.Mask" "F.Paste")
			(net "PSU4_DC_OK_R_BUF")
		)
		(pad "S" smd rect
			(at 1.016 1.1176 180)
			(size 1.016 1.27)
			(layers "F.Cu" "F.Mask" "F.Paste")
			(net "GND")
		)
	)
	(footprint ""
		(layer "F.Cu")
		(at 123.70816 -164.491416 180)
		(property "Reference" "R680"
			(at -30.092904 -46.17974 0)
			(unlocked yes)
			(layer "F.SilkS")
			(effects
				(font
					(size 0.7874 0.5842)
					(thickness 0.1524)
				)
				(justify left)
			)
		)
		(property "Value" ""
			(at 0 0 180)
			(layer "F.Fab")
			(effects
				(font
					(size 1.27 1.27)
				)
			)
		)
		(duplicate_pad_numbers_are_jumpers no)
		(fp_line
			(start 0.7874 0.4064)
			(end -0.7874 0.4064)
			(stroke
				(width 0.1524)
				(type default)
			)
			(layer "F.SilkS")
		)
		(fp_line
			(start 0.7874 -0.4064)
			(end 0.7874 0.4064)
			(stroke
				(width 0.1524)
				(type default)
			)
			(layer "F.SilkS")
		)
		(fp_line
			(start -0.7874 0.4064)
			(end -0.7874 -0.4064)
			(stroke
				(width 0.1524)
				(type default)
			)
			(layer "F.SilkS")
		)
		(fp_line
			(start -0.7874 -0.4064)
			(end 0.7874 -0.4064)
			(stroke
				(width 0.1524)
				(type default)
			)
			(layer "F.SilkS")
		)
		(fp_poly
			(pts
				(xy -0.508 0.2794) (xy -0.508 0.2286) (xy -0.635 0.2286) (xy -0.635 -0.254) (xy -0.5334 -0.254)
				(xy -0.5334 -0.2794) (xy 0.5334 -0.2794) (xy 0.5334 -0.254) (xy 0.635 -0.254) (xy 0.635 0.254) (xy 0.5334 0.254)
				(xy 0.5334 0.2794)
			)
			(stroke
				(width 0)
				(type default)
			)
			(fill no)
			(layer "F.CrtYd")
		)
		(pad "1" smd rect
			(at 0.40005 0 180)
			(size 0.4572 0.508)
			(layers "F.Cu" "F.Mask" "F.Paste")
			(net "COM3_WAKEUP")
		)
		(pad "2" smd rect
			(at -0.40005 0 180)
			(size 0.4572 0.508)
			(layers "F.Cu" "F.Mask" "F.Paste")
			(net "P3V3_NODE1")
		)
	)
	(footprint ""
		(layer "F.Cu")
		(at 142.724886 -51.476656 90)
		(property "Reference" "R1018"
			(at 16.324326 30.452822 90)
			(unlocked yes)
			(layer "F.SilkS")
			(effects
				(font
					(size 0.7874 0.5842)
					(thickness 0.1524)
				)
				(justify left)
			)
		)
		(property "Value" ""
			(at 0 0 90)
			(layer "F.Fab")
			(effects
				(font
					(size 1.27 1.27)
				)
			)
		)
		(duplicate_pad_numbers_are_jumpers no)
		(fp_line
			(start 0.7874 -0.4064)
			(end 0.7874 0.4064)
			(stroke
				(width 0.1524)
				(type default)
			)
			(layer "F.SilkS")
		)
		(fp_line
			(start -0.7874 -0.4064)
			(end 0.7874 -0.4064)
			(stroke
				(width 0.1524)
				(type default)
			)
			(layer "F.SilkS")
		)
		(fp_line
			(start 0.7874 0.4064)
			(end -0.7874 0.4064)
			(stroke
				(width 0.1524)
				(type default)
			)
			(layer "F.SilkS")
		)
		(fp_line
			(start -0.7874 0.4064)
			(end -0.7874 -0.4064)
			(stroke
				(width 0.1524)
				(type default)
			)
			(layer "F.SilkS")
		)
		(fp_poly
			(pts
				(xy -0.508 0.2794) (xy -0.508 0.2286) (xy -0.635 0.2286) (xy -0.635 -0.254) (xy -0.5334 -0.254)
				(xy -0.5334 -0.2794) (xy 0.5334 -0.2794) (xy 0.5334 -0.254) (xy 0.635 -0.254) (xy 0.635 0.254) (xy 0.5334 0.254)
				(xy 0.5334 0.2794)
			)
			(stroke
				(width 0)
				(type default)
			)
			(fill no)
			(layer "F.CrtYd")
		)
		(pad "1" smd rect
			(at 0.40005 0 90)
			(size 0.4572 0.508)
			(layers "F.Cu" "F.Mask" "F.Paste")
			(net "GND")
		)
		(pad "2" smd rect
			(at -0.40005 0 90)
			(size 0.4572 0.508)
			(layers "F.Cu" "F.Mask" "F.Paste")
			(net "UART_RTS_P2_N")
		)
	)
	(footprint ""
		(layer "F.Cu")
		(at 129.06756 -188.126624 -90)
		(property "Reference" "R998"
			(at -4.949444 0.583438 90)
			(unlocked yes)
			(layer "F.SilkS")
			(effects
				(font
					(size 0.7874 0.5842)
					(thickness 0.1524)
				)
				(justify left)
			)
		)
		(property "Value" ""
			(at 0 0 270)
			(layer "F.Fab")
			(effects
				(font
					(size 1.27 1.27)
				)
			)
		)
		(duplicate_pad_numbers_are_jumpers no)
		(fp_line
			(start -0.7874 0.4064)
			(end -0.7874 -0.4064)
			(stroke
				(width 0.1524)
				(type default)
			)
			(layer "F.SilkS")
		)
		(fp_line
			(start 0.7874 0.4064)
			(end -0.7874 0.4064)
			(stroke
				(width 0.1524)
				(type default)
			)
			(layer "F.SilkS")
		)
		(fp_line
			(start -0.7874 -0.4064)
			(end 0.7874 -0.4064)
			(stroke
				(width 0.1524)
				(type default)
			)
			(layer "F.SilkS")
		)
		(fp_line
			(start 0.7874 -0.4064)
			(end 0.7874 0.4064)
			(stroke
				(width 0.1524)
				(type default)
			)
			(layer "F.SilkS")
		)
		(fp_poly
			(pts
				(xy -0.508 0.2794) (xy -0.508 0.2286) (xy -0.635 0.2286) (xy -0.635 -0.254) (xy -0.5334 -0.254)
				(xy -0.5334 -0.2794) (xy 0.5334 -0.2794) (xy 0.5334 -0.254) (xy 0.635 -0.254) (xy 0.635 0.254) (xy 0.5334 0.254)
				(xy 0.5334 0.2794)
			)
			(stroke
				(width 0)
				(type default)
			)
			(fill no)
			(layer "F.CrtYd")
		)
		(pad "1" smd rect
			(at 0.40005 0 270)
			(size 0.4572 0.508)
			(layers "F.Cu" "F.Mask" "F.Paste")
			(net "UART_T10_NODE4_RXD")
		)
		(pad "2" smd rect
			(at -0.40005 0 270)
			(size 0.4572 0.508)
			(layers "F.Cu" "F.Mask" "F.Paste")
			(net "UART_T10_NODE4_RXD_R")
		)
	)
	(footprint ""
		(layer "F.Cu")
		(at 177.649632 -146.90852)
		(property "Reference" "C447"
			(at -5.177282 0.157988 0)
			(unlocked yes)
			(layer "F.SilkS")
			(effects
				(font
					(size 0.7874 0.5842)
					(thickness 0.1524)
				)
				(justify left)
			)
		)
		(property "Value" ""
			(at 0 0 0)
			(layer "F.Fab")
			(effects
				(font
					(size 1.27 1.27)
				)
			)
		)
		(duplicate_pad_numbers_are_jumpers no)
		(fp_line
			(start -1.905 -0.8636)
			(end 1.905 -0.8636)
			(stroke
				(width 0.1524)
				(type default)
			)
			(layer "F.SilkS")
		)
		(fp_line
			(start -1.905 0.8636)
			(end -1.905 -0.8636)
			(stroke
				(width 0.1524)
				(type default)
			)
			(layer "F.SilkS")
		)
		(fp_line
			(start 0 0.8382)
			(end 0 -0.8382)
			(stroke
				(width 0.1524)
				(type default)
			)
			(layer "F.SilkS")
		)
		(fp_line
			(start 1.905 -0.8636)
			(end 1.905 0.8636)
			(stroke
				(width 0.1524)
				(type default)
			)
			(layer "F.SilkS")
		)
		(fp_line
			(start 1.905 0.8636)
			(end -1.905 0.8636)
			(stroke
				(width 0.1524)
				(type default)
			)
			(layer "F.SilkS")
		)
		(fp_rect
			(start -1.524 0.7366)
			(end 1.524 -0.7366)
			(stroke
				(width 0)
				(type default)
			)
			(fill no)
			(layer "F.CrtYd")
		)
		(pad "1" smd rect
			(at 0.94996 0)
			(size 1.1176 1.3716)
			(layers "F.Cu" "F.Mask" "F.Paste")
			(net "P3V3_NODE1")
		)
		(pad "2" smd rect
			(at -0.94996 0)
			(size 1.1176 1.3716)
			(layers "F.Cu" "F.Mask" "F.Paste")
			(net "GND")
		)
	)
	(footprint ""
		(layer "F.Cu")
		(at 127.593852 -155.853892)
		(property "Reference" "R1282"
			(at -62.858142 109.744256 0)
			(unlocked yes)
			(layer "F.SilkS")
			(effects
				(font
					(size 0.7874 0.5842)
					(thickness 0.1524)
				)
				(justify left)
			)
		)
		(property "Value" ""
			(at 0 0 0)
			(layer "F.Fab")
			(effects
				(font
					(size 1.27 1.27)
				)
			)
		)
		(duplicate_pad_numbers_are_jumpers no)
		(fp_line
			(start -0.7874 -0.4064)
			(end 0.7874 -0.4064)
			(stroke
				(width 0.1524)
				(type default)
			)
			(layer "F.SilkS")
		)
		(fp_line
			(start -0.7874 0.4064)
			(end -0.7874 -0.4064)
			(stroke
				(width 0.1524)
				(type default)
			)
			(layer "F.SilkS")
		)
		(fp_line
			(start 0.7874 -0.4064)
			(end 0.7874 0.4064)
			(stroke
				(width 0.1524)
				(type default)
			)
			(layer "F.SilkS")
		)
		(fp_line
			(start 0.7874 0.4064)
			(end -0.7874 0.4064)
			(stroke
				(width 0.1524)
				(type default)
			)
			(layer "F.SilkS")
		)
		(fp_poly
			(pts
				(xy -0.508 0.2794) (xy -0.508 0.2286) (xy -0.635 0.2286) (xy -0.635 -0.254) (xy -0.5334 -0.254)
				(xy -0.5334 -0.2794) (xy 0.5334 -0.2794) (xy 0.5334 -0.254) (xy 0.635 -0.254) (xy 0.635 0.254) (xy 0.5334 0.254)
				(xy 0.5334 0.2794)
			)
			(stroke
				(width 0)
				(type default)
			)
			(fill no)
			(layer "F.CrtYd")
		)
		(pad "1" smd rect
			(at 0.40005 0)
			(size 0.4572 0.508)
			(layers "F.Cu" "F.Mask" "F.Paste")
			(net "P5V_NODE1")
		)
		(pad "2" smd rect
			(at -0.40005 0)
			(size 0.4572 0.508)
			(layers "F.Cu" "F.Mask" "F.Paste")
			(net "PMBUS1_EN")
		)
	)
	(footprint ""
		(layer "F.Cu")
		(at 36.34359 -103.486712 180)
		(property "Reference" "C823"
			(at 0.802132 -3.263138 0)
			(unlocked yes)
			(layer "F.SilkS")
			(effects
				(font
					(size 0.7874 0.5842)
					(thickness 0.1524)
				)
				(justify left)
			)
		)
		(property "Value" ""
			(at 0 0 180)
			(layer "F.Fab")
			(effects
				(font
					(size 1.27 1.27)
				)
			)
		)
		(duplicate_pad_numbers_are_jumpers no)
		(fp_line
			(start 0.7874 0.4064)
			(end -0.7874 0.4064)
			(stroke
				(width 0.1524)
				(type default)
			)
			(layer "F.SilkS")
		)
		(fp_line
			(start 0.7874 -0.4064)
			(end 0.7874 0.4064)
			(stroke
				(width 0.1524)
				(type default)
			)
			(layer "F.SilkS")
		)
		(fp_line
			(start 0 0.381)
			(end 0 -0.381)
			(stroke
				(width 0.1524)
				(type default)
			)
			(layer "F.SilkS")
		)
		(fp_line
			(start -0.7874 0.4064)
			(end -0.7874 -0.4064)
			(stroke
				(width 0.1524)
				(type default)
			)
			(layer "F.SilkS")
		)
		(fp_line
			(start -0.7874 -0.4064)
			(end 0.7874 -0.4064)
			(stroke
				(width 0.1524)
				(type default)
			)
			(layer "F.SilkS")
		)
		(fp_poly
			(pts
				(xy -0.5334 0.254) (xy -0.635 0.254) (xy -0.635 0.2286) (xy -0.635 -0.254) (xy -0.5334 -0.254) (xy -0.5334 -0.2794)
				(xy 0.5334 -0.2794) (xy 0.5334 -0.254) (xy 0.635 -0.254) (xy 0.635 0.254) (xy 0.5334 0.254) (xy 0.5334 0.2794)
				(xy -0.508 0.2794) (xy -0.5334 0.2794)
			)
			(stroke
				(width 0)
				(type default)
			)
			(fill no)
			(layer "F.CrtYd")
		)
		(pad "1" smd rect
			(at 0.40005 0 180)
			(size 0.4572 0.508)
			(layers "F.Cu" "F.Mask" "F.Paste")
			(net "P1V5_SUS_NODE1_ADJ")
		)
		(pad "2" smd rect
			(at -0.40005 0 180)
			(size 0.4572 0.508)
			(layers "F.Cu" "F.Mask" "F.Paste")
			(net "P1V5_SUS_NODE1")
		)
	)
	(footprint ""
		(layer "F.Cu")
		(at 93.339158 -159.826452 90)
		(property "Reference" "R800"
			(at -71.245984 86.162642 0)
			(unlocked yes)
			(layer "F.SilkS")
			(effects
				(font
					(size 0.7874 0.5842)
					(thickness 0.1524)
				)
				(justify left)
			)
		)
		(property "Value" ""
			(at 0 0 90)
			(layer "F.Fab")
			(effects
				(font
					(size 1.27 1.27)
				)
			)
		)
		(duplicate_pad_numbers_are_jumpers no)
		(fp_line
			(start 0.7874 -0.4064)
			(end 0.7874 0.4064)
			(stroke
				(width 0.1524)
				(type default)
			)
			(layer "F.SilkS")
		)
		(fp_line
			(start -0.7874 -0.4064)
			(end 0.7874 -0.4064)
			(stroke
				(width 0.1524)
				(type default)
			)
			(layer "F.SilkS")
		)
		(fp_line
			(start 0.7874 0.4064)
			(end -0.7874 0.4064)
			(stroke
				(width 0.1524)
				(type default)
			)
			(layer "F.SilkS")
		)
		(fp_line
			(start -0.7874 0.4064)
			(end -0.7874 -0.4064)
			(stroke
				(width 0.1524)
				(type default)
			)
			(layer "F.SilkS")
		)
		(fp_poly
			(pts
				(xy -0.508 0.2794) (xy -0.508 0.2286) (xy -0.635 0.2286) (xy -0.635 -0.254) (xy -0.5334 -0.254)
				(xy -0.5334 -0.2794) (xy 0.5334 -0.2794) (xy 0.5334 -0.254) (xy 0.635 -0.254) (xy 0.635 0.254) (xy 0.5334 0.254)
				(xy 0.5334 0.2794)
			)
			(stroke
				(width 0)
				(type default)
			)
			(fill no)
			(layer "F.CrtYd")
		)
		(pad "1" smd rect
			(at 0.40005 0 90)
			(size 0.4572 0.508)
			(layers "F.Cu" "F.Mask" "F.Paste")
			(net "N52410998")
		)
		(pad "2" smd rect
			(at -0.40005 0 90)
			(size 0.4572 0.508)
			(layers "F.Cu" "F.Mask" "F.Paste")
			(net "P3V3_STB_NODE1")
		)
	)
	(footprint ""
		(layer "F.Cu")
		(at 111.87176 -171.609512 180)
		(property "Reference" "R664"
			(at 2.02438 10.435336 0)
			(unlocked yes)
			(layer "F.SilkS")
			(effects
				(font
					(size 0.7874 0.5842)
					(thickness 0.1524)
				)
				(justify left)
			)
		)
		(property "Value" ""
			(at 0 0 180)
			(layer "F.Fab")
			(effects
				(font
					(size 1.27 1.27)
				)
			)
		)
		(duplicate_pad_numbers_are_jumpers no)
		(fp_line
			(start 0.7874 0.4064)
			(end -0.7874 0.4064)
			(stroke
				(width 0.1524)
				(type default)
			)
			(layer "F.SilkS")
		)
		(fp_line
			(start 0.7874 -0.4064)
			(end 0.7874 0.4064)
			(stroke
				(width 0.1524)
				(type default)
			)
			(layer "F.SilkS")
		)
		(fp_line
			(start -0.7874 0.4064)
			(end -0.7874 -0.4064)
			(stroke
				(width 0.1524)
				(type default)
			)
			(layer "F.SilkS")
		)
		(fp_line
			(start -0.7874 -0.4064)
			(end 0.7874 -0.4064)
			(stroke
				(width 0.1524)
				(type default)
			)
			(layer "F.SilkS")
		)
		(fp_poly
			(pts
				(xy -0.508 0.2794) (xy -0.508 0.2286) (xy -0.635 0.2286) (xy -0.635 -0.254) (xy -0.5334 -0.254)
				(xy -0.5334 -0.2794) (xy 0.5334 -0.2794) (xy 0.5334 -0.254) (xy 0.635 -0.254) (xy 0.635 0.254) (xy 0.5334 0.254)
				(xy 0.5334 0.2794)
			)
			(stroke
				(width 0)
				(type default)
			)
			(fill no)
			(layer "F.CrtYd")
		)
		(pad "1" smd rect
			(at 0.40005 0 180)
			(size 0.4572 0.508)
			(layers "F.Cu" "F.Mask" "F.Paste")
			(net "P3V3_NODE1")
		)
		(pad "2" smd rect
			(at -0.40005 0 180)
			(size 0.4572 0.508)
			(layers "F.Cu" "F.Mask" "F.Paste")
			(net "I2C_COM3_SDA")
		)
	)
	(footprint ""
		(layer "F.Cu")
		(at 72.168512 -1.69418 180)
		(property "Reference" "C933"
			(at -1.024636 -1.075182 0)
			(unlocked yes)
			(layer "F.SilkS")
			(effects
				(font
					(size 0.7874 0.5842)
					(thickness 0.1524)
				)
				(justify left)
			)
		)
		(property "Value" ""
			(at 0 0 180)
			(layer "F.Fab")
			(effects
				(font
					(size 1.27 1.27)
				)
			)
		)
		(duplicate_pad_numbers_are_jumpers no)
		(fp_line
			(start 0.7874 0.4064)
			(end -0.7874 0.4064)
			(stroke
				(width 0.1524)
				(type default)
			)
			(layer "F.SilkS")
		)
		(fp_line
			(start 0.7874 -0.4064)
			(end 0.7874 0.4064)
			(stroke
				(width 0.1524)
				(type default)
			)
			(layer "F.SilkS")
		)
		(fp_line
			(start 0 0.381)
			(end 0 -0.381)
			(stroke
				(width 0.1524)
				(type default)
			)
			(layer "F.SilkS")
		)
		(fp_line
			(start -0.7874 0.4064)
			(end -0.7874 -0.4064)
			(stroke
				(width 0.1524)
				(type default)
			)
			(layer "F.SilkS")
		)
		(fp_line
			(start -0.7874 -0.4064)
			(end 0.7874 -0.4064)
			(stroke
				(width 0.1524)
				(type default)
			)
			(layer "F.SilkS")
		)
		(fp_poly
			(pts
				(xy -0.5334 0.254) (xy -0.635 0.254) (xy -0.635 0.2286) (xy -0.635 -0.254) (xy -0.5334 -0.254) (xy -0.5334 -0.2794)
				(xy 0.5334 -0.2794) (xy 0.5334 -0.254) (xy 0.635 -0.254) (xy 0.635 0.254) (xy 0.5334 0.254) (xy 0.5334 0.2794)
				(xy -0.508 0.2794) (xy -0.5334 0.2794)
			)
			(stroke
				(width 0)
				(type default)
			)
			(fill no)
			(layer "F.CrtYd")
		)
		(pad "1" smd rect
			(at 0.40005 0 180)
			(size 0.4572 0.508)
			(layers "F.Cu" "F.Mask" "F.Paste")
			(net "FM_CPLD_NODE1_P3V3_EN")
		)
		(pad "2" smd rect
			(at -0.40005 0 180)
			(size 0.4572 0.508)
			(layers "F.Cu" "F.Mask" "F.Paste")
			(net "GND")
		)
	)
	(footprint ""
		(layer "F.Cu")
		(at 62.817756 -14.910054 -90)
		(property "Reference" "PC81"
			(at 0.031242 8.700008 90)
			(unlocked yes)
			(layer "F.SilkS")
			(effects
				(font
					(size 0.7874 0.5842)
					(thickness 0.1524)
				)
				(justify left)
			)
		)
		(property "Value" ""
			(at 0 0 270)
			(layer "F.Fab")
			(effects
				(font
					(size 1.27 1.27)
				)
			)
		)
		(duplicate_pad_numbers_are_jumpers no)
		(fp_line
			(start -1.905 0.8636)
			(end -1.905 -0.8636)
			(stroke
				(width 0.1524)
				(type default)
			)
			(layer "F.SilkS")
		)
		(fp_line
			(start 1.905 0.8636)
			(end -1.905 0.8636)
			(stroke
				(width 0.1524)
				(type default)
			)
			(layer "F.SilkS")
		)
		(fp_line
			(start 0 0.8382)
			(end 0 -0.8382)
			(stroke
				(width 0.1524)
				(type default)
			)
			(layer "F.SilkS")
		)
		(fp_line
			(start -1.905 -0.8636)
			(end 1.905 -0.8636)
			(stroke
				(width 0.1524)
				(type default)
			)
			(layer "F.SilkS")
		)
		(fp_line
			(start 1.905 -0.8636)
			(end 1.905 0.8636)
			(stroke
				(width 0.1524)
				(type default)
			)
			(layer "F.SilkS")
		)
		(fp_rect
			(start -1.524 0.7366)
			(end 1.524 -0.7366)
			(stroke
				(width 0)
				(type default)
			)
			(fill no)
			(layer "F.CrtYd")
		)
		(pad "1" smd rect
			(at 0.94996 0 270)
			(size 1.1176 1.3716)
			(layers "F.Cu" "F.Mask" "F.Paste")
			(net "PV_VDDR_NODE1")
		)
		(pad "2" smd rect
			(at -0.94996 0 270)
			(size 1.1176 1.3716)
			(layers "F.Cu" "F.Mask" "F.Paste")
			(net "GND")
		)
	)
	(footprint ""
		(layer "F.Cu")
		(at 33.169606 -106.210608 180)
		(property "Reference" "C824"
			(at -1.516126 -0.667766 0)
			(unlocked yes)
			(layer "F.SilkS")
			(effects
				(font
					(size 0.7874 0.5842)
					(thickness 0.1524)
				)
				(justify left)
			)
		)
		(property "Value" ""
			(at 0 0 180)
			(layer "F.Fab")
			(effects
				(font
					(size 1.27 1.27)
				)
			)
		)
		(duplicate_pad_numbers_are_jumpers no)
		(fp_line
			(start 0.7874 0.4064)
			(end -0.7874 0.4064)
			(stroke
				(width 0.1524)
				(type default)
			)
			(layer "F.SilkS")
		)
		(fp_line
			(start 0.7874 -0.4064)
			(end 0.7874 0.4064)
			(stroke
				(width 0.1524)
				(type default)
			)
			(layer "F.SilkS")
		)
		(fp_line
			(start 0 0.381)
			(end 0 -0.381)
			(stroke
				(width 0.1524)
				(type default)
			)
			(layer "F.SilkS")
		)
		(fp_line
			(start -0.7874 0.4064)
			(end -0.7874 -0.4064)
			(stroke
				(width 0.1524)
				(type default)
			)
			(layer "F.SilkS")
		)
		(fp_line
			(start -0.7874 -0.4064)
			(end 0.7874 -0.4064)
			(stroke
				(width 0.1524)
				(type default)
			)
			(layer "F.SilkS")
		)
		(fp_poly
			(pts
				(xy -0.5334 0.254) (xy -0.635 0.254) (xy -0.635 0.2286) (xy -0.635 -0.254) (xy -0.5334 -0.254) (xy -0.5334 -0.2794)
				(xy 0.5334 -0.2794) (xy 0.5334 -0.254) (xy 0.635 -0.254) (xy 0.635 0.254) (xy 0.5334 0.254) (xy 0.5334 0.2794)
				(xy -0.508 0.2794) (xy -0.5334 0.2794)
			)
			(stroke
				(width 0)
				(type default)
			)
			(fill no)
			(layer "F.CrtYd")
		)
		(pad "1" smd rect
			(at 0.40005 0 180)
			(size 0.4572 0.508)
			(layers "F.Cu" "F.Mask" "F.Paste")
			(net "GND")
		)
		(pad "2" smd rect
			(at -0.40005 0 180)
			(size 0.4572 0.508)
			(layers "F.Cu" "F.Mask" "F.Paste")
			(net "PWRGD_NODE1_P1V5_SUS_PG")
		)
	)
	(footprint ""
		(layer "F.Cu")
		(at 38.348412 -19.015202 180)
		(property "Reference" "R212"
			(at -1.984248 -0.002794 0)
			(unlocked yes)
			(layer "F.SilkS")
			(effects
				(font
					(size 0.7874 0.5842)
					(thickness 0.1524)
				)
				(justify left)
			)
		)
		(property "Value" ""
			(at 0 0 180)
			(layer "F.Fab")
			(effects
				(font
					(size 1.27 1.27)
				)
			)
		)
		(duplicate_pad_numbers_are_jumpers no)
		(fp_line
			(start 0.7874 0.4064)
			(end -0.7874 0.4064)
			(stroke
				(width 0.1524)
				(type default)
			)
			(layer "F.SilkS")
		)
		(fp_line
			(start 0.7874 -0.4064)
			(end 0.7874 0.4064)
			(stroke
				(width 0.1524)
				(type default)
			)
			(layer "F.SilkS")
		)
		(fp_line
			(start -0.7874 0.4064)
			(end -0.7874 -0.4064)
			(stroke
				(width 0.1524)
				(type default)
			)
			(layer "F.SilkS")
		)
		(fp_line
			(start -0.7874 -0.4064)
			(end 0.7874 -0.4064)
			(stroke
				(width 0.1524)
				(type default)
			)
			(layer "F.SilkS")
		)
		(fp_poly
			(pts
				(xy -0.508 0.2794) (xy -0.508 0.2286) (xy -0.635 0.2286) (xy -0.635 -0.254) (xy -0.5334 -0.254)
				(xy -0.5334 -0.2794) (xy 0.5334 -0.2794) (xy 0.5334 -0.254) (xy 0.635 -0.254) (xy 0.635 0.254) (xy 0.5334 0.254)
				(xy 0.5334 0.2794)
			)
			(stroke
				(width 0)
				(type default)
			)
			(fill no)
			(layer "F.CrtYd")
		)
		(pad "1" smd rect
			(at 0.40005 0 180)
			(size 0.4572 0.508)
			(layers "F.Cu" "F.Mask" "F.Paste")
			(net "GND")
		)
		(pad "2" smd rect
			(at -0.40005 0 180)
			(size 0.4572 0.508)
			(layers "F.Cu" "F.Mask" "F.Paste")
			(net "PD_NODE1_DM0")
		)
	)
	(footprint ""
		(layer "F.Cu")
		(at 51.310286 -117.869462 -90)
		(property "Reference" "R311"
			(at -0.18034 7.234428 0)
			(unlocked yes)
			(layer "F.SilkS")
			(effects
				(font
					(size 0.7874 0.5842)
					(thickness 0.1524)
				)
				(justify left)
			)
		)
		(property "Value" ""
			(at 0 0 270)
			(layer "F.Fab")
			(effects
				(font
					(size 1.27 1.27)
				)
			)
		)
		(duplicate_pad_numbers_are_jumpers no)
		(fp_line
			(start -0.7874 0.4064)
			(end -0.7874 -0.4064)
			(stroke
				(width 0.1524)
				(type default)
			)
			(layer "F.SilkS")
		)
		(fp_line
			(start 0.7874 0.4064)
			(end -0.7874 0.4064)
			(stroke
				(width 0.1524)
				(type default)
			)
			(layer "F.SilkS")
		)
		(fp_line
			(start -0.7874 -0.4064)
			(end 0.7874 -0.4064)
			(stroke
				(width 0.1524)
				(type default)
			)
			(layer "F.SilkS")
		)
		(fp_line
			(start 0.7874 -0.4064)
			(end 0.7874 0.4064)
			(stroke
				(width 0.1524)
				(type default)
			)
			(layer "F.SilkS")
		)
		(fp_poly
			(pts
				(xy -0.508 0.2794) (xy -0.508 0.2286) (xy -0.635 0.2286) (xy -0.635 -0.254) (xy -0.5334 -0.254)
				(xy -0.5334 -0.2794) (xy 0.5334 -0.2794) (xy 0.5334 -0.254) (xy 0.635 -0.254) (xy 0.635 0.254) (xy 0.5334 0.254)
				(xy 0.5334 0.2794)
			)
			(stroke
				(width 0)
				(type default)
			)
			(fill no)
			(layer "F.CrtYd")
		)
		(pad "1" smd rect
			(at 0.40005 0 270)
			(size 0.4572 0.508)
			(layers "F.Cu" "F.Mask" "F.Paste")
			(net "BMC_NODE1_OSC1_EN")
		)
		(pad "2" smd rect
			(at -0.40005 0 270)
			(size 0.4572 0.508)
			(layers "F.Cu" "F.Mask" "F.Paste")
			(net "BMC_NODE1_OSC1_VDD")
		)
	)
	(footprint ""
		(layer "F.Cu")
		(at 19.195542 -128.414526 90)
		(property "Reference" "PC60"
			(at -2.1082 5.06476 90)
			(unlocked yes)
			(layer "F.SilkS")
			(effects
				(font
					(size 0.7874 0.5842)
					(thickness 0.1524)
				)
				(justify left)
			)
		)
		(property "Value" ""
			(at 0 0 90)
			(layer "F.Fab")
			(effects
				(font
					(size 1.27 1.27)
				)
			)
		)
		(duplicate_pad_numbers_are_jumpers no)
		(fp_line
			(start 0.7874 -0.4064)
			(end 0.7874 0.4064)
			(stroke
				(width 0.1524)
				(type default)
			)
			(layer "F.SilkS")
		)
		(fp_line
			(start -0.7874 -0.4064)
			(end 0.7874 -0.4064)
			(stroke
				(width 0.1524)
				(type default)
			)
			(layer "F.SilkS")
		)
		(fp_line
			(start 0 0.381)
			(end 0 -0.381)
			(stroke
				(width 0.1524)
				(type default)
			)
			(layer "F.SilkS")
		)
		(fp_line
			(start 0.7874 0.4064)
			(end -0.7874 0.4064)
			(stroke
				(width 0.1524)
				(type default)
			)
			(layer "F.SilkS")
		)
		(fp_line
			(start -0.7874 0.4064)
			(end -0.7874 -0.4064)
			(stroke
				(width 0.1524)
				(type default)
			)
			(layer "F.SilkS")
		)
		(fp_poly
			(pts
				(xy -0.5334 0.254) (xy -0.635 0.254) (xy -0.635 0.2286) (xy -0.635 -0.254) (xy -0.5334 -0.254) (xy -0.5334 -0.2794)
				(xy 0.5334 -0.2794) (xy 0.5334 -0.254) (xy 0.635 -0.254) (xy 0.635 0.254) (xy 0.5334 0.254) (xy 0.5334 0.2794)
				(xy -0.508 0.2794) (xy -0.5334 0.2794)
			)
			(stroke
				(width 0)
				(type default)
			)
			(fill no)
			(layer "F.CrtYd")
		)
		(pad "1" smd rect
			(at 0.40005 0 90)
			(size 0.4572 0.508)
			(layers "F.Cu" "F.Mask" "F.Paste")
			(net "SW_P1V05_NODE1_BT")
		)
		(pad "2" smd rect
			(at -0.40005 0 90)
			(size 0.4572 0.508)
			(layers "F.Cu" "F.Mask" "F.Paste")
			(net "SW_P1V05_NODE1_PH")
		)
	)
	(footprint ""
		(layer "F.Cu")
		(at 40.668194 -15.20698)
		(property "Reference" "PJ9"
			(at 0.179578 -0.49022 90)
			(unlocked yes)
			(layer "F.SilkS")
			(effects
				(font
					(size 0.7874 0.5842)
					(thickness 0.1524)
				)
				(justify left)
			)
		)
		(property "Value" ""
			(at 0 0 0)
			(layer "F.Fab")
			(effects
				(font
					(size 1.27 1.27)
				)
			)
		)
		(duplicate_pad_numbers_are_jumpers no)
		(fp_poly
			(pts
				(xy 0.2794 0.907796) (xy 0.254 0.907796) (xy 0.254 1.0414) (xy -0.254 1.0414) (xy -0.254 1.034796)
				(xy -0.254 0.933196) (xy -0.2794 0.933196) (xy -0.2794 -0.133604) (xy -0.254 -0.133604) (xy -0.254 -0.235204)
				(xy 0.254 -0.235204) (xy 0.254 -0.133604) (xy 0.2794 -0.133604)
			)
			(stroke
				(width 0)
				(type default)
			)
			(fill no)
			(layer "F.CrtYd")
		)
		(pad "1" smd custom
			(at 0 -0.000254)
			(size 0.127 0.127)
			(layers "F.Cu" "F.Mask" "F.Paste")
			(net "PV_VDDR_NODE1_MODE")
			(options
				(clearance outline)
				(anchor circle)
			)
			(primitives
				(gr_poly
					(pts
						(xy -0.127 0.508) (xy -0.127 -0.0508) (xy -0.254 -0.0508) (xy -0.254 -0.508) (xy 0.254 -0.508)
						(xy 0.254 -0.0508) (xy 0.127 -0.0508) (xy 0.127 0.508)
					)
					(width 0)
					(fill yes)
				)
			)
		)
		(pad "2" smd rect
			(at 0 0.799846 90)
			(size 0.4572 0.508)
			(layers "F.Cu" "F.Mask" "F.Paste")
			(net "P5V_STB_NODE1")
		)
		(zone
			(layer "F.Cu")
			(hatch none 0.5)
			(connect_pads
				(clearance 0)
			)
			(min_thickness 0.25)
			(keepout
				(tracks allowed)
				(vias not_allowed)
				(pads allowed)
				(copperpour not_allowed)
				(footprints allowed)
			)
			(placement
				(enabled no)
				(sheetname "")
			)
			(fill
				(thermal_gap 0.5)
				(thermal_bridge_width 0.5)
				(island_removal_mode 0)
			)
			(polygon
				(pts
					(xy 40.363394 -14.121384) (xy 40.972994 -14.121384) (xy 40.972994 -15.492984) (xy 40.363394 -15.492984)
				)
			)
		)
	)
	(footprint ""
		(layer "F.Cu")
		(at 161.019998 -144.46123)
		(property "Reference" "C438"
			(at -2.221484 -1.354328 0)
			(unlocked yes)
			(layer "F.SilkS")
			(effects
				(font
					(size 0.7874 0.5842)
					(thickness 0.1524)
				)
				(justify left)
			)
		)
		(property "Value" ""
			(at 0 0 0)
			(layer "F.Fab")
			(effects
				(font
					(size 1.27 1.27)
				)
			)
		)
		(duplicate_pad_numbers_are_jumpers no)
		(fp_line
			(start -0.7874 -0.4064)
			(end 0.7874 -0.4064)
			(stroke
				(width 0.1524)
				(type default)
			)
			(layer "F.SilkS")
		)
		(fp_line
			(start -0.7874 0.4064)
			(end -0.7874 -0.4064)
			(stroke
				(width 0.1524)
				(type default)
			)
			(layer "F.SilkS")
		)
		(fp_line
			(start 0 0.381)
			(end 0 -0.381)
			(stroke
				(width 0.1524)
				(type default)
			)
			(layer "F.SilkS")
		)
		(fp_line
			(start 0.7874 -0.4064)
			(end 0.7874 0.4064)
			(stroke
				(width 0.1524)
				(type default)
			)
			(layer "F.SilkS")
		)
		(fp_line
			(start 0.7874 0.4064)
			(end -0.7874 0.4064)
			(stroke
				(width 0.1524)
				(type default)
			)
			(layer "F.SilkS")
		)
		(fp_poly
			(pts
				(xy -0.5334 0.254) (xy -0.635 0.254) (xy -0.635 0.2286) (xy -0.635 -0.254) (xy -0.5334 -0.254) (xy -0.5334 -0.2794)
				(xy 0.5334 -0.2794) (xy 0.5334 -0.254) (xy 0.635 -0.254) (xy 0.635 0.254) (xy 0.5334 0.254) (xy 0.5334 0.2794)
				(xy -0.508 0.2794) (xy -0.5334 0.2794)
			)
			(stroke
				(width 0)
				(type default)
			)
			(fill no)
			(layer "F.CrtYd")
		)
		(pad "1" smd rect
			(at 0.40005 0)
			(size 0.4572 0.508)
			(layers "F.Cu" "F.Mask" "F.Paste")
			(net "LAN2_XTAL_OUT")
		)
		(pad "2" smd rect
			(at -0.40005 0)
			(size 0.4572 0.508)
			(layers "F.Cu" "F.Mask" "F.Paste")
			(net "GND")
		)
	)
	(footprint ""
		(layer "F.Cu")
		(at 178.459892 -139.65301)
		(property "Reference" "C799"
			(at 1.821434 -0.133096 0)
			(unlocked yes)
			(layer "F.SilkS")
			(effects
				(font
					(size 0.7874 0.5842)
					(thickness 0.1524)
				)
				(justify left)
			)
		)
		(property "Value" ""
			(at 0 0 0)
			(layer "F.Fab")
			(effects
				(font
					(size 1.27 1.27)
				)
			)
		)
		(duplicate_pad_numbers_are_jumpers no)
		(fp_line
			(start -0.7874 -0.4064)
			(end 0.7874 -0.4064)
			(stroke
				(width 0.1524)
				(type default)
			)
			(layer "F.SilkS")
		)
		(fp_line
			(start -0.7874 0.4064)
			(end -0.7874 -0.4064)
			(stroke
				(width 0.1524)
				(type default)
			)
			(layer "F.SilkS")
		)
		(fp_line
			(start 0 0.381)
			(end 0 -0.381)
			(stroke
				(width 0.1524)
				(type default)
			)
			(layer "F.SilkS")
		)
		(fp_line
			(start 0.7874 -0.4064)
			(end 0.7874 0.4064)
			(stroke
				(width 0.1524)
				(type default)
			)
			(layer "F.SilkS")
		)
		(fp_line
			(start 0.7874 0.4064)
			(end -0.7874 0.4064)
			(stroke
				(width 0.1524)
				(type default)
			)
			(layer "F.SilkS")
		)
		(fp_poly
			(pts
				(xy -0.5334 0.254) (xy -0.635 0.254) (xy -0.635 0.2286) (xy -0.635 -0.254) (xy -0.5334 -0.254) (xy -0.5334 -0.2794)
				(xy 0.5334 -0.2794) (xy 0.5334 -0.254) (xy 0.635 -0.254) (xy 0.635 0.254) (xy 0.5334 0.254) (xy 0.5334 0.2794)
				(xy -0.508 0.2794) (xy -0.5334 0.2794)
			)
			(stroke
				(width 0)
				(type default)
			)
			(fill no)
			(layer "F.CrtYd")
		)
		(pad "1" smd rect
			(at 0.40005 0)
			(size 0.4572 0.508)
			(layers "F.Cu" "F.Mask" "F.Paste")
			(net "P3V3_STB_NODE1")
		)
		(pad "2" smd rect
			(at -0.40005 0)
			(size 0.4572 0.508)
			(layers "F.Cu" "F.Mask" "F.Paste")
			(net "GND")
		)
	)
	(footprint ""
		(layer "F.Cu")
		(at 57.207912 -100.35921 -90)
		(property "Reference" "R197"
			(at -1.014222 -0.04064 90)
			(unlocked yes)
			(layer "F.SilkS")
			(effects
				(font
					(size 0.7874 0.5842)
					(thickness 0.1524)
				)
				(justify left)
			)
		)
		(property "Value" ""
			(at 0 0 270)
			(layer "F.Fab")
			(effects
				(font
					(size 1.27 1.27)
				)
			)
		)
		(duplicate_pad_numbers_are_jumpers no)
		(fp_line
			(start -0.7874 0.4064)
			(end -0.7874 -0.4064)
			(stroke
				(width 0.1524)
				(type default)
			)
			(layer "F.SilkS")
		)
		(fp_line
			(start 0.7874 0.4064)
			(end -0.7874 0.4064)
			(stroke
				(width 0.1524)
				(type default)
			)
			(layer "F.SilkS")
		)
		(fp_line
			(start -0.7874 -0.4064)
			(end 0.7874 -0.4064)
			(stroke
				(width 0.1524)
				(type default)
			)
			(layer "F.SilkS")
		)
		(fp_line
			(start 0.7874 -0.4064)
			(end 0.7874 0.4064)
			(stroke
				(width 0.1524)
				(type default)
			)
			(layer "F.SilkS")
		)
		(fp_poly
			(pts
				(xy -0.508 0.2794) (xy -0.508 0.2286) (xy -0.635 0.2286) (xy -0.635 -0.254) (xy -0.5334 -0.254)
				(xy -0.5334 -0.2794) (xy 0.5334 -0.2794) (xy 0.5334 -0.254) (xy 0.635 -0.254) (xy 0.635 0.254) (xy 0.5334 0.254)
				(xy 0.5334 0.2794)
			)
			(stroke
				(width 0)
				(type default)
			)
			(fill no)
			(layer "F.CrtYd")
		)
		(pad "1" smd rect
			(at 0.40005 0 270)
			(size 0.4572 0.508)
			(layers "F.Cu" "F.Mask" "F.Paste")
			(net "P3V3_NODE1")
		)
		(pad "2" smd rect
			(at -0.40005 0 270)
			(size 0.4572 0.508)
			(layers "F.Cu" "F.Mask" "F.Paste")
			(net "PU_TEMP1_NODE1_SYS_SHDN_L")
		)
	)
	(footprint ""
		(layer "F.Cu")
		(at 82.414364 -17.679416 90)
		(property "Reference" "C150"
			(at -4.546854 5.52323 90)
			(unlocked yes)
			(layer "F.SilkS")
			(effects
				(font
					(size 0.7874 0.5842)
					(thickness 0.1524)
				)
				(justify left)
			)
		)
		(property "Value" ""
			(at 0 0 90)
			(layer "F.Fab")
			(effects
				(font
					(size 1.27 1.27)
				)
			)
		)
		(duplicate_pad_numbers_are_jumpers no)
		(fp_line
			(start 0.7874 -0.4064)
			(end 0.7874 0.4064)
			(stroke
				(width 0.1524)
				(type default)
			)
			(layer "F.SilkS")
		)
		(fp_line
			(start -0.7874 -0.4064)
			(end 0.7874 -0.4064)
			(stroke
				(width 0.1524)
				(type default)
			)
			(layer "F.SilkS")
		)
		(fp_line
			(start 0 0.381)
			(end 0 -0.381)
			(stroke
				(width 0.1524)
				(type default)
			)
			(layer "F.SilkS")
		)
		(fp_line
			(start 0.7874 0.4064)
			(end -0.7874 0.4064)
			(stroke
				(width 0.1524)
				(type default)
			)
			(layer "F.SilkS")
		)
		(fp_line
			(start -0.7874 0.4064)
			(end -0.7874 -0.4064)
			(stroke
				(width 0.1524)
				(type default)
			)
			(layer "F.SilkS")
		)
		(fp_poly
			(pts
				(xy -0.5334 0.254) (xy -0.635 0.254) (xy -0.635 0.2286) (xy -0.635 -0.254) (xy -0.5334 -0.254) (xy -0.5334 -0.2794)
				(xy 0.5334 -0.2794) (xy 0.5334 -0.254) (xy 0.635 -0.254) (xy 0.635 0.254) (xy 0.5334 0.254) (xy 0.5334 0.2794)
				(xy -0.508 0.2794) (xy -0.5334 0.2794)
			)
			(stroke
				(width 0)
				(type default)
			)
			(fill no)
			(layer "F.CrtYd")
		)
		(pad "1" smd rect
			(at 0.40005 0 90)
			(size 0.4572 0.508)
			(layers "F.Cu" "F.Mask" "F.Paste")
			(net "PV_VDDR_NODE1")
		)
		(pad "2" smd rect
			(at -0.40005 0 90)
			(size 0.4572 0.508)
			(layers "F.Cu" "F.Mask" "F.Paste")
			(net "GND")
		)
	)
	(footprint ""
		(layer "F.Cu")
		(at 145.65376 -188.126624 -90)
		(property "Reference" "R993"
			(at -5.519674 1.030732 90)
			(unlocked yes)
			(layer "F.SilkS")
			(effects
				(font
					(size 0.7874 0.5842)
					(thickness 0.1524)
				)
				(justify left)
			)
		)
		(property "Value" ""
			(at 0 0 270)
			(layer "F.Fab")
			(effects
				(font
					(size 1.27 1.27)
				)
			)
		)
		(duplicate_pad_numbers_are_jumpers no)
		(fp_line
			(start -0.7874 0.4064)
			(end -0.7874 -0.4064)
			(stroke
				(width 0.1524)
				(type default)
			)
			(layer "F.SilkS")
		)
		(fp_line
			(start 0.7874 0.4064)
			(end -0.7874 0.4064)
			(stroke
				(width 0.1524)
				(type default)
			)
			(layer "F.SilkS")
		)
		(fp_line
			(start -0.7874 -0.4064)
			(end 0.7874 -0.4064)
			(stroke
				(width 0.1524)
				(type default)
			)
			(layer "F.SilkS")
		)
		(fp_line
			(start 0.7874 -0.4064)
			(end 0.7874 0.4064)
			(stroke
				(width 0.1524)
				(type default)
			)
			(layer "F.SilkS")
		)
		(fp_poly
			(pts
				(xy -0.508 0.2794) (xy -0.508 0.2286) (xy -0.635 0.2286) (xy -0.635 -0.254) (xy -0.5334 -0.254)
				(xy -0.5334 -0.2794) (xy 0.5334 -0.2794) (xy 0.5334 -0.254) (xy 0.635 -0.254) (xy 0.635 0.254) (xy 0.5334 0.254)
				(xy 0.5334 0.2794)
			)
			(stroke
				(width 0)
				(type default)
			)
			(fill no)
			(layer "F.CrtYd")
		)
		(pad "1" smd rect
			(at 0.40005 0 270)
			(size 0.4572 0.508)
			(layers "F.Cu" "F.Mask" "F.Paste")
			(net "UART_T12_NODE3_RXD")
		)
		(pad "2" smd rect
			(at -0.40005 0 270)
			(size 0.4572 0.508)
			(layers "F.Cu" "F.Mask" "F.Paste")
			(net "UART_T12_NODE3_RXD_R")
		)
	)
	(footprint ""
		(layer "F.Cu")
		(at 119.12473 -41.529762 180)
		(property "Reference" "R625"
			(at 1.020318 -4.024884 0)
			(unlocked yes)
			(layer "F.SilkS")
			(effects
				(font
					(size 0.7874 0.5842)
					(thickness 0.1524)
				)
				(justify left)
			)
		)
		(property "Value" ""
			(at 0 0 180)
			(layer "F.Fab")
			(effects
				(font
					(size 1.27 1.27)
				)
			)
		)
		(duplicate_pad_numbers_are_jumpers no)
		(fp_line
			(start 0.7874 0.4064)
			(end -0.7874 0.4064)
			(stroke
				(width 0.1524)
				(type default)
			)
			(layer "F.SilkS")
		)
		(fp_line
			(start 0.7874 -0.4064)
			(end 0.7874 0.4064)
			(stroke
				(width 0.1524)
				(type default)
			)
			(layer "F.SilkS")
		)
		(fp_line
			(start -0.7874 0.4064)
			(end -0.7874 -0.4064)
			(stroke
				(width 0.1524)
				(type default)
			)
			(layer "F.SilkS")
		)
		(fp_line
			(start -0.7874 -0.4064)
			(end 0.7874 -0.4064)
			(stroke
				(width 0.1524)
				(type default)
			)
			(layer "F.SilkS")
		)
		(fp_poly
			(pts
				(xy -0.508 0.2794) (xy -0.508 0.2286) (xy -0.635 0.2286) (xy -0.635 -0.254) (xy -0.5334 -0.254)
				(xy -0.5334 -0.2794) (xy 0.5334 -0.2794) (xy 0.5334 -0.254) (xy 0.635 -0.254) (xy 0.635 0.254) (xy 0.5334 0.254)
				(xy 0.5334 0.2794)
			)
			(stroke
				(width 0)
				(type default)
			)
			(fill no)
			(layer "F.CrtYd")
		)
		(pad "1" smd rect
			(at 0.40005 0 180)
			(size 0.4572 0.508)
			(layers "F.Cu" "F.Mask" "F.Paste")
			(net "LPC_CPU_NODE1_CLKOUT1")
		)
		(pad "2" smd rect
			(at -0.40005 0 180)
			(size 0.4572 0.508)
			(layers "F.Cu" "F.Mask" "F.Paste")
			(net "SIO_PCICLK33")
		)
	)
	(footprint ""
		(layer "F.Cu")
		(at 33.344104 -116.518182 180)
		(property "Reference" "R1240"
			(at 6.054344 -1.034034 0)
			(unlocked yes)
			(layer "F.SilkS")
			(effects
				(font
					(size 0.7874 0.5842)
					(thickness 0.1524)
				)
				(justify left)
			)
		)
		(property "Value" ""
			(at 0 0 180)
			(layer "F.Fab")
			(effects
				(font
					(size 1.27 1.27)
				)
			)
		)
		(duplicate_pad_numbers_are_jumpers no)
		(fp_line
			(start 0.7874 0.4064)
			(end -0.7874 0.4064)
			(stroke
				(width 0.1524)
				(type default)
			)
			(layer "F.SilkS")
		)
		(fp_line
			(start 0.7874 -0.4064)
			(end 0.7874 0.4064)
			(stroke
				(width 0.1524)
				(type default)
			)
			(layer "F.SilkS")
		)
		(fp_line
			(start -0.7874 0.4064)
			(end -0.7874 -0.4064)
			(stroke
				(width 0.1524)
				(type default)
			)
			(layer "F.SilkS")
		)
		(fp_line
			(start -0.7874 -0.4064)
			(end 0.7874 -0.4064)
			(stroke
				(width 0.1524)
				(type default)
			)
			(layer "F.SilkS")
		)
		(fp_poly
			(pts
				(xy -0.508 0.2794) (xy -0.508 0.2286) (xy -0.635 0.2286) (xy -0.635 -0.254) (xy -0.5334 -0.254)
				(xy -0.5334 -0.2794) (xy 0.5334 -0.2794) (xy 0.5334 -0.254) (xy 0.635 -0.254) (xy 0.635 0.254) (xy 0.5334 0.254)
				(xy 0.5334 0.2794)
			)
			(stroke
				(width 0)
				(type default)
			)
			(fill no)
			(layer "F.CrtYd")
		)
		(pad "1" smd rect
			(at 0.40005 0 180)
			(size 0.4572 0.508)
			(layers "F.Cu" "F.Mask" "F.Paste")
			(net "GND")
		)
		(pad "2" smd rect
			(at -0.40005 0 180)
			(size 0.4572 0.508)
			(layers "F.Cu" "F.Mask" "F.Paste")
			(net "FM_CPLD_NODE1_P1V5_EN")
		)
	)
	(footprint ""
		(layer "F.Cu")
		(at 32.309308 -187.46851)
		(property "Reference" "R1025"
			(at -3.42011 -4.706874 0)
			(unlocked yes)
			(layer "F.SilkS")
			(effects
				(font
					(size 0.7874 0.5842)
					(thickness 0.1524)
				)
			)
		)
		(property "Value" ""
			(at 0 0 0)
			(layer "F.Fab")
			(effects
				(font
					(size 1.27 1.27)
				)
			)
		)
		(duplicate_pad_numbers_are_jumpers no)
		(fp_line
			(start -1.2954 -0.5842)
			(end 1.2954 -0.5842)
			(stroke
				(width 0.1524)
				(type default)
			)
			(layer "F.SilkS")
		)
		(fp_line
			(start -1.2954 0.5842)
			(end -1.2954 -0.5842)
			(stroke
				(width 0.1524)
				(type default)
			)
			(layer "F.SilkS")
		)
		(fp_line
			(start 1.2954 -0.5842)
			(end 1.2954 0.5842)
			(stroke
				(width 0.1524)
				(type default)
			)
			(layer "F.SilkS")
		)
		(fp_line
			(start 1.2954 0.5842)
			(end -1.2954 0.5842)
			(stroke
				(width 0.1524)
				(type default)
			)
			(layer "F.SilkS")
		)
		(fp_poly
			(pts
				(xy 1.143 -0.3556) (xy 1.143 0.3556) (xy 0.8636 0.3556) (xy 0.8636 0.4572) (xy -0.8636 0.4572) (xy -0.8636 0.4318)
				(xy -0.8636 0.3556) (xy -1.143 0.3556) (xy -1.143 -0.3556) (xy -0.8636 -0.3556) (xy -0.8636 -0.4572)
				(xy 0.8636 -0.4572) (xy 0.8636 -0.3556)
			)
			(stroke
				(width 0)
				(type default)
			)
			(fill no)
			(layer "F.CrtYd")
		)
		(pad "1" smd rect
			(at 0.7366 0 90)
			(size 0.7112 0.8128)
			(layers "F.Cu" "F.Mask" "F.Paste")
			(net "AGND_HSC_NODE1")
		)
		(pad "2" smd rect
			(at -0.7366 0 90)
			(size 0.7112 0.8128)
			(layers "F.Cu" "F.Mask" "F.Paste")
			(net "GND")
		)
	)
	(footprint ""
		(layer "F.Cu")
		(at 75.67676 -188.126624 -90)
		(property "Reference" "R938"
			(at -4.548886 1.292098 90)
			(unlocked yes)
			(layer "F.SilkS")
			(effects
				(font
					(size 0.7874 0.5842)
					(thickness 0.1524)
				)
				(justify left)
			)
		)
		(property "Value" ""
			(at 0 0 270)
			(layer "F.Fab")
			(effects
				(font
					(size 1.27 1.27)
				)
			)
		)
		(duplicate_pad_numbers_are_jumpers no)
		(fp_line
			(start -0.7874 0.4064)
			(end -0.7874 -0.4064)
			(stroke
				(width 0.1524)
				(type default)
			)
			(layer "F.SilkS")
		)
		(fp_line
			(start 0.7874 0.4064)
			(end -0.7874 0.4064)
			(stroke
				(width 0.1524)
				(type default)
			)
			(layer "F.SilkS")
		)
		(fp_line
			(start -0.7874 -0.4064)
			(end 0.7874 -0.4064)
			(stroke
				(width 0.1524)
				(type default)
			)
			(layer "F.SilkS")
		)
		(fp_line
			(start 0.7874 -0.4064)
			(end 0.7874 0.4064)
			(stroke
				(width 0.1524)
				(type default)
			)
			(layer "F.SilkS")
		)
		(fp_poly
			(pts
				(xy -0.508 0.2794) (xy -0.508 0.2286) (xy -0.635 0.2286) (xy -0.635 -0.254) (xy -0.5334 -0.254)
				(xy -0.5334 -0.2794) (xy 0.5334 -0.2794) (xy 0.5334 -0.254) (xy 0.635 -0.254) (xy 0.635 0.254) (xy 0.5334 0.254)
				(xy 0.5334 0.2794)
			)
			(stroke
				(width 0)
				(type default)
			)
			(fill no)
			(layer "F.CrtYd")
		)
		(pad "1" smd rect
			(at 0.40005 0 270)
			(size 0.4572 0.508)
			(layers "F.Cu" "F.Mask" "F.Paste")
			(net "UART_T4_NODE2_RXD")
		)
		(pad "2" smd rect
			(at -0.40005 0 270)
			(size 0.4572 0.508)
			(layers "F.Cu" "F.Mask" "F.Paste")
			(net "UART_T4_NODE2_RXD_R")
		)
	)
	(footprint ""
		(layer "F.Cu")
		(at 69.755004 -165.662356 180)
		(property "Reference" "R676"
			(at 4.49072 0.046228 0)
			(unlocked yes)
			(layer "F.SilkS")
			(effects
				(font
					(size 0.7874 0.5842)
					(thickness 0.1524)
				)
				(justify left)
			)
		)
		(property "Value" ""
			(at 0 0 180)
			(layer "F.Fab")
			(effects
				(font
					(size 1.27 1.27)
				)
			)
		)
		(duplicate_pad_numbers_are_jumpers no)
		(fp_line
			(start 0.7874 0.4064)
			(end -0.7874 0.4064)
			(stroke
				(width 0.1524)
				(type default)
			)
			(layer "F.SilkS")
		)
		(fp_line
			(start 0.7874 -0.4064)
			(end 0.7874 0.4064)
			(stroke
				(width 0.1524)
				(type default)
			)
			(layer "F.SilkS")
		)
		(fp_line
			(start -0.7874 0.4064)
			(end -0.7874 -0.4064)
			(stroke
				(width 0.1524)
				(type default)
			)
			(layer "F.SilkS")
		)
		(fp_line
			(start -0.7874 -0.4064)
			(end 0.7874 -0.4064)
			(stroke
				(width 0.1524)
				(type default)
			)
			(layer "F.SilkS")
		)
		(fp_poly
			(pts
				(xy -0.508 0.2794) (xy -0.508 0.2286) (xy -0.635 0.2286) (xy -0.635 -0.254) (xy -0.5334 -0.254)
				(xy -0.5334 -0.2794) (xy 0.5334 -0.2794) (xy 0.5334 -0.254) (xy 0.635 -0.254) (xy 0.635 0.254) (xy 0.5334 0.254)
				(xy 0.5334 0.2794)
			)
			(stroke
				(width 0)
				(type default)
			)
			(fill no)
			(layer "F.CrtYd")
		)
		(pad "1" smd rect
			(at 0.40005 0 180)
			(size 0.4572 0.508)
			(layers "F.Cu" "F.Mask" "F.Paste")
			(net "CPLD123_RSV2")
		)
		(pad "2" smd rect
			(at -0.40005 0 180)
			(size 0.4572 0.508)
			(layers "F.Cu" "F.Mask" "F.Paste")
			(net "CPLD2_RSV2")
		)
	)
	(footprint ""
		(layer "F.Cu")
		(at 94.211394 -187.822586 180)
		(property "Reference" "C705"
			(at 1.182878 7.364984 0)
			(unlocked yes)
			(layer "F.SilkS")
			(effects
				(font
					(size 0.7874 0.5842)
					(thickness 0.1524)
				)
				(justify left)
			)
		)
		(property "Value" ""
			(at 0 0 180)
			(layer "F.Fab")
			(effects
				(font
					(size 1.27 1.27)
				)
			)
		)
		(duplicate_pad_numbers_are_jumpers no)
		(fp_line
			(start 0.7874 0.4064)
			(end -0.7874 0.4064)
			(stroke
				(width 0.1524)
				(type default)
			)
			(layer "F.SilkS")
		)
		(fp_line
			(start 0.7874 -0.4064)
			(end 0.7874 0.4064)
			(stroke
				(width 0.1524)
				(type default)
			)
			(layer "F.SilkS")
		)
		(fp_line
			(start 0 0.381)
			(end 0 -0.381)
			(stroke
				(width 0.1524)
				(type default)
			)
			(layer "F.SilkS")
		)
		(fp_line
			(start -0.7874 0.4064)
			(end -0.7874 -0.4064)
			(stroke
				(width 0.1524)
				(type default)
			)
			(layer "F.SilkS")
		)
		(fp_line
			(start -0.7874 -0.4064)
			(end 0.7874 -0.4064)
			(stroke
				(width 0.1524)
				(type default)
			)
			(layer "F.SilkS")
		)
		(fp_poly
			(pts
				(xy -0.5334 0.254) (xy -0.635 0.254) (xy -0.635 0.2286) (xy -0.635 -0.254) (xy -0.5334 -0.254) (xy -0.5334 -0.2794)
				(xy 0.5334 -0.2794) (xy 0.5334 -0.254) (xy 0.635 -0.254) (xy 0.635 0.254) (xy 0.5334 0.254) (xy 0.5334 0.2794)
				(xy -0.508 0.2794) (xy -0.5334 0.2794)
			)
			(stroke
				(width 0)
				(type default)
			)
			(fill no)
			(layer "F.CrtYd")
		)
		(pad "1" smd rect
			(at 0.40005 0 180)
			(size 0.4572 0.508)
			(layers "F.Cu" "F.Mask" "F.Paste")
			(net "UART_T6_NODE2_TXD_R")
		)
		(pad "2" smd rect
			(at -0.40005 0 180)
			(size 0.4572 0.508)
			(layers "F.Cu" "F.Mask" "F.Paste")
			(net "GND")
		)
	)
	(footprint ""
		(layer "F.Cu")
		(at 123.75896 -188.126624 90)
		(property "Reference" "C629"
			(at 4.949444 -0.396748 90)
			(unlocked yes)
			(layer "F.SilkS")
			(effects
				(font
					(size 0.7874 0.5842)
					(thickness 0.1524)
				)
				(justify left)
			)
		)
		(property "Value" ""
			(at 0 0 90)
			(layer "F.Fab")
			(effects
				(font
					(size 1.27 1.27)
				)
			)
		)
		(duplicate_pad_numbers_are_jumpers no)
		(fp_line
			(start 0.7874 -0.4064)
			(end 0.7874 0.4064)
			(stroke
				(width 0.1524)
				(type default)
			)
			(layer "F.SilkS")
		)
		(fp_line
			(start -0.7874 -0.4064)
			(end 0.7874 -0.4064)
			(stroke
				(width 0.1524)
				(type default)
			)
			(layer "F.SilkS")
		)
		(fp_line
			(start 0 0.381)
			(end 0 -0.381)
			(stroke
				(width 0.1524)
				(type default)
			)
			(layer "F.SilkS")
		)
		(fp_line
			(start 0.7874 0.4064)
			(end -0.7874 0.4064)
			(stroke
				(width 0.1524)
				(type default)
			)
			(layer "F.SilkS")
		)
		(fp_line
			(start -0.7874 0.4064)
			(end -0.7874 -0.4064)
			(stroke
				(width 0.1524)
				(type default)
			)
			(layer "F.SilkS")
		)
		(fp_poly
			(pts
				(xy -0.5334 0.254) (xy -0.635 0.254) (xy -0.635 0.2286) (xy -0.635 -0.254) (xy -0.5334 -0.254) (xy -0.5334 -0.2794)
				(xy 0.5334 -0.2794) (xy 0.5334 -0.254) (xy 0.635 -0.254) (xy 0.635 0.254) (xy 0.5334 0.254) (xy 0.5334 0.2794)
				(xy -0.508 0.2794) (xy -0.5334 0.2794)
			)
			(stroke
				(width 0)
				(type default)
			)
			(fill no)
			(layer "F.CrtYd")
		)
		(pad "1" smd rect
			(at 0.40005 0 90)
			(size 0.4572 0.508)
			(layers "F.Cu" "F.Mask" "F.Paste")
			(net "T8_NODE3_EN_R")
		)
		(pad "2" smd rect
			(at -0.40005 0 90)
			(size 0.4572 0.508)
			(layers "F.Cu" "F.Mask" "F.Paste")
			(net "GND")
		)
	)
	(footprint ""
		(layer "F.Cu")
		(at 65.38976 -185.205624 -90)
		(property "Reference" "R880"
			(at -4.006088 0.811022 90)
			(unlocked yes)
			(layer "F.SilkS")
			(effects
				(font
					(size 0.7874 0.5842)
					(thickness 0.1524)
				)
				(justify left)
			)
		)
		(property "Value" ""
			(at 0 0 270)
			(layer "F.Fab")
			(effects
				(font
					(size 1.27 1.27)
				)
			)
		)
		(duplicate_pad_numbers_are_jumpers no)
		(fp_line
			(start -0.7874 0.4064)
			(end -0.7874 -0.4064)
			(stroke
				(width 0.1524)
				(type default)
			)
			(layer "F.SilkS")
		)
		(fp_line
			(start 0.7874 0.4064)
			(end -0.7874 0.4064)
			(stroke
				(width 0.1524)
				(type default)
			)
			(layer "F.SilkS")
		)
		(fp_line
			(start -0.7874 -0.4064)
			(end 0.7874 -0.4064)
			(stroke
				(width 0.1524)
				(type default)
			)
			(layer "F.SilkS")
		)
		(fp_line
			(start 0.7874 -0.4064)
			(end 0.7874 0.4064)
			(stroke
				(width 0.1524)
				(type default)
			)
			(layer "F.SilkS")
		)
		(fp_poly
			(pts
				(xy -0.508 0.2794) (xy -0.508 0.2286) (xy -0.635 0.2286) (xy -0.635 -0.254) (xy -0.5334 -0.254)
				(xy -0.5334 -0.2794) (xy 0.5334 -0.2794) (xy 0.5334 -0.254) (xy 0.635 -0.254) (xy 0.635 0.254) (xy 0.5334 0.254)
				(xy 0.5334 0.2794)
			)
			(stroke
				(width 0)
				(type default)
			)
			(fill no)
			(layer "F.CrtYd")
		)
		(pad "1" smd rect
			(at 0.40005 0 270)
			(size 0.4572 0.508)
			(layers "F.Cu" "F.Mask" "F.Paste")
			(net "T2_NODE4_EN")
		)
		(pad "2" smd rect
			(at -0.40005 0 270)
			(size 0.4572 0.508)
			(layers "F.Cu" "F.Mask" "F.Paste")
			(net "T2_NODE4_EN_R")
		)
	)
	(footprint ""
		(layer "F.Cu")
		(at 108.178346 -143.79575)
		(property "Reference" "PR72"
			(at -0.863854 -3.066542 0)
			(unlocked yes)
			(layer "F.SilkS")
			(effects
				(font
					(size 0.635 0.4064)
					(thickness 0.1524)
				)
				(justify left)
			)
		)
		(property "Value" ""
			(at 0 0 0)
			(layer "F.Fab")
			(effects
				(font
					(size 1.27 1.27)
				)
			)
		)
		(duplicate_pad_numbers_are_jumpers no)
		(fp_line
			(start -0.7874 -0.4064)
			(end 0.7874 -0.4064)
			(stroke
				(width 0.1524)
				(type default)
			)
			(layer "F.SilkS")
		)
		(fp_line
			(start -0.7874 0.4064)
			(end -0.7874 -0.4064)
			(stroke
				(width 0.1524)
				(type default)
			)
			(layer "F.SilkS")
		)
		(fp_line
			(start 0.7874 -0.4064)
			(end 0.7874 0.4064)
			(stroke
				(width 0.1524)
				(type default)
			)
			(layer "F.SilkS")
		)
		(fp_line
			(start 0.7874 0.4064)
			(end -0.7874 0.4064)
			(stroke
				(width 0.1524)
				(type default)
			)
			(layer "F.SilkS")
		)
		(fp_poly
			(pts
				(xy -0.508 0.2794) (xy -0.508 0.2286) (xy -0.635 0.2286) (xy -0.635 -0.254) (xy -0.5334 -0.254)
				(xy -0.5334 -0.2794) (xy 0.5334 -0.2794) (xy 0.5334 -0.254) (xy 0.635 -0.254) (xy 0.635 0.254) (xy 0.5334 0.254)
				(xy 0.5334 0.2794)
			)
			(stroke
				(width 0)
				(type default)
			)
			(fill no)
			(layer "F.CrtYd")
		)
		(pad "1" smd rect
			(at 0.40005 0)
			(size 0.4572 0.508)
			(layers "F.Cu" "F.Mask" "F.Paste")
			(net "VR_PVCCP_NODE1_VCC")
		)
		(pad "2" smd rect
			(at -0.40005 0)
			(size 0.4572 0.508)
			(layers "F.Cu" "F.Mask" "F.Paste")
			(net "VR_PVCCP_NODE1_TSEN_R")
		)
	)
	(footprint ""
		(layer "F.Cu")
		(at 180.765704 -11.53668 90)
		(property "Reference" "R817"
			(at -0.869696 -2.188972 90)
			(unlocked yes)
			(layer "F.SilkS")
			(effects
				(font
					(size 0.7874 0.5842)
					(thickness 0.1524)
				)
				(justify left)
			)
		)
		(property "Value" ""
			(at 0 0 90)
			(layer "F.Fab")
			(effects
				(font
					(size 1.27 1.27)
				)
			)
		)
		(duplicate_pad_numbers_are_jumpers no)
		(fp_line
			(start 0.7874 -0.4064)
			(end 0.7874 0.4064)
			(stroke
				(width 0.1524)
				(type default)
			)
			(layer "F.SilkS")
		)
		(fp_line
			(start -0.7874 -0.4064)
			(end 0.7874 -0.4064)
			(stroke
				(width 0.1524)
				(type default)
			)
			(layer "F.SilkS")
		)
		(fp_line
			(start 0.7874 0.4064)
			(end -0.7874 0.4064)
			(stroke
				(width 0.1524)
				(type default)
			)
			(layer "F.SilkS")
		)
		(fp_line
			(start -0.7874 0.4064)
			(end -0.7874 -0.4064)
			(stroke
				(width 0.1524)
				(type default)
			)
			(layer "F.SilkS")
		)
		(fp_poly
			(pts
				(xy -0.508 0.2794) (xy -0.508 0.2286) (xy -0.635 0.2286) (xy -0.635 -0.254) (xy -0.5334 -0.254)
				(xy -0.5334 -0.2794) (xy 0.5334 -0.2794) (xy 0.5334 -0.254) (xy 0.635 -0.254) (xy 0.635 0.254) (xy 0.5334 0.254)
				(xy 0.5334 0.2794)
			)
			(stroke
				(width 0)
				(type default)
			)
			(fill no)
			(layer "F.CrtYd")
		)
		(pad "1" smd rect
			(at 0.40005 0 90)
			(size 0.4572 0.508)
			(layers "F.Cu" "F.Mask" "F.Paste")
			(net "LED_PWR_NODE1_L")
		)
		(pad "2" smd rect
			(at -0.40005 0 90)
			(size 0.4572 0.508)
			(layers "F.Cu" "F.Mask" "F.Paste")
			(net "LED_PWR_GD")
		)
	)
	(footprint ""
		(layer "F.Cu")
		(at 176.666398 -36.848034)
		(property "Reference" "C558"
			(at -4.146042 0.612902 0)
			(unlocked yes)
			(layer "F.SilkS")
			(effects
				(font
					(size 0.7874 0.5842)
					(thickness 0.1524)
				)
				(justify left)
			)
		)
		(property "Value" ""
			(at 0 0 0)
			(layer "F.Fab")
			(effects
				(font
					(size 1.27 1.27)
				)
			)
		)
		(duplicate_pad_numbers_are_jumpers no)
		(fp_line
			(start -0.7874 -0.4064)
			(end 0.7874 -0.4064)
			(stroke
				(width 0.1524)
				(type default)
			)
			(layer "F.SilkS")
		)
		(fp_line
			(start -0.7874 0.4064)
			(end -0.7874 -0.4064)
			(stroke
				(width 0.1524)
				(type default)
			)
			(layer "F.SilkS")
		)
		(fp_line
			(start 0 0.381)
			(end 0 -0.381)
			(stroke
				(width 0.1524)
				(type default)
			)
			(layer "F.SilkS")
		)
		(fp_line
			(start 0.7874 -0.4064)
			(end 0.7874 0.4064)
			(stroke
				(width 0.1524)
				(type default)
			)
			(layer "F.SilkS")
		)
		(fp_line
			(start 0.7874 0.4064)
			(end -0.7874 0.4064)
			(stroke
				(width 0.1524)
				(type default)
			)
			(layer "F.SilkS")
		)
		(fp_poly
			(pts
				(xy -0.5334 0.254) (xy -0.635 0.254) (xy -0.635 0.2286) (xy -0.635 -0.254) (xy -0.5334 -0.254) (xy -0.5334 -0.2794)
				(xy 0.5334 -0.2794) (xy 0.5334 -0.254) (xy 0.635 -0.254) (xy 0.635 0.254) (xy 0.5334 0.254) (xy 0.5334 0.2794)
				(xy -0.508 0.2794) (xy -0.5334 0.2794)
			)
			(stroke
				(width 0)
				(type default)
			)
			(fill no)
			(layer "F.CrtYd")
		)
		(pad "1" smd rect
			(at 0.40005 0)
			(size 0.4572 0.508)
			(layers "F.Cu" "F.Mask" "F.Paste")
			(net "USBPWR_P0")
		)
		(pad "2" smd rect
			(at -0.40005 0)
			(size 0.4572 0.508)
			(layers "F.Cu" "F.Mask" "F.Paste")
			(net "GND")
		)
	)
	(footprint ""
		(layer "F.Cu")
		(at 88.232488 -153.673302)
		(property "Reference" "PC38"
			(at -1.467104 4.67614 0)
			(unlocked yes)
			(layer "F.SilkS")
			(effects
				(font
					(size 0.7874 0.5842)
					(thickness 0.1524)
				)
				(justify left)
			)
		)
		(property "Value" ""
			(at 0 0 0)
			(layer "F.Fab")
			(effects
				(font
					(size 1.27 1.27)
				)
			)
		)
		(duplicate_pad_numbers_are_jumpers no)
		(fp_line
			(start -1.905 -0.8636)
			(end 1.905 -0.8636)
			(stroke
				(width 0.1524)
				(type default)
			)
			(layer "F.SilkS")
		)
		(fp_line
			(start -1.905 0.8636)
			(end -1.905 -0.8636)
			(stroke
				(width 0.1524)
				(type default)
			)
			(layer "F.SilkS")
		)
		(fp_line
			(start 0 0.8382)
			(end 0 -0.8382)
			(stroke
				(width 0.1524)
				(type default)
			)
			(layer "F.SilkS")
		)
		(fp_line
			(start 1.905 -0.8636)
			(end 1.905 0.8636)
			(stroke
				(width 0.1524)
				(type default)
			)
			(layer "F.SilkS")
		)
		(fp_line
			(start 1.905 0.8636)
			(end -1.905 0.8636)
			(stroke
				(width 0.1524)
				(type default)
			)
			(layer "F.SilkS")
		)
		(fp_rect
			(start -1.524 0.7366)
			(end 1.524 -0.7366)
			(stroke
				(width 0)
				(type default)
			)
			(fill no)
			(layer "F.CrtYd")
		)
		(pad "1" smd rect
			(at 0.94996 0)
			(size 1.1176 1.3716)
			(layers "F.Cu" "F.Mask" "F.Paste")
			(net "P1V8_STB_NODE1")
		)
		(pad "2" smd rect
			(at -0.94996 0)
			(size 1.1176 1.3716)
			(layers "F.Cu" "F.Mask" "F.Paste")
			(net "GND")
		)
	)
	(footprint ""
		(layer "F.Cu")
		(at 167.622982 -131.768088 90)
		(property "Reference" "R627"
			(at -2.067052 -3.003296 90)
			(unlocked yes)
			(layer "F.SilkS")
			(effects
				(font
					(size 0.7874 0.5842)
					(thickness 0.1524)
				)
				(justify left)
			)
		)
		(property "Value" ""
			(at 0 0 90)
			(layer "F.Fab")
			(effects
				(font
					(size 1.27 1.27)
				)
			)
		)
		(duplicate_pad_numbers_are_jumpers no)
		(fp_line
			(start 0.7874 -0.4064)
			(end 0.7874 0.4064)
			(stroke
				(width 0.1524)
				(type default)
			)
			(layer "F.SilkS")
		)
		(fp_line
			(start -0.7874 -0.4064)
			(end 0.7874 -0.4064)
			(stroke
				(width 0.1524)
				(type default)
			)
			(layer "F.SilkS")
		)
		(fp_line
			(start 0.7874 0.4064)
			(end -0.7874 0.4064)
			(stroke
				(width 0.1524)
				(type default)
			)
			(layer "F.SilkS")
		)
		(fp_line
			(start -0.7874 0.4064)
			(end -0.7874 -0.4064)
			(stroke
				(width 0.1524)
				(type default)
			)
			(layer "F.SilkS")
		)
		(fp_poly
			(pts
				(xy -0.508 0.2794) (xy -0.508 0.2286) (xy -0.635 0.2286) (xy -0.635 -0.254) (xy -0.5334 -0.254)
				(xy -0.5334 -0.2794) (xy 0.5334 -0.2794) (xy 0.5334 -0.254) (xy 0.635 -0.254) (xy 0.635 0.254) (xy 0.5334 0.254)
				(xy 0.5334 0.2794)
			)
			(stroke
				(width 0)
				(type default)
			)
			(fill no)
			(layer "F.CrtYd")
		)
		(pad "1" smd rect
			(at 0.40005 0 90)
			(size 0.4572 0.508)
			(layers "F.Cu" "F.Mask" "F.Paste")
			(net "CPLD123_RSV1")
		)
		(pad "2" smd rect
			(at -0.40005 0 90)
			(size 0.4572 0.508)
			(layers "F.Cu" "F.Mask" "F.Paste")
			(net "CPLD1_RSV1")
		)
	)
	(footprint ""
		(layer "F.Cu")
		(at 67.749928 -106.303572 -90)
		(property "Reference" "R1238"
			(at 0.174244 -7.77621 90)
			(unlocked yes)
			(layer "F.SilkS")
			(effects
				(font
					(size 0.7874 0.5842)
					(thickness 0.1524)
				)
				(justify left)
			)
		)
		(property "Value" ""
			(at 0 0 270)
			(layer "F.Fab")
			(effects
				(font
					(size 1.27 1.27)
				)
			)
		)
		(duplicate_pad_numbers_are_jumpers no)
		(fp_line
			(start -0.7874 0.4064)
			(end -0.7874 -0.4064)
			(stroke
				(width 0.1524)
				(type default)
			)
			(layer "F.SilkS")
		)
		(fp_line
			(start 0.7874 0.4064)
			(end -0.7874 0.4064)
			(stroke
				(width 0.1524)
				(type default)
			)
			(layer "F.SilkS")
		)
		(fp_line
			(start -0.7874 -0.4064)
			(end 0.7874 -0.4064)
			(stroke
				(width 0.1524)
				(type default)
			)
			(layer "F.SilkS")
		)
		(fp_line
			(start 0.7874 -0.4064)
			(end 0.7874 0.4064)
			(stroke
				(width 0.1524)
				(type default)
			)
			(layer "F.SilkS")
		)
		(fp_poly
			(pts
				(xy -0.508 0.2794) (xy -0.508 0.2286) (xy -0.635 0.2286) (xy -0.635 -0.254) (xy -0.5334 -0.254)
				(xy -0.5334 -0.2794) (xy 0.5334 -0.2794) (xy 0.5334 -0.254) (xy 0.635 -0.254) (xy 0.635 0.254) (xy 0.5334 0.254)
				(xy 0.5334 0.2794)
			)
			(stroke
				(width 0)
				(type default)
			)
			(fill no)
			(layer "F.CrtYd")
		)
		(pad "1" smd rect
			(at 0.40005 0 270)
			(size 0.4572 0.508)
			(layers "F.Cu" "F.Mask" "F.Paste")
			(net "GND")
		)
		(pad "2" smd rect
			(at -0.40005 0 270)
			(size 0.4572 0.508)
			(layers "F.Cu" "F.Mask" "F.Paste")
			(net "FM_CPLD_NODE1_P1V8_EN")
		)
	)
	(footprint ""
		(layer "F.Cu")
		(at 114.849656 -106.35107 90)
		(property "Reference" "PC100"
			(at -0.745236 4.893564 0)
			(unlocked yes)
			(layer "F.SilkS")
			(effects
				(font
					(size 0.7874 0.5842)
					(thickness 0.1524)
				)
				(justify left)
			)
		)
		(property "Value" ""
			(at 0 0 90)
			(layer "F.Fab")
			(effects
				(font
					(size 1.27 1.27)
				)
			)
		)
		(duplicate_pad_numbers_are_jumpers no)
		(fp_line
			(start 2.249932 -4.533392)
			(end 2.249932 4.533392)
			(stroke
				(width 0.1524)
				(type default)
			)
			(layer "F.SilkS")
		)
		(fp_line
			(start -2.249932 -4.533392)
			(end 2.249932 -4.533392)
			(stroke
				(width 0.1524)
				(type default)
			)
			(layer "F.SilkS")
		)
		(fp_line
			(start 2.249932 4.533392)
			(end -2.249932 4.533392)
			(stroke
				(width 0.1524)
				(type default)
			)
			(layer "F.SilkS")
		)
		(fp_line
			(start -2.249932 4.533392)
			(end -2.249932 -4.533392)
			(stroke
				(width 0.1524)
				(type default)
			)
			(layer "F.SilkS")
		)
		(fp_poly
			(pts
				(xy 2.326132 -4.533392) (xy 2.326132 -5.39242) (xy -2.326132 -5.39242) (xy -2.326132 -4.533392)
			)
			(stroke
				(width 0)
				(type default)
			)
			(fill yes)
			(layer "F.SilkS")
		)
		(fp_poly
			(pts
				(xy -1.4605 4.457192) (xy -1.4605 3.750056) (xy -2.249932 3.750056) (xy -2.249932 -3.750056) (xy -1.4605 -3.750056)
				(xy -1.4605 -4.457192) (xy 1.4605 -4.457192) (xy 1.4605 -3.750056) (xy 2.249932 -3.750056) (xy 2.249932 3.750056)
				(xy 1.4605 3.750056) (xy 1.4605 4.457192)
			)
			(stroke
				(width 0)
				(type default)
			)
			(fill no)
			(layer "F.CrtYd")
		)
		(fp_line
			(start 2.249932 -3.750056)
			(end 2.249932 3.750056)
			(stroke
				(width 0.1)
				(type default)
			)
			(layer "F.Fab")
		)
		(fp_line
			(start -2.249932 -3.750056)
			(end 2.249932 -3.750056)
			(stroke
				(width 0.1)
				(type default)
			)
			(layer "F.Fab")
		)
		(fp_line
			(start 2.249932 3.750056)
			(end -2.249932 3.750056)
			(stroke
				(width 0.1)
				(type default)
			)
			(layer "F.Fab")
		)
		(fp_line
			(start -2.249932 3.750056)
			(end -2.249932 -3.750056)
			(stroke
				(width 0.1)
				(type default)
			)
			(layer "F.Fab")
		)
		(fp_text user "+"
			(at 0.4191 -5.642356 180)
			(unlocked yes)
			(layer "F.SilkS")
			(effects
				(font
					(size 1.6002 1.1938)
					(thickness 0.1524)
				)
				(justify left)
			)
		)
		(fp_text user "+"
			(at -0.786384 -6.322314 90)
			(unlocked yes)
			(layer "F.Fab")
			(effects
				(font
					(size 1.905 1.4224)
					(thickness 0.000001)
				)
				(justify left)
			)
		)
		(pad "1" smd rect
			(at 0 -3.199892)
			(size 2.413 2.8194)
			(layers "F.Cu" "F.Mask" "F.Paste")
			(net "PV_VCCP_NODE1")
		)
		(pad "2" smd rect
			(at 0 3.199892)
			(size 2.413 2.8194)
			(layers "F.Cu" "F.Mask" "F.Paste")
			(net "GND")
		)
	)
	(footprint ""
		(layer "F.Cu")
		(at 67.265296 -101.4603 180)
		(property "Reference" "Q30"
			(at 0.534416 2.946908 0)
			(unlocked yes)
			(layer "F.SilkS")
			(effects
				(font
					(size 0.7874 0.5842)
					(thickness 0.1524)
				)
			)
		)
		(property "Value" ""
			(at 0 0 180)
			(layer "F.Fab")
			(effects
				(font
					(size 1.27 1.27)
				)
			)
		)
		(duplicate_pad_numbers_are_jumpers no)
		(fp_line
			(start 1.603248 1.500124)
			(end -1.603248 1.500124)
			(stroke
				(width 0.1524)
				(type default)
			)
			(layer "F.SilkS")
		)
		(fp_line
			(start 1.603248 -1.500124)
			(end 1.603248 1.500124)
			(stroke
				(width 0.1524)
				(type default)
			)
			(layer "F.SilkS")
		)
		(fp_line
			(start -1.603248 1.500124)
			(end -1.603248 -1.500124)
			(stroke
				(width 0.1524)
				(type default)
			)
			(layer "F.SilkS")
		)
		(fp_line
			(start -1.603248 -1.500124)
			(end 1.603248 -1.500124)
			(stroke
				(width 0.1524)
				(type default)
			)
			(layer "F.SilkS")
		)
		(fp_poly
			(pts
				(xy -0.700024 -1.500124) (xy -0.700024 -1.40716) (xy -1.507998 -1.40716) (xy -1.507998 -0.49276)
				(xy -0.700024 -0.49276) (xy -0.700024 0.47244) (xy -1.507998 0.47244) (xy -1.507998 1.41224) (xy -0.700024 1.41224)
				(xy -0.700024 1.500124) (xy 0.700024 1.500124) (xy 0.700024 0.47244) (xy 1.514602 0.47244) (xy 1.514602 -0.46736)
				(xy 0.700024 -0.46736) (xy 0.700024 -1.500124)
			)
			(stroke
				(width 0)
				(type default)
			)
			(fill no)
			(layer "F.CrtYd")
		)
		(fp_line
			(start 0.700024 1.500124)
			(end -0.700024 1.500124)
			(stroke
				(width 0.1)
				(type default)
			)
			(layer "F.Fab")
		)
		(fp_line
			(start 0.700024 -1.500124)
			(end 0.700024 1.500124)
			(stroke
				(width 0.1)
				(type default)
			)
			(layer "F.Fab")
		)
		(fp_line
			(start -0.700024 1.500124)
			(end -0.700024 -1.500124)
			(stroke
				(width 0.1)
				(type default)
			)
			(layer "F.Fab")
		)
		(fp_line
			(start -0.700024 -1.500124)
			(end 0.700024 -1.500124)
			(stroke
				(width 0.1)
				(type default)
			)
			(layer "F.Fab")
		)
		(fp_text user "D"
			(at 2.06375 1.879854 0)
			(unlocked yes)
			(layer "F.SilkS")
			(effects
				(font
					(size 0.635 0.4064)
					(thickness 0.1524)
				)
			)
		)
		(fp_text user "S"
			(at -1.146556 2.002282 0)
			(unlocked yes)
			(layer "F.SilkS")
			(effects
				(font
					(size 0.635 0.4064)
					(thickness 0.1524)
				)
			)
		)
		(fp_text user "G"
			(at -1.252982 -2.044954 0)
			(unlocked yes)
			(layer "F.SilkS")
			(effects
				(font
					(size 0.635 0.4064)
					(thickness 0.1524)
				)
			)
		)
		(fp_text user "D"
			(at 2.098294 0.1016 90)
			(unlocked yes)
			(layer "F.Fab")
			(effects
				(font
					(size 0.7874 0.5842)
					(thickness 0.000001)
				)
			)
		)
		(fp_text user "S"
			(at -1.025906 2.0066 90)
			(unlocked yes)
			(layer "F.Fab")
			(effects
				(font
					(size 0.7874 0.5842)
					(thickness 0.000001)
				)
			)
		)
		(fp_text user "G"
			(at -1.051306 -2.032 90)
			(unlocked yes)
			(layer "F.Fab")
			(effects
				(font
					(size 0.7874 0.5842)
					(thickness 0.000001)
				)
			)
		)
		(pad "D" smd rect
			(at 0.999998 0 90)
			(size 0.8128 0.9144)
			(layers "F.Cu" "F.Mask" "F.Paste")
			(net "FM_CPLD_NODE1_P1V8_SUS_EN_LV")
		)
		(pad "G" smd rect
			(at -0.999998 -0.94996 90)
			(size 0.8128 0.9144)
			(layers "F.Cu" "F.Mask" "F.Paste")
			(net "FM_CPLD_NODE1_P1V8_SUS_EN_G")
		)
		(pad "S" smd rect
			(at -0.999998 0.94996 90)
			(size 0.8128 0.9144)
			(layers "F.Cu" "F.Mask" "F.Paste")
			(net "FM_CPLD_NODE1_P1V8_SUS_EN")
		)
	)
	(footprint ""
		(layer "F.Cu")
		(at 128.05156 -188.126624 90)
		(property "Reference" "C740"
			(at 4.951476 -0.496316 90)
			(unlocked yes)
			(layer "F.SilkS")
			(effects
				(font
					(size 0.7874 0.5842)
					(thickness 0.1524)
				)
				(justify left)
			)
		)
		(property "Value" ""
			(at 0 0 90)
			(layer "F.Fab")
			(effects
				(font
					(size 1.27 1.27)
				)
			)
		)
		(duplicate_pad_numbers_are_jumpers no)
		(fp_line
			(start 0.7874 -0.4064)
			(end 0.7874 0.4064)
			(stroke
				(width 0.1524)
				(type default)
			)
			(layer "F.SilkS")
		)
		(fp_line
			(start -0.7874 -0.4064)
			(end 0.7874 -0.4064)
			(stroke
				(width 0.1524)
				(type default)
			)
			(layer "F.SilkS")
		)
		(fp_line
			(start 0 0.381)
			(end 0 -0.381)
			(stroke
				(width 0.1524)
				(type default)
			)
			(layer "F.SilkS")
		)
		(fp_line
			(start 0.7874 0.4064)
			(end -0.7874 0.4064)
			(stroke
				(width 0.1524)
				(type default)
			)
			(layer "F.SilkS")
		)
		(fp_line
			(start -0.7874 0.4064)
			(end -0.7874 -0.4064)
			(stroke
				(width 0.1524)
				(type default)
			)
			(layer "F.SilkS")
		)
		(fp_poly
			(pts
				(xy -0.5334 0.254) (xy -0.635 0.254) (xy -0.635 0.2286) (xy -0.635 -0.254) (xy -0.5334 -0.254) (xy -0.5334 -0.2794)
				(xy 0.5334 -0.2794) (xy 0.5334 -0.254) (xy 0.635 -0.254) (xy 0.635 0.254) (xy 0.5334 0.254) (xy 0.5334 0.2794)
				(xy -0.508 0.2794) (xy -0.5334 0.2794)
			)
			(stroke
				(width 0)
				(type default)
			)
			(fill no)
			(layer "F.CrtYd")
		)
		(pad "1" smd rect
			(at 0.40005 0 90)
			(size 0.4572 0.508)
			(layers "F.Cu" "F.Mask" "F.Paste")
			(net "UART_T9_NODE4_TXD_R")
		)
		(pad "2" smd rect
			(at -0.40005 0 90)
			(size 0.4572 0.508)
			(layers "F.Cu" "F.Mask" "F.Paste")
			(net "GND")
		)
	)
	(footprint ""
		(layer "F.Cu")
		(at 162.17138 -161.37001 90)
		(property "Reference" "R586"
			(at -8.06577 17.640554 90)
			(unlocked yes)
			(layer "F.SilkS")
			(effects
				(font
					(size 0.7874 0.5842)
					(thickness 0.1524)
				)
				(justify left)
			)
		)
		(property "Value" ""
			(at 0 0 90)
			(layer "F.Fab")
			(effects
				(font
					(size 1.27 1.27)
				)
			)
		)
		(duplicate_pad_numbers_are_jumpers no)
		(fp_line
			(start 0.7874 -0.4064)
			(end 0.7874 0.4064)
			(stroke
				(width 0.1524)
				(type default)
			)
			(layer "F.SilkS")
		)
		(fp_line
			(start -0.7874 -0.4064)
			(end 0.7874 -0.4064)
			(stroke
				(width 0.1524)
				(type default)
			)
			(layer "F.SilkS")
		)
		(fp_line
			(start 0.7874 0.4064)
			(end -0.7874 0.4064)
			(stroke
				(width 0.1524)
				(type default)
			)
			(layer "F.SilkS")
		)
		(fp_line
			(start -0.7874 0.4064)
			(end -0.7874 -0.4064)
			(stroke
				(width 0.1524)
				(type default)
			)
			(layer "F.SilkS")
		)
		(fp_poly
			(pts
				(xy -0.508 0.2794) (xy -0.508 0.2286) (xy -0.635 0.2286) (xy -0.635 -0.254) (xy -0.5334 -0.254)
				(xy -0.5334 -0.2794) (xy 0.5334 -0.2794) (xy 0.5334 -0.254) (xy 0.635 -0.254) (xy 0.635 0.254) (xy 0.5334 0.254)
				(xy 0.5334 0.2794)
			)
			(stroke
				(width 0)
				(type default)
			)
			(fill no)
			(layer "F.CrtYd")
		)
		(pad "1" smd rect
			(at 0.40005 0 90)
			(size 0.4572 0.508)
			(layers "F.Cu" "F.Mask" "F.Paste")
			(net "GND")
		)
		(pad "2" smd rect
			(at -0.40005 0 90)
			(size 0.4572 0.508)
			(layers "F.Cu" "F.Mask" "F.Paste")
			(net "LAN2_NC_SI_TX_EN")
		)
	)
	(footprint ""
		(layer "F.Cu")
		(at 16.499332 -133.709918 180)
		(property "Reference" "PC65"
			(at 0.841248 2.093468 0)
			(unlocked yes)
			(layer "F.SilkS")
			(effects
				(font
					(size 0.7874 0.5842)
					(thickness 0.1524)
				)
				(justify left)
			)
		)
		(property "Value" ""
			(at 0 0 180)
			(layer "F.Fab")
			(effects
				(font
					(size 1.27 1.27)
				)
			)
		)
		(duplicate_pad_numbers_are_jumpers no)
		(fp_line
			(start 0.7874 0.4064)
			(end -0.7874 0.4064)
			(stroke
				(width 0.1524)
				(type default)
			)
			(layer "F.SilkS")
		)
		(fp_line
			(start 0.7874 -0.4064)
			(end 0.7874 0.4064)
			(stroke
				(width 0.1524)
				(type default)
			)
			(layer "F.SilkS")
		)
		(fp_line
			(start 0 0.381)
			(end 0 -0.381)
			(stroke
				(width 0.1524)
				(type default)
			)
			(layer "F.SilkS")
		)
		(fp_line
			(start -0.7874 0.4064)
			(end -0.7874 -0.4064)
			(stroke
				(width 0.1524)
				(type default)
			)
			(layer "F.SilkS")
		)
		(fp_line
			(start -0.7874 -0.4064)
			(end 0.7874 -0.4064)
			(stroke
				(width 0.1524)
				(type default)
			)
			(layer "F.SilkS")
		)
		(fp_poly
			(pts
				(xy -0.5334 0.254) (xy -0.635 0.254) (xy -0.635 0.2286) (xy -0.635 -0.254) (xy -0.5334 -0.254) (xy -0.5334 -0.2794)
				(xy 0.5334 -0.2794) (xy 0.5334 -0.254) (xy 0.635 -0.254) (xy 0.635 0.254) (xy 0.5334 0.254) (xy 0.5334 0.2794)
				(xy -0.508 0.2794) (xy -0.5334 0.2794)
			)
			(stroke
				(width 0)
				(type default)
			)
			(fill no)
			(layer "F.CrtYd")
		)
		(pad "1" smd rect
			(at 0.40005 0 180)
			(size 0.4572 0.508)
			(layers "F.Cu" "F.Mask" "F.Paste")
			(net "VSENSE_P1V05_NODE1_N")
		)
		(pad "2" smd rect
			(at -0.40005 0 180)
			(size 0.4572 0.508)
			(layers "F.Cu" "F.Mask" "F.Paste")
			(net "P1V05_NODE1_VREF")
		)
	)
	(footprint ""
		(layer "F.Cu")
		(at 147.433792 -144.082262)
		(property "Reference" "R275"
			(at -1.293876 1.072642 0)
			(unlocked yes)
			(layer "F.SilkS")
			(effects
				(font
					(size 0.635 0.4064)
					(thickness 0.1524)
				)
				(justify left)
			)
		)
		(property "Value" ""
			(at 0 0 0)
			(layer "F.Fab")
			(effects
				(font
					(size 1.27 1.27)
				)
			)
		)
		(duplicate_pad_numbers_are_jumpers no)
		(fp_line
			(start -0.7874 -0.4064)
			(end 0.7874 -0.4064)
			(stroke
				(width 0.1524)
				(type default)
			)
			(layer "F.SilkS")
		)
		(fp_line
			(start -0.7874 0.4064)
			(end -0.7874 -0.4064)
			(stroke
				(width 0.1524)
				(type default)
			)
			(layer "F.SilkS")
		)
		(fp_line
			(start 0.7874 -0.4064)
			(end 0.7874 0.4064)
			(stroke
				(width 0.1524)
				(type default)
			)
			(layer "F.SilkS")
		)
		(fp_line
			(start 0.7874 0.4064)
			(end -0.7874 0.4064)
			(stroke
				(width 0.1524)
				(type default)
			)
			(layer "F.SilkS")
		)
		(fp_poly
			(pts
				(xy -0.508 0.2794) (xy -0.508 0.2286) (xy -0.635 0.2286) (xy -0.635 -0.254) (xy -0.5334 -0.254)
				(xy -0.5334 -0.2794) (xy 0.5334 -0.2794) (xy 0.5334 -0.254) (xy 0.635 -0.254) (xy 0.635 0.254) (xy 0.5334 0.254)
				(xy 0.5334 0.2794)
			)
			(stroke
				(width 0)
				(type default)
			)
			(fill no)
			(layer "F.CrtYd")
		)
		(pad "1" smd rect
			(at 0.40005 0)
			(size 0.4572 0.508)
			(layers "F.Cu" "F.Mask" "F.Paste")
			(net "P3V3_NODE1")
		)
		(pad "2" smd rect
			(at -0.40005 0)
			(size 0.4572 0.508)
			(layers "F.Cu" "F.Mask" "F.Paste")
			(net "PCIE_SW_PWR_SAV")
		)
	)
	(footprint ""
		(layer "F.Cu")
		(at 100.471732 -171.879768 -90)
		(property "Reference" "U69"
			(at 72.6948 -87.253064 0)
			(unlocked yes)
			(layer "F.SilkS")
			(effects
				(font
					(size 0.7874 0.5842)
					(thickness 0.1524)
				)
			)
		)
		(property "Value" ""
			(at 0 0 270)
			(layer "F.Fab")
			(effects
				(font
					(size 1.27 1.27)
				)
			)
		)
		(duplicate_pad_numbers_are_jumpers no)
		(fp_line
			(start -2.4892 1.524)
			(end -2.4892 0.5588)
			(stroke
				(width 0.1524)
				(type default)
			)
			(layer "F.SilkS")
		)
		(fp_line
			(start 2.4892 1.524)
			(end -2.4892 1.524)
			(stroke
				(width 0.1524)
				(type default)
			)
			(layer "F.SilkS")
		)
		(fp_line
			(start -2.4892 0.5588)
			(end -1.9304 0)
			(stroke
				(width 0.1524)
				(type default)
			)
			(layer "F.SilkS")
		)
		(fp_line
			(start -1.9304 0)
			(end -2.4892 -0.5588)
			(stroke
				(width 0.1524)
				(type default)
			)
			(layer "F.SilkS")
		)
		(fp_line
			(start -2.4892 -0.5588)
			(end -2.4892 -1.524)
			(stroke
				(width 0.1524)
				(type default)
			)
			(layer "F.SilkS")
		)
		(fp_line
			(start -2.4892 -1.524)
			(end 2.4892 -1.524)
			(stroke
				(width 0.1524)
				(type default)
			)
			(layer "F.SilkS")
		)
		(fp_line
			(start 2.4892 -1.524)
			(end 2.4892 1.524)
			(stroke
				(width 0.1524)
				(type default)
			)
			(layer "F.SilkS")
		)
		(fp_circle
			(center -1.905 1.016)
			(end -1.905 0.762)
			(stroke
				(width 0.1524)
				(type default)
			)
			(fill no)
			(layer "F.SilkS")
		)
		(fp_poly
			(pts
				(xy -2.4003 3.5179) (xy -2.4003 2.0066) (xy -2.4892 2.0066) (xy -2.4892 -2.0066) (xy -2.4003 -2.0066)
				(xy -2.4003 -3.5179) (xy 2.4003 -3.5179) (xy 2.4003 -2.0066) (xy 2.4892 -2.0066) (xy 2.4892 2.0066)
				(xy 2.4003 2.0066) (xy 2.4003 3.5179)
			)
			(stroke
				(width 0)
				(type default)
			)
			(fill no)
			(layer "F.CrtYd")
		)
		(pad "1" smd rect
			(at -2.2225 2.7432 270)
			(size 0.3556 1.5494)
			(layers "F.Cu" "F.Mask" "F.Paste")
			(net "I2C_SCL_FANCTRL1_R")
		)
		(pad "2" smd rect
			(at -1.5875 2.7432 270)
			(size 0.3556 1.5494)
			(layers "F.Cu" "F.Mask" "F.Paste")
			(net "GND")
		)
		(pad "3" smd rect
			(at -0.9525 2.7432 270)
			(size 0.3556 1.5494)
			(layers "F.Cu" "F.Mask" "F.Paste")
			(net "P3V3_NODE1")
		)
		(pad "4" smd rect
			(at -0.3175 2.7432 270)
			(size 0.3556 1.5494)
			(layers "F.Cu" "F.Mask" "F.Paste")
			(net "FAN3_TACH_IN")
		)
		(pad "5" smd rect
			(at 0.3175 2.7432 270)
			(size 0.3556 1.5494)
			(layers "F.Cu" "F.Mask" "F.Paste")
			(net "Net_2256")
		)
		(pad "6" smd rect
			(at 0.9525 2.7432 270)
			(size 0.3556 1.5494)
			(layers "F.Cu" "F.Mask" "F.Paste")
			(net "FAN1_TACH_IN")
		)
		(pad "7" smd rect
			(at 1.5875 2.7432 270)
			(size 0.3556 1.5494)
			(layers "F.Cu" "F.Mask" "F.Paste")
			(net "FAN2_TACH_IN")
		)
		(pad "8" smd rect
			(at 2.2225 2.7432 270)
			(size 0.3556 1.5494)
			(layers "F.Cu" "F.Mask" "F.Paste")
			(net "Net_2255")
		)
		(pad "9" smd rect
			(at 2.2225 -2.7432 270)
			(size 0.3556 1.5494)
			(layers "F.Cu" "F.Mask" "F.Paste")
			(net "FAN4_TACH_IN")
		)
		(pad "10" smd rect
			(at 1.5875 -2.7432 270)
			(size 0.3556 1.5494)
			(layers "F.Cu" "F.Mask" "F.Paste")
			(net "Net_2254")
		)
		(pad "11" smd rect
			(at 0.9525 -2.7432 270)
			(size 0.3556 1.5494)
			(layers "F.Cu" "F.Mask" "F.Paste")
			(net "FNACTRL1_ADD")
		)
		(pad "12" smd rect
			(at 0.3175 -2.7432 270)
			(size 0.3556 1.5494)
			(layers "F.Cu" "F.Mask" "F.Paste")
			(net "FNACTRL1_TMP_IN")
		)
		(pad "13" smd rect
			(at -0.3175 -2.7432 270)
			(size 0.3556 1.5494)
			(layers "F.Cu" "F.Mask" "F.Paste")
			(net "CPLD_FAN_MAX_CTRL")
		)
		(pad "14" smd rect
			(at -0.9525 -2.7432 270)
			(size 0.3556 1.5494)
			(layers "F.Cu" "F.Mask" "F.Paste")
			(net "I2C_ALERT_FNACTRL1_N")
		)
		(pad "15" smd rect
			(at -1.5875 -2.7432 270)
			(size 0.3556 1.5494)
			(layers "F.Cu" "F.Mask" "F.Paste")
			(net "FAN_PWM_BUF")
		)
		(pad "16" smd rect
			(at -2.2225 -2.7432 270)
			(size 0.3556 1.5494)
			(layers "F.Cu" "F.Mask" "F.Paste")
			(net "I2C_SDA_FANCTRL1_R")
		)
	)
	(footprint ""
		(layer "F.Cu")
		(at 60.05957 -110.27029 180)
		(property "Reference" "PC16"
			(at 1.977644 -6.787134 0)
			(unlocked yes)
			(layer "F.SilkS")
			(effects
				(font
					(size 0.7874 0.5842)
					(thickness 0.1524)
				)
				(justify left)
			)
		)
		(property "Value" ""
			(at 0 0 180)
			(layer "F.Fab")
			(effects
				(font
					(size 1.27 1.27)
				)
			)
		)
		(duplicate_pad_numbers_are_jumpers no)
		(fp_line
			(start 1.905 0.8636)
			(end -1.905 0.8636)
			(stroke
				(width 0.1524)
				(type default)
			)
			(layer "F.SilkS")
		)
		(fp_line
			(start 1.905 -0.8636)
			(end 1.905 0.8636)
			(stroke
				(width 0.1524)
				(type default)
			)
			(layer "F.SilkS")
		)
		(fp_line
			(start 0 0.8382)
			(end 0 -0.8382)
			(stroke
				(width 0.1524)
				(type default)
			)
			(layer "F.SilkS")
		)
		(fp_line
			(start -1.905 0.8636)
			(end -1.905 -0.8636)
			(stroke
				(width 0.1524)
				(type default)
			)
			(layer "F.SilkS")
		)
		(fp_line
			(start -1.905 -0.8636)
			(end 1.905 -0.8636)
			(stroke
				(width 0.1524)
				(type default)
			)
			(layer "F.SilkS")
		)
		(fp_rect
			(start -1.524 0.7366)
			(end 1.524 -0.7366)
			(stroke
				(width 0)
				(type default)
			)
			(fill no)
			(layer "F.CrtYd")
		)
		(pad "1" smd rect
			(at 0.94996 0 180)
			(size 1.1176 1.3716)
			(layers "F.Cu" "F.Mask" "F.Paste")
			(net "P3V3_STB_NODE1")
		)
		(pad "2" smd rect
			(at -0.94996 0 180)
			(size 1.1176 1.3716)
			(layers "F.Cu" "F.Mask" "F.Paste")
			(net "GND")
		)
	)
	(footprint ""
		(layer "F.Cu")
		(at 47.10176 -182.246524 90)
		(property "Reference" "C614"
			(at -133.313932 -3.637788 90)
			(unlocked yes)
			(layer "F.SilkS")
			(effects
				(font
					(size 0.7874 0.5842)
					(thickness 0.1524)
				)
				(justify left)
			)
		)
		(property "Value" ""
			(at 0 0 90)
			(layer "F.Fab")
			(effects
				(font
					(size 1.27 1.27)
				)
			)
		)
		(duplicate_pad_numbers_are_jumpers no)
		(fp_line
			(start 0.7874 -0.4064)
			(end 0.7874 0.4064)
			(stroke
				(width 0.1524)
				(type default)
			)
			(layer "F.SilkS")
		)
		(fp_line
			(start -0.7874 -0.4064)
			(end 0.7874 -0.4064)
			(stroke
				(width 0.1524)
				(type default)
			)
			(layer "F.SilkS")
		)
		(fp_line
			(start 0 0.381)
			(end 0 -0.381)
			(stroke
				(width 0.1524)
				(type default)
			)
			(layer "F.SilkS")
		)
		(fp_line
			(start 0.7874 0.4064)
			(end -0.7874 0.4064)
			(stroke
				(width 0.1524)
				(type default)
			)
			(layer "F.SilkS")
		)
		(fp_line
			(start -0.7874 0.4064)
			(end -0.7874 -0.4064)
			(stroke
				(width 0.1524)
				(type default)
			)
			(layer "F.SilkS")
		)
		(fp_poly
			(pts
				(xy -0.5334 0.254) (xy -0.635 0.254) (xy -0.635 0.2286) (xy -0.635 -0.254) (xy -0.5334 -0.254) (xy -0.5334 -0.2794)
				(xy 0.5334 -0.2794) (xy 0.5334 -0.254) (xy 0.635 -0.254) (xy 0.635 0.254) (xy 0.5334 0.254) (xy 0.5334 0.2794)
				(xy -0.508 0.2794) (xy -0.5334 0.2794)
			)
			(stroke
				(width 0)
				(type default)
			)
			(fill no)
			(layer "F.CrtYd")
		)
		(pad "1" smd rect
			(at 0.40005 0 90)
			(size 0.4572 0.508)
			(layers "F.Cu" "F.Mask" "F.Paste")
			(net "PSU6_AC_OK")
		)
		(pad "2" smd rect
			(at -0.40005 0 90)
			(size 0.4572 0.508)
			(layers "F.Cu" "F.Mask" "F.Paste")
			(net "GND")
		)
	)
	(footprint ""
		(layer "F.Cu")
		(at 83.245706 -129.052574 -90)
		(property "Reference" "R1260"
			(at 5.993892 4.44754 90)
			(unlocked yes)
			(layer "F.SilkS")
			(effects
				(font
					(size 0.7874 0.5842)
					(thickness 0.1524)
				)
				(justify left)
			)
		)
		(property "Value" ""
			(at 0 0 270)
			(layer "F.Fab")
			(effects
				(font
					(size 1.27 1.27)
				)
			)
		)
		(duplicate_pad_numbers_are_jumpers no)
		(fp_line
			(start -0.7874 0.4064)
			(end -0.7874 -0.4064)
			(stroke
				(width 0.1524)
				(type default)
			)
			(layer "F.SilkS")
		)
		(fp_line
			(start 0.7874 0.4064)
			(end -0.7874 0.4064)
			(stroke
				(width 0.1524)
				(type default)
			)
			(layer "F.SilkS")
		)
		(fp_line
			(start -0.7874 -0.4064)
			(end 0.7874 -0.4064)
			(stroke
				(width 0.1524)
				(type default)
			)
			(layer "F.SilkS")
		)
		(fp_line
			(start 0.7874 -0.4064)
			(end 0.7874 0.4064)
			(stroke
				(width 0.1524)
				(type default)
			)
			(layer "F.SilkS")
		)
		(fp_poly
			(pts
				(xy -0.508 0.2794) (xy -0.508 0.2286) (xy -0.635 0.2286) (xy -0.635 -0.254) (xy -0.5334 -0.254)
				(xy -0.5334 -0.2794) (xy 0.5334 -0.2794) (xy 0.5334 -0.254) (xy 0.635 -0.254) (xy 0.635 0.254) (xy 0.5334 0.254)
				(xy 0.5334 0.2794)
			)
			(stroke
				(width 0)
				(type default)
			)
			(fill no)
			(layer "F.CrtYd")
		)
		(pad "1" smd rect
			(at 0.40005 0 270)
			(size 0.4572 0.508)
			(layers "F.Cu" "F.Mask" "F.Paste")
			(net "PORT80_LOUT0")
		)
		(pad "2" smd rect
			(at -0.40005 0 270)
			(size 0.4572 0.508)
			(layers "F.Cu" "F.Mask" "F.Paste")
			(net "N53313646")
		)
	)
	(footprint ""
		(layer "F.Cu")
		(at 69.842888 -2.723642 180)
		(property "Reference" "PJ5"
			(at 2.811018 -2.520442 90)
			(unlocked yes)
			(layer "F.SilkS")
			(effects
				(font
					(size 0.7874 0.5842)
					(thickness 0.1524)
				)
				(justify left)
			)
		)
		(property "Value" ""
			(at 0 0 180)
			(layer "F.Fab")
			(effects
				(font
					(size 1.27 1.27)
				)
			)
		)
		(duplicate_pad_numbers_are_jumpers no)
		(fp_poly
			(pts
				(xy 0.2794 0.907796) (xy 0.254 0.907796) (xy 0.254 1.0414) (xy -0.254 1.0414) (xy -0.254 1.034796)
				(xy -0.254 0.933196) (xy -0.2794 0.933196) (xy -0.2794 -0.133604) (xy -0.254 -0.133604) (xy -0.254 -0.235204)
				(xy 0.254 -0.235204) (xy 0.254 -0.133604) (xy 0.2794 -0.133604)
			)
			(stroke
				(width 0)
				(type default)
			)
			(fill no)
			(layer "F.CrtYd")
		)
		(pad "1" smd custom
			(at 0 -0.000254 180)
			(size 0.127 0.127)
			(layers "F.Cu" "F.Mask" "F.Paste")
			(net "FM_CPLD_NODE1_P3V3_EN")
			(options
				(clearance outline)
				(anchor circle)
			)
			(primitives
				(gr_poly
					(pts
						(xy -0.127 0.508) (xy -0.127 -0.0508) (xy -0.254 -0.0508) (xy -0.254 -0.508) (xy 0.254 -0.508)
						(xy 0.254 -0.0508) (xy 0.127 -0.0508) (xy 0.127 0.508)
					)
					(width 0)
					(fill yes)
				)
			)
		)
		(pad "2" smd rect
			(at 0 0.799846 270)
			(size 0.4572 0.508)
			(layers "F.Cu" "F.Mask" "F.Paste")
			(net "FM_CPLD_NODE1_P3V3_S_EN")
		)
		(zone
			(layer "F.Cu")
			(hatch none 0.5)
			(connect_pads
				(clearance 0)
			)
			(min_thickness 0.25)
			(keepout
				(tracks allowed)
				(vias not_allowed)
				(pads allowed)
				(copperpour not_allowed)
				(footprints allowed)
			)
			(placement
				(enabled no)
				(sheetname "")
			)
			(fill
				(thermal_gap 0.5)
				(thermal_bridge_width 0.5)
				(island_removal_mode 0)
			)
			(polygon
				(pts
					(xy 70.147688 -3.809238) (xy 69.538088 -3.809238) (xy 69.538088 -2.437638) (xy 70.147688 -2.437638)
				)
			)
		)
	)
	(footprint ""
		(layer "F.Cu")
		(at 4.028186 -27.828494 180)
		(property "Reference" "J36"
			(at -0.899414 2.015236 0)
			(unlocked yes)
			(layer "F.SilkS")
			(effects
				(font
					(size 0.7874 0.5842)
					(thickness 0.1524)
				)
				(justify left)
			)
		)
		(property "Value" ""
			(at 0 0 180)
			(layer "F.Fab")
			(effects
				(font
					(size 1.27 1.27)
				)
			)
		)
		(duplicate_pad_numbers_are_jumpers no)
		(fp_line
			(start 2.715006 1.249934)
			(end -2.715006 1.249934)
			(stroke
				(width 0.1524)
				(type default)
			)
			(layer "F.SilkS")
		)
		(fp_line
			(start 2.715006 -1.249934)
			(end 2.715006 1.249934)
			(stroke
				(width 0.1524)
				(type default)
			)
			(layer "F.SilkS")
		)
		(fp_line
			(start 1.27 -1.249934)
			(end 1.27 -7.249922)
			(stroke
				(width 0.635)
				(type default)
			)
			(layer "F.SilkS")
		)
		(fp_line
			(start -1.27 -7.249922)
			(end -1.27 -1.249934)
			(stroke
				(width 0.635)
				(type default)
			)
			(layer "F.SilkS")
		)
		(fp_line
			(start -2.715006 1.249934)
			(end -2.715006 -1.249934)
			(stroke
				(width 0.1524)
				(type default)
			)
			(layer "F.SilkS")
		)
		(fp_line
			(start -2.715006 -1.249934)
			(end 2.715006 -1.249934)
			(stroke
				(width 0.1524)
				(type default)
			)
			(layer "F.SilkS")
		)
		(fp_poly
			(pts
				(xy 1.4224 1.230122) (xy 0.879602 2.652776) (xy 1.890522 2.652776)
			)
			(stroke
				(width 0)
				(type default)
			)
			(fill yes)
			(layer "F.SilkS")
		)
		(fp_poly
			(pts
				(xy 2.0828 -0.8128) (xy 2.0828 0.8128) (xy -2.0828 0.8128) (xy -2.0828 -0.8128)
			)
			(stroke
				(width 0)
				(type default)
			)
			(fill no)
			(layer "B.CrtYd")
		)
		(fp_poly
			(pts
				(xy -2.715006 1.249934) (xy 2.715006 1.249934) (xy 2.715006 -1.249934) (xy 1.6002 -1.249934) (xy 1.6002 -7.5692)
				(xy -1.6002 -7.5692) (xy -1.6002 -1.249934) (xy -2.715006 -1.249934)
			)
			(stroke
				(width 0)
				(type default)
			)
			(fill no)
			(layer "F.CrtYd")
		)
		(fp_line
			(start 2.715006 1.249934)
			(end -2.715006 1.249934)
			(stroke
				(width 0.1)
				(type default)
			)
			(layer "F.Fab")
		)
		(fp_line
			(start 2.715006 -1.249934)
			(end 2.715006 1.249934)
			(stroke
				(width 0.1)
				(type default)
			)
			(layer "F.Fab")
		)
		(fp_line
			(start -2.715006 1.249934)
			(end -2.715006 -1.249934)
			(stroke
				(width 0.1)
				(type default)
			)
			(layer "F.Fab")
		)
		(fp_line
			(start -2.715006 -1.249934)
			(end 2.715006 -1.249934)
			(stroke
				(width 0.1)
				(type default)
			)
			(layer "F.Fab")
		)
		(fp_text user "1"
			(at 3.469386 -0.092964 0)
			(unlocked yes)
			(layer "F.SilkS")
			(effects
				(font
					(size 0.7874 0.5842)
					(thickness 0.1524)
				)
				(justify left)
			)
		)
		(fp_text user "2"
			(at -3.083814 0.059436 0)
			(unlocked yes)
			(layer "F.SilkS")
			(effects
				(font
					(size 0.7874 0.5842)
					(thickness 0.1524)
				)
				(justify left)
			)
		)
		(fp_text user "1"
			(at 2.351786 0.084836 0)
			(unlocked yes)
			(layer "B.SilkS")
			(effects
				(font
					(size 0.7874 0.5842)
					(thickness 0.1524)
				)
				(justify left mirror)
			)
		)
		(fp_text user "2"
			(at -2.804414 0.186436 0)
			(unlocked yes)
			(layer "B.SilkS")
			(effects
				(font
					(size 0.7874 0.5842)
					(thickness 0.1524)
				)
				(justify left mirror)
			)
		)
		(pad "1" thru_hole rect
			(at 1.27 0 180)
			(size 1.524 1.524)
			(drill 1.016)
			(layers "*.Cu" "*.Mask")
			(remove_unused_layers no)
			(net "GND")
			(clearance 0)
			(padstack
				(mode front_inner_back)
				(layer "Inner"
					(shape circle)
					(size 1.524 1.524)
					(clearance 0)
				)
				(layer "B.Cu"
					(shape rect)
					(size 1.524 1.524)
					(clearance 0)
				)
			)
		)
		(pad "2" thru_hole circle
			(at -1.27 0 180)
			(size 1.524 1.524)
			(drill 1.016)
			(layers "*.Cu" "*.Mask")
			(remove_unused_layers no)
			(net "MATE_N")
			(clearance 0)
		)
	)
	(footprint ""
		(layer "F.Cu")
		(at 8.34009 -7.725156)
		(property "Reference" "R213"
			(at -6.44398 -0.688086 0)
			(unlocked yes)
			(layer "F.SilkS")
			(effects
				(font
					(size 0.7874 0.5842)
					(thickness 0.1524)
				)
				(justify left)
			)
		)
		(property "Value" ""
			(at 0 0 0)
			(layer "F.Fab")
			(effects
				(font
					(size 1.27 1.27)
				)
			)
		)
		(duplicate_pad_numbers_are_jumpers no)
		(fp_line
			(start -0.7874 -0.4064)
			(end 0.7874 -0.4064)
			(stroke
				(width 0.1524)
				(type default)
			)
			(layer "F.SilkS")
		)
		(fp_line
			(start -0.7874 0.4064)
			(end -0.7874 -0.4064)
			(stroke
				(width 0.1524)
				(type default)
			)
			(layer "F.SilkS")
		)
		(fp_line
			(start 0.7874 -0.4064)
			(end 0.7874 0.4064)
			(stroke
				(width 0.1524)
				(type default)
			)
			(layer "F.SilkS")
		)
		(fp_line
			(start 0.7874 0.4064)
			(end -0.7874 0.4064)
			(stroke
				(width 0.1524)
				(type default)
			)
			(layer "F.SilkS")
		)
		(fp_poly
			(pts
				(xy -0.508 0.2794) (xy -0.508 0.2286) (xy -0.635 0.2286) (xy -0.635 -0.254) (xy -0.5334 -0.254)
				(xy -0.5334 -0.2794) (xy 0.5334 -0.2794) (xy 0.5334 -0.254) (xy 0.635 -0.254) (xy 0.635 0.254) (xy 0.5334 0.254)
				(xy 0.5334 0.2794)
			)
			(stroke
				(width 0)
				(type default)
			)
			(fill no)
			(layer "F.CrtYd")
		)
		(pad "1" smd rect
			(at 0.40005 0)
			(size 0.4572 0.508)
			(layers "F.Cu" "F.Mask" "F.Paste")
			(net "PV_VDDR_NODE1_VREF_RW")
		)
		(pad "2" smd rect
			(at -0.40005 0)
			(size 0.4572 0.508)
			(layers "F.Cu" "F.Mask" "F.Paste")
			(net "GND")
		)
	)
	(footprint ""
		(layer "F.Cu")
		(at 161.070798 -161.370518 90)
		(property "Reference" "R576"
			(at -8.066278 17.684496 90)
			(unlocked yes)
			(layer "F.SilkS")
			(effects
				(font
					(size 0.7874 0.5842)
					(thickness 0.1524)
				)
				(justify left)
			)
		)
		(property "Value" ""
			(at 0 0 90)
			(layer "F.Fab")
			(effects
				(font
					(size 1.27 1.27)
				)
			)
		)
		(duplicate_pad_numbers_are_jumpers no)
		(fp_line
			(start 0.7874 -0.4064)
			(end 0.7874 0.4064)
			(stroke
				(width 0.1524)
				(type default)
			)
			(layer "F.SilkS")
		)
		(fp_line
			(start -0.7874 -0.4064)
			(end 0.7874 -0.4064)
			(stroke
				(width 0.1524)
				(type default)
			)
			(layer "F.SilkS")
		)
		(fp_line
			(start 0.7874 0.4064)
			(end -0.7874 0.4064)
			(stroke
				(width 0.1524)
				(type default)
			)
			(layer "F.SilkS")
		)
		(fp_line
			(start -0.7874 0.4064)
			(end -0.7874 -0.4064)
			(stroke
				(width 0.1524)
				(type default)
			)
			(layer "F.SilkS")
		)
		(fp_poly
			(pts
				(xy -0.508 0.2794) (xy -0.508 0.2286) (xy -0.635 0.2286) (xy -0.635 -0.254) (xy -0.5334 -0.254)
				(xy -0.5334 -0.2794) (xy 0.5334 -0.2794) (xy 0.5334 -0.254) (xy 0.635 -0.254) (xy 0.635 0.254) (xy 0.5334 0.254)
				(xy 0.5334 0.2794)
			)
			(stroke
				(width 0)
				(type default)
			)
			(fill no)
			(layer "F.CrtYd")
		)
		(pad "1" smd rect
			(at 0.40005 0 90)
			(size 0.4572 0.508)
			(layers "F.Cu" "F.Mask" "F.Paste")
			(net "P3V3_NODE1")
		)
		(pad "2" smd rect
			(at -0.40005 0 90)
			(size 0.4572 0.508)
			(layers "F.Cu" "F.Mask" "F.Paste")
			(net "LAN2_NC_SI_TDX1")
		)
	)
	(footprint ""
		(layer "F.Cu")
		(at 186.24423 -118.711472 180)
		(property "Reference" "R1247"
			(at -1.20777 0.514858 0)
			(unlocked yes)
			(layer "F.SilkS")
			(effects
				(font
					(size 0.7874 0.5842)
					(thickness 0.1524)
				)
				(justify left)
			)
		)
		(property "Value" ""
			(at 0 0 180)
			(layer "F.Fab")
			(effects
				(font
					(size 1.27 1.27)
				)
			)
		)
		(duplicate_pad_numbers_are_jumpers no)
		(fp_line
			(start 0.7874 0.4064)
			(end -0.7874 0.4064)
			(stroke
				(width 0.1524)
				(type default)
			)
			(layer "F.SilkS")
		)
		(fp_line
			(start 0.7874 -0.4064)
			(end 0.7874 0.4064)
			(stroke
				(width 0.1524)
				(type default)
			)
			(layer "F.SilkS")
		)
		(fp_line
			(start -0.7874 0.4064)
			(end -0.7874 -0.4064)
			(stroke
				(width 0.1524)
				(type default)
			)
			(layer "F.SilkS")
		)
		(fp_line
			(start -0.7874 -0.4064)
			(end 0.7874 -0.4064)
			(stroke
				(width 0.1524)
				(type default)
			)
			(layer "F.SilkS")
		)
		(fp_poly
			(pts
				(xy -0.508 0.2794) (xy -0.508 0.2286) (xy -0.635 0.2286) (xy -0.635 -0.254) (xy -0.5334 -0.254)
				(xy -0.5334 -0.2794) (xy 0.5334 -0.2794) (xy 0.5334 -0.254) (xy 0.635 -0.254) (xy 0.635 0.254) (xy 0.5334 0.254)
				(xy 0.5334 0.2794)
			)
			(stroke
				(width 0)
				(type default)
			)
			(fill no)
			(layer "F.CrtYd")
		)
		(pad "1" smd rect
			(at 0.40005 0 180)
			(size 0.4572 0.508)
			(layers "F.Cu" "F.Mask" "F.Paste")
			(net "PWRGD_NODE1_P3V3_STB_PG_CPLD")
		)
		(pad "2" smd rect
			(at -0.40005 0 180)
			(size 0.4572 0.508)
			(layers "F.Cu" "F.Mask" "F.Paste")
			(net "PWRGD_NODE1_P3V3_STB_PG")
		)
	)
	(footprint ""
		(layer "F.Cu")
		(at 135.83412 -8.585962 180)
		(property "Reference" "J20"
			(at 6.26872 -3.786632 0)
			(unlocked yes)
			(layer "F.SilkS")
			(effects
				(font
					(size 0.7874 0.5842)
					(thickness 0.1524)
				)
				(justify left)
			)
		)
		(property "Value" ""
			(at 0 0 180)
			(layer "F.Fab")
			(effects
				(font
					(size 1.27 1.27)
				)
			)
		)
		(duplicate_pad_numbers_are_jumpers no)
		(fp_line
			(start 6.599936 2.640076)
			(end -6.599936 2.640076)
			(stroke
				(width 0.1524)
				(type default)
			)
			(layer "F.SilkS")
		)
		(fp_line
			(start 6.599936 -2.640076)
			(end 6.599936 2.640076)
			(stroke
				(width 0.1524)
				(type default)
			)
			(layer "F.SilkS")
		)
		(fp_line
			(start -6.599936 2.640076)
			(end -6.599936 -2.640076)
			(stroke
				(width 0.1524)
				(type default)
			)
			(layer "F.SilkS")
		)
		(fp_line
			(start -6.599936 -2.640076)
			(end 6.599936 -2.640076)
			(stroke
				(width 0.1524)
				(type default)
			)
			(layer "F.SilkS")
		)
		(fp_poly
			(pts
				(xy -4.905502 3.179572) (xy -5.667502 5.084572) (xy -4.143502 5.084572)
			)
			(stroke
				(width 0)
				(type default)
			)
			(fill yes)
			(layer "F.SilkS")
		)
		(fp_poly
			(pts
				(xy -5.969 -2.159) (xy 5.969 -2.159) (xy 5.969 2.159) (xy -5.969 2.159)
			)
			(stroke
				(width 0)
				(type default)
			)
			(fill no)
			(layer "B.CrtYd")
		)
		(fp_poly
			(pts
				(xy -6.599936 2.640076) (xy 6.599936 2.640076) (xy 6.599936 -2.640076) (xy -6.599936 -2.640076)
			)
			(stroke
				(width 0)
				(type default)
			)
			(fill no)
			(layer "F.CrtYd")
		)
		(fp_line
			(start 6.599936 2.640076)
			(end -6.599936 2.640076)
			(stroke
				(width 0.1)
				(type default)
			)
			(layer "F.Fab")
		)
		(fp_line
			(start 6.599936 -2.640076)
			(end 6.599936 2.640076)
			(stroke
				(width 0.1)
				(type default)
			)
			(layer "F.Fab")
		)
		(fp_line
			(start -6.599936 2.640076)
			(end -6.599936 -2.640076)
			(stroke
				(width 0.1)
				(type default)
			)
			(layer "F.Fab")
		)
		(fp_line
			(start -6.599936 -2.640076)
			(end 6.599936 -2.640076)
			(stroke
				(width 0.1)
				(type default)
			)
			(layer "F.Fab")
		)
		(fp_poly
			(pts
				(xy -7.4295 1.27) (xy -9.3345 0.508) (xy -9.3345 2.032)
			)
			(stroke
				(width 0)
				(type default)
			)
			(fill yes)
			(layer "F.Fab")
		)
		(fp_text user "10"
			(at 8.181086 -1.537462 0)
			(unlocked yes)
			(layer "F.SilkS")
			(effects
				(font
					(size 0.7874 0.5842)
					(thickness 0.1524)
				)
				(justify left)
			)
		)
		(fp_text user "9"
			(at 7.361936 1.197864 0)
			(unlocked yes)
			(layer "F.SilkS")
			(effects
				(font
					(size 0.7874 0.5842)
					(thickness 0.1524)
				)
				(justify left)
			)
		)
		(fp_text user "1"
			(at -6.69798 0.931672 0)
			(unlocked yes)
			(layer "F.SilkS")
			(effects
				(font
					(size 0.7874 0.5842)
					(thickness 0.1524)
				)
				(justify left)
			)
		)
		(fp_text user "2"
			(at -6.863842 -1.454404 0)
			(unlocked yes)
			(layer "F.SilkS")
			(effects
				(font
					(size 0.7874 0.5842)
					(thickness 0.1524)
				)
				(justify left)
			)
		)
		(fp_text user "9"
			(at 6.342634 1.367536 0)
			(unlocked yes)
			(layer "B.SilkS")
			(effects
				(font
					(size 0.7874 0.5842)
					(thickness 0.1524)
				)
				(justify left mirror)
			)
		)
		(fp_text user "10"
			(at 6.272784 -1.272286 0)
			(unlocked yes)
			(layer "B.SilkS")
			(effects
				(font
					(size 0.7874 0.5842)
					(thickness 0.1524)
				)
				(justify left mirror)
			)
		)
		(fp_text user "1"
			(at -6.849618 1.245616 0)
			(unlocked yes)
			(layer "B.SilkS")
			(effects
				(font
					(size 0.7874 0.5842)
					(thickness 0.1524)
				)
				(justify left mirror)
			)
		)
		(fp_text user "2"
			(at -6.90245 -1.342136 0)
			(unlocked yes)
			(layer "B.SilkS")
			(effects
				(font
					(size 0.7874 0.5842)
					(thickness 0.1524)
				)
				(justify left mirror)
			)
		)
		(fp_text user "10"
			(at 7.5438 -1.361948 180)
			(unlocked yes)
			(layer "B.Fab")
			(effects
				(font
					(size 0.7874 0.5842)
					(thickness 0.000001)
				)
				(justify left mirror)
			)
		)
		(fp_text user "9"
			(at 7.1501 1.178052 180)
			(unlocked yes)
			(layer "B.Fab")
			(effects
				(font
					(size 0.7874 0.5842)
					(thickness 0.000001)
				)
				(justify left mirror)
			)
		)
		(fp_text user "1"
			(at -6.1849 1.178052 180)
			(unlocked yes)
			(layer "B.Fab")
			(effects
				(font
					(size 0.7874 0.5842)
					(thickness 0.000001)
				)
				(justify left mirror)
			)
		)
		(fp_text user "2"
			(at -6.1849 -1.361948 180)
			(unlocked yes)
			(layer "B.Fab")
			(effects
				(font
					(size 0.7874 0.5842)
					(thickness 0.000001)
				)
				(justify left mirror)
			)
		)
		(fp_text user "9"
			(at 6.9469 1.178052 180)
			(unlocked yes)
			(layer "F.Fab")
			(effects
				(font
					(size 0.7874 0.5842)
					(thickness 0.000001)
				)
				(justify left)
			)
		)
		(fp_text user "10"
			(at 6.5532 -1.361948 180)
			(unlocked yes)
			(layer "F.Fab")
			(effects
				(font
					(size 0.7874 0.5842)
					(thickness 0.000001)
				)
				(justify left)
			)
		)
		(fp_text user "1"
			(at -7.5311 1.178052 180)
			(unlocked yes)
			(layer "F.Fab")
			(effects
				(font
					(size 0.7874 0.5842)
					(thickness 0.000001)
				)
				(justify left)
			)
		)
		(fp_text user "2"
			(at -7.5311 -1.361948 180)
			(unlocked yes)
			(layer "F.Fab")
			(effects
				(font
					(size 0.7874 0.5842)
					(thickness 0.000001)
				)
				(justify left)
			)
		)
		(pad "1" thru_hole rect
			(at -5.08 1.27 270)
			(size 1.6764 1.6764)
			(drill 1.1684)
			(layers "*.Cu" "*.Mask")
			(remove_unused_layers no)
			(net "JTAG_CPLD1_TCK")
			(clearance 0)
			(padstack
				(mode front_inner_back)
				(layer "Inner"
					(shape circle)
					(size 1.6764 1.6764)
					(clearance 0)
				)
				(layer "B.Cu"
					(shape rect)
					(size 1.6764 1.6764)
					(clearance 0)
				)
			)
		)
		(pad "2" thru_hole circle
			(at -5.08 -1.27 270)
			(size 1.6764 1.6764)
			(drill 1.1684)
			(layers "*.Cu" "*.Mask")
			(remove_unused_layers no)
			(net "GND")
			(clearance 0)
		)
		(pad "3" thru_hole circle
			(at -2.54 1.27 270)
			(size 1.6764 1.6764)
			(drill 1.1684)
			(layers "*.Cu" "*.Mask")
			(remove_unused_layers no)
			(net "JTAG_CPLD1_TDO")
			(clearance 0)
		)
		(pad "4" thru_hole circle
			(at -2.54 -1.27 270)
			(size 1.6764 1.6764)
			(drill 1.1684)
			(layers "*.Cu" "*.Mask")
			(remove_unused_layers no)
			(net "P3V3_STB_NODE1")
			(clearance 0)
		)
		(pad "5" thru_hole circle
			(at 0 1.27 270)
			(size 1.6764 1.6764)
			(drill 1.1684)
			(layers "*.Cu" "*.Mask")
			(remove_unused_layers no)
			(net "JTAG_CPLD1_TMS")
			(clearance 0)
		)
		(pad "6" thru_hole circle
			(at 0 -1.27 270)
			(size 1.6764 1.6764)
			(drill 1.1684)
			(layers "*.Cu" "*.Mask")
			(remove_unused_layers no)
			(net "Net_583")
			(clearance 0)
		)
		(pad "7" thru_hole circle
			(at 2.54 1.27 270)
			(size 1.6764 1.6764)
			(drill 1.1684)
			(layers "*.Cu" "*.Mask")
			(remove_unused_layers no)
			(net "Net_581")
			(clearance 0)
		)
		(pad "8" thru_hole circle
			(at 2.54 -1.27 270)
			(size 1.6764 1.6764)
			(drill 1.1684)
			(layers "*.Cu" "*.Mask")
			(remove_unused_layers no)
			(net "Net_582")
			(clearance 0)
		)
		(pad "9" thru_hole circle
			(at 5.08 1.27 270)
			(size 1.6764 1.6764)
			(drill 1.1684)
			(layers "*.Cu" "*.Mask")
			(remove_unused_layers no)
			(net "JTAG_CPLD1_TDI")
			(clearance 0)
		)
		(pad "10" thru_hole circle
			(at 5.08 -1.27 270)
			(size 1.6764 1.6764)
			(drill 1.1684)
			(layers "*.Cu" "*.Mask")
			(remove_unused_layers no)
			(net "GND")
			(clearance 0)
		)
	)
	(footprint ""
		(layer "F.Cu")
		(at 130.48107 -154.696668 180)
		(property "Reference" "R297"
			(at 61.214 -110.034832 0)
			(unlocked yes)
			(layer "F.SilkS")
			(effects
				(font
					(size 0.7874 0.5842)
					(thickness 0.1524)
				)
				(justify left)
			)
		)
		(property "Value" ""
			(at 0 0 180)
			(layer "F.Fab")
			(effects
				(font
					(size 1.27 1.27)
				)
			)
		)
		(duplicate_pad_numbers_are_jumpers no)
		(fp_line
			(start 0.7874 0.4064)
			(end -0.7874 0.4064)
			(stroke
				(width 0.1524)
				(type default)
			)
			(layer "F.SilkS")
		)
		(fp_line
			(start 0.7874 -0.4064)
			(end 0.7874 0.4064)
			(stroke
				(width 0.1524)
				(type default)
			)
			(layer "F.SilkS")
		)
		(fp_line
			(start -0.7874 0.4064)
			(end -0.7874 -0.4064)
			(stroke
				(width 0.1524)
				(type default)
			)
			(layer "F.SilkS")
		)
		(fp_line
			(start -0.7874 -0.4064)
			(end 0.7874 -0.4064)
			(stroke
				(width 0.1524)
				(type default)
			)
			(layer "F.SilkS")
		)
		(fp_poly
			(pts
				(xy -0.508 0.2794) (xy -0.508 0.2286) (xy -0.635 0.2286) (xy -0.635 -0.254) (xy -0.5334 -0.254)
				(xy -0.5334 -0.2794) (xy 0.5334 -0.2794) (xy 0.5334 -0.254) (xy 0.635 -0.254) (xy 0.635 0.254) (xy 0.5334 0.254)
				(xy 0.5334 0.2794)
			)
			(stroke
				(width 0)
				(type default)
			)
			(fill no)
			(layer "F.CrtYd")
		)
		(pad "1" smd rect
			(at 0.40005 0 180)
			(size 0.4572 0.508)
			(layers "F.Cu" "F.Mask" "F.Paste")
			(net "P3V3_NODE1")
		)
		(pad "2" smd rect
			(at -0.40005 0 180)
			(size 0.4572 0.508)
			(layers "F.Cu" "F.Mask" "F.Paste")
			(net "PCIE_SW_SCAN_EN")
		)
	)
	(footprint ""
		(layer "F.Cu")
		(at 44.567602 -163.558982 180)
		(property "Reference" "C400"
			(at 0.520192 -1.569466 0)
			(unlocked yes)
			(layer "F.SilkS")
			(effects
				(font
					(size 0.7874 0.5842)
					(thickness 0.1524)
				)
				(justify left)
			)
		)
		(property "Value" ""
			(at 0 0 180)
			(layer "F.Fab")
			(effects
				(font
					(size 1.27 1.27)
				)
			)
		)
		(duplicate_pad_numbers_are_jumpers no)
		(fp_line
			(start 0.7874 0.4064)
			(end -0.7874 0.4064)
			(stroke
				(width 0.1524)
				(type default)
			)
			(layer "F.SilkS")
		)
		(fp_line
			(start 0.7874 -0.4064)
			(end 0.7874 0.4064)
			(stroke
				(width 0.1524)
				(type default)
			)
			(layer "F.SilkS")
		)
		(fp_line
			(start 0 0.381)
			(end 0 -0.381)
			(stroke
				(width 0.1524)
				(type default)
			)
			(layer "F.SilkS")
		)
		(fp_line
			(start -0.7874 0.4064)
			(end -0.7874 -0.4064)
			(stroke
				(width 0.1524)
				(type default)
			)
			(layer "F.SilkS")
		)
		(fp_line
			(start -0.7874 -0.4064)
			(end 0.7874 -0.4064)
			(stroke
				(width 0.1524)
				(type default)
			)
			(layer "F.SilkS")
		)
		(fp_poly
			(pts
				(xy -0.5334 0.254) (xy -0.635 0.254) (xy -0.635 0.2286) (xy -0.635 -0.254) (xy -0.5334 -0.254) (xy -0.5334 -0.2794)
				(xy 0.5334 -0.2794) (xy 0.5334 -0.254) (xy 0.635 -0.254) (xy 0.635 0.254) (xy 0.5334 0.254) (xy 0.5334 0.2794)
				(xy -0.508 0.2794) (xy -0.5334 0.2794)
			)
			(stroke
				(width 0)
				(type default)
			)
			(fill no)
			(layer "F.CrtYd")
		)
		(pad "1" smd rect
			(at 0.40005 0 180)
			(size 0.4572 0.508)
			(layers "F.Cu" "F.Mask" "F.Paste")
			(net "LAN1_XTAL_OUT")
		)
		(pad "2" smd rect
			(at -0.40005 0 180)
			(size 0.4572 0.508)
			(layers "F.Cu" "F.Mask" "F.Paste")
			(net "GND")
		)
	)
	(footprint ""
		(layer "F.Cu")
		(at 69.547486 -148.476462 90)
		(property "Reference" "R300"
			(at 1.233932 -0.049784 90)
			(unlocked yes)
			(layer "F.SilkS")
			(effects
				(font
					(size 0.7874 0.5842)
					(thickness 0.1524)
				)
				(justify left)
			)
		)
		(property "Value" ""
			(at 0 0 90)
			(layer "F.Fab")
			(effects
				(font
					(size 1.27 1.27)
				)
			)
		)
		(duplicate_pad_numbers_are_jumpers no)
		(fp_line
			(start 0.7874 -0.4064)
			(end 0.7874 0.4064)
			(stroke
				(width 0.1524)
				(type default)
			)
			(layer "F.SilkS")
		)
		(fp_line
			(start -0.7874 -0.4064)
			(end 0.7874 -0.4064)
			(stroke
				(width 0.1524)
				(type default)
			)
			(layer "F.SilkS")
		)
		(fp_line
			(start 0.7874 0.4064)
			(end -0.7874 0.4064)
			(stroke
				(width 0.1524)
				(type default)
			)
			(layer "F.SilkS")
		)
		(fp_line
			(start -0.7874 0.4064)
			(end -0.7874 -0.4064)
			(stroke
				(width 0.1524)
				(type default)
			)
			(layer "F.SilkS")
		)
		(fp_poly
			(pts
				(xy -0.508 0.2794) (xy -0.508 0.2286) (xy -0.635 0.2286) (xy -0.635 -0.254) (xy -0.5334 -0.254)
				(xy -0.5334 -0.2794) (xy 0.5334 -0.2794) (xy 0.5334 -0.254) (xy 0.635 -0.254) (xy 0.635 0.254) (xy 0.5334 0.254)
				(xy 0.5334 0.2794)
			)
			(stroke
				(width 0)
				(type default)
			)
			(fill no)
			(layer "F.CrtYd")
		)
		(pad "1" smd rect
			(at 0.40005 0 90)
			(size 0.4572 0.508)
			(layers "F.Cu" "F.Mask" "F.Paste")
			(net "P3V3_NODE1")
		)
		(pad "2" smd rect
			(at -0.40005 0 90)
			(size 0.4572 0.508)
			(layers "F.Cu" "F.Mask" "F.Paste")
			(net "BMC_NODE1_JTAG_TDI")
		)
	)
	(footprint ""
		(layer "F.Cu")
		(at 17.982184 -66.847466 180)
		(property "Reference" "U49"
			(at -2.942336 -0.121666 0)
			(unlocked yes)
			(layer "F.SilkS")
			(effects
				(font
					(size 0.7874 0.5842)
					(thickness 0.1524)
				)
			)
		)
		(property "Value" ""
			(at 0 0 180)
			(layer "F.Fab")
			(effects
				(font
					(size 1.27 1.27)
				)
			)
		)
		(duplicate_pad_numbers_are_jumpers no)
		(fp_line
			(start 1.651 1.905)
			(end -1.651 1.905)
			(stroke
				(width 0.1524)
				(type default)
			)
			(layer "F.SilkS")
		)
		(fp_line
			(start 1.651 -1.905)
			(end 1.651 1.905)
			(stroke
				(width 0.1524)
				(type default)
			)
			(layer "F.SilkS")
		)
		(fp_line
			(start -1.651 1.905)
			(end -1.651 -1.905)
			(stroke
				(width 0.1524)
				(type default)
			)
			(layer "F.SilkS")
		)
		(fp_line
			(start -1.651 -1.905)
			(end 1.651 -1.905)
			(stroke
				(width 0.1524)
				(type default)
			)
			(layer "F.SilkS")
		)
		(fp_poly
			(pts
				(xy -1.524 0.7112) (xy -1.524 1.7526) (xy -0.508 1.7526) (xy -0.508 0.6985) (xy 0.508 0.6985) (xy 0.508 1.7526)
				(xy 1.524 1.7526) (xy 1.524 0.6985) (xy 1.524 -0.6985) (xy 0.508 -0.6985) (xy 0.508 -1.7526) (xy -0.508 -1.7526)
				(xy -0.508 -0.6985) (xy -1.524 -0.6985) (xy -1.524 0.6985)
			)
			(stroke
				(width 0)
				(type default)
			)
			(fill no)
			(layer "F.CrtYd")
		)
		(fp_text user "2"
			(at 2.046224 1.611122 0)
			(unlocked yes)
			(layer "F.SilkS")
			(effects
				(font
					(size 0.635 0.4064)
					(thickness 0.1524)
				)
			)
		)
		(fp_text user "3"
			(at 1.048004 -0.118618 0)
			(unlocked yes)
			(layer "F.SilkS")
			(effects
				(font
					(size 0.635 0.4064)
					(thickness 0.1524)
				)
			)
		)
		(fp_text user "1"
			(at -2.342896 2.741422 0)
			(unlocked yes)
			(layer "F.SilkS")
			(effects
				(font
					(size 0.635 0.4064)
					(thickness 0.1524)
				)
			)
		)
		(pad "1" smd rect
			(at -1.016 1.1176 180)
			(size 1.016 1.27)
			(layers "F.Cu" "F.Mask" "F.Paste")
			(net "GND")
		)
		(pad "2" smd rect
			(at 1.016 1.1176 180)
			(size 1.016 1.27)
			(layers "F.Cu" "F.Mask" "F.Paste")
			(net "P5V_CRT")
		)
		(pad "3" smd rect
			(at 0 -1.1176 180)
			(size 1.016 1.27)
			(layers "F.Cu" "F.Mask" "F.Paste")
			(net "CRT_DDCCLK")
		)
	)
	(footprint ""
		(layer "F.Cu")
		(at 68.61429 -177.760376 90)
		(property "Reference" "D25"
			(at 2.054606 0.570484 90)
			(unlocked yes)
			(layer "F.SilkS")
			(effects
				(font
					(size 0.7874 0.5842)
					(thickness 0.1524)
				)
				(justify left)
			)
		)
		(property "Value" ""
			(at 0 0 90)
			(layer "F.Fab")
			(effects
				(font
					(size 1.27 1.27)
				)
			)
		)
		(duplicate_pad_numbers_are_jumpers no)
		(fp_line
			(start 1.778 -0.5588)
			(end 1.3208 -0.5588)
			(stroke
				(width 0.1524)
				(type default)
			)
			(layer "F.SilkS")
		)
		(fp_line
			(start 1.778 -0.5588)
			(end 1.778 0.5588)
			(stroke
				(width 0.1524)
				(type default)
			)
			(layer "F.SilkS")
		)
		(fp_line
			(start 1.4732 -0.5588)
			(end 1.4732 0.5588)
			(stroke
				(width 0.1524)
				(type default)
			)
			(layer "F.SilkS")
		)
		(fp_line
			(start 1.3208 -0.5588)
			(end 1.3208 0.5588)
			(stroke
				(width 0.1524)
				(type default)
			)
			(layer "F.SilkS")
		)
		(fp_line
			(start -1.3208 -0.5588)
			(end 1.3208 -0.5588)
			(stroke
				(width 0.1524)
				(type default)
			)
			(layer "F.SilkS")
		)
		(fp_line
			(start 1.778 0.5588)
			(end 1.3208 0.5588)
			(stroke
				(width 0.1524)
				(type default)
			)
			(layer "F.SilkS")
		)
		(fp_line
			(start 1.6256 0.5588)
			(end 1.6256 -0.5588)
			(stroke
				(width 0.1524)
				(type default)
			)
			(layer "F.SilkS")
		)
		(fp_line
			(start 1.3208 0.5588)
			(end -1.3208 0.5588)
			(stroke
				(width 0.1524)
				(type default)
			)
			(layer "F.SilkS")
		)
		(fp_line
			(start -1.3208 0.5588)
			(end -1.3208 -0.5588)
			(stroke
				(width 0.1524)
				(type default)
			)
			(layer "F.SilkS")
		)
		(fp_rect
			(start -1.1684 0.508)
			(end 1.1684 -0.508)
			(stroke
				(width 0)
				(type default)
			)
			(fill no)
			(layer "F.CrtYd")
		)
		(fp_line
			(start 0.899922 -0.40005)
			(end 0.899922 0.40005)
			(stroke
				(width 0.1)
				(type default)
			)
			(layer "F.Fab")
		)
		(fp_line
			(start -0.899922 -0.40005)
			(end 0.899922 -0.40005)
			(stroke
				(width 0.1)
				(type default)
			)
			(layer "F.Fab")
		)
		(fp_line
			(start 0.899922 0.40005)
			(end -0.899922 0.40005)
			(stroke
				(width 0.1)
				(type default)
			)
			(layer "F.Fab")
		)
		(fp_line
			(start -0.899922 0.40005)
			(end -0.899922 -0.40005)
			(stroke
				(width 0.1)
				(type default)
			)
			(layer "F.Fab")
		)
		(fp_text user "-"
			(at 1.105154 0.763524 90)
			(unlocked yes)
			(layer "F.SilkS")
			(effects
				(font
					(size 1.27 0.9652)
					(thickness 0.1524)
				)
				(justify left)
			)
		)
		(pad "A" smd rect
			(at -0.750062 0 90)
			(size 0.8128 0.8128)
			(layers "F.Cu" "F.Mask" "F.Paste")
			(net "WDT_LED")
		)
		(pad "C" smd rect
			(at 0.750062 0 90)
			(size 0.8128 0.8128)
			(layers "F.Cu" "F.Mask" "F.Paste")
			(net "GND")
		)
	)
	(footprint ""
		(layer "F.Cu")
		(at 150.293578 -57.249822 -90)
		(property "Reference" "R517"
			(at -14.50213 -26.0858 90)
			(unlocked yes)
			(layer "F.SilkS")
			(effects
				(font
					(size 0.7874 0.5842)
					(thickness 0.1524)
				)
				(justify left)
			)
		)
		(property "Value" ""
			(at 0 0 270)
			(layer "F.Fab")
			(effects
				(font
					(size 1.27 1.27)
				)
			)
		)
		(duplicate_pad_numbers_are_jumpers no)
		(fp_line
			(start -0.7874 0.4064)
			(end -0.7874 -0.4064)
			(stroke
				(width 0.1524)
				(type default)
			)
			(layer "F.SilkS")
		)
		(fp_line
			(start 0.7874 0.4064)
			(end -0.7874 0.4064)
			(stroke
				(width 0.1524)
				(type default)
			)
			(layer "F.SilkS")
		)
		(fp_line
			(start -0.7874 -0.4064)
			(end 0.7874 -0.4064)
			(stroke
				(width 0.1524)
				(type default)
			)
			(layer "F.SilkS")
		)
		(fp_line
			(start 0.7874 -0.4064)
			(end 0.7874 0.4064)
			(stroke
				(width 0.1524)
				(type default)
			)
			(layer "F.SilkS")
		)
		(fp_poly
			(pts
				(xy -0.508 0.2794) (xy -0.508 0.2286) (xy -0.635 0.2286) (xy -0.635 -0.254) (xy -0.5334 -0.254)
				(xy -0.5334 -0.2794) (xy 0.5334 -0.2794) (xy 0.5334 -0.254) (xy 0.635 -0.254) (xy 0.635 0.254) (xy 0.5334 0.254)
				(xy 0.5334 0.2794)
			)
			(stroke
				(width 0)
				(type default)
			)
			(fill no)
			(layer "F.CrtYd")
		)
		(pad "1" smd rect
			(at 0.40005 0 270)
			(size 0.4572 0.508)
			(layers "F.Cu" "F.Mask" "F.Paste")
			(net "P3V3_NODE1")
		)
		(pad "2" smd rect
			(at -0.40005 0 270)
			(size 0.4572 0.508)
			(layers "F.Cu" "F.Mask" "F.Paste")
			(net "SATA_NODE1_GPIO5")
		)
	)
	(footprint ""
		(layer "F.Cu")
		(at 165.811454 -167.764968 180)
		(property "Reference" "C434"
			(at -1.295908 -0.439928 0)
			(unlocked yes)
			(layer "F.SilkS")
			(effects
				(font
					(size 0.7874 0.5842)
					(thickness 0.1524)
				)
				(justify left)
			)
		)
		(property "Value" ""
			(at 0 0 180)
			(layer "F.Fab")
			(effects
				(font
					(size 1.27 1.27)
				)
			)
		)
		(duplicate_pad_numbers_are_jumpers no)
		(fp_line
			(start 0.7874 0.4064)
			(end -0.7874 0.4064)
			(stroke
				(width 0.1524)
				(type default)
			)
			(layer "F.SilkS")
		)
		(fp_line
			(start 0.7874 -0.4064)
			(end 0.7874 0.4064)
			(stroke
				(width 0.1524)
				(type default)
			)
			(layer "F.SilkS")
		)
		(fp_line
			(start 0 0.381)
			(end 0 -0.381)
			(stroke
				(width 0.1524)
				(type default)
			)
			(layer "F.SilkS")
		)
		(fp_line
			(start -0.7874 0.4064)
			(end -0.7874 -0.4064)
			(stroke
				(width 0.1524)
				(type default)
			)
			(layer "F.SilkS")
		)
		(fp_line
			(start -0.7874 -0.4064)
			(end 0.7874 -0.4064)
			(stroke
				(width 0.1524)
				(type default)
			)
			(layer "F.SilkS")
		)
		(fp_poly
			(pts
				(xy -0.5334 0.254) (xy -0.635 0.254) (xy -0.635 0.2286) (xy -0.635 -0.254) (xy -0.5334 -0.254) (xy -0.5334 -0.2794)
				(xy 0.5334 -0.2794) (xy 0.5334 -0.254) (xy 0.635 -0.254) (xy 0.635 0.254) (xy 0.5334 0.254) (xy 0.5334 0.2794)
				(xy -0.508 0.2794) (xy -0.5334 0.2794)
			)
			(stroke
				(width 0)
				(type default)
			)
			(fill no)
			(layer "F.CrtYd")
		)
		(pad "1" smd rect
			(at 0.40005 0 180)
			(size 0.4572 0.508)
			(layers "F.Cu" "F.Mask" "F.Paste")
			(net "P3V3_NODE1")
		)
		(pad "2" smd rect
			(at -0.40005 0 180)
			(size 0.4572 0.508)
			(layers "F.Cu" "F.Mask" "F.Paste")
			(net "GND")
		)
	)
	(footprint ""
		(layer "F.Cu")
		(at 56.24576 -188.126624 90)
		(property "Reference" "C715"
			(at 4.548886 0.310642 90)
			(unlocked yes)
			(layer "F.SilkS")
			(effects
				(font
					(size 0.7874 0.5842)
					(thickness 0.1524)
				)
				(justify left)
			)
		)
		(property "Value" ""
			(at 0 0 90)
			(layer "F.Fab")
			(effects
				(font
					(size 1.27 1.27)
				)
			)
		)
		(duplicate_pad_numbers_are_jumpers no)
		(fp_line
			(start 0.7874 -0.4064)
			(end 0.7874 0.4064)
			(stroke
				(width 0.1524)
				(type default)
			)
			(layer "F.SilkS")
		)
		(fp_line
			(start -0.7874 -0.4064)
			(end 0.7874 -0.4064)
			(stroke
				(width 0.1524)
				(type default)
			)
			(layer "F.SilkS")
		)
		(fp_line
			(start 0 0.381)
			(end 0 -0.381)
			(stroke
				(width 0.1524)
				(type default)
			)
			(layer "F.SilkS")
		)
		(fp_line
			(start 0.7874 0.4064)
			(end -0.7874 0.4064)
			(stroke
				(width 0.1524)
				(type default)
			)
			(layer "F.SilkS")
		)
		(fp_line
			(start -0.7874 0.4064)
			(end -0.7874 -0.4064)
			(stroke
				(width 0.1524)
				(type default)
			)
			(layer "F.SilkS")
		)
		(fp_poly
			(pts
				(xy -0.5334 0.254) (xy -0.635 0.254) (xy -0.635 0.2286) (xy -0.635 -0.254) (xy -0.5334 -0.254) (xy -0.5334 -0.2794)
				(xy 0.5334 -0.2794) (xy 0.5334 -0.254) (xy 0.635 -0.254) (xy 0.635 0.254) (xy 0.5334 0.254) (xy 0.5334 0.2794)
				(xy -0.508 0.2794) (xy -0.5334 0.2794)
			)
			(stroke
				(width 0)
				(type default)
			)
			(fill no)
			(layer "F.CrtYd")
		)
		(pad "1" smd rect
			(at 0.40005 0 90)
			(size 0.4572 0.508)
			(layers "F.Cu" "F.Mask" "F.Paste")
			(net "UART_T2_NODE4_TXD_R")
		)
		(pad "2" smd rect
			(at -0.40005 0 90)
			(size 0.4572 0.508)
			(layers "F.Cu" "F.Mask" "F.Paste")
			(net "GND")
		)
	)
	(footprint ""
		(layer "F.Cu")
		(at 107.595924 -69.156326 -90)
		(property "Reference" "J3"
			(at -11.305286 0.945388 0)
			(unlocked yes)
			(layer "F.SilkS")
			(effects
				(font
					(size 0.7874 0.5842)
					(thickness 0.1524)
				)
				(justify left)
			)
		)
		(property "Value" ""
			(at 0 0 270)
			(layer "F.Fab")
			(effects
				(font
					(size 1.27 1.27)
				)
			)
		)
		(duplicate_pad_numbers_are_jumpers no)
		(fp_line
			(start -10.661396 3.6195)
			(end -10.661396 -1.888744)
			(stroke
				(width 0.1524)
				(type default)
			)
			(layer "F.SilkS")
		)
		(fp_line
			(start -7.719822 3.6195)
			(end -10.661396 3.6195)
			(stroke
				(width 0.1524)
				(type default)
			)
			(layer "F.SilkS")
		)
		(fp_line
			(start 10.638536 3.6195)
			(end 7.720076 3.6195)
			(stroke
				(width 0.1524)
				(type default)
			)
			(layer "F.SilkS")
		)
		(fp_line
			(start 10.638536 -1.913128)
			(end 10.638536 3.6195)
			(stroke
				(width 0.1524)
				(type default)
			)
			(layer "F.SilkS")
		)
		(fp_line
			(start -10.661396 -3.6195)
			(end -7.719822 -3.6195)
			(stroke
				(width 0.1524)
				(type default)
			)
			(layer "F.SilkS")
		)
		(fp_line
			(start 7.720076 -3.6195)
			(end 10.638536 -3.6195)
			(stroke
				(width 0.1524)
				(type default)
			)
			(layer "F.SilkS")
		)
		(fp_poly
			(pts
				(xy -7.249922 4.197604) (xy -7.630922 5.340604) (xy -6.868922 5.340604)
			)
			(stroke
				(width 0)
				(type default)
			)
			(fill yes)
			(layer "F.SilkS")
		)
		(fp_poly
			(pts
				(arc
					(start 10.072878 -3.460496)
					(mid 9.498142 -3.222432)
					(end 9.260078 -2.647696)
				)
				(arc
					(start 9.260078 -2.647696)
					(mid 9.490702 -2.09092)
					(end 10.047478 -1.860296)
				)
				(arc
					(start 10.072878 -1.860296)
					(mid 10.872978 -2.660396)
					(end 10.072878 -3.460496)
				)
			)
			(stroke
				(width 0)
				(type default)
			)
			(fill no)
			(layer "B.CrtYd")
		)
		(fp_poly
			(pts
				(arc
					(start -10.069322 -3.460496)
					(mid -10.626098 -3.229872)
					(end -10.856722 -2.673096)
				)
				(arc
					(start -10.856722 -2.647696)
					(mid -10.626098 -2.09092)
					(end -10.069322 -1.860296)
				)
				(arc
					(start -10.043922 -1.860296)
					(mid -9.243822 -2.660396)
					(end -10.043922 -3.460496)
				)
			)
			(stroke
				(width 0)
				(type default)
			)
			(fill no)
			(layer "B.CrtYd")
		)
		(fp_poly
			(pts
				(xy -10.661396 -3.6195) (xy -7.427722 -3.6195) (xy -7.427722 -4.044696) (xy 7.431278 -4.044696)
				(xy 7.431278 -3.6195) (xy 10.638536 -3.6195) (xy 10.827004 -3.6195) (xy 10.827004 3.621024) (xy 10.638536 3.621024)
				(xy 10.638536 3.6195) (xy 7.431278 3.6195) (xy 7.431278 4.032504) (xy -7.427722 4.032504) (xy -7.427722 3.6195)
				(xy -10.661396 3.6195) (xy -10.671302 3.6195) (xy -10.81151 3.6195) (xy -10.81151 -3.6195) (xy -10.671302 -3.6195)
			)
			(stroke
				(width 0)
				(type default)
			)
			(fill no)
			(layer "F.CrtYd")
		)
		(fp_line
			(start -10.661396 3.6195)
			(end 10.638536 3.6195)
			(stroke
				(width 0.1)
				(type default)
			)
			(layer "F.Fab")
		)
		(fp_line
			(start 10.638536 3.6195)
			(end 10.638536 -3.6195)
			(stroke
				(width 0.1)
				(type default)
			)
			(layer "F.Fab")
		)
		(fp_line
			(start -10.661396 -3.6195)
			(end -10.661396 3.6195)
			(stroke
				(width 0.1)
				(type default)
			)
			(layer "F.Fab")
		)
		(fp_line
			(start 10.638536 -3.6195)
			(end -10.661396 -3.6195)
			(stroke
				(width 0.1)
				(type default)
			)
			(layer "F.Fab")
		)
		(fp_text user "59"
			(at 9.438386 5.19938 0)
			(unlocked yes)
			(layer "F.SilkS")
			(effects
				(font
					(size 0.635 0.4064)
					(thickness 0.1524)
				)
				(justify left)
			)
		)
		(fp_text user "1"
			(at -7.9756 4.418584 0)
			(unlocked yes)
			(layer "F.SilkS")
			(effects
				(font
					(size 0.635 0.4064)
					(thickness 0.1524)
				)
				(justify left)
			)
		)
		(fp_text user "60"
			(at 10.22096 -3.782314 0)
			(unlocked yes)
			(layer "F.SilkS")
			(effects
				(font
					(size 0.635 0.4064)
					(thickness 0.1524)
				)
				(justify left)
			)
		)
		(fp_text user "2"
			(at -8.030718 -4.084828 0)
			(unlocked yes)
			(layer "F.SilkS")
			(effects
				(font
					(size 0.635 0.4064)
					(thickness 0.1524)
				)
				(justify left)
			)
		)
		(fp_text user "59"
			(at 7.1628 4.708906 270)
			(unlocked yes)
			(layer "F.Fab")
			(effects
				(font
					(size 0.7874 0.5842)
					(thickness 0.000001)
				)
				(justify left)
			)
		)
		(fp_text user "1"
			(at -8.1153 4.327906 270)
			(unlocked yes)
			(layer "F.Fab")
			(effects
				(font
					(size 0.7874 0.5842)
					(thickness 0.000001)
				)
				(justify left)
			)
		)
		(fp_text user "2"
			(at -8.1915 -4.536694 270)
			(unlocked yes)
			(layer "F.Fab")
			(effects
				(font
					(size 0.7874 0.5842)
					(thickness 0.000001)
				)
				(justify left)
			)
		)
		(fp_text user "60"
			(at 7.2136 -4.562094 270)
			(unlocked yes)
			(layer "F.Fab")
			(effects
				(font
					(size 0.7874 0.5842)
					(thickness 0.000001)
				)
				(justify left)
			)
		)
		(pad "" np_thru_hole circle
			(at -10.059924 -2.665984)
			(size 0.254 0.254)
			(drill 1.1938)
			(layers "*.Cu" "*.Mask")
			(clearance 0.8509)
			(thermal_gap 0.8509)
		)
		(pad "" np_thru_hole circle
			(at 10.065766 -2.665984)
			(size 0.254 0.254)
			(drill 1.1938)
			(layers "*.Cu" "*.Mask")
			(clearance 0.8509)
			(thermal_gap 0.8509)
		)
		(pad "1" smd rect
			(at -7.249922 2.864104)
			(size 2.286 0.2794)
			(layers "F.Cu" "F.Mask" "F.Paste")
			(net "GND")
		)
		(pad "2" smd rect
			(at -7.249922 -2.864104)
			(size 2.286 0.2794)
			(layers "F.Cu" "F.Mask" "F.Paste")
			(net "GND")
		)
		(pad "3" smd rect
			(at -6.749796 2.864104)
			(size 2.286 0.2794)
			(layers "F.Cu" "F.Mask" "F.Paste")
			(net "XDP_CPU_NODE1_PREQ_L")
		)
		(pad "4" smd rect
			(at -6.749796 -2.864104)
			(size 2.286 0.2794)
			(layers "F.Cu" "F.Mask" "F.Paste")
			(net "XDP_CPU_NODE1_VISA0")
		)
		(pad "5" smd rect
			(at -6.249924 2.864104)
			(size 2.286 0.2794)
			(layers "F.Cu" "F.Mask" "F.Paste")
			(net "XDP_CPU_NODE1_PRDY_L")
		)
		(pad "6" smd rect
			(at -6.249924 -2.864104)
			(size 2.286 0.2794)
			(layers "F.Cu" "F.Mask" "F.Paste")
			(net "XDP_CPU_NODE1_VISA9")
		)
		(pad "7" smd rect
			(at -5.749798 2.864104)
			(size 2.286 0.2794)
			(layers "F.Cu" "F.Mask" "F.Paste")
			(net "GND")
		)
		(pad "8" smd rect
			(at -5.749798 -2.864104)
			(size 2.286 0.2794)
			(layers "F.Cu" "F.Mask" "F.Paste")
			(net "GND")
		)
		(pad "9" smd rect
			(at -5.249926 2.864104)
			(size 2.286 0.2794)
			(layers "F.Cu" "F.Mask" "F.Paste")
			(net "XDP_CPU_NODE1_VISA1")
		)
		(pad "10" smd rect
			(at -5.249926 -2.864104)
			(size 2.286 0.2794)
			(layers "F.Cu" "F.Mask" "F.Paste")
			(net "XDP_CPU_NODE1_VISA10")
		)
		(pad "11" smd rect
			(at -4.7498 2.864104)
			(size 2.286 0.2794)
			(layers "F.Cu" "F.Mask" "F.Paste")
			(net "XDP_CPU_NODE1_VISA2")
		)
		(pad "12" smd rect
			(at -4.7498 -2.864104)
			(size 2.286 0.2794)
			(layers "F.Cu" "F.Mask" "F.Paste")
			(net "XDP_CPU_NODE1_VISA11")
		)
		(pad "13" smd rect
			(at -4.249928 2.864104)
			(size 2.286 0.2794)
			(layers "F.Cu" "F.Mask" "F.Paste")
			(net "GND")
		)
		(pad "14" smd rect
			(at -4.249928 -2.864104)
			(size 2.286 0.2794)
			(layers "F.Cu" "F.Mask" "F.Paste")
			(net "GND")
		)
		(pad "15" smd rect
			(at -3.749802 2.864104)
			(size 2.286 0.2794)
			(layers "F.Cu" "F.Mask" "F.Paste")
			(net "XDP_CPU_NODE1_VISA3")
		)
		(pad "16" smd rect
			(at -3.749802 -2.864104)
			(size 2.286 0.2794)
			(layers "F.Cu" "F.Mask" "F.Paste")
			(net "XDP_CPU_NODE1_VISA12")
		)
		(pad "17" smd rect
			(at -3.24993 2.864104)
			(size 2.286 0.2794)
			(layers "F.Cu" "F.Mask" "F.Paste")
			(net "XDP_CPU_NODE1_VISA4")
		)
		(pad "18" smd rect
			(at -3.24993 -2.864104)
			(size 2.286 0.2794)
			(layers "F.Cu" "F.Mask" "F.Paste")
			(net "XDP_CPU_NODE1_VISA13")
		)
		(pad "19" smd rect
			(at -2.749804 2.864104)
			(size 2.286 0.2794)
			(layers "F.Cu" "F.Mask" "F.Paste")
			(net "GND")
		)
		(pad "20" smd rect
			(at -2.749804 -2.864104)
			(size 2.286 0.2794)
			(layers "F.Cu" "F.Mask" "F.Paste")
			(net "GND")
		)
		(pad "21" smd rect
			(at -2.249932 2.864104)
			(size 2.286 0.2794)
			(layers "F.Cu" "F.Mask" "F.Paste")
			(net "Net_1687")
		)
		(pad "22" smd rect
			(at -2.249932 -2.864104)
			(size 2.286 0.2794)
			(layers "F.Cu" "F.Mask" "F.Paste")
			(net "Net_1688")
		)
		(pad "23" smd rect
			(at -1.749806 2.864104)
			(size 2.286 0.2794)
			(layers "F.Cu" "F.Mask" "F.Paste")
			(net "Net_1689")
		)
		(pad "24" smd rect
			(at -1.749806 -2.864104)
			(size 2.286 0.2794)
			(layers "F.Cu" "F.Mask" "F.Paste")
			(net "Net_1690")
		)
		(pad "25" smd rect
			(at -1.249934 2.864104)
			(size 2.286 0.2794)
			(layers "F.Cu" "F.Mask" "F.Paste")
			(net "GND")
		)
		(pad "26" smd rect
			(at -1.249934 -2.864104)
			(size 2.286 0.2794)
			(layers "F.Cu" "F.Mask" "F.Paste")
			(net "GND")
		)
		(pad "27" smd rect
			(at -0.750062 2.864104)
			(size 2.286 0.2794)
			(layers "F.Cu" "F.Mask" "F.Paste")
			(net "XDP_CPU_NODE1_VISA5")
		)
		(pad "28" smd rect
			(at -0.750062 -2.864104)
			(size 2.286 0.2794)
			(layers "F.Cu" "F.Mask" "F.Paste")
			(net "XDP_CPU_NODE1_VISA14")
		)
		(pad "29" smd rect
			(at -0.249936 2.864104)
			(size 2.286 0.2794)
			(layers "F.Cu" "F.Mask" "F.Paste")
			(net "XDP_CPU_NODE1_VISA6")
		)
		(pad "30" smd rect
			(at -0.249936 -2.864104)
			(size 2.286 0.2794)
			(layers "F.Cu" "F.Mask" "F.Paste")
			(net "XDP_CPU_NODE1_VISA15")
		)
		(pad "31" smd rect
			(at 0.25019 2.864104)
			(size 2.286 0.2794)
			(layers "F.Cu" "F.Mask" "F.Paste")
			(net "GND")
		)
		(pad "32" smd rect
			(at 0.25019 -2.864104)
			(size 2.286 0.2794)
			(layers "F.Cu" "F.Mask" "F.Paste")
			(net "GND")
		)
		(pad "33" smd rect
			(at 0.750062 2.864104)
			(size 2.286 0.2794)
			(layers "F.Cu" "F.Mask" "F.Paste")
			(net "XDP_CPU_NODE1_VISA7")
		)
		(pad "34" smd rect
			(at 0.750062 -2.864104)
			(size 2.286 0.2794)
			(layers "F.Cu" "F.Mask" "F.Paste")
			(net "XDP_CPU_NODE1_VISA16")
		)
		(pad "35" smd rect
			(at 1.250188 2.864104)
			(size 2.286 0.2794)
			(layers "F.Cu" "F.Mask" "F.Paste")
			(net "XDP_CPU_NODE1_VISA8")
		)
		(pad "36" smd rect
			(at 1.250188 -2.864104)
			(size 2.286 0.2794)
			(layers "F.Cu" "F.Mask" "F.Paste")
			(net "XDP_CPU_NODE1_VISA17")
		)
		(pad "37" smd rect
			(at 1.75006 2.864104)
			(size 2.286 0.2794)
			(layers "F.Cu" "F.Mask" "F.Paste")
			(net "GND")
		)
		(pad "38" smd rect
			(at 1.75006 -2.864104)
			(size 2.286 0.2794)
			(layers "F.Cu" "F.Mask" "F.Paste")
			(net "GND")
		)
		(pad "39" smd rect
			(at 2.250186 2.864104)
			(size 2.286 0.2794)
			(layers "F.Cu" "F.Mask" "F.Paste")
			(net "XDP_CPU_NODE1_PWROK_R")
		)
		(pad "40" smd rect
			(at 2.250186 -2.864104)
			(size 2.286 0.2794)
			(layers "F.Cu" "F.Mask" "F.Paste")
			(net "CLK_100M_XDP_NODE1_DP")
		)
		(pad "41" smd rect
			(at 2.750058 2.864104)
			(size 2.286 0.2794)
			(layers "F.Cu" "F.Mask" "F.Paste")
			(net "XDP_CPU_NODE1_PG_RST_R")
		)
		(pad "42" smd rect
			(at 2.750058 -2.864104)
			(size 2.286 0.2794)
			(layers "F.Cu" "F.Mask" "F.Paste")
			(net "CLK_100M_XDP_NODE1_DN")
		)
		(pad "43" smd rect
			(at 3.250184 2.864104)
			(size 2.286 0.2794)
			(layers "F.Cu" "F.Mask" "F.Paste")
			(net "P1V05_STB_NODE1_XDP_A")
		)
		(pad "44" smd rect
			(at 3.250184 -2.864104)
			(size 2.286 0.2794)
			(layers "F.Cu" "F.Mask" "F.Paste")
			(net "P1V05_STB_NODE1_XDP_B")
		)
		(pad "45" smd rect
			(at 3.750056 2.864104)
			(size 2.286 0.2794)
			(layers "F.Cu" "F.Mask" "F.Paste")
			(net "Net_1691")
		)
		(pad "46" smd rect
			(at 3.750056 -2.864104)
			(size 2.286 0.2794)
			(layers "F.Cu" "F.Mask" "F.Paste")
			(net "FM_CPLD_NODE1_CPU_RESET_L")
		)
		(pad "47" smd rect
			(at 4.249928 2.864104)
			(size 2.286 0.2794)
			(layers "F.Cu" "F.Mask" "F.Paste")
			(net "XDP_CPU_NODE1_PWROK_STALL_L")
		)
		(pad "48" smd rect
			(at 4.249928 -2.864104)
			(size 2.286 0.2794)
			(layers "F.Cu" "F.Mask" "F.Paste")
			(net "RST_NODE1_CPU_XDP_RSTIN_L")
		)
		(pad "49" smd rect
			(at 4.7498 2.864104)
			(size 2.286 0.2794)
			(layers "F.Cu" "F.Mask" "F.Paste")
			(net "GND")
		)
		(pad "50" smd rect
			(at 4.7498 -2.864104)
			(size 2.286 0.2794)
			(layers "F.Cu" "F.Mask" "F.Paste")
			(net "GND")
		)
		(pad "51" smd rect
			(at 5.25018 2.864104)
			(size 2.286 0.2794)
			(layers "F.Cu" "F.Mask" "F.Paste")
			(net "SMB_CPU_NODE1_XDP_DAT")
		)
		(pad "52" smd rect
			(at 5.25018 -2.864104)
			(size 2.286 0.2794)
			(layers "F.Cu" "F.Mask" "F.Paste")
			(net "XDP_SOC_CPU_NODE1_TDO")
		)
		(pad "53" smd rect
			(at 5.750052 2.864104)
			(size 2.286 0.2794)
			(layers "F.Cu" "F.Mask" "F.Paste")
			(net "SMB_CPU_NODE1_XDP_CLK")
		)
		(pad "54" smd rect
			(at 5.750052 -2.864104)
			(size 2.286 0.2794)
			(layers "F.Cu" "F.Mask" "F.Paste")
			(net "XDP_SOC_CPU_NODE1_TRST_L")
		)
		(pad "55" smd rect
			(at 6.250178 2.864104)
			(size 2.286 0.2794)
			(layers "F.Cu" "F.Mask" "F.Paste")
			(net "Net_1692")
		)
		(pad "56" smd rect
			(at 6.250178 -2.864104)
			(size 2.286 0.2794)
			(layers "F.Cu" "F.Mask" "F.Paste")
			(net "XDP_SOC_CPU_NODE1_TDI")
		)
		(pad "57" smd rect
			(at 6.75005 2.864104)
			(size 2.286 0.2794)
			(layers "F.Cu" "F.Mask" "F.Paste")
			(net "XDP_SOC_CPU_NODE1_TCK")
		)
		(pad "58" smd rect
			(at 6.75005 -2.864104)
			(size 2.286 0.2794)
			(layers "F.Cu" "F.Mask" "F.Paste")
			(net "XDP_SOC_CPU_NODE1_TMS")
		)
		(pad "59" smd rect
			(at 7.250176 2.864104)
			(size 2.286 0.2794)
			(layers "F.Cu" "F.Mask" "F.Paste")
			(net "GND")
		)
		(pad "60" smd rect
			(at 7.250176 -2.864104)
			(size 2.286 0.2794)
			(layers "F.Cu" "F.Mask" "F.Paste")
			(net "XDP_NODE1_P60")
		)
		(zone
			(layers "F.Cu" "B.Cu" "In1.Cu" "In2.Cu" "In3.Cu" "In4.Cu" "In5.Cu" "In6.Cu"
				"In7.Cu" "In8.Cu"
			)
			(hatch none 0.5)
			(connect_pads
				(clearance 0)
			)
			(min_thickness 0.25)
			(keepout
				(tracks not_allowed)
				(vias allowed)
				(pads allowed)
				(copperpour not_allowed)
				(footprints allowed)
			)
			(placement
				(enabled no)
				(sheetname "")
			)
			(fill
				(thermal_gap 0.5)
				(thermal_bridge_width 0.5)
				(island_removal_mode 0)
			)
			(polygon
				(pts
					(arc
						(start 109.258608 -79.21625)
						(mid 111.265716 -79.21625)
						(end 109.258608 -79.21625)
					)
				)
			)
		)
		(zone
			(layers "F.Cu" "B.Cu" "In1.Cu" "In2.Cu" "In3.Cu" "In4.Cu" "In5.Cu" "In6.Cu"
				"In7.Cu" "In8.Cu"
			)
			(hatch none 0.5)
			(connect_pads
				(clearance 0)
			)
			(min_thickness 0.25)
			(keepout
				(tracks not_allowed)
				(vias allowed)
				(pads allowed)
				(copperpour not_allowed)
				(footprints allowed)
			)
			(placement
				(enabled no)
				(sheetname "")
			)
			(fill
				(thermal_gap 0.5)
				(thermal_bridge_width 0.5)
				(island_removal_mode 0)
			)
			(polygon
				(pts
					(arc
						(start 109.258608 -59.09056)
						(mid 111.265716 -59.09056)
						(end 109.258608 -59.09056)
					)
				)
			)
		)
	)
	(footprint ""
		(layer "F.Cu")
		(at 16.718534 -49.95291 90)
		(property "Reference" "L40"
			(at -3.963924 14.24813 90)
			(unlocked yes)
			(layer "F.SilkS")
			(effects
				(font
					(size 0.7874 0.5842)
					(thickness 0.1524)
				)
			)
		)
		(property "Value" ""
			(at 0 0 90)
			(layer "F.Fab")
			(effects
				(font
					(size 1.27 1.27)
				)
			)
		)
		(duplicate_pad_numbers_are_jumpers no)
		(fp_line
			(start 1.2954 -0.635)
			(end 1.2954 0.635)
			(stroke
				(width 0.1524)
				(type default)
			)
			(layer "F.SilkS")
		)
		(fp_line
			(start -1.2954 -0.635)
			(end 1.2954 -0.635)
			(stroke
				(width 0.1524)
				(type default)
			)
			(layer "F.SilkS")
		)
		(fp_line
			(start -1.2954 -0.635)
			(end -1.2954 0.635)
			(stroke
				(width 0.1524)
				(type default)
			)
			(layer "F.SilkS")
		)
		(fp_line
			(start 0.127 -0.5842)
			(end 0.127 0.5842)
			(stroke
				(width 0.1524)
				(type default)
			)
			(layer "F.SilkS")
		)
		(fp_line
			(start -0.127 -0.5842)
			(end -0.127 0.5842)
			(stroke
				(width 0.1524)
				(type default)
			)
			(layer "F.SilkS")
		)
		(fp_line
			(start 1.2954 0.635)
			(end -1.2954 0.635)
			(stroke
				(width 0.1524)
				(type default)
			)
			(layer "F.SilkS")
		)
		(fp_poly
			(pts
				(xy -0.9144 0.508) (xy -0.9144 0.3556) (xy -1.143 0.3556) (xy -1.143 -0.3556) (xy -0.9144 -0.3556)
				(xy -0.9144 -0.508) (xy 0.9144 -0.508) (xy 0.9144 -0.3556) (xy 1.143 -0.3556) (xy 1.143 0.3556)
				(xy 0.9144 0.3556) (xy 0.9144 0.508)
			)
			(stroke
				(width 0)
				(type default)
			)
			(fill no)
			(layer "F.CrtYd")
		)
		(pad "1" smd rect
			(at 0.7366 0 180)
			(size 0.7112 0.8128)
			(layers "F.Cu" "F.Mask" "F.Paste")
			(net "BMC_NODE1_GFX_GREEN")
		)
		(pad "2" smd rect
			(at -0.7366 0 180)
			(size 0.7112 0.8128)
			(layers "F.Cu" "F.Mask" "F.Paste")
			(net "CRT_G_L")
		)
	)
	(footprint ""
		(layer "F.Cu")
		(at 175.000158 -26.75001)
		(property "Reference" "H7"
			(at 0 0 0)
			(layer "F.SilkS")
			(hide yes)
			(effects
				(font
					(size 1.27 1.27)
				)
			)
		)
		(property "Value" ""
			(at 0 0 0)
			(layer "F.Fab")
			(effects
				(font
					(size 1.27 1.27)
				)
			)
		)
		(duplicate_pad_numbers_are_jumpers no)
		(fp_poly
			(pts
				(arc
					(start 5.999988 4.99999)
					(mid 0 10.999978)
					(end -5.999988 4.99999)
				)
				(arc
					(start -5.999988 0)
					(mid 0 -5.999988)
					(end 5.999988 0)
				)
			)
			(stroke
				(width 0)
				(type default)
			)
			(fill no)
			(layer "B.CrtYd")
		)
		(fp_poly
			(pts
				(arc
					(start 5.999988 4.99999)
					(mid 0 10.999978)
					(end -5.999988 4.99999)
				)
				(arc
					(start -5.999988 0)
					(mid 0 -5.999988)
					(end 5.999988 0)
				)
			)
			(stroke
				(width 0)
				(type default)
			)
			(fill no)
			(layer "F.CrtYd")
		)
		(pad "" np_thru_hole circle
			(at 0 0)
			(size 3.81 3.81)
			(drill 3.81)
			(layers "*.Cu" "*.Mask")
			(clearance 0.381)
			(thermal_gap 0.381)
		)
	)
	(footprint ""
		(layer "F.Cu")
		(at 87.331804 -80.669638 180)
		(property "Reference" "C78"
			(at -2.485136 0.04445 0)
			(unlocked yes)
			(layer "F.SilkS")
			(effects
				(font
					(size 0.7874 0.5842)
					(thickness 0.1524)
				)
			)
		)
		(property "Value" ""
			(at 0 0 180)
			(layer "F.Fab")
			(effects
				(font
					(size 1.27 1.27)
				)
			)
		)
		(duplicate_pad_numbers_are_jumpers no)
		(fp_line
			(start 1.2954 0.5842)
			(end -1.2954 0.5842)
			(stroke
				(width 0.1524)
				(type default)
			)
			(layer "F.SilkS")
		)
		(fp_line
			(start 1.2954 -0.5842)
			(end 1.2954 0.5842)
			(stroke
				(width 0.1524)
				(type default)
			)
			(layer "F.SilkS")
		)
		(fp_line
			(start 0 -0.5842)
			(end 0 0.5842)
			(stroke
				(width 0.1524)
				(type default)
			)
			(layer "F.SilkS")
		)
		(fp_line
			(start -1.2954 0.5842)
			(end -1.2954 -0.5842)
			(stroke
				(width 0.1524)
				(type default)
			)
			(layer "F.SilkS")
		)
		(fp_line
			(start -1.2954 -0.5842)
			(end 1.2954 -0.5842)
			(stroke
				(width 0.1524)
				(type default)
			)
			(layer "F.SilkS")
		)
		(fp_poly
			(pts
				(xy 0.8636 -0.4572) (xy 0.8636 -0.3556) (xy 1.143 -0.3556) (xy 1.143 0.3556) (xy 0.8636 0.3556)
				(xy 0.8636 0.4572) (xy -0.8636 0.4572) (xy -0.8636 0.3556) (xy -1.143 0.3556) (xy -1.143 -0.3556)
				(xy -0.8636 -0.3556) (xy -0.8636 -0.4572)
			)
			(stroke
				(width 0)
				(type default)
			)
			(fill no)
			(layer "F.CrtYd")
		)
		(fp_line
			(start 0.884936 0.504952)
			(end -0.884936 0.504952)
			(stroke
				(width 0.1)
				(type default)
			)
			(layer "F.Fab")
		)
		(fp_line
			(start 0.884936 -0.504952)
			(end 0.884936 0.504952)
			(stroke
				(width 0.1)
				(type default)
			)
			(layer "F.Fab")
		)
		(fp_line
			(start -0.884936 0.504952)
			(end -0.884936 -0.504952)
			(stroke
				(width 0.1)
				(type default)
			)
			(layer "F.Fab")
		)
		(fp_line
			(start -0.884936 -0.504952)
			(end 0.884936 -0.504952)
			(stroke
				(width 0.1)
				(type default)
			)
			(layer "F.Fab")
		)
		(pad "1" smd rect
			(at 0.7366 0 270)
			(size 0.7112 0.8128)
			(layers "F.Cu" "F.Mask" "F.Paste")
			(net "P1V05_VCCPLLCPU1SIO_NODE1")
		)
		(pad "2" smd rect
			(at -0.7366 0 270)
			(size 0.7112 0.8128)
			(layers "F.Cu" "F.Mask" "F.Paste")
			(net "GND")
		)
	)
	(footprint ""
		(layer "F.Cu")
		(at 23.934928 -106.698796 180)
		(property "Reference" "PC61"
			(at 2.223008 -1.108202 0)
			(unlocked yes)
			(layer "F.SilkS")
			(effects
				(font
					(size 0.7874 0.5842)
					(thickness 0.1524)
				)
				(justify left)
			)
		)
		(property "Value" ""
			(at 0 0 180)
			(layer "F.Fab")
			(effects
				(font
					(size 1.27 1.27)
				)
			)
		)
		(duplicate_pad_numbers_are_jumpers no)
		(fp_line
			(start 0.7874 0.4064)
			(end -0.7874 0.4064)
			(stroke
				(width 0.1524)
				(type default)
			)
			(layer "F.SilkS")
		)
		(fp_line
			(start 0.7874 -0.4064)
			(end 0.7874 0.4064)
			(stroke
				(width 0.1524)
				(type default)
			)
			(layer "F.SilkS")
		)
		(fp_line
			(start 0 0.381)
			(end 0 -0.381)
			(stroke
				(width 0.1524)
				(type default)
			)
			(layer "F.SilkS")
		)
		(fp_line
			(start -0.7874 0.4064)
			(end -0.7874 -0.4064)
			(stroke
				(width 0.1524)
				(type default)
			)
			(layer "F.SilkS")
		)
		(fp_line
			(start -0.7874 -0.4064)
			(end 0.7874 -0.4064)
			(stroke
				(width 0.1524)
				(type default)
			)
			(layer "F.SilkS")
		)
		(fp_poly
			(pts
				(xy -0.5334 0.254) (xy -0.635 0.254) (xy -0.635 0.2286) (xy -0.635 -0.254) (xy -0.5334 -0.254) (xy -0.5334 -0.2794)
				(xy 0.5334 -0.2794) (xy 0.5334 -0.254) (xy 0.635 -0.254) (xy 0.635 0.254) (xy 0.5334 0.254) (xy 0.5334 0.2794)
				(xy -0.508 0.2794) (xy -0.5334 0.2794)
			)
			(stroke
				(width 0)
				(type default)
			)
			(fill no)
			(layer "F.CrtYd")
		)
		(pad "1" smd rect
			(at 0.40005 0 180)
			(size 0.4572 0.508)
			(layers "F.Cu" "F.Mask" "F.Paste")
			(net "P1V05_NODE1")
		)
		(pad "2" smd rect
			(at -0.40005 0 180)
			(size 0.4572 0.508)
			(layers "F.Cu" "F.Mask" "F.Paste")
			(net "GND")
		)
	)
	(footprint ""
		(layer "F.Cu")
		(at 101.558598 -131.539488 -90)
		(property "Reference" "PR50"
			(at 3.448812 2.180082 90)
			(unlocked yes)
			(layer "F.SilkS")
			(effects
				(font
					(size 0.7874 0.5842)
					(thickness 0.1524)
				)
				(justify left)
			)
		)
		(property "Value" ""
			(at 0 0 270)
			(layer "F.Fab")
			(effects
				(font
					(size 1.27 1.27)
				)
			)
		)
		(duplicate_pad_numbers_are_jumpers no)
		(fp_line
			(start -0.7874 0.4064)
			(end -0.7874 -0.4064)
			(stroke
				(width 0.1524)
				(type default)
			)
			(layer "F.SilkS")
		)
		(fp_line
			(start 0.7874 0.4064)
			(end -0.7874 0.4064)
			(stroke
				(width 0.1524)
				(type default)
			)
			(layer "F.SilkS")
		)
		(fp_line
			(start -0.7874 -0.4064)
			(end 0.7874 -0.4064)
			(stroke
				(width 0.1524)
				(type default)
			)
			(layer "F.SilkS")
		)
		(fp_line
			(start 0.7874 -0.4064)
			(end 0.7874 0.4064)
			(stroke
				(width 0.1524)
				(type default)
			)
			(layer "F.SilkS")
		)
		(fp_poly
			(pts
				(xy -0.508 0.2794) (xy -0.508 0.2286) (xy -0.635 0.2286) (xy -0.635 -0.254) (xy -0.5334 -0.254)
				(xy -0.5334 -0.2794) (xy 0.5334 -0.2794) (xy 0.5334 -0.254) (xy 0.635 -0.254) (xy 0.635 0.254) (xy 0.5334 0.254)
				(xy 0.5334 0.2794)
			)
			(stroke
				(width 0)
				(type default)
			)
			(fill no)
			(layer "F.CrtYd")
		)
		(pad "1" smd rect
			(at 0.40005 0 270)
			(size 0.4572 0.508)
			(layers "F.Cu" "F.Mask" "F.Paste")
			(net "P1V05_NODE1")
		)
		(pad "2" smd rect
			(at -0.40005 0 270)
			(size 0.4572 0.508)
			(layers "F.Cu" "F.Mask" "F.Paste")
			(net "SVID_CPU_NODE1_PVCCP_CLK")
		)
	)
	(footprint ""
		(layer "F.Cu")
		(at 152.662128 -150.14067 180)
		(property "Reference" "R597"
			(at 1.287272 3.575558 0)
			(unlocked yes)
			(layer "F.SilkS")
			(effects
				(font
					(size 0.635 0.4064)
					(thickness 0.1524)
				)
				(justify left)
			)
		)
		(property "Value" ""
			(at 0 0 180)
			(layer "F.Fab")
			(effects
				(font
					(size 1.27 1.27)
				)
			)
		)
		(duplicate_pad_numbers_are_jumpers no)
		(fp_line
			(start 0.7874 0.4064)
			(end -0.7874 0.4064)
			(stroke
				(width 0.1524)
				(type default)
			)
			(layer "F.SilkS")
		)
		(fp_line
			(start 0.7874 -0.4064)
			(end 0.7874 0.4064)
			(stroke
				(width 0.1524)
				(type default)
			)
			(layer "F.SilkS")
		)
		(fp_line
			(start -0.7874 0.4064)
			(end -0.7874 -0.4064)
			(stroke
				(width 0.1524)
				(type default)
			)
			(layer "F.SilkS")
		)
		(fp_line
			(start -0.7874 -0.4064)
			(end 0.7874 -0.4064)
			(stroke
				(width 0.1524)
				(type default)
			)
			(layer "F.SilkS")
		)
		(fp_poly
			(pts
				(xy -0.508 0.2794) (xy -0.508 0.2286) (xy -0.635 0.2286) (xy -0.635 -0.254) (xy -0.5334 -0.254)
				(xy -0.5334 -0.2794) (xy 0.5334 -0.2794) (xy 0.5334 -0.254) (xy 0.635 -0.254) (xy 0.635 0.254) (xy 0.5334 0.254)
				(xy 0.5334 0.2794)
			)
			(stroke
				(width 0)
				(type default)
			)
			(fill no)
			(layer "F.CrtYd")
		)
		(pad "1" smd rect
			(at 0.40005 0 180)
			(size 0.4572 0.508)
			(layers "F.Cu" "F.Mask" "F.Paste")
			(net "P3V3_NODE1")
		)
		(pad "2" smd rect
			(at -0.40005 0 180)
			(size 0.4572 0.508)
			(layers "F.Cu" "F.Mask" "F.Paste")
			(net "LAN2_DISABLE_N")
		)
	)
	(footprint ""
		(layer "F.Cu")
		(at 181.2036 -188.4172 -90)
		(property "Reference" "R1295"
			(at -1.1176 -0.10287 90)
			(unlocked yes)
			(layer "F.SilkS")
			(effects
				(font
					(size 0.7874 0.5842)
					(thickness 0.1524)
				)
				(justify left)
			)
		)
		(property "Value" ""
			(at 0 0 270)
			(layer "F.Fab")
			(effects
				(font
					(size 1.27 1.27)
				)
			)
		)
		(duplicate_pad_numbers_are_jumpers no)
		(fp_line
			(start -0.7874 0.4064)
			(end -0.7874 -0.4064)
			(stroke
				(width 0.1524)
				(type default)
			)
			(layer "F.SilkS")
		)
		(fp_line
			(start 0.7874 0.4064)
			(end -0.7874 0.4064)
			(stroke
				(width 0.1524)
				(type default)
			)
			(layer "F.SilkS")
		)
		(fp_line
			(start -0.7874 -0.4064)
			(end 0.7874 -0.4064)
			(stroke
				(width 0.1524)
				(type default)
			)
			(layer "F.SilkS")
		)
		(fp_line
			(start 0.7874 -0.4064)
			(end 0.7874 0.4064)
			(stroke
				(width 0.1524)
				(type default)
			)
			(layer "F.SilkS")
		)
		(fp_poly
			(pts
				(xy -0.508 0.2794) (xy -0.508 0.2286) (xy -0.635 0.2286) (xy -0.635 -0.254) (xy -0.5334 -0.254)
				(xy -0.5334 -0.2794) (xy 0.5334 -0.2794) (xy 0.5334 -0.254) (xy 0.635 -0.254) (xy 0.635 0.254) (xy 0.5334 0.254)
				(xy 0.5334 0.2794)
			)
			(stroke
				(width 0)
				(type default)
			)
			(fill no)
			(layer "F.CrtYd")
		)
		(pad "1" smd rect
			(at 0.40005 0 270)
			(size 0.4572 0.508)
			(layers "F.Cu" "F.Mask" "F.Paste")
			(net "POWER_SW1_PWR_CTR_12V")
		)
		(pad "2" smd rect
			(at -0.40005 0 270)
			(size 0.4572 0.508)
			(layers "F.Cu" "F.Mask" "F.Paste")
			(net "POWER_SW1_PWR_CTR_12V_R")
		)
	)
	(footprint ""
		(layer "F.Cu")
		(at 147.929346 -150.244048 90)
		(property "Reference" "R301"
			(at -4.65455 0.006858 90)
			(unlocked yes)
			(layer "F.SilkS")
			(effects
				(font
					(size 0.7874 0.5842)
					(thickness 0.1524)
				)
				(justify left)
			)
		)
		(property "Value" ""
			(at 0 0 90)
			(layer "F.Fab")
			(effects
				(font
					(size 1.27 1.27)
				)
			)
		)
		(duplicate_pad_numbers_are_jumpers no)
		(fp_line
			(start 0.7874 -0.4064)
			(end 0.7874 0.4064)
			(stroke
				(width 0.1524)
				(type default)
			)
			(layer "F.SilkS")
		)
		(fp_line
			(start -0.7874 -0.4064)
			(end 0.7874 -0.4064)
			(stroke
				(width 0.1524)
				(type default)
			)
			(layer "F.SilkS")
		)
		(fp_line
			(start 0.7874 0.4064)
			(end -0.7874 0.4064)
			(stroke
				(width 0.1524)
				(type default)
			)
			(layer "F.SilkS")
		)
		(fp_line
			(start -0.7874 0.4064)
			(end -0.7874 -0.4064)
			(stroke
				(width 0.1524)
				(type default)
			)
			(layer "F.SilkS")
		)
		(fp_poly
			(pts
				(xy -0.508 0.2794) (xy -0.508 0.2286) (xy -0.635 0.2286) (xy -0.635 -0.254) (xy -0.5334 -0.254)
				(xy -0.5334 -0.2794) (xy 0.5334 -0.2794) (xy 0.5334 -0.254) (xy 0.635 -0.254) (xy 0.635 0.254) (xy 0.5334 0.254)
				(xy 0.5334 0.2794)
			)
			(stroke
				(width 0)
				(type default)
			)
			(fill no)
			(layer "F.CrtYd")
		)
		(pad "1" smd rect
			(at 0.40005 0 90)
			(size 0.4572 0.508)
			(layers "F.Cu" "F.Mask" "F.Paste")
			(net "PCIE_SW_EEPROM_CLK")
		)
		(pad "2" smd rect
			(at -0.40005 0 90)
			(size 0.4572 0.508)
			(layers "F.Cu" "F.Mask" "F.Paste")
			(net "P3V3_NODE1")
		)
	)
	(footprint ""
		(layer "F.Cu")
		(at 158.48076 -188.126624 90)
		(property "Reference" "R1219"
			(at 5.519674 -3.661918 90)
			(unlocked yes)
			(layer "F.SilkS")
			(effects
				(font
					(size 0.7874 0.5842)
					(thickness 0.1524)
				)
				(justify left)
			)
		)
		(property "Value" ""
			(at 0 0 90)
			(layer "F.Fab")
			(effects
				(font
					(size 1.27 1.27)
				)
			)
		)
		(duplicate_pad_numbers_are_jumpers no)
		(fp_line
			(start 0.7874 -0.4064)
			(end 0.7874 0.4064)
			(stroke
				(width 0.1524)
				(type default)
			)
			(layer "F.SilkS")
		)
		(fp_line
			(start -0.7874 -0.4064)
			(end 0.7874 -0.4064)
			(stroke
				(width 0.1524)
				(type default)
			)
			(layer "F.SilkS")
		)
		(fp_line
			(start 0.7874 0.4064)
			(end -0.7874 0.4064)
			(stroke
				(width 0.1524)
				(type default)
			)
			(layer "F.SilkS")
		)
		(fp_line
			(start -0.7874 0.4064)
			(end -0.7874 -0.4064)
			(stroke
				(width 0.1524)
				(type default)
			)
			(layer "F.SilkS")
		)
		(fp_poly
			(pts
				(xy -0.508 0.2794) (xy -0.508 0.2286) (xy -0.635 0.2286) (xy -0.635 -0.254) (xy -0.5334 -0.254)
				(xy -0.5334 -0.2794) (xy 0.5334 -0.2794) (xy 0.5334 -0.254) (xy 0.635 -0.254) (xy 0.635 0.254) (xy 0.5334 0.254)
				(xy 0.5334 0.2794)
			)
			(stroke
				(width 0)
				(type default)
			)
			(fill no)
			(layer "F.CrtYd")
		)
		(pad "1" smd rect
			(at 0.40005 0 90)
			(size 0.4572 0.508)
			(layers "F.Cu" "F.Mask" "F.Paste")
			(net "FAN1_TACH_R")
		)
		(pad "2" smd rect
			(at -0.40005 0 90)
			(size 0.4572 0.508)
			(layers "F.Cu" "F.Mask" "F.Paste")
			(net "GND")
		)
	)
	(footprint ""
		(layer "F.Cu")
		(at 182.2196 -188.4172 -90)
		(property "Reference" "R1293"
			(at -1.1176 -0.10287 90)
			(unlocked yes)
			(layer "F.SilkS")
			(effects
				(font
					(size 0.7874 0.5842)
					(thickness 0.1524)
				)
				(justify left)
			)
		)
		(property "Value" ""
			(at 0 0 270)
			(layer "F.Fab")
			(effects
				(font
					(size 1.27 1.27)
				)
			)
		)
		(duplicate_pad_numbers_are_jumpers no)
		(fp_line
			(start -0.7874 0.4064)
			(end -0.7874 -0.4064)
			(stroke
				(width 0.1524)
				(type default)
			)
			(layer "F.SilkS")
		)
		(fp_line
			(start 0.7874 0.4064)
			(end -0.7874 0.4064)
			(stroke
				(width 0.1524)
				(type default)
			)
			(layer "F.SilkS")
		)
		(fp_line
			(start -0.7874 -0.4064)
			(end 0.7874 -0.4064)
			(stroke
				(width 0.1524)
				(type default)
			)
			(layer "F.SilkS")
		)
		(fp_line
			(start 0.7874 -0.4064)
			(end 0.7874 0.4064)
			(stroke
				(width 0.1524)
				(type default)
			)
			(layer "F.SilkS")
		)
		(fp_poly
			(pts
				(xy -0.508 0.2794) (xy -0.508 0.2286) (xy -0.635 0.2286) (xy -0.635 -0.254) (xy -0.5334 -0.254)
				(xy -0.5334 -0.2794) (xy 0.5334 -0.2794) (xy 0.5334 -0.254) (xy 0.635 -0.254) (xy 0.635 0.254) (xy 0.5334 0.254)
				(xy 0.5334 0.2794)
			)
			(stroke
				(width 0)
				(type default)
			)
			(fill no)
			(layer "F.CrtYd")
		)
		(pad "1" smd rect
			(at 0.40005 0 270)
			(size 0.4572 0.508)
			(layers "F.Cu" "F.Mask" "F.Paste")
			(net "POWER_SW1_PWR_CTR_12V")
		)
		(pad "2" smd rect
			(at -0.40005 0 270)
			(size 0.4572 0.508)
			(layers "F.Cu" "F.Mask" "F.Paste")
			(net "POWER_SW1_PWR_CTR_12V_R")
		)
	)
	(footprint ""
		(layer "F.Cu")
		(at 34.800286 -8.56869 90)
		(property "Reference" "PR40"
			(at -1.92659 -9.192514 90)
			(unlocked yes)
			(layer "F.SilkS")
			(effects
				(font
					(size 0.7874 0.5842)
					(thickness 0.1524)
				)
				(justify left)
			)
		)
		(property "Value" ""
			(at 0 0 90)
			(layer "F.Fab")
			(effects
				(font
					(size 1.27 1.27)
				)
			)
		)
		(duplicate_pad_numbers_are_jumpers no)
		(fp_line
			(start 0.7874 -0.4064)
			(end 0.7874 0.4064)
			(stroke
				(width 0.1524)
				(type default)
			)
			(layer "F.SilkS")
		)
		(fp_line
			(start -0.7874 -0.4064)
			(end 0.7874 -0.4064)
			(stroke
				(width 0.1524)
				(type default)
			)
			(layer "F.SilkS")
		)
		(fp_line
			(start 0.7874 0.4064)
			(end -0.7874 0.4064)
			(stroke
				(width 0.1524)
				(type default)
			)
			(layer "F.SilkS")
		)
		(fp_line
			(start -0.7874 0.4064)
			(end -0.7874 -0.4064)
			(stroke
				(width 0.1524)
				(type default)
			)
			(layer "F.SilkS")
		)
		(fp_poly
			(pts
				(xy -0.508 0.2794) (xy -0.508 0.2286) (xy -0.635 0.2286) (xy -0.635 -0.254) (xy -0.5334 -0.254)
				(xy -0.5334 -0.2794) (xy 0.5334 -0.2794) (xy 0.5334 -0.254) (xy 0.635 -0.254) (xy 0.635 0.254) (xy 0.5334 0.254)
				(xy 0.5334 0.2794)
			)
			(stroke
				(width 0)
				(type default)
			)
			(fill no)
			(layer "F.CrtYd")
		)
		(pad "1" smd rect
			(at 0.40005 0 90)
			(size 0.4572 0.508)
			(layers "F.Cu" "F.Mask" "F.Paste")
			(net "PV_VDDR_NODE1_V0")
		)
		(pad "2" smd rect
			(at -0.40005 0 90)
			(size 0.4572 0.508)
			(layers "F.Cu" "F.Mask" "F.Paste")
			(net "PV_VDDR_NODE1_VREF")
		)
	)
	(footprint ""
		(layer "F.Cu")
		(at 83.209384 -93.763338 180)
		(property "Reference" "C109"
			(at -3.768344 -1.4351 0)
			(unlocked yes)
			(layer "F.SilkS")
			(effects
				(font
					(size 0.7874 0.5842)
					(thickness 0.1524)
				)
			)
		)
		(property "Value" ""
			(at 0 0 180)
			(layer "F.Fab")
			(effects
				(font
					(size 1.27 1.27)
				)
			)
		)
		(duplicate_pad_numbers_are_jumpers no)
		(fp_line
			(start 1.2954 0.5842)
			(end -1.2954 0.5842)
			(stroke
				(width 0.1524)
				(type default)
			)
			(layer "F.SilkS")
		)
		(fp_line
			(start 1.2954 -0.5842)
			(end 1.2954 0.5842)
			(stroke
				(width 0.1524)
				(type default)
			)
			(layer "F.SilkS")
		)
		(fp_line
			(start 0 -0.5842)
			(end 0 0.5842)
			(stroke
				(width 0.1524)
				(type default)
			)
			(layer "F.SilkS")
		)
		(fp_line
			(start -1.2954 0.5842)
			(end -1.2954 -0.5842)
			(stroke
				(width 0.1524)
				(type default)
			)
			(layer "F.SilkS")
		)
		(fp_line
			(start -1.2954 -0.5842)
			(end 1.2954 -0.5842)
			(stroke
				(width 0.1524)
				(type default)
			)
			(layer "F.SilkS")
		)
		(fp_poly
			(pts
				(xy 0.8636 -0.4572) (xy 0.8636 -0.3556) (xy 1.143 -0.3556) (xy 1.143 0.3556) (xy 0.8636 0.3556)
				(xy 0.8636 0.4572) (xy -0.8636 0.4572) (xy -0.8636 0.3556) (xy -1.143 0.3556) (xy -1.143 -0.3556)
				(xy -0.8636 -0.3556) (xy -0.8636 -0.4572)
			)
			(stroke
				(width 0)
				(type default)
			)
			(fill no)
			(layer "F.CrtYd")
		)
		(fp_line
			(start 0.884936 0.504952)
			(end -0.884936 0.504952)
			(stroke
				(width 0.1)
				(type default)
			)
			(layer "F.Fab")
		)
		(fp_line
			(start 0.884936 -0.504952)
			(end 0.884936 0.504952)
			(stroke
				(width 0.1)
				(type default)
			)
			(layer "F.Fab")
		)
		(fp_line
			(start -0.884936 0.504952)
			(end -0.884936 -0.504952)
			(stroke
				(width 0.1)
				(type default)
			)
			(layer "F.Fab")
		)
		(fp_line
			(start -0.884936 -0.504952)
			(end 0.884936 -0.504952)
			(stroke
				(width 0.1)
				(type default)
			)
			(layer "F.Fab")
		)
		(pad "1" smd rect
			(at 0.7366 0 270)
			(size 0.7112 0.8128)
			(layers "F.Cu" "F.Mask" "F.Paste")
			(net "P3V3_SUS_NODE1")
		)
		(pad "2" smd rect
			(at -0.7366 0 270)
			(size 0.7112 0.8128)
			(layers "F.Cu" "F.Mask" "F.Paste")
			(net "GND")
		)
	)
	(footprint ""
		(layer "F.Cu")
		(at 87.10676 -188.126624 -90)
		(property "Reference" "R951"
			(at -4.548886 1.93548 90)
			(unlocked yes)
			(layer "F.SilkS")
			(effects
				(font
					(size 0.7874 0.5842)
					(thickness 0.1524)
				)
				(justify left)
			)
		)
		(property "Value" ""
			(at 0 0 270)
			(layer "F.Fab")
			(effects
				(font
					(size 1.27 1.27)
				)
			)
		)
		(duplicate_pad_numbers_are_jumpers no)
		(fp_line
			(start -0.7874 0.4064)
			(end -0.7874 -0.4064)
			(stroke
				(width 0.1524)
				(type default)
			)
			(layer "F.SilkS")
		)
		(fp_line
			(start 0.7874 0.4064)
			(end -0.7874 0.4064)
			(stroke
				(width 0.1524)
				(type default)
			)
			(layer "F.SilkS")
		)
		(fp_line
			(start -0.7874 -0.4064)
			(end 0.7874 -0.4064)
			(stroke
				(width 0.1524)
				(type default)
			)
			(layer "F.SilkS")
		)
		(fp_line
			(start 0.7874 -0.4064)
			(end 0.7874 0.4064)
			(stroke
				(width 0.1524)
				(type default)
			)
			(layer "F.SilkS")
		)
		(fp_poly
			(pts
				(xy -0.508 0.2794) (xy -0.508 0.2286) (xy -0.635 0.2286) (xy -0.635 -0.254) (xy -0.5334 -0.254)
				(xy -0.5334 -0.2794) (xy 0.5334 -0.2794) (xy 0.5334 -0.254) (xy 0.635 -0.254) (xy 0.635 0.254) (xy 0.5334 0.254)
				(xy 0.5334 0.2794)
			)
			(stroke
				(width 0)
				(type default)
			)
			(fill no)
			(layer "F.CrtYd")
		)
		(pad "1" smd rect
			(at 0.40005 0 270)
			(size 0.4572 0.508)
			(layers "F.Cu" "F.Mask" "F.Paste")
			(net "UART_T6_NODE4_RXD")
		)
		(pad "2" smd rect
			(at -0.40005 0 270)
			(size 0.4572 0.508)
			(layers "F.Cu" "F.Mask" "F.Paste")
			(net "UART_T6_NODE4_RXD_R")
		)
	)
	(footprint ""
		(layer "F.Cu")
		(at 15.21206 -112.127284 -90)
		(property "Reference" "PC63"
			(at 7.979156 -0.13208 0)
			(unlocked yes)
			(layer "F.SilkS")
			(effects
				(font
					(size 0.7874 0.5842)
					(thickness 0.1524)
				)
				(justify left)
			)
		)
		(property "Value" ""
			(at 0 0 270)
			(layer "F.Fab")
			(effects
				(font
					(size 1.27 1.27)
				)
			)
		)
		(duplicate_pad_numbers_are_jumpers no)
		(fp_line
			(start -2.249932 4.533392)
			(end -2.249932 -4.533392)
			(stroke
				(width 0.1524)
				(type default)
			)
			(layer "F.SilkS")
		)
		(fp_line
			(start 2.249932 4.533392)
			(end -2.249932 4.533392)
			(stroke
				(width 0.1524)
				(type default)
			)
			(layer "F.SilkS")
		)
		(fp_line
			(start -2.249932 -4.533392)
			(end 2.249932 -4.533392)
			(stroke
				(width 0.1524)
				(type default)
			)
			(layer "F.SilkS")
		)
		(fp_line
			(start 2.249932 -4.533392)
			(end 2.249932 4.533392)
			(stroke
				(width 0.1524)
				(type default)
			)
			(layer "F.SilkS")
		)
		(fp_poly
			(pts
				(xy 2.326132 -4.533392) (xy 2.326132 -5.39242) (xy -2.326132 -5.39242) (xy -2.326132 -4.533392)
			)
			(stroke
				(width 0)
				(type default)
			)
			(fill yes)
			(layer "F.SilkS")
		)
		(fp_poly
			(pts
				(xy -1.4605 4.457192) (xy -1.4605 3.750056) (xy -2.249932 3.750056) (xy -2.249932 -3.750056) (xy -1.4605 -3.750056)
				(xy -1.4605 -4.457192) (xy 1.4605 -4.457192) (xy 1.4605 -3.750056) (xy 2.249932 -3.750056) (xy 2.249932 3.750056)
				(xy 1.4605 3.750056) (xy 1.4605 4.457192)
			)
			(stroke
				(width 0)
				(type default)
			)
			(fill no)
			(layer "F.CrtYd")
		)
		(fp_line
			(start -2.249932 3.750056)
			(end -2.249932 -3.750056)
			(stroke
				(width 0.1)
				(type default)
			)
			(layer "F.Fab")
		)
		(fp_line
			(start 2.249932 3.750056)
			(end -2.249932 3.750056)
			(stroke
				(width 0.1)
				(type default)
			)
			(layer "F.Fab")
		)
		(fp_line
			(start -2.249932 -3.750056)
			(end 2.249932 -3.750056)
			(stroke
				(width 0.1)
				(type default)
			)
			(layer "F.Fab")
		)
		(fp_line
			(start 2.249932 -3.750056)
			(end 2.249932 3.750056)
			(stroke
				(width 0.1)
				(type default)
			)
			(layer "F.Fab")
		)
		(fp_text user "+"
			(at 2.42062 -6.084062 270)
			(unlocked yes)
			(layer "F.SilkS")
			(effects
				(font
					(size 1.27 0.9652)
					(thickness 0.1524)
				)
				(justify left)
			)
		)
		(fp_text user "+"
			(at -0.786384 -6.322314 270)
			(unlocked yes)
			(layer "F.Fab")
			(effects
				(font
					(size 1.905 1.4224)
					(thickness 0.000001)
				)
				(justify left)
			)
		)
		(pad "1" smd rect
			(at 0 -3.199892 180)
			(size 2.413 2.8194)
			(layers "F.Cu" "F.Mask" "F.Paste")
			(net "P1V05_NODE1")
		)
		(pad "2" smd rect
			(at 0 3.199892 180)
			(size 2.413 2.8194)
			(layers "F.Cu" "F.Mask" "F.Paste")
			(net "GND")
		)
	)
	(footprint ""
		(layer "F.Cu")
		(at 142.910052 -134.19455 180)
		(property "Reference" "R1228"
			(at 3.280918 -3.039364 0)
			(unlocked yes)
			(layer "F.SilkS")
			(effects
				(font
					(size 0.7874 0.5842)
					(thickness 0.1524)
				)
				(justify left)
			)
		)
		(property "Value" ""
			(at 0 0 180)
			(layer "F.Fab")
			(effects
				(font
					(size 1.27 1.27)
				)
			)
		)
		(duplicate_pad_numbers_are_jumpers no)
		(fp_line
			(start 0.7874 0.4064)
			(end -0.7874 0.4064)
			(stroke
				(width 0.1524)
				(type default)
			)
			(layer "F.SilkS")
		)
		(fp_line
			(start 0.7874 -0.4064)
			(end 0.7874 0.4064)
			(stroke
				(width 0.1524)
				(type default)
			)
			(layer "F.SilkS")
		)
		(fp_line
			(start -0.7874 0.4064)
			(end -0.7874 -0.4064)
			(stroke
				(width 0.1524)
				(type default)
			)
			(layer "F.SilkS")
		)
		(fp_line
			(start -0.7874 -0.4064)
			(end 0.7874 -0.4064)
			(stroke
				(width 0.1524)
				(type default)
			)
			(layer "F.SilkS")
		)
		(fp_poly
			(pts
				(xy -0.508 0.2794) (xy -0.508 0.2286) (xy -0.635 0.2286) (xy -0.635 -0.254) (xy -0.5334 -0.254)
				(xy -0.5334 -0.2794) (xy 0.5334 -0.2794) (xy 0.5334 -0.254) (xy 0.635 -0.254) (xy 0.635 0.254) (xy 0.5334 0.254)
				(xy 0.5334 0.2794)
			)
			(stroke
				(width 0)
				(type default)
			)
			(fill no)
			(layer "F.CrtYd")
		)
		(pad "1" smd rect
			(at 0.40005 0 180)
			(size 0.4572 0.508)
			(layers "F.Cu" "F.Mask" "F.Paste")
			(net "PCIE_SW_PRSNT1")
		)
		(pad "2" smd rect
			(at -0.40005 0 180)
			(size 0.4572 0.508)
			(layers "F.Cu" "F.Mask" "F.Paste")
			(net "GND")
		)
	)
	(footprint ""
		(layer "F.Cu")
		(at 113.944654 -46.847252)
		(property "Reference" "R619"
			(at -4.284472 0.187706 0)
			(unlocked yes)
			(layer "F.SilkS")
			(effects
				(font
					(size 0.7874 0.5842)
					(thickness 0.1524)
				)
				(justify left)
			)
		)
		(property "Value" ""
			(at 0 0 0)
			(layer "F.Fab")
			(effects
				(font
					(size 1.27 1.27)
				)
			)
		)
		(duplicate_pad_numbers_are_jumpers no)
		(fp_line
			(start -0.7874 -0.4064)
			(end 0.7874 -0.4064)
			(stroke
				(width 0.1524)
				(type default)
			)
			(layer "F.SilkS")
		)
		(fp_line
			(start -0.7874 0.4064)
			(end -0.7874 -0.4064)
			(stroke
				(width 0.1524)
				(type default)
			)
			(layer "F.SilkS")
		)
		(fp_line
			(start 0.7874 -0.4064)
			(end 0.7874 0.4064)
			(stroke
				(width 0.1524)
				(type default)
			)
			(layer "F.SilkS")
		)
		(fp_line
			(start 0.7874 0.4064)
			(end -0.7874 0.4064)
			(stroke
				(width 0.1524)
				(type default)
			)
			(layer "F.SilkS")
		)
		(fp_poly
			(pts
				(xy -0.508 0.2794) (xy -0.508 0.2286) (xy -0.635 0.2286) (xy -0.635 -0.254) (xy -0.5334 -0.254)
				(xy -0.5334 -0.2794) (xy 0.5334 -0.2794) (xy 0.5334 -0.254) (xy 0.635 -0.254) (xy 0.635 0.254) (xy 0.5334 0.254)
				(xy 0.5334 0.2794)
			)
			(stroke
				(width 0)
				(type default)
			)
			(fill no)
			(layer "F.CrtYd")
		)
		(pad "1" smd rect
			(at 0.40005 0)
			(size 0.4572 0.508)
			(layers "F.Cu" "F.Mask" "F.Paste")
			(net "P3V3_NODE1")
		)
		(pad "2" smd rect
			(at -0.40005 0)
			(size 0.4572 0.508)
			(layers "F.Cu" "F.Mask" "F.Paste")
			(net "N21550241")
		)
	)
	(footprint ""
		(layer "F.Cu")
		(at 156.779468 -173.004988 -90)
		(property "Reference" "C913"
			(at 1.112266 -1.232662 90)
			(unlocked yes)
			(layer "F.SilkS")
			(effects
				(font
					(size 0.7874 0.5842)
					(thickness 0.1524)
				)
				(justify left)
			)
		)
		(property "Value" ""
			(at 0 0 270)
			(layer "F.Fab")
			(effects
				(font
					(size 1.27 1.27)
				)
			)
		)
		(duplicate_pad_numbers_are_jumpers no)
		(fp_line
			(start -0.7874 0.4064)
			(end -0.7874 -0.4064)
			(stroke
				(width 0.1524)
				(type default)
			)
			(layer "F.SilkS")
		)
		(fp_line
			(start 0.7874 0.4064)
			(end -0.7874 0.4064)
			(stroke
				(width 0.1524)
				(type default)
			)
			(layer "F.SilkS")
		)
		(fp_line
			(start 0 0.381)
			(end 0 -0.381)
			(stroke
				(width 0.1524)
				(type default)
			)
			(layer "F.SilkS")
		)
		(fp_line
			(start -0.7874 -0.4064)
			(end 0.7874 -0.4064)
			(stroke
				(width 0.1524)
				(type default)
			)
			(layer "F.SilkS")
		)
		(fp_line
			(start 0.7874 -0.4064)
			(end 0.7874 0.4064)
			(stroke
				(width 0.1524)
				(type default)
			)
			(layer "F.SilkS")
		)
		(fp_poly
			(pts
				(xy -0.5334 0.254) (xy -0.635 0.254) (xy -0.635 0.2286) (xy -0.635 -0.254) (xy -0.5334 -0.254) (xy -0.5334 -0.2794)
				(xy 0.5334 -0.2794) (xy 0.5334 -0.254) (xy 0.635 -0.254) (xy 0.635 0.254) (xy 0.5334 0.254) (xy 0.5334 0.2794)
				(xy -0.508 0.2794) (xy -0.5334 0.2794)
			)
			(stroke
				(width 0)
				(type default)
			)
			(fill no)
			(layer "F.CrtYd")
		)
		(pad "1" smd rect
			(at 0.40005 0 270)
			(size 0.4572 0.508)
			(layers "F.Cu" "F.Mask" "F.Paste")
			(net "P3V3_NODE1")
		)
		(pad "2" smd rect
			(at -0.40005 0 270)
			(size 0.4572 0.508)
			(layers "F.Cu" "F.Mask" "F.Paste")
			(net "GND")
		)
	)
	(footprint ""
		(layer "F.Cu")
		(at 59.260486 -118.910862 90)
		(property "Reference" "R341"
			(at -5.140706 0.82804 90)
			(unlocked yes)
			(layer "F.SilkS")
			(effects
				(font
					(size 0.7874 0.5842)
					(thickness 0.1524)
				)
				(justify left)
			)
		)
		(property "Value" ""
			(at 0 0 90)
			(layer "F.Fab")
			(effects
				(font
					(size 1.27 1.27)
				)
			)
		)
		(duplicate_pad_numbers_are_jumpers no)
		(fp_line
			(start 0.7874 -0.4064)
			(end 0.7874 0.4064)
			(stroke
				(width 0.1524)
				(type default)
			)
			(layer "F.SilkS")
		)
		(fp_line
			(start -0.7874 -0.4064)
			(end 0.7874 -0.4064)
			(stroke
				(width 0.1524)
				(type default)
			)
			(layer "F.SilkS")
		)
		(fp_line
			(start 0.7874 0.4064)
			(end -0.7874 0.4064)
			(stroke
				(width 0.1524)
				(type default)
			)
			(layer "F.SilkS")
		)
		(fp_line
			(start -0.7874 0.4064)
			(end -0.7874 -0.4064)
			(stroke
				(width 0.1524)
				(type default)
			)
			(layer "F.SilkS")
		)
		(fp_poly
			(pts
				(xy -0.508 0.2794) (xy -0.508 0.2286) (xy -0.635 0.2286) (xy -0.635 -0.254) (xy -0.5334 -0.254)
				(xy -0.5334 -0.2794) (xy 0.5334 -0.2794) (xy 0.5334 -0.254) (xy 0.635 -0.254) (xy 0.635 0.254) (xy 0.5334 0.254)
				(xy 0.5334 0.2794)
			)
			(stroke
				(width 0)
				(type default)
			)
			(fill no)
			(layer "F.CrtYd")
		)
		(pad "1" smd rect
			(at 0.40005 0 90)
			(size 0.4572 0.508)
			(layers "F.Cu" "F.Mask" "F.Paste")
			(net "P3V3_NODE1")
		)
		(pad "2" smd rect
			(at -0.40005 0 90)
			(size 0.4572 0.508)
			(layers "F.Cu" "F.Mask" "F.Paste")
			(net "BMC_ROMD1")
		)
	)
	(footprint ""
		(layer "F.Cu")
		(at 145.07845 -51.671474 -90)
		(property "Reference" "R629"
			(at -16.205708 -29.039566 90)
			(unlocked yes)
			(layer "F.SilkS")
			(effects
				(font
					(size 0.7874 0.5842)
					(thickness 0.1524)
				)
				(justify left)
			)
		)
		(property "Value" ""
			(at 0 0 270)
			(layer "F.Fab")
			(effects
				(font
					(size 1.27 1.27)
				)
			)
		)
		(duplicate_pad_numbers_are_jumpers no)
		(fp_line
			(start -1.905 0.8636)
			(end -1.905 -0.8636)
			(stroke
				(width 0.1524)
				(type default)
			)
			(layer "F.SilkS")
		)
		(fp_line
			(start 1.905 0.8636)
			(end -1.905 0.8636)
			(stroke
				(width 0.1524)
				(type default)
			)
			(layer "F.SilkS")
		)
		(fp_line
			(start -1.905 -0.8636)
			(end 1.905 -0.8636)
			(stroke
				(width 0.1524)
				(type default)
			)
			(layer "F.SilkS")
		)
		(fp_line
			(start 1.905 -0.8636)
			(end 1.905 0.8636)
			(stroke
				(width 0.1524)
				(type default)
			)
			(layer "F.SilkS")
		)
		(fp_poly
			(pts
				(xy 1.524 0.6858) (xy 1.524 -0.6858) (xy 1.524 -0.7366) (xy -1.524 -0.7366) (xy -1.524 -0.6858)
				(xy -1.524 0.6858) (xy -1.524 0.7366) (xy 1.524 0.7366)
			)
			(stroke
				(width 0)
				(type default)
			)
			(fill no)
			(layer "F.CrtYd")
		)
		(pad "1" smd rect
			(at 0.94996 0 270)
			(size 1.1176 1.3716)
			(layers "F.Cu" "F.Mask" "F.Paste")
			(net "P5V_NODE1")
		)
		(pad "2" smd rect
			(at -0.94996 0 270)
			(size 1.1176 1.3716)
			(layers "F.Cu" "F.Mask" "F.Paste")
			(net "SATA_P7")
		)
	)
	(footprint ""
		(layer "F.Cu")
		(at 51.67376 -185.205624 90)
		(property "Reference" "R833"
			(at 4.006088 0.055372 90)
			(unlocked yes)
			(layer "F.SilkS")
			(effects
				(font
					(size 0.7874 0.5842)
					(thickness 0.1524)
				)
				(justify left)
			)
		)
		(property "Value" ""
			(at 0 0 90)
			(layer "F.Fab")
			(effects
				(font
					(size 1.27 1.27)
				)
			)
		)
		(duplicate_pad_numbers_are_jumpers no)
		(fp_line
			(start 0.7874 -0.4064)
			(end 0.7874 0.4064)
			(stroke
				(width 0.1524)
				(type default)
			)
			(layer "F.SilkS")
		)
		(fp_line
			(start -0.7874 -0.4064)
			(end 0.7874 -0.4064)
			(stroke
				(width 0.1524)
				(type default)
			)
			(layer "F.SilkS")
		)
		(fp_line
			(start 0.7874 0.4064)
			(end -0.7874 0.4064)
			(stroke
				(width 0.1524)
				(type default)
			)
			(layer "F.SilkS")
		)
		(fp_line
			(start -0.7874 0.4064)
			(end -0.7874 -0.4064)
			(stroke
				(width 0.1524)
				(type default)
			)
			(layer "F.SilkS")
		)
		(fp_poly
			(pts
				(xy -0.508 0.2794) (xy -0.508 0.2286) (xy -0.635 0.2286) (xy -0.635 -0.254) (xy -0.5334 -0.254)
				(xy -0.5334 -0.2794) (xy 0.5334 -0.2794) (xy 0.5334 -0.254) (xy 0.635 -0.254) (xy 0.635 0.254) (xy 0.5334 0.254)
				(xy 0.5334 0.2794)
			)
			(stroke
				(width 0)
				(type default)
			)
			(fill no)
			(layer "F.CrtYd")
		)
		(pad "1" smd rect
			(at 0.40005 0 90)
			(size 0.4572 0.508)
			(layers "F.Cu" "F.Mask" "F.Paste")
			(net "PSU2_AC_OK_R")
		)
		(pad "2" smd rect
			(at -0.40005 0 90)
			(size 0.4572 0.508)
			(layers "F.Cu" "F.Mask" "F.Paste")
			(net "PSU2_AC_OK")
		)
	)
	(footprint ""
		(layer "F.Cu")
		(at 73.337166 -96.709992 -90)
		(property "Reference" "R109"
			(at 54.98719 -28.313888 90)
			(unlocked yes)
			(layer "F.SilkS")
			(effects
				(font
					(size 0.7874 0.5842)
					(thickness 0.1524)
				)
				(justify left)
			)
		)
		(property "Value" ""
			(at 0 0 270)
			(layer "F.Fab")
			(effects
				(font
					(size 1.27 1.27)
				)
			)
		)
		(duplicate_pad_numbers_are_jumpers no)
		(fp_line
			(start -0.7874 0.4064)
			(end -0.7874 -0.4064)
			(stroke
				(width 0.1524)
				(type default)
			)
			(layer "F.SilkS")
		)
		(fp_line
			(start 0.7874 0.4064)
			(end -0.7874 0.4064)
			(stroke
				(width 0.1524)
				(type default)
			)
			(layer "F.SilkS")
		)
		(fp_line
			(start -0.7874 -0.4064)
			(end 0.7874 -0.4064)
			(stroke
				(width 0.1524)
				(type default)
			)
			(layer "F.SilkS")
		)
		(fp_line
			(start 0.7874 -0.4064)
			(end 0.7874 0.4064)
			(stroke
				(width 0.1524)
				(type default)
			)
			(layer "F.SilkS")
		)
		(fp_poly
			(pts
				(xy -0.508 0.2794) (xy -0.508 0.2286) (xy -0.635 0.2286) (xy -0.635 -0.254) (xy -0.5334 -0.254)
				(xy -0.5334 -0.2794) (xy 0.5334 -0.2794) (xy 0.5334 -0.254) (xy 0.635 -0.254) (xy 0.635 0.254) (xy 0.5334 0.254)
				(xy 0.5334 0.2794)
			)
			(stroke
				(width 0)
				(type default)
			)
			(fill no)
			(layer "F.CrtYd")
		)
		(pad "1" smd rect
			(at 0.40005 0 270)
			(size 0.4572 0.508)
			(layers "F.Cu" "F.Mask" "F.Paste")
			(net "H_CPU_NODE1_ERR1_R")
		)
		(pad "2" smd rect
			(at -0.40005 0 270)
			(size 0.4572 0.508)
			(layers "F.Cu" "F.Mask" "F.Paste")
			(net "P3V3_NODE1")
		)
	)
	(footprint ""
		(layer "F.Cu")
		(at 52.17414 -163.89985 90)
		(property "Reference" "R539"
			(at -131.03606 -3.360928 90)
			(unlocked yes)
			(layer "F.SilkS")
			(effects
				(font
					(size 0.7874 0.5842)
					(thickness 0.1524)
				)
				(justify left)
			)
		)
		(property "Value" ""
			(at 0 0 90)
			(layer "F.Fab")
			(effects
				(font
					(size 1.27 1.27)
				)
			)
		)
		(duplicate_pad_numbers_are_jumpers no)
		(fp_line
			(start 0.7874 -0.4064)
			(end 0.7874 0.4064)
			(stroke
				(width 0.1524)
				(type default)
			)
			(layer "F.SilkS")
		)
		(fp_line
			(start -0.7874 -0.4064)
			(end 0.7874 -0.4064)
			(stroke
				(width 0.1524)
				(type default)
			)
			(layer "F.SilkS")
		)
		(fp_line
			(start 0.7874 0.4064)
			(end -0.7874 0.4064)
			(stroke
				(width 0.1524)
				(type default)
			)
			(layer "F.SilkS")
		)
		(fp_line
			(start -0.7874 0.4064)
			(end -0.7874 -0.4064)
			(stroke
				(width 0.1524)
				(type default)
			)
			(layer "F.SilkS")
		)
		(fp_poly
			(pts
				(xy -0.508 0.2794) (xy -0.508 0.2286) (xy -0.635 0.2286) (xy -0.635 -0.254) (xy -0.5334 -0.254)
				(xy -0.5334 -0.2794) (xy 0.5334 -0.2794) (xy 0.5334 -0.254) (xy 0.635 -0.254) (xy 0.635 0.254) (xy 0.5334 0.254)
				(xy 0.5334 0.2794)
			)
			(stroke
				(width 0)
				(type default)
			)
			(fill no)
			(layer "F.CrtYd")
		)
		(pad "1" smd rect
			(at 0.40005 0 90)
			(size 0.4572 0.508)
			(layers "F.Cu" "F.Mask" "F.Paste")
			(net "P3V3_NODE1")
		)
		(pad "2" smd rect
			(at -0.40005 0 90)
			(size 0.4572 0.508)
			(layers "F.Cu" "F.Mask" "F.Paste")
			(net "SMB_LAN1_CLK")
		)
	)
	(footprint ""
		(layer "F.Cu")
		(at 155.926028 -176.083722 90)
		(property "Reference" "R1304"
			(at -0.647192 1.858772 90)
			(unlocked yes)
			(layer "F.SilkS")
			(effects
				(font
					(size 0.7874 0.5842)
					(thickness 0.1524)
				)
				(justify left)
			)
		)
		(property "Value" ""
			(at 0 0 90)
			(layer "F.Fab")
			(effects
				(font
					(size 1.27 1.27)
				)
			)
		)
		(duplicate_pad_numbers_are_jumpers no)
		(fp_line
			(start 0.7874 -0.4064)
			(end 0.7874 0.4064)
			(stroke
				(width 0.1524)
				(type default)
			)
			(layer "F.SilkS")
		)
		(fp_line
			(start -0.7874 -0.4064)
			(end 0.7874 -0.4064)
			(stroke
				(width 0.1524)
				(type default)
			)
			(layer "F.SilkS")
		)
		(fp_line
			(start 0.7874 0.4064)
			(end -0.7874 0.4064)
			(stroke
				(width 0.1524)
				(type default)
			)
			(layer "F.SilkS")
		)
		(fp_line
			(start -0.7874 0.4064)
			(end -0.7874 -0.4064)
			(stroke
				(width 0.1524)
				(type default)
			)
			(layer "F.SilkS")
		)
		(fp_poly
			(pts
				(xy -0.508 0.2794) (xy -0.508 0.2286) (xy -0.635 0.2286) (xy -0.635 -0.254) (xy -0.5334 -0.254)
				(xy -0.5334 -0.2794) (xy 0.5334 -0.2794) (xy 0.5334 -0.254) (xy 0.635 -0.254) (xy 0.635 0.254) (xy 0.5334 0.254)
				(xy 0.5334 0.2794)
			)
			(stroke
				(width 0)
				(type default)
			)
			(fill no)
			(layer "F.CrtYd")
		)
		(pad "1" smd rect
			(at 0.40005 0 90)
			(size 0.4572 0.508)
			(layers "F.Cu" "F.Mask" "F.Paste")
			(net "P3V3_NODE1")
		)
		(pad "2" smd rect
			(at -0.40005 0 90)
			(size 0.4572 0.508)
			(layers "F.Cu" "F.Mask" "F.Paste")
			(net "N54365556")
		)
	)
	(footprint ""
		(layer "F.Cu")
		(at 94.451932 -173.290992)
		(property "Reference" "R764"
			(at 86.67369 74.174096 0)
			(unlocked yes)
			(layer "F.SilkS")
			(effects
				(font
					(size 0.7874 0.5842)
					(thickness 0.1524)
				)
				(justify left)
			)
		)
		(property "Value" ""
			(at 0 0 0)
			(layer "F.Fab")
			(effects
				(font
					(size 1.27 1.27)
				)
			)
		)
		(duplicate_pad_numbers_are_jumpers no)
		(fp_line
			(start -0.7874 -0.4064)
			(end 0.7874 -0.4064)
			(stroke
				(width 0.1524)
				(type default)
			)
			(layer "F.SilkS")
		)
		(fp_line
			(start -0.7874 0.4064)
			(end -0.7874 -0.4064)
			(stroke
				(width 0.1524)
				(type default)
			)
			(layer "F.SilkS")
		)
		(fp_line
			(start 0.7874 -0.4064)
			(end 0.7874 0.4064)
			(stroke
				(width 0.1524)
				(type default)
			)
			(layer "F.SilkS")
		)
		(fp_line
			(start 0.7874 0.4064)
			(end -0.7874 0.4064)
			(stroke
				(width 0.1524)
				(type default)
			)
			(layer "F.SilkS")
		)
		(fp_poly
			(pts
				(xy -0.508 0.2794) (xy -0.508 0.2286) (xy -0.635 0.2286) (xy -0.635 -0.254) (xy -0.5334 -0.254)
				(xy -0.5334 -0.2794) (xy 0.5334 -0.2794) (xy 0.5334 -0.254) (xy 0.635 -0.254) (xy 0.635 0.254) (xy 0.5334 0.254)
				(xy 0.5334 0.2794)
			)
			(stroke
				(width 0)
				(type default)
			)
			(fill no)
			(layer "F.CrtYd")
		)
		(pad "1" smd rect
			(at 0.40005 0)
			(size 0.4572 0.508)
			(layers "F.Cu" "F.Mask" "F.Paste")
			(net "I2C_SCL_FANCTRL1_R")
		)
		(pad "2" smd rect
			(at -0.40005 0)
			(size 0.4572 0.508)
			(layers "F.Cu" "F.Mask" "F.Paste")
			(net "I2C_COM3_SCL")
		)
	)
	(footprint ""
		(layer "F.Cu")
		(at 12.6365 -131.590288 180)
		(property "Reference" "PR30"
			(at 4.026662 -0.012446 0)
			(unlocked yes)
			(layer "F.SilkS")
			(effects
				(font
					(size 0.7874 0.5842)
					(thickness 0.1524)
				)
				(justify left)
			)
		)
		(property "Value" ""
			(at 0 0 180)
			(layer "F.Fab")
			(effects
				(font
					(size 1.27 1.27)
				)
			)
		)
		(duplicate_pad_numbers_are_jumpers no)
		(fp_line
			(start 0.7874 0.4064)
			(end -0.7874 0.4064)
			(stroke
				(width 0.1524)
				(type default)
			)
			(layer "F.SilkS")
		)
		(fp_line
			(start 0.7874 -0.4064)
			(end 0.7874 0.4064)
			(stroke
				(width 0.1524)
				(type default)
			)
			(layer "F.SilkS")
		)
		(fp_line
			(start -0.7874 0.4064)
			(end -0.7874 -0.4064)
			(stroke
				(width 0.1524)
				(type default)
			)
			(layer "F.SilkS")
		)
		(fp_line
			(start -0.7874 -0.4064)
			(end 0.7874 -0.4064)
			(stroke
				(width 0.1524)
				(type default)
			)
			(layer "F.SilkS")
		)
		(fp_poly
			(pts
				(xy -0.508 0.2794) (xy -0.508 0.2286) (xy -0.635 0.2286) (xy -0.635 -0.254) (xy -0.5334 -0.254)
				(xy -0.5334 -0.2794) (xy 0.5334 -0.2794) (xy 0.5334 -0.254) (xy 0.635 -0.254) (xy 0.635 0.254) (xy 0.5334 0.254)
				(xy 0.5334 0.2794)
			)
			(stroke
				(width 0)
				(type default)
			)
			(fill no)
			(layer "F.CrtYd")
		)
		(pad "1" smd rect
			(at 0.40005 0 180)
			(size 0.4572 0.508)
			(layers "F.Cu" "F.Mask" "F.Paste")
			(net "P1V05_NODE1")
		)
		(pad "2" smd rect
			(at -0.40005 0 180)
			(size 0.4572 0.508)
			(layers "F.Cu" "F.Mask" "F.Paste")
			(net "VSENSE_P1V05_NODE1_P")
		)
	)
	(footprint ""
		(layer "F.Cu")
		(at 69.242686 -169.87393)
		(property "Reference" "C885"
			(at -2.755646 1.095502 0)
			(unlocked yes)
			(layer "F.SilkS")
			(effects
				(font
					(size 0.7874 0.5842)
					(thickness 0.1524)
				)
			)
		)
		(property "Value" ""
			(at 0 0 0)
			(layer "F.Fab")
			(effects
				(font
					(size 1.27 1.27)
				)
			)
		)
		(duplicate_pad_numbers_are_jumpers no)
		(fp_line
			(start -1.2954 -0.5842)
			(end 1.2954 -0.5842)
			(stroke
				(width 0.1524)
				(type default)
			)
			(layer "F.SilkS")
		)
		(fp_line
			(start -1.2954 0.5842)
			(end -1.2954 -0.5842)
			(stroke
				(width 0.1524)
				(type default)
			)
			(layer "F.SilkS")
		)
		(fp_line
			(start 0 -0.5842)
			(end 0 0.5842)
			(stroke
				(width 0.1524)
				(type default)
			)
			(layer "F.SilkS")
		)
		(fp_line
			(start 1.2954 -0.5842)
			(end 1.2954 0.5842)
			(stroke
				(width 0.1524)
				(type default)
			)
			(layer "F.SilkS")
		)
		(fp_line
			(start 1.2954 0.5842)
			(end -1.2954 0.5842)
			(stroke
				(width 0.1524)
				(type default)
			)
			(layer "F.SilkS")
		)
		(fp_poly
			(pts
				(xy 0.8636 -0.4572) (xy 0.8636 -0.3556) (xy 1.143 -0.3556) (xy 1.143 0.3556) (xy 0.8636 0.3556)
				(xy 0.8636 0.4572) (xy -0.8636 0.4572) (xy -0.8636 0.3556) (xy -1.143 0.3556) (xy -1.143 -0.3556)
				(xy -0.8636 -0.3556) (xy -0.8636 -0.4572)
			)
			(stroke
				(width 0)
				(type default)
			)
			(fill no)
			(layer "F.CrtYd")
		)
		(fp_line
			(start -0.884936 -0.504952)
			(end 0.884936 -0.504952)
			(stroke
				(width 0.1)
				(type default)
			)
			(layer "F.Fab")
		)
		(fp_line
			(start -0.884936 0.504952)
			(end -0.884936 -0.504952)
			(stroke
				(width 0.1)
				(type default)
			)
			(layer "F.Fab")
		)
		(fp_line
			(start 0.884936 -0.504952)
			(end 0.884936 0.504952)
			(stroke
				(width 0.1)
				(type default)
			)
			(layer "F.Fab")
		)
		(fp_line
			(start 0.884936 0.504952)
			(end -0.884936 0.504952)
			(stroke
				(width 0.1)
				(type default)
			)
			(layer "F.Fab")
		)
		(pad "1" smd rect
			(at 0.7366 0 90)
			(size 0.7112 0.8128)
			(layers "F.Cu" "F.Mask" "F.Paste")
			(net "P3V3_NODE1")
		)
		(pad "2" smd rect
			(at -0.7366 0 90)
			(size 0.7112 0.8128)
			(layers "F.Cu" "F.Mask" "F.Paste")
			(net "GND")
		)
	)
	(footprint ""
		(layer "F.Cu")
		(at 86.744048 -128.998726 -90)
		(property "Reference" "R1255"
			(at 5.940044 4.769104 90)
			(unlocked yes)
			(layer "F.SilkS")
			(effects
				(font
					(size 0.7874 0.5842)
					(thickness 0.1524)
				)
				(justify left)
			)
		)
		(property "Value" ""
			(at 0 0 270)
			(layer "F.Fab")
			(effects
				(font
					(size 1.27 1.27)
				)
			)
		)
		(duplicate_pad_numbers_are_jumpers no)
		(fp_line
			(start -0.7874 0.4064)
			(end -0.7874 -0.4064)
			(stroke
				(width 0.1524)
				(type default)
			)
			(layer "F.SilkS")
		)
		(fp_line
			(start 0.7874 0.4064)
			(end -0.7874 0.4064)
			(stroke
				(width 0.1524)
				(type default)
			)
			(layer "F.SilkS")
		)
		(fp_line
			(start -0.7874 -0.4064)
			(end 0.7874 -0.4064)
			(stroke
				(width 0.1524)
				(type default)
			)
			(layer "F.SilkS")
		)
		(fp_line
			(start 0.7874 -0.4064)
			(end 0.7874 0.4064)
			(stroke
				(width 0.1524)
				(type default)
			)
			(layer "F.SilkS")
		)
		(fp_poly
			(pts
				(xy -0.508 0.2794) (xy -0.508 0.2286) (xy -0.635 0.2286) (xy -0.635 -0.254) (xy -0.5334 -0.254)
				(xy -0.5334 -0.2794) (xy 0.5334 -0.2794) (xy 0.5334 -0.254) (xy 0.635 -0.254) (xy 0.635 0.254) (xy 0.5334 0.254)
				(xy 0.5334 0.2794)
			)
			(stroke
				(width 0)
				(type default)
			)
			(fill no)
			(layer "F.CrtYd")
		)
		(pad "1" smd rect
			(at 0.40005 0 270)
			(size 0.4572 0.508)
			(layers "F.Cu" "F.Mask" "F.Paste")
			(net "PORT80_LOUT3")
		)
		(pad "2" smd rect
			(at -0.40005 0 270)
			(size 0.4572 0.508)
			(layers "F.Cu" "F.Mask" "F.Paste")
			(net "N53313501")
		)
	)
	(footprint ""
		(layer "F.Cu")
		(at 6.862572 -3.711194 -90)
		(property "Reference" "C179"
			(at 1.545844 2.645664 90)
			(unlocked yes)
			(layer "F.SilkS")
			(effects
				(font
					(size 0.7874 0.5842)
					(thickness 0.1524)
				)
				(justify left)
			)
		)
		(property "Value" ""
			(at 0 0 270)
			(layer "F.Fab")
			(effects
				(font
					(size 1.27 1.27)
				)
			)
		)
		(duplicate_pad_numbers_are_jumpers no)
		(fp_line
			(start -0.7874 0.4064)
			(end -0.7874 -0.4064)
			(stroke
				(width 0.1524)
				(type default)
			)
			(layer "F.SilkS")
		)
		(fp_line
			(start 0.7874 0.4064)
			(end -0.7874 0.4064)
			(stroke
				(width 0.1524)
				(type default)
			)
			(layer "F.SilkS")
		)
		(fp_line
			(start 0 0.381)
			(end 0 -0.381)
			(stroke
				(width 0.1524)
				(type default)
			)
			(layer "F.SilkS")
		)
		(fp_line
			(start -0.7874 -0.4064)
			(end 0.7874 -0.4064)
			(stroke
				(width 0.1524)
				(type default)
			)
			(layer "F.SilkS")
		)
		(fp_line
			(start 0.7874 -0.4064)
			(end 0.7874 0.4064)
			(stroke
				(width 0.1524)
				(type default)
			)
			(layer "F.SilkS")
		)
		(fp_poly
			(pts
				(xy -0.5334 0.254) (xy -0.635 0.254) (xy -0.635 0.2286) (xy -0.635 -0.254) (xy -0.5334 -0.254) (xy -0.5334 -0.2794)
				(xy 0.5334 -0.2794) (xy 0.5334 -0.254) (xy 0.635 -0.254) (xy 0.635 0.254) (xy 0.5334 0.254) (xy 0.5334 0.2794)
				(xy -0.508 0.2794) (xy -0.5334 0.2794)
			)
			(stroke
				(width 0)
				(type default)
			)
			(fill no)
			(layer "F.CrtYd")
		)
		(pad "1" smd rect
			(at 0.40005 0 270)
			(size 0.4572 0.508)
			(layers "F.Cu" "F.Mask" "F.Paste")
			(net "P3V3_STB_NODE1")
		)
		(pad "2" smd rect
			(at -0.40005 0 270)
			(size 0.4572 0.508)
			(layers "F.Cu" "F.Mask" "F.Paste")
			(net "GND")
		)
	)
	(footprint ""
		(layer "F.Cu")
		(at 103.828342 -151.711152 180)
		(property "Reference" "PC35"
			(at 1.052576 -3.409696 90)
			(unlocked yes)
			(layer "F.SilkS")
			(effects
				(font
					(size 0.7874 0.5842)
					(thickness 0.1524)
				)
				(justify left)
			)
		)
		(property "Value" ""
			(at 0 0 180)
			(layer "F.Fab")
			(effects
				(font
					(size 1.27 1.27)
				)
			)
		)
		(duplicate_pad_numbers_are_jumpers no)
		(fp_line
			(start 0.7874 0.4064)
			(end -0.7874 0.4064)
			(stroke
				(width 0.1524)
				(type default)
			)
			(layer "F.SilkS")
		)
		(fp_line
			(start 0.7874 -0.4064)
			(end 0.7874 0.4064)
			(stroke
				(width 0.1524)
				(type default)
			)
			(layer "F.SilkS")
		)
		(fp_line
			(start 0 0.381)
			(end 0 -0.381)
			(stroke
				(width 0.1524)
				(type default)
			)
			(layer "F.SilkS")
		)
		(fp_line
			(start -0.7874 0.4064)
			(end -0.7874 -0.4064)
			(stroke
				(width 0.1524)
				(type default)
			)
			(layer "F.SilkS")
		)
		(fp_line
			(start -0.7874 -0.4064)
			(end 0.7874 -0.4064)
			(stroke
				(width 0.1524)
				(type default)
			)
			(layer "F.SilkS")
		)
		(fp_poly
			(pts
				(xy -0.5334 0.254) (xy -0.635 0.254) (xy -0.635 0.2286) (xy -0.635 -0.254) (xy -0.5334 -0.254) (xy -0.5334 -0.2794)
				(xy 0.5334 -0.2794) (xy 0.5334 -0.254) (xy 0.635 -0.254) (xy 0.635 0.254) (xy 0.5334 0.254) (xy 0.5334 0.2794)
				(xy -0.508 0.2794) (xy -0.5334 0.2794)
			)
			(stroke
				(width 0)
				(type default)
			)
			(fill no)
			(layer "F.CrtYd")
		)
		(pad "1" smd rect
			(at 0.40005 0 180)
			(size 0.4572 0.508)
			(layers "F.Cu" "F.Mask" "F.Paste")
			(net "P5V_STB_NODE1")
		)
		(pad "2" smd rect
			(at -0.40005 0 180)
			(size 0.4572 0.508)
			(layers "F.Cu" "F.Mask" "F.Paste")
			(net "GND")
		)
	)
	(footprint ""
		(layer "F.Cu")
		(at 66.194686 -121.044462 -90)
		(property "Reference" "R346"
			(at 6.142736 -7.938516 90)
			(unlocked yes)
			(layer "F.SilkS")
			(effects
				(font
					(size 0.7874 0.5842)
					(thickness 0.1524)
				)
				(justify left)
			)
		)
		(property "Value" ""
			(at 0 0 270)
			(layer "F.Fab")
			(effects
				(font
					(size 1.27 1.27)
				)
			)
		)
		(duplicate_pad_numbers_are_jumpers no)
		(fp_line
			(start -0.7874 0.4064)
			(end -0.7874 -0.4064)
			(stroke
				(width 0.1524)
				(type default)
			)
			(layer "F.SilkS")
		)
		(fp_line
			(start 0.7874 0.4064)
			(end -0.7874 0.4064)
			(stroke
				(width 0.1524)
				(type default)
			)
			(layer "F.SilkS")
		)
		(fp_line
			(start -0.7874 -0.4064)
			(end 0.7874 -0.4064)
			(stroke
				(width 0.1524)
				(type default)
			)
			(layer "F.SilkS")
		)
		(fp_line
			(start 0.7874 -0.4064)
			(end 0.7874 0.4064)
			(stroke
				(width 0.1524)
				(type default)
			)
			(layer "F.SilkS")
		)
		(fp_poly
			(pts
				(xy -0.508 0.2794) (xy -0.508 0.2286) (xy -0.635 0.2286) (xy -0.635 -0.254) (xy -0.5334 -0.254)
				(xy -0.5334 -0.2794) (xy 0.5334 -0.2794) (xy 0.5334 -0.254) (xy 0.635 -0.254) (xy 0.635 0.254) (xy 0.5334 0.254)
				(xy 0.5334 0.2794)
			)
			(stroke
				(width 0)
				(type default)
			)
			(fill no)
			(layer "F.CrtYd")
		)
		(pad "1" smd rect
			(at 0.40005 0 270)
			(size 0.4572 0.508)
			(layers "F.Cu" "F.Mask" "F.Paste")
			(net "P3V3_NODE1")
		)
		(pad "2" smd rect
			(at -0.40005 0 270)
			(size 0.4572 0.508)
			(layers "F.Cu" "F.Mask" "F.Paste")
			(net "PU_I2C_BMC_SCL")
		)
	)
	(footprint ""
		(layer "F.Cu")
		(at 82.927952 -139.751562 180)
		(property "Reference" "U122"
			(at -3.44932 -0.056134 90)
			(unlocked yes)
			(layer "F.SilkS")
			(effects
				(font
					(size 0.7874 0.5842)
					(thickness 0.1524)
				)
				(justify left)
			)
		)
		(property "Value" ""
			(at 0 0 180)
			(layer "F.Fab")
			(effects
				(font
					(size 1.27 1.27)
				)
			)
		)
		(duplicate_pad_numbers_are_jumpers no)
		(fp_line
			(start 0.525018 3.075178)
			(end 0.525018 2.489962)
			(stroke
				(width 0.1524)
				(type default)
			)
			(layer "F.SilkS")
		)
		(fp_line
			(start 0.525018 3.075178)
			(end 0.525018 0.025146)
			(stroke
				(width 0.1524)
				(type default)
			)
			(layer "F.SilkS")
		)
		(fp_line
			(start 0.525018 0.686562)
			(end 0.525018 0.025146)
			(stroke
				(width 0.1524)
				(type default)
			)
			(layer "F.SilkS")
		)
		(fp_line
			(start 0.525018 0.025146)
			(end 0.320802 0.025146)
			(stroke
				(width 0.1524)
				(type default)
			)
			(layer "F.SilkS")
		)
		(fp_line
			(start 0.320802 3.075178)
			(end 0.525018 3.075178)
			(stroke
				(width 0.1524)
				(type default)
			)
			(layer "F.SilkS")
		)
		(fp_line
			(start -2.320798 0.025146)
			(end -2.525014 0.025146)
			(stroke
				(width 0.1524)
				(type default)
			)
			(layer "F.SilkS")
		)
		(fp_line
			(start -2.525014 3.075178)
			(end -2.320798 3.075178)
			(stroke
				(width 0.1524)
				(type default)
			)
			(layer "F.SilkS")
		)
		(fp_line
			(start -2.525014 3.075178)
			(end -2.525014 0.025146)
			(stroke
				(width 0.1524)
				(type default)
			)
			(layer "F.SilkS")
		)
		(fp_line
			(start -2.525014 2.540762)
			(end -2.525014 3.075178)
			(stroke
				(width 0.1524)
				(type default)
			)
			(layer "F.SilkS")
		)
		(fp_line
			(start -2.525014 0.025146)
			(end -2.525014 0.661162)
			(stroke
				(width 0.1524)
				(type default)
			)
			(layer "F.SilkS")
		)
		(fp_poly
			(pts
				(xy 0 -0.519938) (xy 0.299974 -1.420114) (xy -0.299974 -1.420114)
			)
			(stroke
				(width 0)
				(type default)
			)
			(fill yes)
			(layer "F.SilkS")
		)
		(fp_poly
			(pts
				(xy 0.525018 0.025146) (xy 0.244602 0.025146) (xy 0.244602 -0.532638) (xy -2.244598 -0.532638) (xy -2.244598 0.025146)
				(xy -2.525014 0.025146) (xy -2.525014 3.075178) (xy -2.244598 3.075178) (xy -2.244598 3.632962)
				(xy 0.244602 3.632962) (xy 0.244602 3.075178) (xy 0.525018 3.075178)
			)
			(stroke
				(width 0)
				(type default)
			)
			(fill no)
			(layer "F.CrtYd")
		)
		(fp_line
			(start 0.525018 3.075178)
			(end -2.525014 3.075178)
			(stroke
				(width 0.1)
				(type default)
			)
			(layer "F.Fab")
		)
		(fp_line
			(start 0.525018 0.025146)
			(end 0.525018 3.075178)
			(stroke
				(width 0.1)
				(type default)
			)
			(layer "F.Fab")
		)
		(fp_line
			(start -2.525014 3.075178)
			(end -2.525014 0.025146)
			(stroke
				(width 0.1)
				(type default)
			)
			(layer "F.Fab")
		)
		(fp_line
			(start -2.525014 0.025146)
			(end 0.525018 0.025146)
			(stroke
				(width 0.1)
				(type default)
			)
			(layer "F.Fab")
		)
		(fp_poly
			(pts
				(xy 0 -0.519938) (xy 0.302514 -1.427734) (xy -0.302514 -1.427734)
			)
			(stroke
				(width 0)
				(type default)
			)
			(fill yes)
			(layer "F.Fab")
		)
		(fp_text user "10"
			(at 0.729234 4.007612 0)
			(unlocked yes)
			(layer "F.SilkS")
			(effects
				(font
					(size 0.635 0.4064)
					(thickness 0.1524)
				)
				(justify left)
			)
		)
		(fp_text user "1"
			(at -0.482346 -0.944118 0)
			(unlocked yes)
			(layer "F.SilkS")
			(effects
				(font
					(size 0.635 0.4064)
					(thickness 0.1524)
				)
				(justify left)
			)
		)
		(fp_text user "5"
			(at -2.255774 -0.562102 0)
			(unlocked yes)
			(layer "F.SilkS")
			(effects
				(font
					(size 0.635 0.4064)
					(thickness 0.1524)
				)
				(justify left)
			)
		)
		(fp_text user "6"
			(at -2.274062 3.62077 0)
			(unlocked yes)
			(layer "F.SilkS")
			(effects
				(font
					(size 0.635 0.4064)
					(thickness 0.1524)
				)
				(justify left)
			)
		)
		(fp_text user "10"
			(at 1.565402 3.700272 0)
			(unlocked yes)
			(layer "F.Fab")
			(effects
				(font
					(size 0.7874 0.5842)
					(thickness 0.000001)
				)
				(justify left)
			)
		)
		(fp_text user "1"
			(at 0.790702 -0.695706 0)
			(unlocked yes)
			(layer "F.Fab")
			(effects
				(font
					(size 0.7874 0.5842)
					(thickness 0.000001)
				)
				(justify left)
			)
		)
		(fp_text user "6"
			(at -2.155698 3.725672 0)
			(unlocked yes)
			(layer "F.Fab")
			(effects
				(font
					(size 0.7874 0.5842)
					(thickness 0.000001)
				)
				(justify left)
			)
		)
		(fp_text user "5"
			(at -2.155698 -0.695706 0)
			(unlocked yes)
			(layer "F.Fab")
			(effects
				(font
					(size 0.7874 0.5842)
					(thickness 0.000001)
				)
				(justify left)
			)
		)
		(pad "1" smd rect
			(at 0 0)
			(size 0.2794 0.9144)
			(layers "F.Cu" "F.Mask" "F.Paste")
			(net "P1V26_BMC_NODE1")
		)
		(pad "2" smd rect
			(at -0.499872 0)
			(size 0.2794 0.9144)
			(layers "F.Cu" "F.Mask" "F.Paste")
			(net "P1V26_BMC_NODE1")
		)
		(pad "3" smd rect
			(at -0.999998 0)
			(size 0.2794 0.9144)
			(layers "F.Cu" "F.Mask" "F.Paste")
			(net "P1V26_BMC_NODE1")
		)
		(pad "4" smd rect
			(at -1.500124 0)
			(size 0.2794 0.9144)
			(layers "F.Cu" "F.Mask" "F.Paste")
			(net "P1V26_BMC_NODE1_ADJ")
		)
		(pad "5" smd rect
			(at -1.999996 0 180)
			(size 0.2794 0.9144)
			(layers "F.Cu" "F.Mask" "F.Paste")
			(net "PWRGD_NODE1_P1V26_BMC_PG")
		)
		(pad "6" smd rect
			(at -1.999996 3.100324 180)
			(size 0.2794 0.9144)
			(layers "F.Cu" "F.Mask" "F.Paste")
			(net "FM_CPLD_NODE1_P1V26_BMC_EN")
		)
		(pad "7" smd rect
			(at -1.500124 3.100324)
			(size 0.2794 0.9144)
			(layers "F.Cu" "F.Mask" "F.Paste")
			(net "P1V8_NODE1")
		)
		(pad "8" smd rect
			(at -0.999998 3.100324)
			(size 0.2794 0.9144)
			(layers "F.Cu" "F.Mask" "F.Paste")
			(net "P1V8_NODE1")
		)
		(pad "9" smd rect
			(at -0.499872 3.100324)
			(size 0.2794 0.9144)
			(layers "F.Cu" "F.Mask" "F.Paste")
			(net "P1V8_NODE1")
		)
		(pad "10" smd rect
			(at 0 3.100324)
			(size 0.2794 0.9144)
			(layers "F.Cu" "F.Mask" "F.Paste")
			(net "P5V_STB_NODE1")
		)
		(pad "TH" smd rect
			(at -0.999998 1.550162 90)
			(size 1.7526 2.667)
			(layers "F.Cu" "F.Mask" "F.Paste")
			(net "GND")
		)
		(zone
			(layer "F.Cu")
			(hatch none 0.5)
			(connect_pads
				(clearance 0)
			)
			(min_thickness 0.25)
			(keepout
				(tracks allowed)
				(vias not_allowed)
				(pads allowed)
				(copperpour not_allowed)
				(footprints allowed)
			)
			(placement
				(enabled no)
				(sheetname "")
			)
			(fill
				(thermal_gap 0.5)
				(thermal_bridge_width 0.5)
				(island_removal_mode 0)
			)
			(polygon
				(pts
					(xy 82.394552 -140.284962) (xy 85.442552 -140.284962) (xy 85.442552 -142.316962) (xy 82.394552 -142.316962)
					(xy 82.394552 -140.386562) (xy 82.521552 -140.386562) (xy 82.521552 -142.240762) (xy 85.340952 -142.240762)
					(xy 85.340952 -140.361162) (xy 82.394552 -140.361162)
				)
			)
		)
	)
	(footprint ""
		(layer "F.Cu")
		(at 42.252646 -112.033558 180)
		(property "Reference" "PC21"
			(at 1.472692 4.605782 0)
			(unlocked yes)
			(layer "F.SilkS")
			(effects
				(font
					(size 0.7874 0.5842)
					(thickness 0.1524)
				)
				(justify left)
			)
		)
		(property "Value" ""
			(at 0 0 180)
			(layer "F.Fab")
			(effects
				(font
					(size 1.27 1.27)
				)
			)
		)
		(duplicate_pad_numbers_are_jumpers no)
		(fp_line
			(start 0.7874 0.4064)
			(end -0.7874 0.4064)
			(stroke
				(width 0.1524)
				(type default)
			)
			(layer "F.SilkS")
		)
		(fp_line
			(start 0.7874 -0.4064)
			(end 0.7874 0.4064)
			(stroke
				(width 0.1524)
				(type default)
			)
			(layer "F.SilkS")
		)
		(fp_line
			(start 0 0.381)
			(end 0 -0.381)
			(stroke
				(width 0.1524)
				(type default)
			)
			(layer "F.SilkS")
		)
		(fp_line
			(start -0.7874 0.4064)
			(end -0.7874 -0.4064)
			(stroke
				(width 0.1524)
				(type default)
			)
			(layer "F.SilkS")
		)
		(fp_line
			(start -0.7874 -0.4064)
			(end 0.7874 -0.4064)
			(stroke
				(width 0.1524)
				(type default)
			)
			(layer "F.SilkS")
		)
		(fp_poly
			(pts
				(xy -0.5334 0.254) (xy -0.635 0.254) (xy -0.635 0.2286) (xy -0.635 -0.254) (xy -0.5334 -0.254) (xy -0.5334 -0.2794)
				(xy 0.5334 -0.2794) (xy 0.5334 -0.254) (xy 0.635 -0.254) (xy 0.635 0.254) (xy 0.5334 0.254) (xy 0.5334 0.2794)
				(xy -0.508 0.2794) (xy -0.5334 0.2794)
			)
			(stroke
				(width 0)
				(type default)
			)
			(fill no)
			(layer "F.CrtYd")
		)
		(pad "1" smd rect
			(at 0.40005 0 180)
			(size 0.4572 0.508)
			(layers "F.Cu" "F.Mask" "F.Paste")
			(net "P3V3_STB_NODE1_FB")
		)
		(pad "2" smd rect
			(at -0.40005 0 180)
			(size 0.4572 0.508)
			(layers "F.Cu" "F.Mask" "F.Paste")
			(net "P3V3_STB_NODE1")
		)
	)
	(footprint ""
		(layer "F.Cu")
		(at 129.74447 -112.04575)
		(property "Reference" "R4"
			(at -2.464054 0.117602 0)
			(unlocked yes)
			(layer "F.SilkS")
			(effects
				(font
					(size 0.7874 0.5842)
					(thickness 0.1524)
				)
				(justify left)
			)
		)
		(property "Value" ""
			(at 0 0 0)
			(layer "F.Fab")
			(effects
				(font
					(size 1.27 1.27)
				)
			)
		)
		(duplicate_pad_numbers_are_jumpers no)
		(fp_line
			(start -0.7874 -0.4064)
			(end 0.7874 -0.4064)
			(stroke
				(width 0.1524)
				(type default)
			)
			(layer "F.SilkS")
		)
		(fp_line
			(start -0.7874 0.4064)
			(end -0.7874 -0.4064)
			(stroke
				(width 0.1524)
				(type default)
			)
			(layer "F.SilkS")
		)
		(fp_line
			(start 0.7874 -0.4064)
			(end 0.7874 0.4064)
			(stroke
				(width 0.1524)
				(type default)
			)
			(layer "F.SilkS")
		)
		(fp_line
			(start 0.7874 0.4064)
			(end -0.7874 0.4064)
			(stroke
				(width 0.1524)
				(type default)
			)
			(layer "F.SilkS")
		)
		(fp_poly
			(pts
				(xy -0.508 0.2794) (xy -0.508 0.2286) (xy -0.635 0.2286) (xy -0.635 -0.254) (xy -0.5334 -0.254)
				(xy -0.5334 -0.2794) (xy 0.5334 -0.2794) (xy 0.5334 -0.254) (xy 0.635 -0.254) (xy 0.635 0.254) (xy 0.5334 0.254)
				(xy 0.5334 0.2794)
			)
			(stroke
				(width 0)
				(type default)
			)
			(fill no)
			(layer "F.CrtYd")
		)
		(pad "1" smd rect
			(at 0.40005 0)
			(size 0.4572 0.508)
			(layers "F.Cu" "F.Mask" "F.Paste")
			(net "XTAL_CLK_NODE1_X1")
		)
		(pad "2" smd rect
			(at -0.40005 0)
			(size 0.4572 0.508)
			(layers "F.Cu" "F.Mask" "F.Paste")
			(net "XTAL_CLK_NODE1_X2")
		)
	)
	(footprint ""
		(layer "F.Cu")
		(at 176.90465 -56.227472 180)
		(property "Reference" "C561"
			(at 3.75666 2.155698 0)
			(unlocked yes)
			(layer "F.SilkS")
			(effects
				(font
					(size 0.7874 0.5842)
					(thickness 0.1524)
				)
				(justify left)
			)
		)
		(property "Value" ""
			(at 0 0 180)
			(layer "F.Fab")
			(effects
				(font
					(size 1.27 1.27)
				)
			)
		)
		(duplicate_pad_numbers_are_jumpers no)
		(fp_line
			(start 0.7874 0.4064)
			(end -0.7874 0.4064)
			(stroke
				(width 0.1524)
				(type default)
			)
			(layer "F.SilkS")
		)
		(fp_line
			(start 0.7874 -0.4064)
			(end 0.7874 0.4064)
			(stroke
				(width 0.1524)
				(type default)
			)
			(layer "F.SilkS")
		)
		(fp_line
			(start 0 0.381)
			(end 0 -0.381)
			(stroke
				(width 0.1524)
				(type default)
			)
			(layer "F.SilkS")
		)
		(fp_line
			(start -0.7874 0.4064)
			(end -0.7874 -0.4064)
			(stroke
				(width 0.1524)
				(type default)
			)
			(layer "F.SilkS")
		)
		(fp_line
			(start -0.7874 -0.4064)
			(end 0.7874 -0.4064)
			(stroke
				(width 0.1524)
				(type default)
			)
			(layer "F.SilkS")
		)
		(fp_poly
			(pts
				(xy -0.5334 0.254) (xy -0.635 0.254) (xy -0.635 0.2286) (xy -0.635 -0.254) (xy -0.5334 -0.254) (xy -0.5334 -0.2794)
				(xy 0.5334 -0.2794) (xy 0.5334 -0.254) (xy 0.635 -0.254) (xy 0.635 0.254) (xy 0.5334 0.254) (xy 0.5334 0.2794)
				(xy -0.508 0.2794) (xy -0.5334 0.2794)
			)
			(stroke
				(width 0)
				(type default)
			)
			(fill no)
			(layer "F.CrtYd")
		)
		(pad "1" smd rect
			(at 0.40005 0 180)
			(size 0.4572 0.508)
			(layers "F.Cu" "F.Mask" "F.Paste")
			(net "USBPWR_P1")
		)
		(pad "2" smd rect
			(at -0.40005 0 180)
			(size 0.4572 0.508)
			(layers "F.Cu" "F.Mask" "F.Paste")
			(net "GND")
		)
	)
	(footprint ""
		(layer "F.Cu")
		(at 149.508972 -32.570928 180)
		(property "Reference" "R649"
			(at 1.179576 3.705352 0)
			(unlocked yes)
			(layer "F.SilkS")
			(effects
				(font
					(size 0.7874 0.5842)
					(thickness 0.1524)
				)
				(justify left)
			)
		)
		(property "Value" ""
			(at 0 0 180)
			(layer "F.Fab")
			(effects
				(font
					(size 1.27 1.27)
				)
			)
		)
		(duplicate_pad_numbers_are_jumpers no)
		(fp_line
			(start 0.7874 0.4064)
			(end -0.7874 0.4064)
			(stroke
				(width 0.1524)
				(type default)
			)
			(layer "F.SilkS")
		)
		(fp_line
			(start 0.7874 -0.4064)
			(end 0.7874 0.4064)
			(stroke
				(width 0.1524)
				(type default)
			)
			(layer "F.SilkS")
		)
		(fp_line
			(start -0.7874 0.4064)
			(end -0.7874 -0.4064)
			(stroke
				(width 0.1524)
				(type default)
			)
			(layer "F.SilkS")
		)
		(fp_line
			(start -0.7874 -0.4064)
			(end 0.7874 -0.4064)
			(stroke
				(width 0.1524)
				(type default)
			)
			(layer "F.SilkS")
		)
		(fp_poly
			(pts
				(xy -0.508 0.2794) (xy -0.508 0.2286) (xy -0.635 0.2286) (xy -0.635 -0.254) (xy -0.5334 -0.254)
				(xy -0.5334 -0.2794) (xy 0.5334 -0.2794) (xy 0.5334 -0.254) (xy 0.635 -0.254) (xy 0.635 0.254) (xy 0.5334 0.254)
				(xy 0.5334 0.2794)
			)
			(stroke
				(width 0)
				(type default)
			)
			(fill no)
			(layer "F.CrtYd")
		)
		(pad "1" smd rect
			(at 0.40005 0 180)
			(size 0.4572 0.508)
			(layers "F.Cu" "F.Mask" "F.Paste")
			(net "P3V3_NODE1")
		)
		(pad "2" smd rect
			(at -0.40005 0 180)
			(size 0.4572 0.508)
			(layers "F.Cu" "F.Mask" "F.Paste")
			(net "N21624804")
		)
	)
	(footprint ""
		(layer "F.Cu")
		(at 55.10276 -185.205624 -90)
		(property "Reference" "R820"
			(at -4.006088 0.048514 90)
			(unlocked yes)
			(layer "F.SilkS")
			(effects
				(font
					(size 0.7874 0.5842)
					(thickness 0.1524)
				)
				(justify left)
			)
		)
		(property "Value" ""
			(at 0 0 270)
			(layer "F.Fab")
			(effects
				(font
					(size 1.27 1.27)
				)
			)
		)
		(duplicate_pad_numbers_are_jumpers no)
		(fp_line
			(start -0.7874 0.4064)
			(end -0.7874 -0.4064)
			(stroke
				(width 0.1524)
				(type default)
			)
			(layer "F.SilkS")
		)
		(fp_line
			(start 0.7874 0.4064)
			(end -0.7874 0.4064)
			(stroke
				(width 0.1524)
				(type default)
			)
			(layer "F.SilkS")
		)
		(fp_line
			(start -0.7874 -0.4064)
			(end 0.7874 -0.4064)
			(stroke
				(width 0.1524)
				(type default)
			)
			(layer "F.SilkS")
		)
		(fp_line
			(start 0.7874 -0.4064)
			(end 0.7874 0.4064)
			(stroke
				(width 0.1524)
				(type default)
			)
			(layer "F.SilkS")
		)
		(fp_poly
			(pts
				(xy -0.508 0.2794) (xy -0.508 0.2286) (xy -0.635 0.2286) (xy -0.635 -0.254) (xy -0.5334 -0.254)
				(xy -0.5334 -0.2794) (xy 0.5334 -0.2794) (xy 0.5334 -0.254) (xy 0.635 -0.254) (xy 0.635 0.254) (xy 0.5334 0.254)
				(xy 0.5334 0.2794)
			)
			(stroke
				(width 0)
				(type default)
			)
			(fill no)
			(layer "F.CrtYd")
		)
		(pad "1" smd rect
			(at 0.40005 0 270)
			(size 0.4572 0.508)
			(layers "F.Cu" "F.Mask" "F.Paste")
			(net "I2C_PSU1_SCL")
		)
		(pad "2" smd rect
			(at -0.40005 0 270)
			(size 0.4572 0.508)
			(layers "F.Cu" "F.Mask" "F.Paste")
			(net "I2C_PSU1_R_SCL")
		)
	)
	(footprint ""
		(layer "F.Cu")
		(at 36.354004 -75.37069 180)
		(property "Reference" "L9"
			(at 5.272786 0.501396 0)
			(unlocked yes)
			(layer "F.SilkS")
			(effects
				(font
					(size 0.7874 0.5842)
					(thickness 0.1524)
				)
				(justify left)
			)
		)
		(property "Value" ""
			(at 0 0 180)
			(layer "F.Fab")
			(effects
				(font
					(size 1.27 1.27)
				)
			)
		)
		(duplicate_pad_numbers_are_jumpers no)
		(fp_line
			(start 0.7874 0.4064)
			(end -0.7874 0.4064)
			(stroke
				(width 0.1524)
				(type default)
			)
			(layer "F.SilkS")
		)
		(fp_line
			(start 0.7874 -0.4064)
			(end 0.7874 0.4064)
			(stroke
				(width 0.1524)
				(type default)
			)
			(layer "F.SilkS")
		)
		(fp_line
			(start 0.0889 0.4064)
			(end 0.0889 -0.4064)
			(stroke
				(width 0.1524)
				(type default)
			)
			(layer "F.SilkS")
		)
		(fp_line
			(start -0.0889 0.4064)
			(end -0.0889 -0.4064)
			(stroke
				(width 0.1524)
				(type default)
			)
			(layer "F.SilkS")
		)
		(fp_line
			(start -0.7874 0.4064)
			(end -0.7874 -0.4064)
			(stroke
				(width 0.1524)
				(type default)
			)
			(layer "F.SilkS")
		)
		(fp_line
			(start -0.7874 -0.4064)
			(end 0.7874 -0.4064)
			(stroke
				(width 0.1524)
				(type default)
			)
			(layer "F.SilkS")
		)
		(fp_poly
			(pts
				(xy -0.5334 0.254) (xy -0.635 0.254) (xy -0.635 0.2286) (xy -0.635 -0.254) (xy -0.5334 -0.254) (xy -0.5334 -0.2794)
				(xy 0.5334 -0.2794) (xy 0.5334 -0.254) (xy 0.635 -0.254) (xy 0.635 0.254) (xy 0.5334 0.254) (xy 0.5334 0.2794)
				(xy -0.508 0.2794) (xy -0.5334 0.2794)
			)
			(stroke
				(width 0)
				(type default)
			)
			(fill no)
			(layer "F.CrtYd")
		)
		(pad "1" smd rect
			(at 0.40005 0 180)
			(size 0.4572 0.508)
			(layers "F.Cu" "F.Mask" "F.Paste")
			(net "P1V8_NODE1")
		)
		(pad "2" smd rect
			(at -0.40005 0 180)
			(size 0.4572 0.508)
			(layers "F.Cu" "F.Mask" "F.Paste")
			(net "P1V8_VCCASFRHPLL_NODE1")
		)
	)
	(footprint ""
		(layer "F.Cu")
		(at 75.938888 -154.194256 -90)
		(property "Reference" "PC4"
			(at -1.663192 0.101346 90)
			(unlocked yes)
			(layer "F.SilkS")
			(effects
				(font
					(size 0.7874 0.5842)
					(thickness 0.1524)
				)
				(justify left)
			)
		)
		(property "Value" ""
			(at 0 0 270)
			(layer "F.Fab")
			(effects
				(font
					(size 1.27 1.27)
				)
			)
		)
		(duplicate_pad_numbers_are_jumpers no)
		(fp_line
			(start -0.7874 0.4064)
			(end -0.7874 -0.4064)
			(stroke
				(width 0.1524)
				(type default)
			)
			(layer "F.SilkS")
		)
		(fp_line
			(start 0.7874 0.4064)
			(end -0.7874 0.4064)
			(stroke
				(width 0.1524)
				(type default)
			)
			(layer "F.SilkS")
		)
		(fp_line
			(start 0 0.381)
			(end 0 -0.381)
			(stroke
				(width 0.1524)
				(type default)
			)
			(layer "F.SilkS")
		)
		(fp_line
			(start -0.7874 -0.4064)
			(end 0.7874 -0.4064)
			(stroke
				(width 0.1524)
				(type default)
			)
			(layer "F.SilkS")
		)
		(fp_line
			(start 0.7874 -0.4064)
			(end 0.7874 0.4064)
			(stroke
				(width 0.1524)
				(type default)
			)
			(layer "F.SilkS")
		)
		(fp_poly
			(pts
				(xy -0.5334 0.254) (xy -0.635 0.254) (xy -0.635 0.2286) (xy -0.635 -0.254) (xy -0.5334 -0.254) (xy -0.5334 -0.2794)
				(xy 0.5334 -0.2794) (xy 0.5334 -0.254) (xy 0.635 -0.254) (xy 0.635 0.254) (xy 0.5334 0.254) (xy 0.5334 0.2794)
				(xy -0.508 0.2794) (xy -0.5334 0.2794)
			)
			(stroke
				(width 0)
				(type default)
			)
			(fill no)
			(layer "F.CrtYd")
		)
		(pad "1" smd rect
			(at 0.40005 0 270)
			(size 0.4572 0.508)
			(layers "F.Cu" "F.Mask" "F.Paste")
			(net "SW_P5V_STB_NODE1_BT")
		)
		(pad "2" smd rect
			(at -0.40005 0 270)
			(size 0.4572 0.508)
			(layers "F.Cu" "F.Mask" "F.Paste")
			(net "SW_P5V_STB_NODE1_PH")
		)
	)
	(footprint ""
		(layer "F.Cu")
		(at 107.925616 -151.017732 -90)
		(property "Reference" "R1130"
			(at 2.599944 1.310386 90)
			(unlocked yes)
			(layer "F.SilkS")
			(effects
				(font
					(size 0.635 0.4064)
					(thickness 0.1524)
				)
				(justify left)
			)
		)
		(property "Value" ""
			(at 0 0 270)
			(layer "F.Fab")
			(effects
				(font
					(size 1.27 1.27)
				)
			)
		)
		(duplicate_pad_numbers_are_jumpers no)
		(fp_line
			(start -1.905 0.8636)
			(end -1.905 -0.8636)
			(stroke
				(width 0.1524)
				(type default)
			)
			(layer "F.SilkS")
		)
		(fp_line
			(start 1.905 0.8636)
			(end -1.905 0.8636)
			(stroke
				(width 0.1524)
				(type default)
			)
			(layer "F.SilkS")
		)
		(fp_line
			(start -1.905 -0.8636)
			(end 1.905 -0.8636)
			(stroke
				(width 0.1524)
				(type default)
			)
			(layer "F.SilkS")
		)
		(fp_line
			(start 1.905 -0.8636)
			(end 1.905 0.8636)
			(stroke
				(width 0.1524)
				(type default)
			)
			(layer "F.SilkS")
		)
		(fp_poly
			(pts
				(xy 1.524 0.6858) (xy 1.524 -0.6858) (xy 1.524 -0.7366) (xy -1.524 -0.7366) (xy -1.524 -0.6858)
				(xy -1.524 0.6858) (xy -1.524 0.7366) (xy 1.524 0.7366)
			)
			(stroke
				(width 0)
				(type default)
			)
			(fill no)
			(layer "F.CrtYd")
		)
		(pad "1" smd rect
			(at 0.94996 0 270)
			(size 1.1176 1.3716)
			(layers "F.Cu" "F.Mask" "F.Paste")
			(net "P12V_AUX")
		)
		(pad "2" smd rect
			(at -0.94996 0 270)
			(size 1.1176 1.3716)
			(layers "F.Cu" "F.Mask" "F.Paste")
			(net "N52411159")
		)
	)
	(footprint ""
		(layer "F.Cu")
		(at 12.213082 -23.12416 180)
		(property "Reference" "U52"
			(at 5.611368 -0.876046 90)
			(unlocked yes)
			(layer "F.SilkS")
			(effects
				(font
					(size 0.7874 0.5842)
					(thickness 0.1524)
				)
				(justify left)
			)
		)
		(property "Value" ""
			(at 0 0 180)
			(layer "F.Fab")
			(effects
				(font
					(size 1.27 1.27)
				)
			)
		)
		(duplicate_pad_numbers_are_jumpers no)
		(fp_line
			(start 4.9022 2.0066)
			(end -4.9022 2.0066)
			(stroke
				(width 0.1524)
				(type default)
			)
			(layer "F.SilkS")
		)
		(fp_line
			(start 4.9022 -2.0066)
			(end 4.9022 2.0066)
			(stroke
				(width 0.1524)
				(type default)
			)
			(layer "F.SilkS")
		)
		(fp_line
			(start -4.318 0)
			(end -4.9022 -0.5842)
			(stroke
				(width 0.1524)
				(type default)
			)
			(layer "F.SilkS")
		)
		(fp_line
			(start -4.9022 2.0066)
			(end -4.9022 0.5842)
			(stroke
				(width 0.1524)
				(type default)
			)
			(layer "F.SilkS")
		)
		(fp_line
			(start -4.9022 0.5842)
			(end -4.318 0)
			(stroke
				(width 0.1524)
				(type default)
			)
			(layer "F.SilkS")
		)
		(fp_line
			(start -4.9022 -0.5842)
			(end -4.9022 -2.0066)
			(stroke
				(width 0.1524)
				(type default)
			)
			(layer "F.SilkS")
		)
		(fp_line
			(start -4.9022 -2.0066)
			(end 4.9022 -2.0066)
			(stroke
				(width 0.1524)
				(type default)
			)
			(layer "F.SilkS")
		)
		(fp_circle
			(center -4.318 1.524)
			(end -4.572 1.524)
			(stroke
				(width 0.1524)
				(type default)
			)
			(fill no)
			(layer "F.SilkS")
		)
		(fp_rect
			(start -4.9022 3.6703)
			(end 4.9022 -3.6703)
			(stroke
				(width 0)
				(type default)
			)
			(fill no)
			(layer "F.CrtYd")
		)
		(pad "1" smd rect
			(at -4.225036 2.921 180)
			(size 0.3556 1.4986)
			(layers "F.Cu" "F.Mask" "F.Paste")
			(net "N54251527")
		)
		(pad "2" smd rect
			(at -3.57505 2.921 180)
			(size 0.3556 1.4986)
			(layers "F.Cu" "F.Mask" "F.Paste")
			(net "N54251529")
		)
		(pad "3" smd rect
			(at -2.925064 2.921 180)
			(size 0.3556 1.4986)
			(layers "F.Cu" "F.Mask" "F.Paste")
			(net "N54251541")
		)
		(pad "4" smd rect
			(at -2.275078 2.921 180)
			(size 0.3556 1.4986)
			(layers "F.Cu" "F.Mask" "F.Paste")
			(net "UART_RX_P2_L")
		)
		(pad "5" smd rect
			(at -1.625092 2.921 180)
			(size 0.3556 1.4986)
			(layers "F.Cu" "F.Mask" "F.Paste")
			(net "UART_DSR_P2_L_N")
		)
		(pad "6" smd rect
			(at -0.975106 2.921 180)
			(size 0.3556 1.4986)
			(layers "F.Cu" "F.Mask" "F.Paste")
			(net "UART_CTS_P2_L_N")
		)
		(pad "7" smd rect
			(at -0.32512 2.921 180)
			(size 0.3556 1.4986)
			(layers "F.Cu" "F.Mask" "F.Paste")
			(net "N54251449")
		)
		(pad "8" smd rect
			(at 0.32512 2.921 180)
			(size 0.3556 1.4986)
			(layers "F.Cu" "F.Mask" "F.Paste")
			(net "N54251449")
		)
		(pad "9" smd rect
			(at 0.975106 2.921 180)
			(size 0.3556 1.4986)
			(layers "F.Cu" "F.Mask" "F.Paste")
			(net "UART_RTS_P2_L_N")
		)
		(pad "10" smd rect
			(at 1.625092 2.921 180)
			(size 0.3556 1.4986)
			(layers "F.Cu" "F.Mask" "F.Paste")
			(net "UART_TX_P2_L")
		)
		(pad "11" smd rect
			(at 2.275078 2.921 180)
			(size 0.3556 1.4986)
			(layers "F.Cu" "F.Mask" "F.Paste")
			(net "UART_DTR_P2_L_N")
		)
		(pad "12" smd rect
			(at 2.925064 2.921 180)
			(size 0.3556 1.4986)
			(layers "F.Cu" "F.Mask" "F.Paste")
			(net "UART_DTR_P2_N")
		)
		(pad "13" smd rect
			(at 3.57505 2.921 180)
			(size 0.3556 1.4986)
			(layers "F.Cu" "F.Mask" "F.Paste")
			(net "UART_TX_P2")
		)
		(pad "14" smd rect
			(at 4.225036 2.921 180)
			(size 0.3556 1.4986)
			(layers "F.Cu" "F.Mask" "F.Paste")
			(net "UART_RTS_P2_N")
		)
		(pad "15" smd rect
			(at 4.225036 -2.921 180)
			(size 0.3556 1.4986)
			(layers "F.Cu" "F.Mask" "F.Paste")
			(net "Net_501")
		)
		(pad "16" smd rect
			(at 3.57505 -2.921 180)
			(size 0.3556 1.4986)
			(layers "F.Cu" "F.Mask" "F.Paste")
			(net "Net_502")
		)
		(pad "17" smd rect
			(at 2.925064 -2.921 180)
			(size 0.3556 1.4986)
			(layers "F.Cu" "F.Mask" "F.Paste")
			(net "UART_CTS_P2_N")
		)
		(pad "18" smd rect
			(at 2.275078 -2.921 180)
			(size 0.3556 1.4986)
			(layers "F.Cu" "F.Mask" "F.Paste")
			(net "UART_DSR_P2_N")
		)
		(pad "19" smd rect
			(at 1.625092 -2.921 180)
			(size 0.3556 1.4986)
			(layers "F.Cu" "F.Mask" "F.Paste")
			(net "UART_RX_P2")
		)
		(pad "20" smd rect
			(at 0.975106 -2.921 180)
			(size 0.3556 1.4986)
			(layers "F.Cu" "F.Mask" "F.Paste")
			(net "Net_2258")
		)
		(pad "21" smd rect
			(at 0.32512 -2.921 180)
			(size 0.3556 1.4986)
			(layers "F.Cu" "F.Mask" "F.Paste")
			(net "Net_2259")
		)
		(pad "22" smd rect
			(at -0.32512 -2.921 180)
			(size 0.3556 1.4986)
			(layers "F.Cu" "F.Mask" "F.Paste")
			(net "N54251489")
		)
		(pad "23" smd rect
			(at -0.975106 -2.921 180)
			(size 0.3556 1.4986)
			(layers "F.Cu" "F.Mask" "F.Paste")
			(net "N54251487")
		)
		(pad "24" smd rect
			(at -1.625092 -2.921 180)
			(size 0.3556 1.4986)
			(layers "F.Cu" "F.Mask" "F.Paste")
			(net "N54251519")
		)
		(pad "25" smd rect
			(at -2.275078 -2.921 180)
			(size 0.3556 1.4986)
			(layers "F.Cu" "F.Mask" "F.Paste")
			(net "GND")
		)
		(pad "26" smd rect
			(at -2.925064 -2.921 180)
			(size 0.3556 1.4986)
			(layers "F.Cu" "F.Mask" "F.Paste")
			(net "P3V3_NODE1")
		)
		(pad "27" smd rect
			(at -3.57505 -2.921 180)
			(size 0.3556 1.4986)
			(layers "F.Cu" "F.Mask" "F.Paste")
			(net "N54251539")
		)
		(pad "28" smd rect
			(at -4.225036 -2.921 180)
			(size 0.3556 1.4986)
			(layers "F.Cu" "F.Mask" "F.Paste")
			(net "N54251517")
		)
	)
	(footprint ""
		(layer "F.Cu")
		(at 117.33276 -188.126624 90)
		(property "Reference" "C751"
			(at 4.839208 0.193802 90)
			(unlocked yes)
			(layer "F.SilkS")
			(effects
				(font
					(size 0.7874 0.5842)
					(thickness 0.1524)
				)
				(justify left)
			)
		)
		(property "Value" ""
			(at 0 0 90)
			(layer "F.Fab")
			(effects
				(font
					(size 1.27 1.27)
				)
			)
		)
		(duplicate_pad_numbers_are_jumpers no)
		(fp_line
			(start 0.7874 -0.4064)
			(end 0.7874 0.4064)
			(stroke
				(width 0.1524)
				(type default)
			)
			(layer "F.SilkS")
		)
		(fp_line
			(start -0.7874 -0.4064)
			(end 0.7874 -0.4064)
			(stroke
				(width 0.1524)
				(type default)
			)
			(layer "F.SilkS")
		)
		(fp_line
			(start 0 0.381)
			(end 0 -0.381)
			(stroke
				(width 0.1524)
				(type default)
			)
			(layer "F.SilkS")
		)
		(fp_line
			(start 0.7874 0.4064)
			(end -0.7874 0.4064)
			(stroke
				(width 0.1524)
				(type default)
			)
			(layer "F.SilkS")
		)
		(fp_line
			(start -0.7874 0.4064)
			(end -0.7874 -0.4064)
			(stroke
				(width 0.1524)
				(type default)
			)
			(layer "F.SilkS")
		)
		(fp_poly
			(pts
				(xy -0.5334 0.254) (xy -0.635 0.254) (xy -0.635 0.2286) (xy -0.635 -0.254) (xy -0.5334 -0.254) (xy -0.5334 -0.2794)
				(xy 0.5334 -0.2794) (xy 0.5334 -0.254) (xy 0.635 -0.254) (xy 0.635 0.254) (xy 0.5334 0.254) (xy 0.5334 0.2794)
				(xy -0.508 0.2794) (xy -0.5334 0.2794)
			)
			(stroke
				(width 0)
				(type default)
			)
			(fill no)
			(layer "F.CrtYd")
		)
		(pad "1" smd rect
			(at 0.40005 0 90)
			(size 0.4572 0.508)
			(layers "F.Cu" "F.Mask" "F.Paste")
			(net "UART_T8_NODE2_TXD_R")
		)
		(pad "2" smd rect
			(at -0.40005 0 90)
			(size 0.4572 0.508)
			(layers "F.Cu" "F.Mask" "F.Paste")
			(net "GND")
		)
	)
	(footprint ""
		(layer "F.Cu")
		(at 45.130974 -123.21667 90)
		(property "Reference" "U16"
			(at -0.094742 3.428746 0)
			(unlocked yes)
			(layer "F.SilkS")
			(effects
				(font
					(size 0.7874 0.5842)
					(thickness 0.1524)
				)
			)
		)
		(property "Value" ""
			(at 0 0 90)
			(layer "F.Fab")
			(effects
				(font
					(size 1.27 1.27)
				)
			)
		)
		(duplicate_pad_numbers_are_jumpers no)
		(fp_line
			(start 1.1176 -1.7018)
			(end 1.1176 1.7018)
			(stroke
				(width 0.1524)
				(type default)
			)
			(layer "F.SilkS")
		)
		(fp_line
			(start -1.1176 -1.7018)
			(end 1.1176 -1.7018)
			(stroke
				(width 0.1524)
				(type default)
			)
			(layer "F.SilkS")
		)
		(fp_line
			(start -1.1176 -1.7018)
			(end -1.1176 -0.254)
			(stroke
				(width 0.1524)
				(type default)
			)
			(layer "F.SilkS")
		)
		(fp_line
			(start -1.1176 -0.254)
			(end -0.7112 0)
			(stroke
				(width 0.1524)
				(type default)
			)
			(layer "F.SilkS")
		)
		(fp_line
			(start -0.7112 0)
			(end -1.1176 0.254)
			(stroke
				(width 0.1524)
				(type default)
			)
			(layer "F.SilkS")
		)
		(fp_line
			(start -1.1176 0.254)
			(end -1.1176 1.7018)
			(stroke
				(width 0.1524)
				(type default)
			)
			(layer "F.SilkS")
		)
		(fp_line
			(start 1.1176 1.7018)
			(end -1.1176 1.7018)
			(stroke
				(width 0.1524)
				(type default)
			)
			(layer "F.SilkS")
		)
		(fp_poly
			(pts
				(xy -0.675386 1.8161) (xy -0.446786 2.4003) (xy -0.878586 2.4003)
			)
			(stroke
				(width 0)
				(type default)
			)
			(fill yes)
			(layer "F.SilkS")
		)
		(fp_rect
			(start -1.1176 1.5494)
			(end 1.1176 -1.5494)
			(stroke
				(width 0)
				(type default)
			)
			(fill no)
			(layer "F.CrtYd")
		)
		(fp_line
			(start 1.1176 -1.5494)
			(end 1.1176 1.5494)
			(stroke
				(width 0.1)
				(type default)
			)
			(layer "F.Fab")
		)
		(fp_line
			(start -1.1176 -1.5494)
			(end 1.1176 -1.5494)
			(stroke
				(width 0.1)
				(type default)
			)
			(layer "F.Fab")
		)
		(fp_line
			(start -1.1176 -1.5494)
			(end -1.1176 -0.254)
			(stroke
				(width 0.1)
				(type default)
			)
			(layer "F.Fab")
		)
		(fp_line
			(start -1.1176 -0.254)
			(end -1.1176 0.254)
			(stroke
				(width 0.1)
				(type default)
			)
			(layer "F.Fab")
		)
		(fp_line
			(start -1.1176 0.254)
			(end -1.1176 1.5494)
			(stroke
				(width 0.1)
				(type default)
			)
			(layer "F.Fab")
		)
		(fp_line
			(start 1.1176 1.5494)
			(end -1.1176 1.5494)
			(stroke
				(width 0.1)
				(type default)
			)
			(layer "F.Fab")
		)
		(fp_poly
			(pts
				(xy -0.675386 1.8161) (xy -0.446786 2.4003) (xy -0.878586 2.4003)
			)
			(stroke
				(width 0)
				(type default)
			)
			(fill yes)
			(layer "F.Fab")
		)
		(pad "1" smd rect
			(at -0.649986 0.962406 90)
			(size 0.3302 1.1684)
			(layers "F.Cu" "F.Mask" "F.Paste")
			(net "Net_1785")
		)
		(pad "2" smd rect
			(at 0 0.962406 90)
			(size 0.3302 1.1684)
			(layers "F.Cu" "F.Mask" "F.Paste")
			(net "FM_BMC_NODE1_RESET_L")
		)
		(pad "3" smd rect
			(at 0.649986 0.962406 90)
			(size 0.3302 1.1684)
			(layers "F.Cu" "F.Mask" "F.Paste")
			(net "GND")
		)
		(pad "4" smd rect
			(at 0.649986 -0.962406 90)
			(size 0.3302 1.1684)
			(layers "F.Cu" "F.Mask" "F.Paste")
			(net "BMC_NODE1_DDR_RST_L")
		)
		(pad "5" smd rect
			(at -0.649986 -0.962406 90)
			(size 0.3302 1.1684)
			(layers "F.Cu" "F.Mask" "F.Paste")
			(net "P3V3_NODE1")
		)
	)
	(footprint ""
		(layer "F.Cu")
		(at 184.7342 -173.4058 180)
		(property "Reference" "R1073"
			(at -9.9568 -17.42567 0)
			(unlocked yes)
			(layer "F.SilkS")
			(effects
				(font
					(size 0.7874 0.5842)
					(thickness 0.1524)
				)
				(justify left)
			)
		)
		(property "Value" ""
			(at 0 0 180)
			(layer "F.Fab")
			(effects
				(font
					(size 1.27 1.27)
				)
			)
		)
		(duplicate_pad_numbers_are_jumpers no)
		(fp_line
			(start 0.7874 0.4064)
			(end -0.7874 0.4064)
			(stroke
				(width 0.1524)
				(type default)
			)
			(layer "F.SilkS")
		)
		(fp_line
			(start 0.7874 -0.4064)
			(end 0.7874 0.4064)
			(stroke
				(width 0.1524)
				(type default)
			)
			(layer "F.SilkS")
		)
		(fp_line
			(start -0.7874 0.4064)
			(end -0.7874 -0.4064)
			(stroke
				(width 0.1524)
				(type default)
			)
			(layer "F.SilkS")
		)
		(fp_line
			(start -0.7874 -0.4064)
			(end 0.7874 -0.4064)
			(stroke
				(width 0.1524)
				(type default)
			)
			(layer "F.SilkS")
		)
		(fp_poly
			(pts
				(xy -0.508 0.2794) (xy -0.508 0.2286) (xy -0.635 0.2286) (xy -0.635 -0.254) (xy -0.5334 -0.254)
				(xy -0.5334 -0.2794) (xy 0.5334 -0.2794) (xy 0.5334 -0.254) (xy 0.635 -0.254) (xy 0.635 0.254) (xy 0.5334 0.254)
				(xy 0.5334 0.2794)
			)
			(stroke
				(width 0)
				(type default)
			)
			(fill no)
			(layer "F.CrtYd")
		)
		(pad "1" smd rect
			(at 0.40005 0 180)
			(size 0.4572 0.508)
			(layers "F.Cu" "F.Mask" "F.Paste")
			(net "POWER_SW2_PWR_CTR_12V")
		)
		(pad "2" smd rect
			(at -0.40005 0 180)
			(size 0.4572 0.508)
			(layers "F.Cu" "F.Mask" "F.Paste")
			(net "POWER_SW2_PWR_CTR_12V_R")
		)
	)
	(footprint ""
		(layer "F.Cu")
		(at 25.973278 -44.100496 -90)
		(property "Reference" "R632"
			(at 4.987036 -0.546608 90)
			(unlocked yes)
			(layer "F.SilkS")
			(effects
				(font
					(size 0.7874 0.5842)
					(thickness 0.1524)
				)
				(justify left)
			)
		)
		(property "Value" ""
			(at 0 0 270)
			(layer "F.Fab")
			(effects
				(font
					(size 1.27 1.27)
				)
			)
		)
		(duplicate_pad_numbers_are_jumpers no)
		(fp_line
			(start -0.7874 0.4064)
			(end -0.7874 -0.4064)
			(stroke
				(width 0.1524)
				(type default)
			)
			(layer "F.SilkS")
		)
		(fp_line
			(start 0.7874 0.4064)
			(end -0.7874 0.4064)
			(stroke
				(width 0.1524)
				(type default)
			)
			(layer "F.SilkS")
		)
		(fp_line
			(start -0.7874 -0.4064)
			(end 0.7874 -0.4064)
			(stroke
				(width 0.1524)
				(type default)
			)
			(layer "F.SilkS")
		)
		(fp_line
			(start 0.7874 -0.4064)
			(end 0.7874 0.4064)
			(stroke
				(width 0.1524)
				(type default)
			)
			(layer "F.SilkS")
		)
		(fp_poly
			(pts
				(xy -0.508 0.2794) (xy -0.508 0.2286) (xy -0.635 0.2286) (xy -0.635 -0.254) (xy -0.5334 -0.254)
				(xy -0.5334 -0.2794) (xy 0.5334 -0.2794) (xy 0.5334 -0.254) (xy 0.635 -0.254) (xy 0.635 0.254) (xy 0.5334 0.254)
				(xy 0.5334 0.2794)
			)
			(stroke
				(width 0)
				(type default)
			)
			(fill no)
			(layer "F.CrtYd")
		)
		(pad "1" smd rect
			(at 0.40005 0 270)
			(size 0.4572 0.508)
			(layers "F.Cu" "F.Mask" "F.Paste")
			(net "P3V3_NODE1")
		)
		(pad "2" smd rect
			(at -0.40005 0 270)
			(size 0.4572 0.508)
			(layers "F.Cu" "F.Mask" "F.Paste")
			(net "SMB_BMC_NODE1_DDC_DAT")
		)
	)
	(footprint ""
		(layer "F.Cu")
		(at 84.45246 -84.690204)
		(property "Reference" "Y2"
			(at 1.400048 17.674082 90)
			(unlocked yes)
			(layer "F.SilkS")
			(effects
				(font
					(size 0.7874 0.5842)
					(thickness 0.1524)
				)
				(justify left)
			)
		)
		(property "Value" ""
			(at 0 0 0)
			(layer "F.Fab")
			(effects
				(font
					(size 1.27 1.27)
				)
			)
		)
		(duplicate_pad_numbers_are_jumpers no)
		(fp_line
			(start -1.042162 -2.200402)
			(end -1.042162 2.200402)
			(stroke
				(width 0.1524)
				(type default)
			)
			(layer "F.SilkS")
		)
		(fp_line
			(start -1.042162 2.200402)
			(end -0.0127 2.200402)
			(stroke
				(width 0.1524)
				(type default)
			)
			(layer "F.SilkS")
		)
		(fp_line
			(start -0.1143 -2.200402)
			(end -1.042162 -2.200402)
			(stroke
				(width 0.1524)
				(type default)
			)
			(layer "F.SilkS")
		)
		(fp_line
			(start -0.1143 -2.200402)
			(end 1.042162 -2.200402)
			(stroke
				(width 0.1524)
				(type default)
			)
			(layer "F.SilkS")
		)
		(fp_line
			(start 1.042162 -2.200402)
			(end 1.042162 2.200402)
			(stroke
				(width 0.1524)
				(type default)
			)
			(layer "F.SilkS")
		)
		(fp_line
			(start 1.042162 2.200402)
			(end -0.0381 2.200402)
			(stroke
				(width 0.1524)
				(type default)
			)
			(layer "F.SilkS")
		)
		(fp_poly
			(pts
				(xy -0.8001 -2.100072) (xy -0.8001 -1.8288) (xy -0.9652 -1.8288) (xy -0.9652 -0.6858) (xy -0.8001 -0.6858)
				(xy -0.8001 0.6858) (xy -0.9652 0.6858) (xy -0.9652 1.8288) (xy -0.8001 1.8288) (xy -0.8001 2.100072)
				(xy 0.8001 2.100072) (xy 0.8001 1.8288) (xy 0.9652 1.8288) (xy 0.9652 0.6858) (xy 0.8001 0.6858)
				(xy 0.8001 -0.6858) (xy 0.9652 -0.6858) (xy 0.9652 -1.8288) (xy 0.8001 -1.8288) (xy 0.8001 -2.100072)
			)
			(stroke
				(width 0)
				(type default)
			)
			(fill no)
			(layer "F.CrtYd")
		)
		(fp_line
			(start -0.8001 -2.100072)
			(end -0.8001 2.100072)
			(stroke
				(width 0.1)
				(type default)
			)
			(layer "F.Fab")
		)
		(fp_line
			(start -0.8001 2.100072)
			(end 0.8001 2.100072)
			(stroke
				(width 0.1)
				(type default)
			)
			(layer "F.Fab")
		)
		(fp_line
			(start 0.8001 -2.100072)
			(end -0.8001 -2.100072)
			(stroke
				(width 0.1)
				(type default)
			)
			(layer "F.Fab")
		)
		(fp_line
			(start 0.8001 2.100072)
			(end 0.8001 -2.100072)
			(stroke
				(width 0.1)
				(type default)
			)
			(layer "F.Fab")
		)
		(pad "1" smd rect
			(at 0 -1.249934 270)
			(size 1.016 1.8034)
			(layers "F.Cu" "F.Mask" "F.Paste")
			(net "XTAL_CPU_NODE1_X2PAD")
		)
		(pad "2" smd rect
			(at 0 1.249934 90)
			(size 1.016 1.8034)
			(layers "F.Cu" "F.Mask" "F.Paste")
			(net "XTAL_CPU_NODE1_X1PAD")
		)
	)
	(footprint ""
		(layer "F.Cu")
		(at 125.21057 -26.569416 -90)
		(property "Reference" "R1150"
			(at 5.325618 -0.028448 90)
			(unlocked yes)
			(layer "F.SilkS")
			(effects
				(font
					(size 0.7874 0.5842)
					(thickness 0.1524)
				)
				(justify left)
			)
		)
		(property "Value" ""
			(at 0 0 270)
			(layer "F.Fab")
			(effects
				(font
					(size 1.27 1.27)
				)
			)
		)
		(duplicate_pad_numbers_are_jumpers no)
		(fp_line
			(start -0.7874 0.4064)
			(end -0.7874 -0.4064)
			(stroke
				(width 0.1524)
				(type default)
			)
			(layer "F.SilkS")
		)
		(fp_line
			(start 0.7874 0.4064)
			(end -0.7874 0.4064)
			(stroke
				(width 0.1524)
				(type default)
			)
			(layer "F.SilkS")
		)
		(fp_line
			(start -0.7874 -0.4064)
			(end 0.7874 -0.4064)
			(stroke
				(width 0.1524)
				(type default)
			)
			(layer "F.SilkS")
		)
		(fp_line
			(start 0.7874 -0.4064)
			(end 0.7874 0.4064)
			(stroke
				(width 0.1524)
				(type default)
			)
			(layer "F.SilkS")
		)
		(fp_poly
			(pts
				(xy -0.508 0.2794) (xy -0.508 0.2286) (xy -0.635 0.2286) (xy -0.635 -0.254) (xy -0.5334 -0.254)
				(xy -0.5334 -0.2794) (xy 0.5334 -0.2794) (xy 0.5334 -0.254) (xy 0.635 -0.254) (xy 0.635 0.254) (xy 0.5334 0.254)
				(xy 0.5334 0.2794)
			)
			(stroke
				(width 0)
				(type default)
			)
			(fill no)
			(layer "F.CrtYd")
		)
		(pad "1" smd rect
			(at 0.40005 0 270)
			(size 0.4572 0.508)
			(layers "F.Cu" "F.Mask" "F.Paste")
			(net "P3V3_NODE1")
		)
		(pad "2" smd rect
			(at -0.40005 0 270)
			(size 0.4572 0.508)
			(layers "F.Cu" "F.Mask" "F.Paste")
			(net "SIO_GPIO47")
		)
	)
	(footprint ""
		(layer "F.Cu")
		(at 80.01254 -76.186284 180)
		(property "Reference" "R78"
			(at 0.364744 -16.257524 0)
			(unlocked yes)
			(layer "F.SilkS")
			(effects
				(font
					(size 0.7874 0.5842)
					(thickness 0.1524)
				)
				(justify left)
			)
		)
		(property "Value" ""
			(at 0 0 180)
			(layer "F.Fab")
			(effects
				(font
					(size 1.27 1.27)
				)
			)
		)
		(duplicate_pad_numbers_are_jumpers no)
		(fp_line
			(start 0.7874 0.4064)
			(end -0.7874 0.4064)
			(stroke
				(width 0.1524)
				(type default)
			)
			(layer "F.SilkS")
		)
		(fp_line
			(start 0.7874 -0.4064)
			(end 0.7874 0.4064)
			(stroke
				(width 0.1524)
				(type default)
			)
			(layer "F.SilkS")
		)
		(fp_line
			(start -0.7874 0.4064)
			(end -0.7874 -0.4064)
			(stroke
				(width 0.1524)
				(type default)
			)
			(layer "F.SilkS")
		)
		(fp_line
			(start -0.7874 -0.4064)
			(end 0.7874 -0.4064)
			(stroke
				(width 0.1524)
				(type default)
			)
			(layer "F.SilkS")
		)
		(fp_poly
			(pts
				(xy -0.508 0.2794) (xy -0.508 0.2286) (xy -0.635 0.2286) (xy -0.635 -0.254) (xy -0.5334 -0.254)
				(xy -0.5334 -0.2794) (xy 0.5334 -0.2794) (xy 0.5334 -0.254) (xy 0.635 -0.254) (xy 0.635 0.254) (xy 0.5334 0.254)
				(xy 0.5334 0.2794)
			)
			(stroke
				(width 0)
				(type default)
			)
			(fill no)
			(layer "F.CrtYd")
		)
		(pad "1" smd rect
			(at 0.40005 0 180)
			(size 0.4572 0.508)
			(layers "F.Cu" "F.Mask" "F.Paste")
			(net "XDP_SOC_CPU_NODE1_TCK")
		)
		(pad "2" smd rect
			(at -0.40005 0 180)
			(size 0.4572 0.508)
			(layers "F.Cu" "F.Mask" "F.Paste")
			(net "GND")
		)
	)
	(footprint ""
		(layer "F.Cu")
		(at 33.936178 -175.459898 90)
		(property "Reference" "R1021"
			(at -10.516108 -3.602228 90)
			(unlocked yes)
			(layer "F.SilkS")
			(effects
				(font
					(size 0.7874 0.5842)
					(thickness 0.1524)
				)
				(justify left)
			)
		)
		(property "Value" ""
			(at 0 0 90)
			(layer "F.Fab")
			(effects
				(font
					(size 1.27 1.27)
				)
			)
		)
		(duplicate_pad_numbers_are_jumpers no)
		(fp_line
			(start 0.7874 -0.4064)
			(end 0.7874 0.4064)
			(stroke
				(width 0.1524)
				(type default)
			)
			(layer "F.SilkS")
		)
		(fp_line
			(start -0.7874 -0.4064)
			(end 0.7874 -0.4064)
			(stroke
				(width 0.1524)
				(type default)
			)
			(layer "F.SilkS")
		)
		(fp_line
			(start 0.7874 0.4064)
			(end -0.7874 0.4064)
			(stroke
				(width 0.1524)
				(type default)
			)
			(layer "F.SilkS")
		)
		(fp_line
			(start -0.7874 0.4064)
			(end -0.7874 -0.4064)
			(stroke
				(width 0.1524)
				(type default)
			)
			(layer "F.SilkS")
		)
		(fp_poly
			(pts
				(xy -0.508 0.2794) (xy -0.508 0.2286) (xy -0.635 0.2286) (xy -0.635 -0.254) (xy -0.5334 -0.254)
				(xy -0.5334 -0.2794) (xy 0.5334 -0.2794) (xy 0.5334 -0.254) (xy 0.635 -0.254) (xy 0.635 0.254) (xy 0.5334 0.254)
				(xy 0.5334 0.2794)
			)
			(stroke
				(width 0)
				(type default)
			)
			(fill no)
			(layer "F.CrtYd")
		)
		(pad "1" smd rect
			(at 0.40005 0 90)
			(size 0.4572 0.508)
			(layers "F.Cu" "F.Mask" "F.Paste")
			(net "VR_HSC_NODE1_GATE_R")
		)
		(pad "2" smd rect
			(at -0.40005 0 90)
			(size 0.4572 0.508)
			(layers "F.Cu" "F.Mask" "F.Paste")
			(net "VR_HSC_NODE1_GATE")
		)
	)
	(footprint ""
		(layer "F.Cu")
		(at 119.49176 -175.426624 90)
		(property "Reference" "R797"
			(at -57.011316 32.663638 90)
			(unlocked yes)
			(layer "F.SilkS")
			(effects
				(font
					(size 0.7874 0.5842)
					(thickness 0.1524)
				)
				(justify left)
			)
		)
		(property "Value" ""
			(at 0 0 90)
			(layer "F.Fab")
			(effects
				(font
					(size 1.27 1.27)
				)
			)
		)
		(duplicate_pad_numbers_are_jumpers no)
		(fp_line
			(start 0.7874 -0.4064)
			(end 0.7874 0.4064)
			(stroke
				(width 0.1524)
				(type default)
			)
			(layer "F.SilkS")
		)
		(fp_line
			(start -0.7874 -0.4064)
			(end 0.7874 -0.4064)
			(stroke
				(width 0.1524)
				(type default)
			)
			(layer "F.SilkS")
		)
		(fp_line
			(start 0.7874 0.4064)
			(end -0.7874 0.4064)
			(stroke
				(width 0.1524)
				(type default)
			)
			(layer "F.SilkS")
		)
		(fp_line
			(start -0.7874 0.4064)
			(end -0.7874 -0.4064)
			(stroke
				(width 0.1524)
				(type default)
			)
			(layer "F.SilkS")
		)
		(fp_poly
			(pts
				(xy -0.508 0.2794) (xy -0.508 0.2286) (xy -0.635 0.2286) (xy -0.635 -0.254) (xy -0.5334 -0.254)
				(xy -0.5334 -0.2794) (xy 0.5334 -0.2794) (xy 0.5334 -0.254) (xy 0.635 -0.254) (xy 0.635 0.254) (xy 0.5334 0.254)
				(xy 0.5334 0.2794)
			)
			(stroke
				(width 0)
				(type default)
			)
			(fill no)
			(layer "F.CrtYd")
		)
		(pad "1" smd rect
			(at 0.40005 0 90)
			(size 0.4572 0.508)
			(layers "F.Cu" "F.Mask" "F.Paste")
			(net "N31328108")
		)
		(pad "2" smd rect
			(at -0.40005 0 90)
			(size 0.4572 0.508)
			(layers "F.Cu" "F.Mask" "F.Paste")
			(net "GND")
		)
	)
	(footprint ""
		(layer "F.Cu")
		(at 163.235894 -126.42342 180)
		(property "Reference" "Q28"
			(at -1.400556 1.019556 0)
			(unlocked yes)
			(layer "F.SilkS")
			(effects
				(font
					(size 0.7874 0.5842)
					(thickness 0.1524)
				)
				(justify left)
			)
		)
		(property "Value" ""
			(at 0 0 180)
			(layer "F.Fab")
			(effects
				(font
					(size 1.27 1.27)
				)
			)
		)
		(duplicate_pad_numbers_are_jumpers no)
		(fp_line
			(start 2.584196 2.48412)
			(end -0.5842 2.48412)
			(stroke
				(width 0.1524)
				(type default)
			)
			(layer "F.SilkS")
		)
		(fp_line
			(start 2.584196 -0.5842)
			(end 2.584196 2.48412)
			(stroke
				(width 0.1524)
				(type default)
			)
			(layer "F.SilkS")
		)
		(fp_line
			(start -0.5842 2.48412)
			(end -0.5842 -0.5842)
			(stroke
				(width 0.1524)
				(type default)
			)
			(layer "F.SilkS")
		)
		(fp_line
			(start -0.5842 -0.5842)
			(end 2.584196 -0.5842)
			(stroke
				(width 0.1524)
				(type default)
			)
			(layer "F.SilkS")
		)
		(fp_poly
			(pts
				(xy -0.508 -0.4572) (xy 0.299974 -0.4572) (xy 0.299974 -0.54991) (xy 1.700022 -0.54991) (xy 1.700022 0.49276)
				(xy 2.507996 0.49276) (xy 2.507996 1.40716) (xy 1.700022 1.40716) (xy 1.700022 2.450084) (xy 0.299974 2.450084)
				(xy 0.299974 2.35712) (xy -0.508 2.35712)
			)
			(stroke
				(width 0)
				(type default)
			)
			(fill no)
			(layer "F.CrtYd")
		)
		(fp_line
			(start 1.700022 2.450084)
			(end 0.299974 2.450084)
			(stroke
				(width 0.1)
				(type default)
			)
			(layer "F.Fab")
		)
		(fp_line
			(start 1.700022 -0.54991)
			(end 1.700022 2.450084)
			(stroke
				(width 0.1)
				(type default)
			)
			(layer "F.Fab")
		)
		(fp_line
			(start 0.299974 2.450084)
			(end 0.299974 -0.54991)
			(stroke
				(width 0.1)
				(type default)
			)
			(layer "F.Fab")
		)
		(fp_line
			(start 0.299974 -0.54991)
			(end 1.700022 -0.54991)
			(stroke
				(width 0.1)
				(type default)
			)
			(layer "F.Fab")
		)
		(fp_text user "C"
			(at 3.180842 0.813562 0)
			(unlocked yes)
			(layer "F.SilkS")
			(effects
				(font
					(size 0.635 0.4064)
					(thickness 0.1524)
				)
				(justify left)
			)
		)
		(fp_text user "B"
			(at -0.743712 -0.070866 0)
			(unlocked yes)
			(layer "F.SilkS")
			(effects
				(font
					(size 0.635 0.4064)
					(thickness 0.1524)
				)
				(justify left)
			)
		)
		(fp_text user "E"
			(at -0.771398 1.22809 0)
			(unlocked yes)
			(layer "F.SilkS")
			(effects
				(font
					(size 0.635 0.4064)
					(thickness 0.1524)
				)
				(justify left)
			)
		)
		(fp_text user "C"
			(at 2.8702 0.99187 180)
			(unlocked yes)
			(layer "F.Fab")
			(effects
				(font
					(size 0.7874 0.5842)
					(thickness 0.000001)
				)
				(justify left)
			)
		)
		(fp_text user "B"
			(at -1.5494 0.00127 180)
			(unlocked yes)
			(layer "F.Fab")
			(effects
				(font
					(size 0.7874 0.5842)
					(thickness 0.000001)
				)
				(justify left)
			)
		)
		(fp_text user "E"
			(at -1.5748 1.95707 180)
			(unlocked yes)
			(layer "F.Fab")
			(effects
				(font
					(size 0.7874 0.5842)
					(thickness 0.000001)
				)
				(justify left)
			)
		)
		(pad "B" smd rect
			(at 0 0 270)
			(size 0.8128 0.9144)
			(layers "F.Cu" "F.Mask" "F.Paste")
			(net "FM_CPLD_NODE1_JTAG_POK_R_L")
		)
		(pad "C" smd rect
			(at 1.999996 0.94996 270)
			(size 0.8128 0.9144)
			(layers "F.Cu" "F.Mask" "F.Paste")
			(net "FM_CPU_NODE1_JTAG_POK")
		)
		(pad "E" smd rect
			(at 0 1.89992 270)
			(size 0.8128 0.9144)
			(layers "F.Cu" "F.Mask" "F.Paste")
			(net "GND")
		)
	)
	(footprint ""
		(layer "F.Cu")
		(at 32.014668 -170.403266 180)
		(property "Reference" "R1281"
			(at 3.536188 -7.111746 0)
			(unlocked yes)
			(layer "F.SilkS")
			(effects
				(font
					(size 0.7874 0.5842)
					(thickness 0.1524)
				)
				(justify left)
			)
		)
		(property "Value" ""
			(at 0 0 180)
			(layer "F.Fab")
			(effects
				(font
					(size 1.27 1.27)
				)
			)
		)
		(duplicate_pad_numbers_are_jumpers no)
		(fp_line
			(start 0.7874 0.4064)
			(end -0.7874 0.4064)
			(stroke
				(width 0.1524)
				(type default)
			)
			(layer "F.SilkS")
		)
		(fp_line
			(start 0.7874 -0.4064)
			(end 0.7874 0.4064)
			(stroke
				(width 0.1524)
				(type default)
			)
			(layer "F.SilkS")
		)
		(fp_line
			(start -0.7874 0.4064)
			(end -0.7874 -0.4064)
			(stroke
				(width 0.1524)
				(type default)
			)
			(layer "F.SilkS")
		)
		(fp_line
			(start -0.7874 -0.4064)
			(end 0.7874 -0.4064)
			(stroke
				(width 0.1524)
				(type default)
			)
			(layer "F.SilkS")
		)
		(fp_poly
			(pts
				(xy -0.508 0.2794) (xy -0.508 0.2286) (xy -0.635 0.2286) (xy -0.635 -0.254) (xy -0.5334 -0.254)
				(xy -0.5334 -0.2794) (xy 0.5334 -0.2794) (xy 0.5334 -0.254) (xy 0.635 -0.254) (xy 0.635 0.254) (xy 0.5334 0.254)
				(xy 0.5334 0.2794)
			)
			(stroke
				(width 0)
				(type default)
			)
			(fill no)
			(layer "F.CrtYd")
		)
		(pad "1" smd rect
			(at 0.40005 0 180)
			(size 0.4572 0.508)
			(layers "F.Cu" "F.Mask" "F.Paste")
			(net "CM_PWR_CTL_IN")
		)
		(pad "2" smd rect
			(at -0.40005 0 180)
			(size 0.4572 0.508)
			(layers "F.Cu" "F.Mask" "F.Paste")
			(net "CM_PWR_CTL_IN_R")
		)
	)
	(footprint ""
		(layer "F.Cu")
		(at 93.711522 -129.768092 90)
		(property "Reference" "C811"
			(at -4.228084 -0.049276 90)
			(unlocked yes)
			(layer "F.SilkS")
			(effects
				(font
					(size 0.7874 0.5842)
					(thickness 0.1524)
				)
				(justify left)
			)
		)
		(property "Value" ""
			(at 0 0 90)
			(layer "F.Fab")
			(effects
				(font
					(size 1.27 1.27)
				)
			)
		)
		(duplicate_pad_numbers_are_jumpers no)
		(fp_line
			(start 0.7874 -0.4064)
			(end 0.7874 0.4064)
			(stroke
				(width 0.1524)
				(type default)
			)
			(layer "F.SilkS")
		)
		(fp_line
			(start -0.7874 -0.4064)
			(end 0.7874 -0.4064)
			(stroke
				(width 0.1524)
				(type default)
			)
			(layer "F.SilkS")
		)
		(fp_line
			(start 0 0.381)
			(end 0 -0.381)
			(stroke
				(width 0.1524)
				(type default)
			)
			(layer "F.SilkS")
		)
		(fp_line
			(start 0.7874 0.4064)
			(end -0.7874 0.4064)
			(stroke
				(width 0.1524)
				(type default)
			)
			(layer "F.SilkS")
		)
		(fp_line
			(start -0.7874 0.4064)
			(end -0.7874 -0.4064)
			(stroke
				(width 0.1524)
				(type default)
			)
			(layer "F.SilkS")
		)
		(fp_poly
			(pts
				(xy -0.5334 0.254) (xy -0.635 0.254) (xy -0.635 0.2286) (xy -0.635 -0.254) (xy -0.5334 -0.254) (xy -0.5334 -0.2794)
				(xy 0.5334 -0.2794) (xy 0.5334 -0.254) (xy 0.635 -0.254) (xy 0.635 0.254) (xy 0.5334 0.254) (xy 0.5334 0.2794)
				(xy -0.508 0.2794) (xy -0.5334 0.2794)
			)
			(stroke
				(width 0)
				(type default)
			)
			(fill no)
			(layer "F.CrtYd")
		)
		(pad "1" smd rect
			(at 0.40005 0 90)
			(size 0.4572 0.508)
			(layers "F.Cu" "F.Mask" "F.Paste")
			(net "FM_CPLD_NODE1_P1V05_SUS_EN")
		)
		(pad "2" smd rect
			(at -0.40005 0 90)
			(size 0.4572 0.508)
			(layers "F.Cu" "F.Mask" "F.Paste")
			(net "GND")
		)
	)
	(footprint ""
		(layer "F.Cu")
		(at 116.387372 -137.018522 180)
		(property "Reference" "PR67"
			(at -4.285488 4.322826 0)
			(unlocked yes)
			(layer "F.SilkS")
			(effects
				(font
					(size 0.635 0.4064)
					(thickness 0.1524)
				)
				(justify left)
			)
		)
		(property "Value" ""
			(at 0 0 180)
			(layer "F.Fab")
			(effects
				(font
					(size 1.27 1.27)
				)
			)
		)
		(duplicate_pad_numbers_are_jumpers no)
		(fp_line
			(start 0.7874 0.4064)
			(end -0.7874 0.4064)
			(stroke
				(width 0.1524)
				(type default)
			)
			(layer "F.SilkS")
		)
		(fp_line
			(start 0.7874 -0.4064)
			(end 0.7874 0.4064)
			(stroke
				(width 0.1524)
				(type default)
			)
			(layer "F.SilkS")
		)
		(fp_line
			(start -0.7874 0.4064)
			(end -0.7874 -0.4064)
			(stroke
				(width 0.1524)
				(type default)
			)
			(layer "F.SilkS")
		)
		(fp_line
			(start -0.7874 -0.4064)
			(end 0.7874 -0.4064)
			(stroke
				(width 0.1524)
				(type default)
			)
			(layer "F.SilkS")
		)
		(fp_poly
			(pts
				(xy -0.508 0.2794) (xy -0.508 0.2286) (xy -0.635 0.2286) (xy -0.635 -0.254) (xy -0.5334 -0.254)
				(xy -0.5334 -0.2794) (xy 0.5334 -0.2794) (xy 0.5334 -0.254) (xy 0.635 -0.254) (xy 0.635 0.254) (xy 0.5334 0.254)
				(xy 0.5334 0.2794)
			)
			(stroke
				(width 0)
				(type default)
			)
			(fill no)
			(layer "F.CrtYd")
		)
		(pad "1" smd rect
			(at 0.40005 0 180)
			(size 0.4572 0.508)
			(layers "F.Cu" "F.Mask" "F.Paste")
			(net "VR_PVCCP_NODE1_FB")
		)
		(pad "2" smd rect
			(at -0.40005 0 180)
			(size 0.4572 0.508)
			(layers "F.Cu" "F.Mask" "F.Paste")
			(net "VR_PVCCP_NODE1_FB_RC")
		)
	)
	(footprint ""
		(layer "F.Cu")
		(at 126.563628 -158.606744 180)
		(property "Reference" "U116"
			(at 60.31611 -109.30128 90)
			(unlocked yes)
			(layer "F.SilkS")
			(effects
				(font
					(size 0.7874 0.5842)
					(thickness 0.1524)
				)
			)
		)
		(property "Value" ""
			(at 0 0 180)
			(layer "F.Fab")
			(effects
				(font
					(size 1.27 1.27)
				)
			)
		)
		(duplicate_pad_numbers_are_jumpers no)
		(fp_line
			(start 1.651 1.905)
			(end -1.651 1.905)
			(stroke
				(width 0.1524)
				(type default)
			)
			(layer "F.SilkS")
		)
		(fp_line
			(start 1.651 -1.905)
			(end 1.651 1.905)
			(stroke
				(width 0.1524)
				(type default)
			)
			(layer "F.SilkS")
		)
		(fp_line
			(start -1.651 1.905)
			(end -1.651 -1.905)
			(stroke
				(width 0.1524)
				(type default)
			)
			(layer "F.SilkS")
		)
		(fp_line
			(start -1.651 -1.905)
			(end 1.651 -1.905)
			(stroke
				(width 0.1524)
				(type default)
			)
			(layer "F.SilkS")
		)
		(fp_poly
			(pts
				(xy -1.524 0.7112) (xy -1.524 1.7526) (xy -0.508 1.7526) (xy -0.508 0.6985) (xy 0.508 0.6985) (xy 0.508 1.7526)
				(xy 1.524 1.7526) (xy 1.524 0.6985) (xy 1.524 -0.6985) (xy 0.508 -0.6985) (xy 0.508 -1.7526) (xy -0.508 -1.7526)
				(xy -0.508 -0.6985) (xy -1.524 -0.6985) (xy -1.524 0.6985)
			)
			(stroke
				(width 0)
				(type default)
			)
			(fill no)
			(layer "F.CrtYd")
		)
		(fp_text user "S"
			(at 0.401828 2.537206 0)
			(unlocked yes)
			(layer "F.SilkS")
			(effects
				(font
					(size 0.635 0.4064)
					(thickness 0.1524)
				)
			)
		)
		(fp_text user "D"
			(at 0.375412 -2.77114 0)
			(unlocked yes)
			(layer "F.SilkS")
			(effects
				(font
					(size 0.635 0.4064)
					(thickness 0.1524)
				)
			)
		)
		(fp_text user "G"
			(at -0.715772 2.537206 0)
			(unlocked yes)
			(layer "F.SilkS")
			(effects
				(font
					(size 0.635 0.4064)
					(thickness 0.1524)
				)
			)
		)
		(pad "D" smd rect
			(at 0 -1.1176 180)
			(size 1.016 1.27)
			(layers "F.Cu" "F.Mask" "F.Paste")
			(net "I2C_PSU1_SCL")
		)
		(pad "G" smd rect
			(at -1.016 1.1176 180)
			(size 1.016 1.27)
			(layers "F.Cu" "F.Mask" "F.Paste")
			(net "PMBUS1_EN")
		)
		(pad "S" smd rect
			(at 1.016 1.1176 180)
			(size 1.016 1.27)
			(layers "F.Cu" "F.Mask" "F.Paste")
			(net "I2C_PSU1_SCL_MOS")
		)
	)
	(footprint ""
		(layer "F.Cu")
		(at 38.126416 -185.583068)
		(property "Reference" "D20"
			(at 0.114554 -4.710176 90)
			(unlocked yes)
			(layer "F.SilkS")
			(effects
				(font
					(size 0.7874 0.5842)
					(thickness 0.1524)
				)
			)
		)
		(property "Value" ""
			(at 0 0 0)
			(layer "F.Fab")
			(effects
				(font
					(size 1.27 1.27)
				)
			)
		)
		(duplicate_pad_numbers_are_jumpers no)
		(fp_line
			(start -1.519936 -1.6002)
			(end 1.519936 -1.6002)
			(stroke
				(width 0.1524)
				(type default)
			)
			(layer "F.SilkS")
		)
		(fp_line
			(start -1.519936 1.6002)
			(end -1.519936 -1.5748)
			(stroke
				(width 0.1524)
				(type default)
			)
			(layer "F.SilkS")
		)
		(fp_line
			(start 1.519936 -1.6002)
			(end 1.519936 1.6002)
			(stroke
				(width 0.1524)
				(type default)
			)
			(layer "F.SilkS")
		)
		(fp_line
			(start 1.519936 1.6002)
			(end -1.519936 1.6002)
			(stroke
				(width 0.1524)
				(type default)
			)
			(layer "F.SilkS")
		)
		(fp_poly
			(pts
				(xy -1.519936 0.700024) (xy -1.3716 0.700024) (xy -1.3716 1.4732) (xy -0.5334 1.4732) (xy -0.5334 0.700024)
				(xy 0.5334 0.700024) (xy 0.5334 1.4732) (xy 1.3716 1.4732) (xy 1.3716 0.700024) (xy 1.519936 0.700024)
				(xy 1.519936 -0.700024) (xy 0.4064 -0.700024) (xy 0.4064 -1.4732) (xy -0.4064 -1.4732) (xy -0.4064 -0.700024)
				(xy -1.519936 -0.700024)
			)
			(stroke
				(width 0)
				(type default)
			)
			(fill no)
			(layer "F.CrtYd")
		)
		(fp_line
			(start -1.519936 -0.700024)
			(end 1.519936 -0.700024)
			(stroke
				(width 0.1)
				(type default)
			)
			(layer "F.Fab")
		)
		(fp_line
			(start -1.519936 0.700024)
			(end -1.519936 -0.700024)
			(stroke
				(width 0.1)
				(type default)
			)
			(layer "F.Fab")
		)
		(fp_line
			(start 1.519936 -0.700024)
			(end 1.519936 0.700024)
			(stroke
				(width 0.1)
				(type default)
			)
			(layer "F.Fab")
		)
		(fp_line
			(start 1.519936 0.700024)
			(end -1.519936 0.700024)
			(stroke
				(width 0.1)
				(type default)
			)
			(layer "F.Fab")
		)
		(fp_text user "1"
			(at -1.761236 0.8001 0)
			(unlocked yes)
			(layer "F.SilkS")
			(effects
				(font
					(size 0.635 0.4064)
					(thickness 0.1524)
				)
			)
		)
		(fp_text user "3"
			(at 0 -2.08915 0)
			(unlocked yes)
			(layer "F.SilkS")
			(effects
				(font
					(size 0.635 0.4064)
					(thickness 0.1524)
				)
			)
		)
		(fp_text user "2"
			(at 0.78105 2.431796 0)
			(unlocked yes)
			(layer "F.SilkS")
			(effects
				(font
					(size 0.635 0.4064)
					(thickness 0.1524)
				)
			)
		)
		(pad "1" smd rect
			(at -0.94996 0.999998)
			(size 0.8128 0.9144)
			(layers "F.Cu" "F.Mask" "F.Paste")
			(net "GND")
		)
		(pad "2" smd rect
			(at 0.94996 0.999998)
			(size 0.8128 0.9144)
			(layers "F.Cu" "F.Mask" "F.Paste")
			(net "Net_1678")
		)
		(pad "3" smd rect
			(at 0 -0.999998)
			(size 0.8128 0.9144)
			(layers "F.Cu" "F.Mask" "F.Paste")
			(net "P12V_PDB")
		)
	)
	(footprint ""
		(layer "F.Cu")
		(at 41.862248 -169.659046 90)
		(property "Reference" "R1070"
			(at -2.440686 -2.464562 90)
			(unlocked yes)
			(layer "F.SilkS")
			(effects
				(font
					(size 0.7874 0.5842)
					(thickness 0.1524)
				)
				(justify left)
			)
		)
		(property "Value" ""
			(at 0 0 90)
			(layer "F.Fab")
			(effects
				(font
					(size 1.27 1.27)
				)
			)
		)
		(duplicate_pad_numbers_are_jumpers no)
		(fp_line
			(start 0.7874 -0.4064)
			(end 0.7874 0.4064)
			(stroke
				(width 0.1524)
				(type default)
			)
			(layer "F.SilkS")
		)
		(fp_line
			(start -0.7874 -0.4064)
			(end 0.7874 -0.4064)
			(stroke
				(width 0.1524)
				(type default)
			)
			(layer "F.SilkS")
		)
		(fp_line
			(start 0.7874 0.4064)
			(end -0.7874 0.4064)
			(stroke
				(width 0.1524)
				(type default)
			)
			(layer "F.SilkS")
		)
		(fp_line
			(start -0.7874 0.4064)
			(end -0.7874 -0.4064)
			(stroke
				(width 0.1524)
				(type default)
			)
			(layer "F.SilkS")
		)
		(fp_poly
			(pts
				(xy -0.508 0.2794) (xy -0.508 0.2286) (xy -0.635 0.2286) (xy -0.635 -0.254) (xy -0.5334 -0.254)
				(xy -0.5334 -0.2794) (xy 0.5334 -0.2794) (xy 0.5334 -0.254) (xy 0.635 -0.254) (xy 0.635 0.254) (xy 0.5334 0.254)
				(xy 0.5334 0.2794)
			)
			(stroke
				(width 0)
				(type default)
			)
			(fill no)
			(layer "F.CrtYd")
		)
		(pad "1" smd rect
			(at 0.40005 0 90)
			(size 0.4572 0.508)
			(layers "F.Cu" "F.Mask" "F.Paste")
			(net "N53103066")
		)
		(pad "2" smd rect
			(at -0.40005 0 90)
			(size 0.4572 0.508)
			(layers "F.Cu" "F.Mask" "F.Paste")
			(net "P12V_DBG")
		)
	)
	(footprint ""
		(layer "F.Cu")
		(at 93.993462 -15.849092 90)
		(property "Reference" "R192"
			(at -0.249428 -1.191768 90)
			(unlocked yes)
			(layer "F.SilkS")
			(effects
				(font
					(size 0.7874 0.5842)
					(thickness 0.1524)
				)
				(justify left)
			)
		)
		(property "Value" ""
			(at 0 0 90)
			(layer "F.Fab")
			(effects
				(font
					(size 1.27 1.27)
				)
			)
		)
		(duplicate_pad_numbers_are_jumpers no)
		(fp_line
			(start 0.7874 -0.4064)
			(end 0.7874 0.4064)
			(stroke
				(width 0.1524)
				(type default)
			)
			(layer "F.SilkS")
		)
		(fp_line
			(start -0.7874 -0.4064)
			(end 0.7874 -0.4064)
			(stroke
				(width 0.1524)
				(type default)
			)
			(layer "F.SilkS")
		)
		(fp_line
			(start 0.7874 0.4064)
			(end -0.7874 0.4064)
			(stroke
				(width 0.1524)
				(type default)
			)
			(layer "F.SilkS")
		)
		(fp_line
			(start -0.7874 0.4064)
			(end -0.7874 -0.4064)
			(stroke
				(width 0.1524)
				(type default)
			)
			(layer "F.SilkS")
		)
		(fp_poly
			(pts
				(xy -0.508 0.2794) (xy -0.508 0.2286) (xy -0.635 0.2286) (xy -0.635 -0.254) (xy -0.5334 -0.254)
				(xy -0.5334 -0.2794) (xy 0.5334 -0.2794) (xy 0.5334 -0.254) (xy 0.635 -0.254) (xy 0.635 0.254) (xy 0.5334 0.254)
				(xy 0.5334 0.2794)
			)
			(stroke
				(width 0)
				(type default)
			)
			(fill no)
			(layer "F.CrtYd")
		)
		(pad "1" smd rect
			(at 0.40005 0 90)
			(size 0.4572 0.508)
			(layers "F.Cu" "F.Mask" "F.Paste")
			(net "LPC_CPU_NODE1_LAD2")
		)
		(pad "2" smd rect
			(at -0.40005 0 90)
			(size 0.4572 0.508)
			(layers "F.Cu" "F.Mask" "F.Paste")
			(net "LPC_CPU_TPM_LAD2")
		)
	)
	(footprint ""
		(layer "F.Cu")
		(at 145.65376 -185.205624 90)
		(property "Reference" "C756"
			(at 4.768088 -0.544068 90)
			(unlocked yes)
			(layer "F.SilkS")
			(effects
				(font
					(size 0.7874 0.5842)
					(thickness 0.1524)
				)
				(justify left)
			)
		)
		(property "Value" ""
			(at 0 0 90)
			(layer "F.Fab")
			(effects
				(font
					(size 1.27 1.27)
				)
			)
		)
		(duplicate_pad_numbers_are_jumpers no)
		(fp_line
			(start 0.7874 -0.4064)
			(end 0.7874 0.4064)
			(stroke
				(width 0.1524)
				(type default)
			)
			(layer "F.SilkS")
		)
		(fp_line
			(start -0.7874 -0.4064)
			(end 0.7874 -0.4064)
			(stroke
				(width 0.1524)
				(type default)
			)
			(layer "F.SilkS")
		)
		(fp_line
			(start 0 0.381)
			(end 0 -0.381)
			(stroke
				(width 0.1524)
				(type default)
			)
			(layer "F.SilkS")
		)
		(fp_line
			(start 0.7874 0.4064)
			(end -0.7874 0.4064)
			(stroke
				(width 0.1524)
				(type default)
			)
			(layer "F.SilkS")
		)
		(fp_line
			(start -0.7874 0.4064)
			(end -0.7874 -0.4064)
			(stroke
				(width 0.1524)
				(type default)
			)
			(layer "F.SilkS")
		)
		(fp_poly
			(pts
				(xy -0.5334 0.254) (xy -0.635 0.254) (xy -0.635 0.2286) (xy -0.635 -0.254) (xy -0.5334 -0.254) (xy -0.5334 -0.2794)
				(xy 0.5334 -0.2794) (xy 0.5334 -0.254) (xy 0.635 -0.254) (xy 0.635 0.254) (xy 0.5334 0.254) (xy 0.5334 0.2794)
				(xy -0.508 0.2794) (xy -0.5334 0.2794)
			)
			(stroke
				(width 0)
				(type default)
			)
			(fill no)
			(layer "F.CrtYd")
		)
		(pad "1" smd rect
			(at 0.40005 0 90)
			(size 0.4572 0.508)
			(layers "F.Cu" "F.Mask" "F.Paste")
			(net "UART_T12_NODE3_RXD")
		)
		(pad "2" smd rect
			(at -0.40005 0 90)
			(size 0.4572 0.508)
			(layers "F.Cu" "F.Mask" "F.Paste")
			(net "GND")
		)
	)
	(footprint ""
		(layer "F.Cu")
		(at 182.819294 -134.39902 -90)
		(property "Reference" "Q27"
			(at 2.188464 -12.60221 90)
			(unlocked yes)
			(layer "F.SilkS")
			(effects
				(font
					(size 0.7874 0.5842)
					(thickness 0.1524)
				)
				(justify left)
			)
		)
		(property "Value" ""
			(at 0 0 270)
			(layer "F.Fab")
			(effects
				(font
					(size 1.27 1.27)
				)
			)
		)
		(duplicate_pad_numbers_are_jumpers no)
		(fp_line
			(start -0.5842 2.48412)
			(end -0.5842 -0.5842)
			(stroke
				(width 0.1524)
				(type default)
			)
			(layer "F.SilkS")
		)
		(fp_line
			(start 2.584196 2.48412)
			(end -0.5842 2.48412)
			(stroke
				(width 0.1524)
				(type default)
			)
			(layer "F.SilkS")
		)
		(fp_line
			(start -0.5842 -0.5842)
			(end 2.584196 -0.5842)
			(stroke
				(width 0.1524)
				(type default)
			)
			(layer "F.SilkS")
		)
		(fp_line
			(start 2.584196 -0.5842)
			(end 2.584196 2.48412)
			(stroke
				(width 0.1524)
				(type default)
			)
			(layer "F.SilkS")
		)
		(fp_poly
			(pts
				(xy -0.508 -0.4572) (xy 0.299974 -0.4572) (xy 0.299974 -0.54991) (xy 1.700022 -0.54991) (xy 1.700022 0.49276)
				(xy 2.507996 0.49276) (xy 2.507996 1.40716) (xy 1.700022 1.40716) (xy 1.700022 2.450084) (xy 0.299974 2.450084)
				(xy 0.299974 2.35712) (xy -0.508 2.35712)
			)
			(stroke
				(width 0)
				(type default)
			)
			(fill no)
			(layer "F.CrtYd")
		)
		(fp_line
			(start 0.299974 2.450084)
			(end 0.299974 -0.54991)
			(stroke
				(width 0.1)
				(type default)
			)
			(layer "F.Fab")
		)
		(fp_line
			(start 1.700022 2.450084)
			(end 0.299974 2.450084)
			(stroke
				(width 0.1)
				(type default)
			)
			(layer "F.Fab")
		)
		(fp_line
			(start 0.299974 -0.54991)
			(end 1.700022 -0.54991)
			(stroke
				(width 0.1)
				(type default)
			)
			(layer "F.Fab")
		)
		(fp_line
			(start 1.700022 -0.54991)
			(end 1.700022 2.450084)
			(stroke
				(width 0.1)
				(type default)
			)
			(layer "F.Fab")
		)
		(fp_text user "E"
			(at -1.506474 1.979676 0)
			(unlocked yes)
			(layer "F.SilkS")
			(effects
				(font
					(size 0.635 0.4064)
					(thickness 0.1524)
				)
				(justify left)
			)
		)
		(fp_text user "C"
			(at 3.154172 1.685036 90)
			(unlocked yes)
			(layer "F.SilkS")
			(effects
				(font
					(size 0.635 0.4064)
					(thickness 0.1524)
				)
				(justify left)
			)
		)
		(fp_text user "B"
			(at 0.704596 -0.817626 0)
			(unlocked yes)
			(layer "F.SilkS")
			(effects
				(font
					(size 0.635 0.4064)
					(thickness 0.1524)
				)
				(justify left)
			)
		)
		(fp_text user "E"
			(at -1.5748 1.95707 270)
			(unlocked yes)
			(layer "F.Fab")
			(effects
				(font
					(size 0.7874 0.5842)
					(thickness 0.000001)
				)
				(justify left)
			)
		)
		(fp_text user "C"
			(at 2.8702 0.99187 270)
			(unlocked yes)
			(layer "F.Fab")
			(effects
				(font
					(size 0.7874 0.5842)
					(thickness 0.000001)
				)
				(justify left)
			)
		)
		(fp_text user "B"
			(at -1.5494 0.00127 270)
			(unlocked yes)
			(layer "F.Fab")
			(effects
				(font
					(size 0.7874 0.5842)
					(thickness 0.000001)
				)
				(justify left)
			)
		)
		(pad "B" smd rect
			(at 0 0)
			(size 0.8128 0.9144)
			(layers "F.Cu" "F.Mask" "F.Paste")
			(net "FM_NODE1_DFX_GPIO_GRP05_R")
		)
		(pad "C" smd rect
			(at 1.999996 0.94996)
			(size 0.8128 0.9144)
			(layers "F.Cu" "F.Mask" "F.Paste")
			(net "FM_NODE1_CORE0_1_RST_L")
		)
		(pad "E" smd rect
			(at 0 1.89992)
			(size 0.8128 0.9144)
			(layers "F.Cu" "F.Mask" "F.Paste")
			(net "GND")
		)
	)
	(footprint ""
		(layer "F.Cu")
		(at 96.697546 -138.030458 180)
		(property "Reference" "J21"
			(at 0.057404 1.38049 90)
			(unlocked yes)
			(layer "F.SilkS")
			(effects
				(font
					(size 0.7874 0.5842)
					(thickness 0.1524)
				)
				(justify left)
			)
		)
		(property "Value" ""
			(at 0 0 180)
			(layer "F.Fab")
			(effects
				(font
					(size 1.27 1.27)
				)
			)
		)
		(duplicate_pad_numbers_are_jumpers no)
		(fp_poly
			(pts
				(xy 0.2794 0.907796) (xy 0.254 0.907796) (xy 0.254 1.0414) (xy -0.254 1.0414) (xy -0.254 1.034796)
				(xy -0.254 0.933196) (xy -0.2794 0.933196) (xy -0.2794 -0.133604) (xy -0.254 -0.133604) (xy -0.254 -0.235204)
				(xy 0.254 -0.235204) (xy 0.254 -0.133604) (xy 0.2794 -0.133604)
			)
			(stroke
				(width 0)
				(type default)
			)
			(fill no)
			(layer "F.CrtYd")
		)
		(pad "1" smd custom
			(at 0 -0.000254 180)
			(size 0.127 0.127)
			(layers "F.Cu" "F.Mask" "F.Paste")
			(net "P1V05_SUS_NODE1")
			(options
				(clearance outline)
				(anchor circle)
			)
			(primitives
				(gr_poly
					(pts
						(xy -0.127 0.508) (xy -0.127 -0.0508) (xy -0.254 -0.0508) (xy -0.254 -0.508) (xy 0.254 -0.508)
						(xy 0.254 -0.0508) (xy 0.127 -0.0508) (xy 0.127 0.508)
					)
					(width 0)
					(fill yes)
				)
			)
		)
		(pad "2" smd rect
			(at 0 0.799846 270)
			(size 0.4572 0.508)
			(layers "F.Cu" "F.Mask" "F.Paste")
			(net "P1V05_SUS_NODE1_ADJ_S")
		)
		(zone
			(layer "F.Cu")
			(hatch none 0.5)
			(connect_pads
				(clearance 0)
			)
			(min_thickness 0.25)
			(keepout
				(tracks allowed)
				(vias not_allowed)
				(pads allowed)
				(copperpour not_allowed)
				(footprints allowed)
			)
			(placement
				(enabled no)
				(sheetname "")
			)
			(fill
				(thermal_gap 0.5)
				(thermal_bridge_width 0.5)
				(island_removal_mode 0)
			)
			(polygon
				(pts
					(xy 97.002346 -139.116054) (xy 96.392746 -139.116054) (xy 96.392746 -137.744454) (xy 97.002346 -137.744454)
				)
			)
		)
	)
	(footprint ""
		(layer "F.Cu")
		(at 169.728896 -41.679114)
		(property "Reference" "R266"
			(at -1.178814 -2.168398 0)
			(unlocked yes)
			(layer "F.SilkS")
			(effects
				(font
					(size 0.7874 0.5842)
					(thickness 0.1524)
				)
				(justify left)
			)
		)
		(property "Value" ""
			(at 0 0 0)
			(layer "F.Fab")
			(effects
				(font
					(size 1.27 1.27)
				)
			)
		)
		(duplicate_pad_numbers_are_jumpers no)
		(fp_line
			(start -0.7874 -0.4064)
			(end 0.7874 -0.4064)
			(stroke
				(width 0.1524)
				(type default)
			)
			(layer "F.SilkS")
		)
		(fp_line
			(start -0.7874 0.4064)
			(end -0.7874 -0.4064)
			(stroke
				(width 0.1524)
				(type default)
			)
			(layer "F.SilkS")
		)
		(fp_line
			(start 0.7874 -0.4064)
			(end 0.7874 0.4064)
			(stroke
				(width 0.1524)
				(type default)
			)
			(layer "F.SilkS")
		)
		(fp_line
			(start 0.7874 0.4064)
			(end -0.7874 0.4064)
			(stroke
				(width 0.1524)
				(type default)
			)
			(layer "F.SilkS")
		)
		(fp_poly
			(pts
				(xy -0.508 0.2794) (xy -0.508 0.2286) (xy -0.635 0.2286) (xy -0.635 -0.254) (xy -0.5334 -0.254)
				(xy -0.5334 -0.2794) (xy 0.5334 -0.2794) (xy 0.5334 -0.254) (xy 0.635 -0.254) (xy 0.635 0.254) (xy 0.5334 0.254)
				(xy 0.5334 0.2794)
			)
			(stroke
				(width 0)
				(type default)
			)
			(fill no)
			(layer "F.CrtYd")
		)
		(pad "1" smd rect
			(at 0.40005 0)
			(size 0.4572 0.508)
			(layers "F.Cu" "F.Mask" "F.Paste")
			(net "USB1_L_DP")
		)
		(pad "2" smd rect
			(at -0.40005 0)
			(size 0.4572 0.508)
			(layers "F.Cu" "F.Mask" "F.Paste")
			(net "USB1_DP")
		)
	)
	(footprint ""
		(layer "F.Cu")
		(at 11.889994 -29.778706 90)
		(property "Reference" "R654"
			(at -1.126744 -1.052322 90)
			(unlocked yes)
			(layer "F.SilkS")
			(effects
				(font
					(size 0.7874 0.5842)
					(thickness 0.1524)
				)
				(justify left)
			)
		)
		(property "Value" ""
			(at 0 0 90)
			(layer "F.Fab")
			(effects
				(font
					(size 1.27 1.27)
				)
			)
		)
		(duplicate_pad_numbers_are_jumpers no)
		(fp_line
			(start 0.7874 -0.4064)
			(end 0.7874 0.4064)
			(stroke
				(width 0.1524)
				(type default)
			)
			(layer "F.SilkS")
		)
		(fp_line
			(start -0.7874 -0.4064)
			(end 0.7874 -0.4064)
			(stroke
				(width 0.1524)
				(type default)
			)
			(layer "F.SilkS")
		)
		(fp_line
			(start 0.7874 0.4064)
			(end -0.7874 0.4064)
			(stroke
				(width 0.1524)
				(type default)
			)
			(layer "F.SilkS")
		)
		(fp_line
			(start -0.7874 0.4064)
			(end -0.7874 -0.4064)
			(stroke
				(width 0.1524)
				(type default)
			)
			(layer "F.SilkS")
		)
		(fp_poly
			(pts
				(xy -0.508 0.2794) (xy -0.508 0.2286) (xy -0.635 0.2286) (xy -0.635 -0.254) (xy -0.5334 -0.254)
				(xy -0.5334 -0.2794) (xy 0.5334 -0.2794) (xy 0.5334 -0.254) (xy 0.635 -0.254) (xy 0.635 0.254) (xy 0.5334 0.254)
				(xy 0.5334 0.2794)
			)
			(stroke
				(width 0)
				(type default)
			)
			(fill no)
			(layer "F.CrtYd")
		)
		(pad "1" smd rect
			(at 0.40005 0 90)
			(size 0.4572 0.508)
			(layers "F.Cu" "F.Mask" "F.Paste")
			(net "GND")
		)
		(pad "2" smd rect
			(at -0.40005 0 90)
			(size 0.4572 0.508)
			(layers "F.Cu" "F.Mask" "F.Paste")
			(net "N54251449")
		)
	)
	(footprint ""
		(layer "F.Cu")
		(at 59.113166 -96.709992 -90)
		(property "Reference" "R55"
			(at 54.98719 -28.440888 90)
			(unlocked yes)
			(layer "F.SilkS")
			(effects
				(font
					(size 0.7874 0.5842)
					(thickness 0.1524)
				)
				(justify left)
			)
		)
		(property "Value" ""
			(at 0 0 270)
			(layer "F.Fab")
			(effects
				(font
					(size 1.27 1.27)
				)
			)
		)
		(duplicate_pad_numbers_are_jumpers no)
		(fp_line
			(start -0.7874 0.4064)
			(end -0.7874 -0.4064)
			(stroke
				(width 0.1524)
				(type default)
			)
			(layer "F.SilkS")
		)
		(fp_line
			(start 0.7874 0.4064)
			(end -0.7874 0.4064)
			(stroke
				(width 0.1524)
				(type default)
			)
			(layer "F.SilkS")
		)
		(fp_line
			(start -0.7874 -0.4064)
			(end 0.7874 -0.4064)
			(stroke
				(width 0.1524)
				(type default)
			)
			(layer "F.SilkS")
		)
		(fp_line
			(start 0.7874 -0.4064)
			(end 0.7874 0.4064)
			(stroke
				(width 0.1524)
				(type default)
			)
			(layer "F.SilkS")
		)
		(fp_poly
			(pts
				(xy -0.508 0.2794) (xy -0.508 0.2286) (xy -0.635 0.2286) (xy -0.635 -0.254) (xy -0.5334 -0.254)
				(xy -0.5334 -0.2794) (xy 0.5334 -0.2794) (xy 0.5334 -0.254) (xy 0.635 -0.254) (xy 0.635 0.254) (xy 0.5334 0.254)
				(xy 0.5334 0.2794)
			)
			(stroke
				(width 0)
				(type default)
			)
			(fill no)
			(layer "F.CrtYd")
		)
		(pad "1" smd rect
			(at 0.40005 0 270)
			(size 0.4572 0.508)
			(layers "F.Cu" "F.Mask" "F.Paste")
			(net "PD_CPU_NODE1_DFX_GPIO_GRP1_1")
		)
		(pad "2" smd rect
			(at -0.40005 0 270)
			(size 0.4572 0.508)
			(layers "F.Cu" "F.Mask" "F.Paste")
			(net "GND")
		)
	)
	(footprint ""
		(layer "F.Cu")
		(at 184.3786 -180.7972)
		(property "Reference" "R1321"
			(at 9.3218 17.12087 0)
			(unlocked yes)
			(layer "F.SilkS")
			(effects
				(font
					(size 0.7874 0.5842)
					(thickness 0.1524)
				)
				(justify left)
			)
		)
		(property "Value" ""
			(at 0 0 0)
			(layer "F.Fab")
			(effects
				(font
					(size 1.27 1.27)
				)
			)
		)
		(duplicate_pad_numbers_are_jumpers no)
		(fp_line
			(start -0.7874 -0.4064)
			(end 0.7874 -0.4064)
			(stroke
				(width 0.1524)
				(type default)
			)
			(layer "F.SilkS")
		)
		(fp_line
			(start -0.7874 0.4064)
			(end -0.7874 -0.4064)
			(stroke
				(width 0.1524)
				(type default)
			)
			(layer "F.SilkS")
		)
		(fp_line
			(start 0.7874 -0.4064)
			(end 0.7874 0.4064)
			(stroke
				(width 0.1524)
				(type default)
			)
			(layer "F.SilkS")
		)
		(fp_line
			(start 0.7874 0.4064)
			(end -0.7874 0.4064)
			(stroke
				(width 0.1524)
				(type default)
			)
			(layer "F.SilkS")
		)
		(fp_poly
			(pts
				(xy -0.508 0.2794) (xy -0.508 0.2286) (xy -0.635 0.2286) (xy -0.635 -0.254) (xy -0.5334 -0.254)
				(xy -0.5334 -0.2794) (xy 0.5334 -0.2794) (xy 0.5334 -0.254) (xy 0.635 -0.254) (xy 0.635 0.254) (xy 0.5334 0.254)
				(xy 0.5334 0.2794)
			)
			(stroke
				(width 0)
				(type default)
			)
			(fill no)
			(layer "F.CrtYd")
		)
		(pad "1" smd rect
			(at 0.40005 0)
			(size 0.4572 0.508)
			(layers "F.Cu" "F.Mask" "F.Paste")
			(net "POWER_SW3_PWR_CTR_12V")
		)
		(pad "2" smd rect
			(at -0.40005 0)
			(size 0.4572 0.508)
			(layers "F.Cu" "F.Mask" "F.Paste")
			(net "POWER_SW3_PWR_CTR_12V_R")
		)
	)
	(footprint ""
		(layer "F.Cu")
		(at 120.496838 -151.266906 90)
		(property "Reference" "R1039"
			(at -1.702308 2.418842 90)
			(unlocked yes)
			(layer "F.SilkS")
			(effects
				(font
					(size 0.635 0.4064)
					(thickness 0.1524)
				)
				(justify left)
			)
		)
		(property "Value" ""
			(at 0 0 90)
			(layer "F.Fab")
			(effects
				(font
					(size 1.27 1.27)
				)
			)
		)
		(duplicate_pad_numbers_are_jumpers no)
		(fp_line
			(start 0.7874 -0.4064)
			(end 0.7874 0.4064)
			(stroke
				(width 0.1524)
				(type default)
			)
			(layer "F.SilkS")
		)
		(fp_line
			(start -0.7874 -0.4064)
			(end 0.7874 -0.4064)
			(stroke
				(width 0.1524)
				(type default)
			)
			(layer "F.SilkS")
		)
		(fp_line
			(start 0.7874 0.4064)
			(end -0.7874 0.4064)
			(stroke
				(width 0.1524)
				(type default)
			)
			(layer "F.SilkS")
		)
		(fp_line
			(start -0.7874 0.4064)
			(end -0.7874 -0.4064)
			(stroke
				(width 0.1524)
				(type default)
			)
			(layer "F.SilkS")
		)
		(fp_poly
			(pts
				(xy -0.508 0.2794) (xy -0.508 0.2286) (xy -0.635 0.2286) (xy -0.635 -0.254) (xy -0.5334 -0.254)
				(xy -0.5334 -0.2794) (xy 0.5334 -0.2794) (xy 0.5334 -0.254) (xy 0.635 -0.254) (xy 0.635 0.254) (xy 0.5334 0.254)
				(xy 0.5334 0.2794)
			)
			(stroke
				(width 0)
				(type default)
			)
			(fill no)
			(layer "F.CrtYd")
		)
		(pad "1" smd rect
			(at 0.40005 0 90)
			(size 0.4572 0.508)
			(layers "F.Cu" "F.Mask" "F.Paste")
			(net "N52998343")
		)
		(pad "2" smd rect
			(at -0.40005 0 90)
			(size 0.4572 0.508)
			(layers "F.Cu" "F.Mask" "F.Paste")
			(net "P12V_AUX")
		)
	)
	(footprint ""
		(layer "F.Cu")
		(at 65.751202 -162.729926)
		(property "Reference" "Q35"
			(at 7.759446 1.055624 90)
			(unlocked yes)
			(layer "F.SilkS")
			(effects
				(font
					(size 0.7874 0.5842)
					(thickness 0.1524)
				)
			)
		)
		(property "Value" ""
			(at 0 0 0)
			(layer "F.Fab")
			(effects
				(font
					(size 1.27 1.27)
				)
			)
		)
		(duplicate_pad_numbers_are_jumpers no)
		(fp_line
			(start -0.100076 -0.525018)
			(end 1.044448 -0.525018)
			(stroke
				(width 0.1524)
				(type default)
			)
			(layer "F.SilkS")
		)
		(fp_line
			(start -0.100076 -0.320294)
			(end -0.100076 -0.525018)
			(stroke
				(width 0.1524)
				(type default)
			)
			(layer "F.SilkS")
		)
		(fp_line
			(start -0.100076 2.474976)
			(end -0.100076 2.295906)
			(stroke
				(width 0.1524)
				(type default)
			)
			(layer "F.SilkS")
		)
		(fp_line
			(start 1.044448 2.474976)
			(end -0.100076 2.474976)
			(stroke
				(width 0.1524)
				(type default)
			)
			(layer "F.SilkS")
		)
		(fp_line
			(start 1.755648 -0.525018)
			(end 2.899918 -0.525018)
			(stroke
				(width 0.1524)
				(type default)
			)
			(layer "F.SilkS")
		)
		(fp_line
			(start 2.899918 -0.525018)
			(end 2.899918 -0.345694)
			(stroke
				(width 0.1524)
				(type default)
			)
			(layer "F.SilkS")
		)
		(fp_line
			(start 2.899918 2.295906)
			(end 2.899918 2.474976)
			(stroke
				(width 0.1524)
				(type default)
			)
			(layer "F.SilkS")
		)
		(fp_line
			(start 2.899918 2.474976)
			(end 1.755648 2.474976)
			(stroke
				(width 0.1524)
				(type default)
			)
			(layer "F.SilkS")
		)
		(fp_poly
			(pts
				(xy -0.10795 -1.347724) (xy 0.410972 -1.347724) (xy 0.14732 -0.770382)
			)
			(stroke
				(width 0)
				(type default)
			)
			(fill yes)
			(layer "F.SilkS")
		)
		(fp_poly
			(pts
				(xy -0.100076 -0.525018) (xy -0.100076 -0.244094) (xy -0.301752 -0.244094) (xy -0.301752 2.194306)
				(xy -0.100076 2.194306) (xy -0.100076 2.474976) (xy 1.120648 2.474976) (xy 1.120648 2.651506) (xy 1.679448 2.651506)
				(xy 1.679448 2.474976) (xy 2.899918 2.474976) (xy 2.899918 2.219706) (xy 3.101848 2.219706) (xy 3.101848 -0.269494)
				(xy 2.899918 -0.269494) (xy 2.899918 -0.525018) (xy 1.679448 -0.525018) (xy 1.679448 -0.701294)
				(xy 1.120648 -0.701294) (xy 1.120648 -0.525018)
			)
			(stroke
				(width 0)
				(type default)
			)
			(fill no)
			(layer "F.CrtYd")
		)
		(fp_line
			(start -0.100076 -0.525018)
			(end 2.899918 -0.525018)
			(stroke
				(width 0.1)
				(type default)
			)
			(layer "F.Fab")
		)
		(fp_line
			(start -0.100076 2.474976)
			(end -0.100076 -0.525018)
			(stroke
				(width 0.1)
				(type default)
			)
			(layer "F.Fab")
		)
		(fp_line
			(start 2.899918 -0.525018)
			(end 2.899918 2.474976)
			(stroke
				(width 0.1)
				(type default)
			)
			(layer "F.Fab")
		)
		(fp_line
			(start 2.899918 2.474976)
			(end -0.100076 2.474976)
			(stroke
				(width 0.1)
				(type default)
			)
			(layer "F.Fab")
		)
		(pad "1" smd rect
			(at 0 0 270)
			(size 0.3556 0.508)
			(layers "F.Cu" "F.Mask" "F.Paste")
			(net "P5V_NODE1")
		)
		(pad "2" smd rect
			(at 0 0.649986 270)
			(size 0.3556 0.508)
			(layers "F.Cu" "F.Mask" "F.Paste")
			(net "P5V_NODE1")
		)
		(pad "3" smd rect
			(at 0 1.299972 270)
			(size 0.3556 0.508)
			(layers "F.Cu" "F.Mask" "F.Paste")
			(net "P5V_NODE1")
		)
		(pad "4" smd rect
			(at 0 1.949958 270)
			(size 0.3556 0.508)
			(layers "F.Cu" "F.Mask" "F.Paste")
			(net "FM_CPLD_NODE1_P5V_EN_LV")
		)
		(pad "5" smd custom
			(at 1.400048 0.975106 270)
			(size 0.569976 0.569976)
			(layers "F.Cu" "F.Mask" "F.Paste")
			(net "P5V_STB_NODE1")
			(options
				(clearance outline)
				(anchor circle)
			)
			(primitives
				(gr_poly
					(pts
						(xy -1.225042 1.139952) (xy -1.225042 0.724916) (xy -1.605026 0.724916) (xy -1.605026 0.295148)
						(xy -1.225042 0.295148) (xy -1.225042 -0.839978) (xy -1.175004 -0.839978) (xy -1.175004 -1.139952)
						(xy -0.774954 -1.139952) (xy -0.774954 -0.839978) (xy -0.525018 -0.839978) (xy -0.525018 -1.139952)
						(xy -0.124968 -1.139952) (xy -0.124968 -0.839978) (xy 0.124968 -0.839978) (xy 0.124968 -1.139952)
						(xy 0.525018 -1.139952) (xy 0.525018 -0.839978) (xy 0.774954 -0.839978) (xy 0.774954 -1.139952)
						(xy 1.175004 -1.139952) (xy 1.175004 -0.839978) (xy 1.225042 -0.839978) (xy 1.225042 0.295148)
						(xy 1.605026 0.295148) (xy 1.605026 0.724916) (xy 1.225042 0.724916) (xy 1.225042 1.139952)
					)
					(width 0)
					(fill yes)
				)
			)
		)
		(zone
			(layer "F.Cu")
			(hatch none 0.5)
			(connect_pads
				(clearance 0)
			)
			(min_thickness 0.25)
			(keepout
				(tracks not_allowed)
				(vias allowed)
				(pads allowed)
				(copperpour not_allowed)
				(footprints allowed)
			)
			(placement
				(enabled no)
				(sheetname "")
			)
			(fill
				(thermal_gap 0.5)
				(thermal_bridge_width 0.5)
				(island_removal_mode 0)
			)
			(polygon
				(pts
					(xy 66.08445 -163.25342) (xy 66.08445 -160.25622) (xy 66.46545 -160.25622) (xy 66.46545 -163.25342)
				)
			)
		)
		(zone
			(layer "F.Cu")
			(hatch none 0.5)
			(connect_pads
				(clearance 0)
			)
			(min_thickness 0.25)
			(keepout
				(tracks allowed)
				(vias not_allowed)
				(pads allowed)
				(copperpour not_allowed)
				(footprints allowed)
			)
			(placement
				(enabled no)
				(sheetname "")
			)
			(fill
				(thermal_gap 0.5)
				(thermal_bridge_width 0.5)
				(island_removal_mode 0)
			)
			(polygon
				(pts
					(xy 66.46545 -163.25342) (xy 66.46545 -160.25622) (xy 66.08445 -160.25622) (xy 66.08445 -163.25342)
				)
			)
		)
	)
	(footprint ""
		(layer "F.Cu")
		(at 62.028324 -98.542856 180)
		(property "Reference" "R1093"
			(at -24.628094 -53.301646 0)
			(unlocked yes)
			(layer "F.SilkS")
			(effects
				(font
					(size 0.7874 0.5842)
					(thickness 0.1524)
				)
				(justify left)
			)
		)
		(property "Value" ""
			(at 0 0 180)
			(layer "F.Fab")
			(effects
				(font
					(size 1.27 1.27)
				)
			)
		)
		(duplicate_pad_numbers_are_jumpers no)
		(fp_line
			(start 0.7874 0.4064)
			(end -0.7874 0.4064)
			(stroke
				(width 0.1524)
				(type default)
			)
			(layer "F.SilkS")
		)
		(fp_line
			(start 0.7874 -0.4064)
			(end 0.7874 0.4064)
			(stroke
				(width 0.1524)
				(type default)
			)
			(layer "F.SilkS")
		)
		(fp_line
			(start -0.7874 0.4064)
			(end -0.7874 -0.4064)
			(stroke
				(width 0.1524)
				(type default)
			)
			(layer "F.SilkS")
		)
		(fp_line
			(start -0.7874 -0.4064)
			(end 0.7874 -0.4064)
			(stroke
				(width 0.1524)
				(type default)
			)
			(layer "F.SilkS")
		)
		(fp_poly
			(pts
				(xy -0.508 0.2794) (xy -0.508 0.2286) (xy -0.635 0.2286) (xy -0.635 -0.254) (xy -0.5334 -0.254)
				(xy -0.5334 -0.2794) (xy 0.5334 -0.2794) (xy 0.5334 -0.254) (xy 0.635 -0.254) (xy 0.635 0.254) (xy 0.5334 0.254)
				(xy 0.5334 0.2794)
			)
			(stroke
				(width 0)
				(type default)
			)
			(fill no)
			(layer "F.CrtYd")
		)
		(pad "1" smd rect
			(at 0.40005 0 180)
			(size 0.4572 0.508)
			(layers "F.Cu" "F.Mask" "F.Paste")
			(net "GND")
		)
		(pad "2" smd rect
			(at -0.40005 0 180)
			(size 0.4572 0.508)
			(layers "F.Cu" "F.Mask" "F.Paste")
			(net "P1V8_SUS_NODE1")
		)
	)
	(footprint ""
		(layer "F.Cu")
		(at 90.814398 -176.562512 180)
		(property "Reference" "R1178"
			(at -85.972142 -76.337414 0)
			(unlocked yes)
			(layer "F.SilkS")
			(effects
				(font
					(size 0.7874 0.5842)
					(thickness 0.1524)
				)
				(justify left)
			)
		)
		(property "Value" ""
			(at 0 0 180)
			(layer "F.Fab")
			(effects
				(font
					(size 1.27 1.27)
				)
			)
		)
		(duplicate_pad_numbers_are_jumpers no)
		(fp_line
			(start 0.7874 0.4064)
			(end -0.7874 0.4064)
			(stroke
				(width 0.1524)
				(type default)
			)
			(layer "F.SilkS")
		)
		(fp_line
			(start 0.7874 -0.4064)
			(end 0.7874 0.4064)
			(stroke
				(width 0.1524)
				(type default)
			)
			(layer "F.SilkS")
		)
		(fp_line
			(start -0.7874 0.4064)
			(end -0.7874 -0.4064)
			(stroke
				(width 0.1524)
				(type default)
			)
			(layer "F.SilkS")
		)
		(fp_line
			(start -0.7874 -0.4064)
			(end 0.7874 -0.4064)
			(stroke
				(width 0.1524)
				(type default)
			)
			(layer "F.SilkS")
		)
		(fp_poly
			(pts
				(xy -0.508 0.2794) (xy -0.508 0.2286) (xy -0.635 0.2286) (xy -0.635 -0.254) (xy -0.5334 -0.254)
				(xy -0.5334 -0.2794) (xy 0.5334 -0.2794) (xy 0.5334 -0.254) (xy 0.635 -0.254) (xy 0.635 0.254) (xy 0.5334 0.254)
				(xy 0.5334 0.2794)
			)
			(stroke
				(width 0)
				(type default)
			)
			(fill no)
			(layer "F.CrtYd")
		)
		(pad "1" smd rect
			(at 0.40005 0 180)
			(size 0.4572 0.508)
			(layers "F.Cu" "F.Mask" "F.Paste")
			(net "CPLD_UART_RTS_P4_N")
		)
		(pad "2" smd rect
			(at -0.40005 0 180)
			(size 0.4572 0.508)
			(layers "F.Cu" "F.Mask" "F.Paste")
			(net "GND")
		)
	)
	(footprint ""
		(layer "F.Cu")
		(at 113.730532 -132.012944 90)
		(property "Reference" "PR58"
			(at -0.690372 5.281676 90)
			(unlocked yes)
			(layer "F.SilkS")
			(effects
				(font
					(size 0.7874 0.5842)
					(thickness 0.1524)
				)
				(justify left)
			)
		)
		(property "Value" ""
			(at 0 0 90)
			(layer "F.Fab")
			(effects
				(font
					(size 1.27 1.27)
				)
			)
		)
		(duplicate_pad_numbers_are_jumpers no)
		(fp_line
			(start 0.7874 -0.4064)
			(end 0.7874 0.4064)
			(stroke
				(width 0.1524)
				(type default)
			)
			(layer "F.SilkS")
		)
		(fp_line
			(start -0.7874 -0.4064)
			(end 0.7874 -0.4064)
			(stroke
				(width 0.1524)
				(type default)
			)
			(layer "F.SilkS")
		)
		(fp_line
			(start 0.7874 0.4064)
			(end -0.7874 0.4064)
			(stroke
				(width 0.1524)
				(type default)
			)
			(layer "F.SilkS")
		)
		(fp_line
			(start -0.7874 0.4064)
			(end -0.7874 -0.4064)
			(stroke
				(width 0.1524)
				(type default)
			)
			(layer "F.SilkS")
		)
		(fp_poly
			(pts
				(xy -0.508 0.2794) (xy -0.508 0.2286) (xy -0.635 0.2286) (xy -0.635 -0.254) (xy -0.5334 -0.254)
				(xy -0.5334 -0.2794) (xy 0.5334 -0.2794) (xy 0.5334 -0.254) (xy 0.635 -0.254) (xy 0.635 0.254) (xy 0.5334 0.254)
				(xy 0.5334 0.2794)
			)
			(stroke
				(width 0)
				(type default)
			)
			(fill no)
			(layer "F.CrtYd")
		)
		(pad "1" smd rect
			(at 0.40005 0 90)
			(size 0.4572 0.508)
			(layers "F.Cu" "F.Mask" "F.Paste")
			(net "VR_PVCCP_NODE1_ISEN1P_CC")
		)
		(pad "2" smd rect
			(at -0.40005 0 90)
			(size 0.4572 0.508)
			(layers "F.Cu" "F.Mask" "F.Paste")
			(net "VR_PVCCP_NODE1_ISEN1P_RR")
		)
	)
	(footprint ""
		(layer "F.Cu")
		(at 94.211394 -186.806586)
		(property "Reference" "R905"
			(at -1.182878 -7.236714 0)
			(unlocked yes)
			(layer "F.SilkS")
			(effects
				(font
					(size 0.7874 0.5842)
					(thickness 0.1524)
				)
				(justify left)
			)
		)
		(property "Value" ""
			(at 0 0 0)
			(layer "F.Fab")
			(effects
				(font
					(size 1.27 1.27)
				)
			)
		)
		(duplicate_pad_numbers_are_jumpers no)
		(fp_line
			(start -0.7874 -0.4064)
			(end 0.7874 -0.4064)
			(stroke
				(width 0.1524)
				(type default)
			)
			(layer "F.SilkS")
		)
		(fp_line
			(start -0.7874 0.4064)
			(end -0.7874 -0.4064)
			(stroke
				(width 0.1524)
				(type default)
			)
			(layer "F.SilkS")
		)
		(fp_line
			(start 0.7874 -0.4064)
			(end 0.7874 0.4064)
			(stroke
				(width 0.1524)
				(type default)
			)
			(layer "F.SilkS")
		)
		(fp_line
			(start 0.7874 0.4064)
			(end -0.7874 0.4064)
			(stroke
				(width 0.1524)
				(type default)
			)
			(layer "F.SilkS")
		)
		(fp_poly
			(pts
				(xy -0.508 0.2794) (xy -0.508 0.2286) (xy -0.635 0.2286) (xy -0.635 -0.254) (xy -0.5334 -0.254)
				(xy -0.5334 -0.2794) (xy 0.5334 -0.2794) (xy 0.5334 -0.254) (xy 0.635 -0.254) (xy 0.635 0.254) (xy 0.5334 0.254)
				(xy 0.5334 0.2794)
			)
			(stroke
				(width 0)
				(type default)
			)
			(fill no)
			(layer "F.CrtYd")
		)
		(pad "1" smd rect
			(at 0.40005 0)
			(size 0.4572 0.508)
			(layers "F.Cu" "F.Mask" "F.Paste")
			(net "T5_NODE4_EN")
		)
		(pad "2" smd rect
			(at -0.40005 0)
			(size 0.4572 0.508)
			(layers "F.Cu" "F.Mask" "F.Paste")
			(net "T5_NODE4_EN_R")
		)
	)
	(footprint ""
		(layer "F.Cu")
		(at 84.458048 -128.998726 -90)
		(property "Reference" "R1253"
			(at 5.940044 4.586224 90)
			(unlocked yes)
			(layer "F.SilkS")
			(effects
				(font
					(size 0.7874 0.5842)
					(thickness 0.1524)
				)
				(justify left)
			)
		)
		(property "Value" ""
			(at 0 0 270)
			(layer "F.Fab")
			(effects
				(font
					(size 1.27 1.27)
				)
			)
		)
		(duplicate_pad_numbers_are_jumpers no)
		(fp_line
			(start -0.7874 0.4064)
			(end -0.7874 -0.4064)
			(stroke
				(width 0.1524)
				(type default)
			)
			(layer "F.SilkS")
		)
		(fp_line
			(start 0.7874 0.4064)
			(end -0.7874 0.4064)
			(stroke
				(width 0.1524)
				(type default)
			)
			(layer "F.SilkS")
		)
		(fp_line
			(start -0.7874 -0.4064)
			(end 0.7874 -0.4064)
			(stroke
				(width 0.1524)
				(type default)
			)
			(layer "F.SilkS")
		)
		(fp_line
			(start 0.7874 -0.4064)
			(end 0.7874 0.4064)
			(stroke
				(width 0.1524)
				(type default)
			)
			(layer "F.SilkS")
		)
		(fp_poly
			(pts
				(xy -0.508 0.2794) (xy -0.508 0.2286) (xy -0.635 0.2286) (xy -0.635 -0.254) (xy -0.5334 -0.254)
				(xy -0.5334 -0.2794) (xy 0.5334 -0.2794) (xy 0.5334 -0.254) (xy 0.635 -0.254) (xy 0.635 0.254) (xy 0.5334 0.254)
				(xy 0.5334 0.2794)
			)
			(stroke
				(width 0)
				(type default)
			)
			(fill no)
			(layer "F.CrtYd")
		)
		(pad "1" smd rect
			(at 0.40005 0 270)
			(size 0.4572 0.508)
			(layers "F.Cu" "F.Mask" "F.Paste")
			(net "PORT80_LOUT1")
		)
		(pad "2" smd rect
			(at -0.40005 0 270)
			(size 0.4572 0.508)
			(layers "F.Cu" "F.Mask" "F.Paste")
			(net "N53313464")
		)
	)
	(footprint ""
		(layer "F.Cu")
		(at 94.451932 -176.338992)
		(property "Reference" "R738"
			(at 86.67369 74.174096 0)
			(unlocked yes)
			(layer "F.SilkS")
			(effects
				(font
					(size 0.7874 0.5842)
					(thickness 0.1524)
				)
				(justify left)
			)
		)
		(property "Value" ""
			(at 0 0 0)
			(layer "F.Fab")
			(effects
				(font
					(size 1.27 1.27)
				)
			)
		)
		(duplicate_pad_numbers_are_jumpers no)
		(fp_line
			(start -0.7874 -0.4064)
			(end 0.7874 -0.4064)
			(stroke
				(width 0.1524)
				(type default)
			)
			(layer "F.SilkS")
		)
		(fp_line
			(start -0.7874 0.4064)
			(end -0.7874 -0.4064)
			(stroke
				(width 0.1524)
				(type default)
			)
			(layer "F.SilkS")
		)
		(fp_line
			(start 0.7874 -0.4064)
			(end 0.7874 0.4064)
			(stroke
				(width 0.1524)
				(type default)
			)
			(layer "F.SilkS")
		)
		(fp_line
			(start 0.7874 0.4064)
			(end -0.7874 0.4064)
			(stroke
				(width 0.1524)
				(type default)
			)
			(layer "F.SilkS")
		)
		(fp_poly
			(pts
				(xy -0.508 0.2794) (xy -0.508 0.2286) (xy -0.635 0.2286) (xy -0.635 -0.254) (xy -0.5334 -0.254)
				(xy -0.5334 -0.2794) (xy 0.5334 -0.2794) (xy 0.5334 -0.254) (xy 0.635 -0.254) (xy 0.635 0.254) (xy 0.5334 0.254)
				(xy 0.5334 0.2794)
			)
			(stroke
				(width 0)
				(type default)
			)
			(fill no)
			(layer "F.CrtYd")
		)
		(pad "1" smd rect
			(at 0.40005 0)
			(size 0.4572 0.508)
			(layers "F.Cu" "F.Mask" "F.Paste")
			(net "N21698939")
		)
		(pad "2" smd rect
			(at -0.40005 0)
			(size 0.4572 0.508)
			(layers "F.Cu" "F.Mask" "F.Paste")
			(net "P3V3_NODE1")
		)
	)
	(footprint ""
		(layer "F.Cu")
		(at 109.291374 -160.395158 90)
		(property "Reference" "U126"
			(at -69.92493 88.239346 0)
			(unlocked yes)
			(layer "F.SilkS")
			(effects
				(font
					(size 0.7874 0.5842)
					(thickness 0.1524)
				)
			)
		)
		(property "Value" ""
			(at 0 0 90)
			(layer "F.Fab")
			(effects
				(font
					(size 1.27 1.27)
				)
			)
		)
		(duplicate_pad_numbers_are_jumpers no)
		(fp_line
			(start 1.651 -1.905)
			(end 1.651 1.905)
			(stroke
				(width 0.1524)
				(type default)
			)
			(layer "F.SilkS")
		)
		(fp_line
			(start -1.651 -1.905)
			(end 1.651 -1.905)
			(stroke
				(width 0.1524)
				(type default)
			)
			(layer "F.SilkS")
		)
		(fp_line
			(start 1.651 1.905)
			(end -1.651 1.905)
			(stroke
				(width 0.1524)
				(type default)
			)
			(layer "F.SilkS")
		)
		(fp_line
			(start -1.651 1.905)
			(end -1.651 -1.905)
			(stroke
				(width 0.1524)
				(type default)
			)
			(layer "F.SilkS")
		)
		(fp_poly
			(pts
				(xy -1.524 0.7112) (xy -1.524 1.7526) (xy -0.508 1.7526) (xy -0.508 0.6985) (xy 0.508 0.6985) (xy 0.508 1.7526)
				(xy 1.524 1.7526) (xy 1.524 0.6985) (xy 1.524 -0.6985) (xy 0.508 -0.6985) (xy 0.508 -1.7526) (xy -0.508 -1.7526)
				(xy -0.508 -0.6985) (xy -1.524 -0.6985) (xy -1.524 0.6985)
			)
			(stroke
				(width 0)
				(type default)
			)
			(fill no)
			(layer "F.CrtYd")
		)
		(fp_text user "D"
			(at 1.691386 -2.260092 0)
			(unlocked yes)
			(layer "F.SilkS")
			(effects
				(font
					(size 0.635 0.4064)
					(thickness 0.1524)
				)
			)
		)
		(fp_text user "G"
			(at -1.093978 0.053086 0)
			(unlocked yes)
			(layer "F.SilkS")
			(effects
				(font
					(size 0.635 0.4064)
					(thickness 0.1524)
				)
			)
		)
		(fp_text user "S"
			(at 1.208532 2.574036 0)
			(unlocked yes)
			(layer "F.SilkS")
			(effects
				(font
					(size 0.635 0.4064)
					(thickness 0.1524)
				)
			)
		)
		(pad "D" smd rect
			(at 0 -1.1176 90)
			(size 1.016 1.27)
			(layers "F.Cu" "F.Mask" "F.Paste")
			(net "I2C_PSU2_SCL")
		)
		(pad "G" smd rect
			(at -1.016 1.1176 90)
			(size 1.016 1.27)
			(layers "F.Cu" "F.Mask" "F.Paste")
			(net "PMBUS2_EN")
		)
		(pad "S" smd rect
			(at 1.016 1.1176 90)
			(size 1.016 1.27)
			(layers "F.Cu" "F.Mask" "F.Paste")
			(net "I2C_PSU2_SCL_MOS")
		)
	)
	(footprint ""
		(layer "F.Cu")
		(at 93.854778 -117.955314 -90)
		(property "Reference" "TP173"
			(at 0 0 270)
			(layer "F.SilkS")
			(hide yes)
			(effects
				(font
					(size 1.27 1.27)
				)
			)
		)
		(property "Value" ""
			(at 0 0 270)
			(layer "F.Fab")
			(effects
				(font
					(size 1.27 1.27)
				)
			)
		)
		(duplicate_pad_numbers_are_jumpers no)
		(fp_poly
			(pts
				(arc
					(start 0 0.3302)
					(mid 0 -0.3302)
					(end 0 0.3302)
				)
			)
			(stroke
				(width 0)
				(type default)
			)
			(fill no)
			(layer "B.CrtYd")
		)
		(pad "1" thru_hole circle
			(at 0 0 270)
			(size 0.508 0.508)
			(drill 0.254)
			(layers "*.Cu" "*.Mask")
			(remove_unused_layers no)
			(net "N53313289")
			(clearance 0.127)
			(thermal_gap 0.127)
			(padstack
				(mode front_inner_back)
				(layer "Inner"
					(shape circle)
					(size 0.508 0.508)
					(clearance 0.127)
				)
				(layer "B.Cu"
					(shape circle)
					(size 0.6604 0.6604)
					(clearance 0.0508)
				)
			)
		)
	)
	(footprint ""
		(layer "F.Cu")
		(at 104.514142 -158.277052 90)
		(property "Reference" "PR13"
			(at -1.761998 2.672588 90)
			(unlocked yes)
			(layer "F.SilkS")
			(effects
				(font
					(size 0.635 0.4064)
					(thickness 0.1524)
				)
				(justify left)
			)
		)
		(property "Value" ""
			(at 0 0 90)
			(layer "F.Fab")
			(effects
				(font
					(size 1.27 1.27)
				)
			)
		)
		(duplicate_pad_numbers_are_jumpers no)
		(fp_line
			(start 0.7874 -0.4064)
			(end 0.7874 0.4064)
			(stroke
				(width 0.1524)
				(type default)
			)
			(layer "F.SilkS")
		)
		(fp_line
			(start -0.7874 -0.4064)
			(end 0.7874 -0.4064)
			(stroke
				(width 0.1524)
				(type default)
			)
			(layer "F.SilkS")
		)
		(fp_line
			(start 0.7874 0.4064)
			(end -0.7874 0.4064)
			(stroke
				(width 0.1524)
				(type default)
			)
			(layer "F.SilkS")
		)
		(fp_line
			(start -0.7874 0.4064)
			(end -0.7874 -0.4064)
			(stroke
				(width 0.1524)
				(type default)
			)
			(layer "F.SilkS")
		)
		(fp_poly
			(pts
				(xy -0.508 0.2794) (xy -0.508 0.2286) (xy -0.635 0.2286) (xy -0.635 -0.254) (xy -0.5334 -0.254)
				(xy -0.5334 -0.2794) (xy 0.5334 -0.2794) (xy 0.5334 -0.254) (xy 0.635 -0.254) (xy 0.635 0.254) (xy 0.5334 0.254)
				(xy 0.5334 0.2794)
			)
			(stroke
				(width 0)
				(type default)
			)
			(fill no)
			(layer "F.CrtYd")
		)
		(pad "1" smd rect
			(at 0.40005 0 90)
			(size 0.4572 0.508)
			(layers "F.Cu" "F.Mask" "F.Paste")
			(net "P1V8_STB_NODE1_VREG5")
		)
		(pad "2" smd rect
			(at -0.40005 0 90)
			(size 0.4572 0.508)
			(layers "F.Cu" "F.Mask" "F.Paste")
			(net "PWRGD_NODE1_P1V8_STB_PG")
		)
	)
	(footprint ""
		(layer "F.Cu")
		(at 29.050488 -130.589782 90)
		(property "Reference" "C834"
			(at -0.586486 -2.10439 90)
			(unlocked yes)
			(layer "F.SilkS")
			(effects
				(font
					(size 0.7874 0.5842)
					(thickness 0.1524)
				)
				(justify left)
			)
		)
		(property "Value" ""
			(at 0 0 90)
			(layer "F.Fab")
			(effects
				(font
					(size 1.27 1.27)
				)
			)
		)
		(duplicate_pad_numbers_are_jumpers no)
		(fp_line
			(start 0.7874 -0.4064)
			(end 0.7874 0.4064)
			(stroke
				(width 0.1524)
				(type default)
			)
			(layer "F.SilkS")
		)
		(fp_line
			(start -0.7874 -0.4064)
			(end 0.7874 -0.4064)
			(stroke
				(width 0.1524)
				(type default)
			)
			(layer "F.SilkS")
		)
		(fp_line
			(start 0 0.381)
			(end 0 -0.381)
			(stroke
				(width 0.1524)
				(type default)
			)
			(layer "F.SilkS")
		)
		(fp_line
			(start 0.7874 0.4064)
			(end -0.7874 0.4064)
			(stroke
				(width 0.1524)
				(type default)
			)
			(layer "F.SilkS")
		)
		(fp_line
			(start -0.7874 0.4064)
			(end -0.7874 -0.4064)
			(stroke
				(width 0.1524)
				(type default)
			)
			(layer "F.SilkS")
		)
		(fp_poly
			(pts
				(xy -0.5334 0.254) (xy -0.635 0.254) (xy -0.635 0.2286) (xy -0.635 -0.254) (xy -0.5334 -0.254) (xy -0.5334 -0.2794)
				(xy 0.5334 -0.2794) (xy 0.5334 -0.254) (xy 0.635 -0.254) (xy 0.635 0.254) (xy 0.5334 0.254) (xy 0.5334 0.2794)
				(xy -0.508 0.2794) (xy -0.5334 0.2794)
			)
			(stroke
				(width 0)
				(type default)
			)
			(fill no)
			(layer "F.CrtYd")
		)
		(pad "1" smd rect
			(at 0.40005 0 90)
			(size 0.4572 0.508)
			(layers "F.Cu" "F.Mask" "F.Paste")
			(net "GND")
		)
		(pad "2" smd rect
			(at -0.40005 0 90)
			(size 0.4572 0.508)
			(layers "F.Cu" "F.Mask" "F.Paste")
			(net "PWRGD_NODE1_P1V538_BMC_PG")
		)
	)
	(footprint ""
		(layer "F.Cu")
		(at 165.811454 -163.848288)
		(property "Reference" "R577"
			(at 1.22936 0.186182 0)
			(unlocked yes)
			(layer "F.SilkS")
			(effects
				(font
					(size 0.7874 0.5842)
					(thickness 0.1524)
				)
				(justify left)
			)
		)
		(property "Value" ""
			(at 0 0 0)
			(layer "F.Fab")
			(effects
				(font
					(size 1.27 1.27)
				)
			)
		)
		(duplicate_pad_numbers_are_jumpers no)
		(fp_line
			(start -0.7874 -0.4064)
			(end 0.7874 -0.4064)
			(stroke
				(width 0.1524)
				(type default)
			)
			(layer "F.SilkS")
		)
		(fp_line
			(start -0.7874 0.4064)
			(end -0.7874 -0.4064)
			(stroke
				(width 0.1524)
				(type default)
			)
			(layer "F.SilkS")
		)
		(fp_line
			(start 0.7874 -0.4064)
			(end 0.7874 0.4064)
			(stroke
				(width 0.1524)
				(type default)
			)
			(layer "F.SilkS")
		)
		(fp_line
			(start 0.7874 0.4064)
			(end -0.7874 0.4064)
			(stroke
				(width 0.1524)
				(type default)
			)
			(layer "F.SilkS")
		)
		(fp_poly
			(pts
				(xy -0.508 0.2794) (xy -0.508 0.2286) (xy -0.635 0.2286) (xy -0.635 -0.254) (xy -0.5334 -0.254)
				(xy -0.5334 -0.2794) (xy 0.5334 -0.2794) (xy 0.5334 -0.254) (xy 0.635 -0.254) (xy 0.635 0.254) (xy 0.5334 0.254)
				(xy 0.5334 0.2794)
			)
			(stroke
				(width 0)
				(type default)
			)
			(fill no)
			(layer "F.CrtYd")
		)
		(pad "1" smd rect
			(at 0.40005 0)
			(size 0.4572 0.508)
			(layers "F.Cu" "F.Mask" "F.Paste")
			(net "SPI_LAN2_NVM_SI")
		)
		(pad "2" smd rect
			(at -0.40005 0)
			(size 0.4572 0.508)
			(layers "F.Cu" "F.Mask" "F.Paste")
			(net "LAN2_NVM_SI_R")
		)
	)
	(footprint ""
		(layer "F.Cu")
		(at 67.67576 -188.126624 90)
		(property "Reference" "C637"
			(at 4.548886 -0.5842 90)
			(unlocked yes)
			(layer "F.SilkS")
			(effects
				(font
					(size 0.7874 0.5842)
					(thickness 0.1524)
				)
				(justify left)
			)
		)
		(property "Value" ""
			(at 0 0 90)
			(layer "F.Fab")
			(effects
				(font
					(size 1.27 1.27)
				)
			)
		)
		(duplicate_pad_numbers_are_jumpers no)
		(fp_line
			(start 0.7874 -0.4064)
			(end 0.7874 0.4064)
			(stroke
				(width 0.1524)
				(type default)
			)
			(layer "F.SilkS")
		)
		(fp_line
			(start -0.7874 -0.4064)
			(end 0.7874 -0.4064)
			(stroke
				(width 0.1524)
				(type default)
			)
			(layer "F.SilkS")
		)
		(fp_line
			(start 0 0.381)
			(end 0 -0.381)
			(stroke
				(width 0.1524)
				(type default)
			)
			(layer "F.SilkS")
		)
		(fp_line
			(start 0.7874 0.4064)
			(end -0.7874 0.4064)
			(stroke
				(width 0.1524)
				(type default)
			)
			(layer "F.SilkS")
		)
		(fp_line
			(start -0.7874 0.4064)
			(end -0.7874 -0.4064)
			(stroke
				(width 0.1524)
				(type default)
			)
			(layer "F.SilkS")
		)
		(fp_poly
			(pts
				(xy -0.5334 0.254) (xy -0.635 0.254) (xy -0.635 0.2286) (xy -0.635 -0.254) (xy -0.5334 -0.254) (xy -0.5334 -0.2794)
				(xy 0.5334 -0.2794) (xy 0.5334 -0.254) (xy 0.635 -0.254) (xy 0.635 0.254) (xy 0.5334 0.254) (xy 0.5334 0.2794)
				(xy -0.508 0.2794) (xy -0.5334 0.2794)
			)
			(stroke
				(width 0)
				(type default)
			)
			(fill no)
			(layer "F.CrtYd")
		)
		(pad "1" smd rect
			(at 0.40005 0 90)
			(size 0.4572 0.508)
			(layers "F.Cu" "F.Mask" "F.Paste")
			(net "T2_NODE2_EN_R")
		)
		(pad "2" smd rect
			(at -0.40005 0 90)
			(size 0.4572 0.508)
			(layers "F.Cu" "F.Mask" "F.Paste")
			(net "GND")
		)
	)
	(footprint ""
		(layer "F.Cu")
		(at 162.296602 -175.827436 90)
		(property "Reference" "U57"
			(at -5.918708 -0.275082 0)
			(unlocked yes)
			(layer "F.SilkS")
			(effects
				(font
					(size 0.7874 0.5842)
					(thickness 0.1524)
				)
				(justify left)
			)
		)
		(property "Value" ""
			(at 0 0 90)
			(layer "F.Fab")
			(effects
				(font
					(size 1.27 1.27)
				)
			)
		)
		(duplicate_pad_numbers_are_jumpers no)
		(fp_line
			(start 4.9022 -2.0066)
			(end 4.9022 2.0066)
			(stroke
				(width 0.1524)
				(type default)
			)
			(layer "F.SilkS")
		)
		(fp_line
			(start -4.9022 -2.0066)
			(end 4.9022 -2.0066)
			(stroke
				(width 0.1524)
				(type default)
			)
			(layer "F.SilkS")
		)
		(fp_line
			(start -4.9022 -0.5842)
			(end -4.9022 -2.0066)
			(stroke
				(width 0.1524)
				(type default)
			)
			(layer "F.SilkS")
		)
		(fp_line
			(start -4.318 0)
			(end -4.9022 -0.5842)
			(stroke
				(width 0.1524)
				(type default)
			)
			(layer "F.SilkS")
		)
		(fp_line
			(start -4.9022 0.5842)
			(end -4.318 0)
			(stroke
				(width 0.1524)
				(type default)
			)
			(layer "F.SilkS")
		)
		(fp_line
			(start 4.9022 2.0066)
			(end -4.9022 2.0066)
			(stroke
				(width 0.1524)
				(type default)
			)
			(layer "F.SilkS")
		)
		(fp_line
			(start -4.9022 2.0066)
			(end -4.9022 0.5842)
			(stroke
				(width 0.1524)
				(type default)
			)
			(layer "F.SilkS")
		)
		(fp_circle
			(center -4.318 1.524)
			(end -4.318 1.778)
			(stroke
				(width 0.1524)
				(type default)
			)
			(fill no)
			(layer "F.SilkS")
		)
		(fp_rect
			(start -4.9022 3.6703)
			(end 4.9022 -3.6703)
			(stroke
				(width 0)
				(type default)
			)
			(fill no)
			(layer "F.CrtYd")
		)
		(pad "1" smd rect
			(at -4.225036 2.921 90)
			(size 0.3556 1.4986)
			(layers "F.Cu" "F.Mask" "F.Paste")
			(net "N54365611")
		)
		(pad "2" smd rect
			(at -3.57505 2.921 90)
			(size 0.3556 1.4986)
			(layers "F.Cu" "F.Mask" "F.Paste")
			(net "N54365613")
		)
		(pad "3" smd rect
			(at -2.925064 2.921 90)
			(size 0.3556 1.4986)
			(layers "F.Cu" "F.Mask" "F.Paste")
			(net "N54365625")
		)
		(pad "4" smd rect
			(at -2.275078 2.921 90)
			(size 0.3556 1.4986)
			(layers "F.Cu" "F.Mask" "F.Paste")
			(net "UART_RX_RP5_L")
		)
		(pad "5" smd rect
			(at -1.625092 2.921 90)
			(size 0.3556 1.4986)
			(layers "F.Cu" "F.Mask" "F.Paste")
			(net "UART_RI_RP5_L_N")
		)
		(pad "6" smd rect
			(at -0.975106 2.921 90)
			(size 0.3556 1.4986)
			(layers "F.Cu" "F.Mask" "F.Paste")
			(net "N54365542")
		)
		(pad "7" smd rect
			(at -0.32512 2.921 90)
			(size 0.3556 1.4986)
			(layers "F.Cu" "F.Mask" "F.Paste")
			(net "N54365542")
		)
		(pad "8" smd rect
			(at 0.32512 2.921 90)
			(size 0.3556 1.4986)
			(layers "F.Cu" "F.Mask" "F.Paste")
			(net "N54365542")
		)
		(pad "9" smd rect
			(at 0.975106 2.921 90)
			(size 0.3556 1.4986)
			(layers "F.Cu" "F.Mask" "F.Paste")
			(net "UART_RTS_RP5_L_N")
		)
		(pad "10" smd rect
			(at 1.625092 2.921 90)
			(size 0.3556 1.4986)
			(layers "F.Cu" "F.Mask" "F.Paste")
			(net "UART_TX_RP5_L")
		)
		(pad "11" smd rect
			(at 2.275078 2.921 90)
			(size 0.3556 1.4986)
			(layers "F.Cu" "F.Mask" "F.Paste")
			(net "UART_DTR_RP5_L_N")
		)
		(pad "12" smd rect
			(at 2.925064 2.921 90)
			(size 0.3556 1.4986)
			(layers "F.Cu" "F.Mask" "F.Paste")
			(net "CPLD_UART_DTR_P3_R_N")
		)
		(pad "13" smd rect
			(at 3.57505 2.921 90)
			(size 0.3556 1.4986)
			(layers "F.Cu" "F.Mask" "F.Paste")
			(net "CPLD_UART_TX_P3")
		)
		(pad "14" smd rect
			(at 4.225036 2.921 90)
			(size 0.3556 1.4986)
			(layers "F.Cu" "F.Mask" "F.Paste")
			(net "CPLD_UART_RTS_P3_R_N")
		)
		(pad "15" smd rect
			(at 4.225036 -2.921 90)
			(size 0.3556 1.4986)
			(layers "F.Cu" "F.Mask" "F.Paste")
			(net "Net_2298")
		)
		(pad "16" smd rect
			(at 3.57505 -2.921 90)
			(size 0.3556 1.4986)
			(layers "F.Cu" "F.Mask" "F.Paste")
			(net "Net_2299")
		)
		(pad "17" smd rect
			(at 2.925064 -2.921 90)
			(size 0.3556 1.4986)
			(layers "F.Cu" "F.Mask" "F.Paste")
			(net "Net_2300")
		)
		(pad "18" smd rect
			(at 2.275078 -2.921 90)
			(size 0.3556 1.4986)
			(layers "F.Cu" "F.Mask" "F.Paste")
			(net "CPLD_UART_RI_P3_LS_N")
		)
		(pad "19" smd rect
			(at 1.625092 -2.921 90)
			(size 0.3556 1.4986)
			(layers "F.Cu" "F.Mask" "F.Paste")
			(net "CPLD_UART_RX_P3_R")
		)
		(pad "20" smd rect
			(at 0.975106 -2.921 90)
			(size 0.3556 1.4986)
			(layers "F.Cu" "F.Mask" "F.Paste")
			(net "Net_2301")
		)
		(pad "21" smd rect
			(at 0.32512 -2.921 90)
			(size 0.3556 1.4986)
			(layers "F.Cu" "F.Mask" "F.Paste")
			(net "Net_2302")
		)
		(pad "22" smd rect
			(at -0.32512 -2.921 90)
			(size 0.3556 1.4986)
			(layers "F.Cu" "F.Mask" "F.Paste")
			(net "N54365556")
		)
		(pad "23" smd rect
			(at -0.975106 -2.921 90)
			(size 0.3556 1.4986)
			(layers "F.Cu" "F.Mask" "F.Paste")
			(net "N54365554")
		)
		(pad "24" smd rect
			(at -1.625092 -2.921 90)
			(size 0.3556 1.4986)
			(layers "F.Cu" "F.Mask" "F.Paste")
			(net "N54365603")
		)
		(pad "25" smd rect
			(at -2.275078 -2.921 90)
			(size 0.3556 1.4986)
			(layers "F.Cu" "F.Mask" "F.Paste")
			(net "GND")
		)
		(pad "26" smd rect
			(at -2.925064 -2.921 90)
			(size 0.3556 1.4986)
			(layers "F.Cu" "F.Mask" "F.Paste")
			(net "P3V3_NODE1")
		)
		(pad "27" smd rect
			(at -3.57505 -2.921 90)
			(size 0.3556 1.4986)
			(layers "F.Cu" "F.Mask" "F.Paste")
			(net "N54365623")
		)
		(pad "28" smd rect
			(at -4.225036 -2.921 90)
			(size 0.3556 1.4986)
			(layers "F.Cu" "F.Mask" "F.Paste")
			(net "N54365601")
		)
	)
	(footprint ""
		(layer "F.Cu")
		(at 110.170976 -153.54808)
		(property "Reference" "R1128"
			(at -0.694182 5.341874 0)
			(unlocked yes)
			(layer "F.SilkS")
			(effects
				(font
					(size 0.635 0.4064)
					(thickness 0.1524)
				)
				(justify left)
			)
		)
		(property "Value" ""
			(at 0 0 0)
			(layer "F.Fab")
			(effects
				(font
					(size 1.27 1.27)
				)
			)
		)
		(duplicate_pad_numbers_are_jumpers no)
		(fp_line
			(start -0.7874 -0.4064)
			(end 0.7874 -0.4064)
			(stroke
				(width 0.1524)
				(type default)
			)
			(layer "F.SilkS")
		)
		(fp_line
			(start -0.7874 0.4064)
			(end -0.7874 -0.4064)
			(stroke
				(width 0.1524)
				(type default)
			)
			(layer "F.SilkS")
		)
		(fp_line
			(start 0.7874 -0.4064)
			(end 0.7874 0.4064)
			(stroke
				(width 0.1524)
				(type default)
			)
			(layer "F.SilkS")
		)
		(fp_line
			(start 0.7874 0.4064)
			(end -0.7874 0.4064)
			(stroke
				(width 0.1524)
				(type default)
			)
			(layer "F.SilkS")
		)
		(fp_poly
			(pts
				(xy -0.508 0.2794) (xy -0.508 0.2286) (xy -0.635 0.2286) (xy -0.635 -0.254) (xy -0.5334 -0.254)
				(xy -0.5334 -0.2794) (xy 0.5334 -0.2794) (xy 0.5334 -0.254) (xy 0.635 -0.254) (xy 0.635 0.254) (xy 0.5334 0.254)
				(xy 0.5334 0.2794)
			)
			(stroke
				(width 0)
				(type default)
			)
			(fill no)
			(layer "F.CrtYd")
		)
		(pad "1" smd rect
			(at 0.40005 0)
			(size 0.4572 0.508)
			(layers "F.Cu" "F.Mask" "F.Paste")
			(net "N52411214")
		)
		(pad "2" smd rect
			(at -0.40005 0)
			(size 0.4572 0.508)
			(layers "F.Cu" "F.Mask" "F.Paste")
			(net "N52411212")
		)
	)
	(footprint ""
		(layer "F.Cu")
		(at 99.516184 -17.689322)
		(property "Reference" "R205"
			(at 0.049276 -1.34747 0)
			(unlocked yes)
			(layer "F.SilkS")
			(effects
				(font
					(size 0.7874 0.5842)
					(thickness 0.1524)
				)
				(justify left)
			)
		)
		(property "Value" ""
			(at 0 0 0)
			(layer "F.Fab")
			(effects
				(font
					(size 1.27 1.27)
				)
			)
		)
		(duplicate_pad_numbers_are_jumpers no)
		(fp_line
			(start -0.7874 -0.4064)
			(end 0.7874 -0.4064)
			(stroke
				(width 0.1524)
				(type default)
			)
			(layer "F.SilkS")
		)
		(fp_line
			(start -0.7874 0.4064)
			(end -0.7874 -0.4064)
			(stroke
				(width 0.1524)
				(type default)
			)
			(layer "F.SilkS")
		)
		(fp_line
			(start 0.7874 -0.4064)
			(end 0.7874 0.4064)
			(stroke
				(width 0.1524)
				(type default)
			)
			(layer "F.SilkS")
		)
		(fp_line
			(start 0.7874 0.4064)
			(end -0.7874 0.4064)
			(stroke
				(width 0.1524)
				(type default)
			)
			(layer "F.SilkS")
		)
		(fp_poly
			(pts
				(xy -0.508 0.2794) (xy -0.508 0.2286) (xy -0.635 0.2286) (xy -0.635 -0.254) (xy -0.5334 -0.254)
				(xy -0.5334 -0.2794) (xy 0.5334 -0.2794) (xy 0.5334 -0.254) (xy 0.635 -0.254) (xy 0.635 0.254) (xy 0.5334 0.254)
				(xy 0.5334 0.2794)
			)
			(stroke
				(width 0)
				(type default)
			)
			(fill no)
			(layer "F.CrtYd")
		)
		(pad "1" smd rect
			(at 0.40005 0)
			(size 0.4572 0.508)
			(layers "F.Cu" "F.Mask" "F.Paste")
			(net "GND")
		)
		(pad "2" smd rect
			(at -0.40005 0)
			(size 0.4572 0.508)
			(layers "F.Cu" "F.Mask" "F.Paste")
			(net "PD_NODE1_DM7")
		)
	)
	(footprint ""
		(layer "F.Cu")
		(at 70.377812 -1.685544 180)
		(property "Reference" "R1237"
			(at 1.09982 -1.040892 0)
			(unlocked yes)
			(layer "F.SilkS")
			(effects
				(font
					(size 0.7874 0.5842)
					(thickness 0.1524)
				)
				(justify left)
			)
		)
		(property "Value" ""
			(at 0 0 180)
			(layer "F.Fab")
			(effects
				(font
					(size 1.27 1.27)
				)
			)
		)
		(duplicate_pad_numbers_are_jumpers no)
		(fp_line
			(start 0.7874 0.4064)
			(end -0.7874 0.4064)
			(stroke
				(width 0.1524)
				(type default)
			)
			(layer "F.SilkS")
		)
		(fp_line
			(start 0.7874 -0.4064)
			(end 0.7874 0.4064)
			(stroke
				(width 0.1524)
				(type default)
			)
			(layer "F.SilkS")
		)
		(fp_line
			(start -0.7874 0.4064)
			(end -0.7874 -0.4064)
			(stroke
				(width 0.1524)
				(type default)
			)
			(layer "F.SilkS")
		)
		(fp_line
			(start -0.7874 -0.4064)
			(end 0.7874 -0.4064)
			(stroke
				(width 0.1524)
				(type default)
			)
			(layer "F.SilkS")
		)
		(fp_poly
			(pts
				(xy -0.508 0.2794) (xy -0.508 0.2286) (xy -0.635 0.2286) (xy -0.635 -0.254) (xy -0.5334 -0.254)
				(xy -0.5334 -0.2794) (xy 0.5334 -0.2794) (xy 0.5334 -0.254) (xy 0.635 -0.254) (xy 0.635 0.254) (xy 0.5334 0.254)
				(xy 0.5334 0.2794)
			)
			(stroke
				(width 0)
				(type default)
			)
			(fill no)
			(layer "F.CrtYd")
		)
		(pad "1" smd rect
			(at 0.40005 0 180)
			(size 0.4572 0.508)
			(layers "F.Cu" "F.Mask" "F.Paste")
			(net "GND")
		)
		(pad "2" smd rect
			(at -0.40005 0 180)
			(size 0.4572 0.508)
			(layers "F.Cu" "F.Mask" "F.Paste")
			(net "FM_CPLD_NODE1_P3V3_EN")
		)
	)
	(footprint ""
		(layer "F.Cu")
		(at 47.10176 -188.126624 90)
		(property "Reference" "R852"
			(at 4.548886 0.205232 90)
			(unlocked yes)
			(layer "F.SilkS")
			(effects
				(font
					(size 0.7874 0.5842)
					(thickness 0.1524)
				)
				(justify left)
			)
		)
		(property "Value" ""
			(at 0 0 90)
			(layer "F.Fab")
			(effects
				(font
					(size 1.27 1.27)
				)
			)
		)
		(duplicate_pad_numbers_are_jumpers no)
		(fp_line
			(start 0.7874 -0.4064)
			(end 0.7874 0.4064)
			(stroke
				(width 0.1524)
				(type default)
			)
			(layer "F.SilkS")
		)
		(fp_line
			(start -0.7874 -0.4064)
			(end 0.7874 -0.4064)
			(stroke
				(width 0.1524)
				(type default)
			)
			(layer "F.SilkS")
		)
		(fp_line
			(start 0.7874 0.4064)
			(end -0.7874 0.4064)
			(stroke
				(width 0.1524)
				(type default)
			)
			(layer "F.SilkS")
		)
		(fp_line
			(start -0.7874 0.4064)
			(end -0.7874 -0.4064)
			(stroke
				(width 0.1524)
				(type default)
			)
			(layer "F.SilkS")
		)
		(fp_poly
			(pts
				(xy -0.508 0.2794) (xy -0.508 0.2286) (xy -0.635 0.2286) (xy -0.635 -0.254) (xy -0.5334 -0.254)
				(xy -0.5334 -0.2794) (xy 0.5334 -0.2794) (xy 0.5334 -0.254) (xy 0.635 -0.254) (xy 0.635 0.254) (xy 0.5334 0.254)
				(xy 0.5334 0.2794)
			)
			(stroke
				(width 0)
				(type default)
			)
			(fill no)
			(layer "F.CrtYd")
		)
		(pad "1" smd rect
			(at 0.40005 0 90)
			(size 0.4572 0.508)
			(layers "F.Cu" "F.Mask" "F.Paste")
			(net "PSU6_AC_OK_R")
		)
		(pad "2" smd rect
			(at -0.40005 0 90)
			(size 0.4572 0.508)
			(layers "F.Cu" "F.Mask" "F.Paste")
			(net "GND")
		)
	)
	(footprint ""
		(layer "F.Cu")
		(at 127.03556 -188.126624 90)
		(property "Reference" "C764"
			(at 4.949444 -0.396748 90)
			(unlocked yes)
			(layer "F.SilkS")
			(effects
				(font
					(size 0.7874 0.5842)
					(thickness 0.1524)
				)
				(justify left)
			)
		)
		(property "Value" ""
			(at 0 0 90)
			(layer "F.Fab")
			(effects
				(font
					(size 1.27 1.27)
				)
			)
		)
		(duplicate_pad_numbers_are_jumpers no)
		(fp_line
			(start 0.7874 -0.4064)
			(end 0.7874 0.4064)
			(stroke
				(width 0.1524)
				(type default)
			)
			(layer "F.SilkS")
		)
		(fp_line
			(start -0.7874 -0.4064)
			(end 0.7874 -0.4064)
			(stroke
				(width 0.1524)
				(type default)
			)
			(layer "F.SilkS")
		)
		(fp_line
			(start 0 0.381)
			(end 0 -0.381)
			(stroke
				(width 0.1524)
				(type default)
			)
			(layer "F.SilkS")
		)
		(fp_line
			(start 0.7874 0.4064)
			(end -0.7874 0.4064)
			(stroke
				(width 0.1524)
				(type default)
			)
			(layer "F.SilkS")
		)
		(fp_line
			(start -0.7874 0.4064)
			(end -0.7874 -0.4064)
			(stroke
				(width 0.1524)
				(type default)
			)
			(layer "F.SilkS")
		)
		(fp_poly
			(pts
				(xy -0.5334 0.254) (xy -0.635 0.254) (xy -0.635 0.2286) (xy -0.635 -0.254) (xy -0.5334 -0.254) (xy -0.5334 -0.2794)
				(xy 0.5334 -0.2794) (xy 0.5334 -0.254) (xy 0.635 -0.254) (xy 0.635 0.254) (xy 0.5334 0.254) (xy 0.5334 0.2794)
				(xy -0.508 0.2794) (xy -0.5334 0.2794)
			)
			(stroke
				(width 0)
				(type default)
			)
			(fill no)
			(layer "F.CrtYd")
		)
		(pad "1" smd rect
			(at 0.40005 0 90)
			(size 0.4572 0.508)
			(layers "F.Cu" "F.Mask" "F.Paste")
			(net "UART_T10_NODE4_TXD_R")
		)
		(pad "2" smd rect
			(at -0.40005 0 90)
			(size 0.4572 0.508)
			(layers "F.Cu" "F.Mask" "F.Paste")
			(net "GND")
		)
	)
	(footprint ""
		(layer "F.Cu")
		(at 60.05957 -108.23829 180)
		(property "Reference" "PC17"
			(at 1.977644 -5.782056 0)
			(unlocked yes)
			(layer "F.SilkS")
			(effects
				(font
					(size 0.7874 0.5842)
					(thickness 0.1524)
				)
				(justify left)
			)
		)
		(property "Value" ""
			(at 0 0 180)
			(layer "F.Fab")
			(effects
				(font
					(size 1.27 1.27)
				)
			)
		)
		(duplicate_pad_numbers_are_jumpers no)
		(fp_line
			(start 1.905 0.8636)
			(end -1.905 0.8636)
			(stroke
				(width 0.1524)
				(type default)
			)
			(layer "F.SilkS")
		)
		(fp_line
			(start 1.905 -0.8636)
			(end 1.905 0.8636)
			(stroke
				(width 0.1524)
				(type default)
			)
			(layer "F.SilkS")
		)
		(fp_line
			(start 0 0.8382)
			(end 0 -0.8382)
			(stroke
				(width 0.1524)
				(type default)
			)
			(layer "F.SilkS")
		)
		(fp_line
			(start -1.905 0.8636)
			(end -1.905 -0.8636)
			(stroke
				(width 0.1524)
				(type default)
			)
			(layer "F.SilkS")
		)
		(fp_line
			(start -1.905 -0.8636)
			(end 1.905 -0.8636)
			(stroke
				(width 0.1524)
				(type default)
			)
			(layer "F.SilkS")
		)
		(fp_rect
			(start -1.524 0.7366)
			(end 1.524 -0.7366)
			(stroke
				(width 0)
				(type default)
			)
			(fill no)
			(layer "F.CrtYd")
		)
		(pad "1" smd rect
			(at 0.94996 0 180)
			(size 1.1176 1.3716)
			(layers "F.Cu" "F.Mask" "F.Paste")
			(net "P3V3_STB_NODE1")
		)
		(pad "2" smd rect
			(at -0.94996 0 180)
			(size 1.1176 1.3716)
			(layers "F.Cu" "F.Mask" "F.Paste")
			(net "GND")
		)
	)
	(footprint ""
		(layer "F.Cu")
		(at 115.93576 -175.426624 90)
		(property "Reference" "R1048"
			(at -57.01538 32.987488 90)
			(unlocked yes)
			(layer "F.SilkS")
			(effects
				(font
					(size 0.7874 0.5842)
					(thickness 0.1524)
				)
				(justify left)
			)
		)
		(property "Value" ""
			(at 0 0 90)
			(layer "F.Fab")
			(effects
				(font
					(size 1.27 1.27)
				)
			)
		)
		(duplicate_pad_numbers_are_jumpers no)
		(fp_line
			(start 0.7874 -0.4064)
			(end 0.7874 0.4064)
			(stroke
				(width 0.1524)
				(type default)
			)
			(layer "F.SilkS")
		)
		(fp_line
			(start -0.7874 -0.4064)
			(end 0.7874 -0.4064)
			(stroke
				(width 0.1524)
				(type default)
			)
			(layer "F.SilkS")
		)
		(fp_line
			(start 0.7874 0.4064)
			(end -0.7874 0.4064)
			(stroke
				(width 0.1524)
				(type default)
			)
			(layer "F.SilkS")
		)
		(fp_line
			(start -0.7874 0.4064)
			(end -0.7874 -0.4064)
			(stroke
				(width 0.1524)
				(type default)
			)
			(layer "F.SilkS")
		)
		(fp_poly
			(pts
				(xy -0.508 0.2794) (xy -0.508 0.2286) (xy -0.635 0.2286) (xy -0.635 -0.254) (xy -0.5334 -0.254)
				(xy -0.5334 -0.2794) (xy 0.5334 -0.2794) (xy 0.5334 -0.254) (xy 0.635 -0.254) (xy 0.635 0.254) (xy 0.5334 0.254)
				(xy 0.5334 0.2794)
			)
			(stroke
				(width 0)
				(type default)
			)
			(fill no)
			(layer "F.CrtYd")
		)
		(pad "1" smd rect
			(at 0.40005 0 90)
			(size 0.4572 0.508)
			(layers "F.Cu" "F.Mask" "F.Paste")
			(net "N31341801")
		)
		(pad "2" smd rect
			(at -0.40005 0 90)
			(size 0.4572 0.508)
			(layers "F.Cu" "F.Mask" "F.Paste")
			(net "GND")
		)
	)
	(footprint ""
		(layer "F.Cu")
		(at 23.847298 -113.015522 180)
		(property "Reference" "PC67"
			(at -2.939542 -2.669794 0)
			(unlocked yes)
			(layer "F.SilkS")
			(effects
				(font
					(size 0.7874 0.5842)
					(thickness 0.1524)
				)
				(justify left)
			)
		)
		(property "Value" ""
			(at 0 0 180)
			(layer "F.Fab")
			(effects
				(font
					(size 1.27 1.27)
				)
			)
		)
		(duplicate_pad_numbers_are_jumpers no)
		(fp_line
			(start 1.905 0.8636)
			(end -1.905 0.8636)
			(stroke
				(width 0.1524)
				(type default)
			)
			(layer "F.SilkS")
		)
		(fp_line
			(start 1.905 -0.8636)
			(end 1.905 0.8636)
			(stroke
				(width 0.1524)
				(type default)
			)
			(layer "F.SilkS")
		)
		(fp_line
			(start 0 0.8382)
			(end 0 -0.8382)
			(stroke
				(width 0.1524)
				(type default)
			)
			(layer "F.SilkS")
		)
		(fp_line
			(start -1.905 0.8636)
			(end -1.905 -0.8636)
			(stroke
				(width 0.1524)
				(type default)
			)
			(layer "F.SilkS")
		)
		(fp_line
			(start -1.905 -0.8636)
			(end 1.905 -0.8636)
			(stroke
				(width 0.1524)
				(type default)
			)
			(layer "F.SilkS")
		)
		(fp_rect
			(start -1.524 0.7366)
			(end 1.524 -0.7366)
			(stroke
				(width 0)
				(type default)
			)
			(fill no)
			(layer "F.CrtYd")
		)
		(pad "1" smd rect
			(at 0.94996 0 180)
			(size 1.1176 1.3716)
			(layers "F.Cu" "F.Mask" "F.Paste")
			(net "P1V05_NODE1")
		)
		(pad "2" smd rect
			(at -0.94996 0 180)
			(size 1.1176 1.3716)
			(layers "F.Cu" "F.Mask" "F.Paste")
			(net "GND")
		)
	)
	(footprint ""
		(layer "F.Cu")
		(at 44.254166 -121.35866)
		(property "Reference" "C225"
			(at -3.842766 -0.000508 0)
			(unlocked yes)
			(layer "F.SilkS")
			(effects
				(font
					(size 0.7874 0.5842)
					(thickness 0.1524)
				)
				(justify left)
			)
		)
		(property "Value" ""
			(at 0 0 0)
			(layer "F.Fab")
			(effects
				(font
					(size 1.27 1.27)
				)
			)
		)
		(duplicate_pad_numbers_are_jumpers no)
		(fp_line
			(start -0.7874 -0.4064)
			(end 0.7874 -0.4064)
			(stroke
				(width 0.1524)
				(type default)
			)
			(layer "F.SilkS")
		)
		(fp_line
			(start -0.7874 0.4064)
			(end -0.7874 -0.4064)
			(stroke
				(width 0.1524)
				(type default)
			)
			(layer "F.SilkS")
		)
		(fp_line
			(start 0 0.381)
			(end 0 -0.381)
			(stroke
				(width 0.1524)
				(type default)
			)
			(layer "F.SilkS")
		)
		(fp_line
			(start 0.7874 -0.4064)
			(end 0.7874 0.4064)
			(stroke
				(width 0.1524)
				(type default)
			)
			(layer "F.SilkS")
		)
		(fp_line
			(start 0.7874 0.4064)
			(end -0.7874 0.4064)
			(stroke
				(width 0.1524)
				(type default)
			)
			(layer "F.SilkS")
		)
		(fp_poly
			(pts
				(xy -0.5334 0.254) (xy -0.635 0.254) (xy -0.635 0.2286) (xy -0.635 -0.254) (xy -0.5334 -0.254) (xy -0.5334 -0.2794)
				(xy 0.5334 -0.2794) (xy 0.5334 -0.254) (xy 0.635 -0.254) (xy 0.635 0.254) (xy 0.5334 0.254) (xy 0.5334 0.2794)
				(xy -0.508 0.2794) (xy -0.5334 0.2794)
			)
			(stroke
				(width 0)
				(type default)
			)
			(fill no)
			(layer "F.CrtYd")
		)
		(pad "1" smd rect
			(at 0.40005 0)
			(size 0.4572 0.508)
			(layers "F.Cu" "F.Mask" "F.Paste")
			(net "GND")
		)
		(pad "2" smd rect
			(at -0.40005 0)
			(size 0.4572 0.508)
			(layers "F.Cu" "F.Mask" "F.Paste")
			(net "P3V3_NODE1")
		)
	)
	(footprint ""
		(layer "F.Cu")
		(at 100.481638 -181.315106 -90)
		(property "Reference" "U131"
			(at 75.997816 -85.36686 0)
			(unlocked yes)
			(layer "F.SilkS")
			(effects
				(font
					(size 0.7874 0.5842)
					(thickness 0.1524)
				)
			)
		)
		(property "Value" ""
			(at 0 0 270)
			(layer "F.Fab")
			(effects
				(font
					(size 1.27 1.27)
				)
			)
		)
		(duplicate_pad_numbers_are_jumpers no)
		(fp_line
			(start -1.100074 1.3462)
			(end -1.100074 -1.3462)
			(stroke
				(width 0.1524)
				(type default)
			)
			(layer "F.SilkS")
		)
		(fp_line
			(start 1.100074 1.3462)
			(end -1.100074 1.3462)
			(stroke
				(width 0.1524)
				(type default)
			)
			(layer "F.SilkS")
		)
		(fp_line
			(start -1.100074 -1.3462)
			(end 1.100074 -1.3462)
			(stroke
				(width 0.1524)
				(type default)
			)
			(layer "F.SilkS")
		)
		(fp_line
			(start 1.100074 -1.3462)
			(end 1.100074 1.3462)
			(stroke
				(width 0.1524)
				(type default)
			)
			(layer "F.SilkS")
		)
		(fp_poly
			(pts
				(xy -1.256538 0.9906) (xy -2.018538 0.6096) (xy -2.018538 1.3716)
			)
			(stroke
				(width 0)
				(type default)
			)
			(fill yes)
			(layer "F.SilkS")
		)
		(fp_poly
			(pts
				(xy -0.8636 1.2192) (xy -0.8636 0.6858) (xy -1.1176 0.6858) (xy -1.1176 -0.6858) (xy -0.8636 -0.6858)
				(xy -0.8636 -1.2192) (xy 0.8636 -1.2192) (xy 0.8636 -0.6858) (xy 1.1176 -0.6858) (xy 1.1176 0.6858)
				(xy 0.8636 0.6858) (xy 0.8636 1.2192)
			)
			(stroke
				(width 0)
				(type default)
			)
			(fill no)
			(layer "F.CrtYd")
		)
		(pad "1" smd rect
			(at -0.649986 0.94996 270)
			(size 0.4064 0.508)
			(layers "F.Cu" "F.Mask" "F.Paste")
			(net "ATTENTION_LED_N")
		)
		(pad "2" smd rect
			(at 0 0.94996 270)
			(size 0.4064 0.508)
			(layers "F.Cu" "F.Mask" "F.Paste")
			(net "GND")
		)
		(pad "3" smd rect
			(at 0.649986 0.94996 270)
			(size 0.4064 0.508)
			(layers "F.Cu" "F.Mask" "F.Paste")
			(net "CM_STATUS_LED_N")
		)
		(pad "4" smd rect
			(at 0.649986 -0.94996 270)
			(size 0.4064 0.508)
			(layers "F.Cu" "F.Mask" "F.Paste")
			(net "CM_STATUS_LED_R")
		)
		(pad "5" smd rect
			(at 0 -0.94996 270)
			(size 0.4064 0.508)
			(layers "F.Cu" "F.Mask" "F.Paste")
			(net "P3V3_NODE1")
		)
		(pad "6" smd rect
			(at -0.649986 -0.94996 270)
			(size 0.4064 0.508)
			(layers "F.Cu" "F.Mask" "F.Paste")
			(net "ATTENTION_LED_R")
		)
	)
	(footprint ""
		(layer "F.Cu")
		(at 32.920178 -175.459898 90)
		(property "Reference" "C779"
			(at -10.516108 -3.729228 90)
			(unlocked yes)
			(layer "F.SilkS")
			(effects
				(font
					(size 0.7874 0.5842)
					(thickness 0.1524)
				)
				(justify left)
			)
		)
		(property "Value" ""
			(at 0 0 90)
			(layer "F.Fab")
			(effects
				(font
					(size 1.27 1.27)
				)
			)
		)
		(duplicate_pad_numbers_are_jumpers no)
		(fp_line
			(start 0.7874 -0.4064)
			(end 0.7874 0.4064)
			(stroke
				(width 0.1524)
				(type default)
			)
			(layer "F.SilkS")
		)
		(fp_line
			(start -0.7874 -0.4064)
			(end 0.7874 -0.4064)
			(stroke
				(width 0.1524)
				(type default)
			)
			(layer "F.SilkS")
		)
		(fp_line
			(start 0 0.381)
			(end 0 -0.381)
			(stroke
				(width 0.1524)
				(type default)
			)
			(layer "F.SilkS")
		)
		(fp_line
			(start 0.7874 0.4064)
			(end -0.7874 0.4064)
			(stroke
				(width 0.1524)
				(type default)
			)
			(layer "F.SilkS")
		)
		(fp_line
			(start -0.7874 0.4064)
			(end -0.7874 -0.4064)
			(stroke
				(width 0.1524)
				(type default)
			)
			(layer "F.SilkS")
		)
		(fp_poly
			(pts
				(xy -0.5334 0.254) (xy -0.635 0.254) (xy -0.635 0.2286) (xy -0.635 -0.254) (xy -0.5334 -0.254) (xy -0.5334 -0.2794)
				(xy 0.5334 -0.2794) (xy 0.5334 -0.254) (xy 0.635 -0.254) (xy 0.635 0.254) (xy 0.5334 0.254) (xy 0.5334 0.2794)
				(xy -0.508 0.2794) (xy -0.5334 0.2794)
			)
			(stroke
				(width 0)
				(type default)
			)
			(fill no)
			(layer "F.CrtYd")
		)
		(pad "1" smd rect
			(at 0.40005 0 90)
			(size 0.4572 0.508)
			(layers "F.Cu" "F.Mask" "F.Paste")
			(net "VR_HSC_NODE1_GATE_R")
		)
		(pad "2" smd rect
			(at -0.40005 0 90)
			(size 0.4572 0.508)
			(layers "F.Cu" "F.Mask" "F.Paste")
			(net "GND")
		)
	)
	(footprint ""
		(layer "F.Cu")
		(at 149.33676 -188.126624 -90)
		(property "Reference" "R987"
			(at -5.519674 2.681732 90)
			(unlocked yes)
			(layer "F.SilkS")
			(effects
				(font
					(size 0.7874 0.5842)
					(thickness 0.1524)
				)
				(justify left)
			)
		)
		(property "Value" ""
			(at 0 0 270)
			(layer "F.Fab")
			(effects
				(font
					(size 1.27 1.27)
				)
			)
		)
		(duplicate_pad_numbers_are_jumpers no)
		(fp_line
			(start -0.7874 0.4064)
			(end -0.7874 -0.4064)
			(stroke
				(width 0.1524)
				(type default)
			)
			(layer "F.SilkS")
		)
		(fp_line
			(start 0.7874 0.4064)
			(end -0.7874 0.4064)
			(stroke
				(width 0.1524)
				(type default)
			)
			(layer "F.SilkS")
		)
		(fp_line
			(start -0.7874 -0.4064)
			(end 0.7874 -0.4064)
			(stroke
				(width 0.1524)
				(type default)
			)
			(layer "F.SilkS")
		)
		(fp_line
			(start 0.7874 -0.4064)
			(end 0.7874 0.4064)
			(stroke
				(width 0.1524)
				(type default)
			)
			(layer "F.SilkS")
		)
		(fp_poly
			(pts
				(xy -0.508 0.2794) (xy -0.508 0.2286) (xy -0.635 0.2286) (xy -0.635 -0.254) (xy -0.5334 -0.254)
				(xy -0.5334 -0.2794) (xy 0.5334 -0.2794) (xy 0.5334 -0.254) (xy 0.635 -0.254) (xy 0.635 0.254) (xy 0.5334 0.254)
				(xy 0.5334 0.2794)
			)
			(stroke
				(width 0)
				(type default)
			)
			(fill no)
			(layer "F.CrtYd")
		)
		(pad "1" smd rect
			(at 0.40005 0 270)
			(size 0.4572 0.508)
			(layers "F.Cu" "F.Mask" "F.Paste")
			(net "UART_T12_NODE2_RXD")
		)
		(pad "2" smd rect
			(at -0.40005 0 270)
			(size 0.4572 0.508)
			(layers "F.Cu" "F.Mask" "F.Paste")
			(net "UART_T12_NODE2_RXD_R")
		)
	)
	(footprint ""
		(layer "F.Cu")
		(at 95.048578 -120.637046 90)
		(property "Reference" "C1122"
			(at 0.577342 0.760222 0)
			(unlocked yes)
			(layer "F.SilkS")
			(effects
				(font
					(size 0.7874 0.5842)
					(thickness 0.1524)
				)
				(justify left)
			)
		)
		(property "Value" ""
			(at 0 0 90)
			(layer "F.Fab")
			(effects
				(font
					(size 1.27 1.27)
				)
			)
		)
		(duplicate_pad_numbers_are_jumpers no)
		(fp_line
			(start 0.7874 -0.4064)
			(end 0.7874 0.4064)
			(stroke
				(width 0.1524)
				(type default)
			)
			(layer "F.SilkS")
		)
		(fp_line
			(start -0.7874 -0.4064)
			(end 0.7874 -0.4064)
			(stroke
				(width 0.1524)
				(type default)
			)
			(layer "F.SilkS")
		)
		(fp_line
			(start 0 0.381)
			(end 0 -0.381)
			(stroke
				(width 0.1524)
				(type default)
			)
			(layer "F.SilkS")
		)
		(fp_line
			(start 0.7874 0.4064)
			(end -0.7874 0.4064)
			(stroke
				(width 0.1524)
				(type default)
			)
			(layer "F.SilkS")
		)
		(fp_line
			(start -0.7874 0.4064)
			(end -0.7874 -0.4064)
			(stroke
				(width 0.1524)
				(type default)
			)
			(layer "F.SilkS")
		)
		(fp_poly
			(pts
				(xy -0.5334 0.254) (xy -0.635 0.254) (xy -0.635 0.2286) (xy -0.635 -0.254) (xy -0.5334 -0.254) (xy -0.5334 -0.2794)
				(xy 0.5334 -0.2794) (xy 0.5334 -0.254) (xy 0.635 -0.254) (xy 0.635 0.254) (xy 0.5334 0.254) (xy 0.5334 0.2794)
				(xy -0.508 0.2794) (xy -0.5334 0.2794)
			)
			(stroke
				(width 0)
				(type default)
			)
			(fill no)
			(layer "F.CrtYd")
		)
		(pad "1" smd rect
			(at 0.40005 0 90)
			(size 0.4572 0.508)
			(layers "F.Cu" "F.Mask" "F.Paste")
			(net "P3V3_NODE1")
		)
		(pad "2" smd rect
			(at -0.40005 0 90)
			(size 0.4572 0.508)
			(layers "F.Cu" "F.Mask" "F.Paste")
			(net "GND")
		)
	)
	(footprint ""
		(layer "F.Cu")
		(at 116.18976 -188.126624 -90)
		(property "Reference" "R991"
			(at -4.885182 -0.369062 90)
			(unlocked yes)
			(layer "F.SilkS")
			(effects
				(font
					(size 0.7874 0.5842)
					(thickness 0.1524)
				)
				(justify left)
			)
		)
		(property "Value" ""
			(at 0 0 270)
			(layer "F.Fab")
			(effects
				(font
					(size 1.27 1.27)
				)
			)
		)
		(duplicate_pad_numbers_are_jumpers no)
		(fp_line
			(start -0.7874 0.4064)
			(end -0.7874 -0.4064)
			(stroke
				(width 0.1524)
				(type default)
			)
			(layer "F.SilkS")
		)
		(fp_line
			(start 0.7874 0.4064)
			(end -0.7874 0.4064)
			(stroke
				(width 0.1524)
				(type default)
			)
			(layer "F.SilkS")
		)
		(fp_line
			(start -0.7874 -0.4064)
			(end 0.7874 -0.4064)
			(stroke
				(width 0.1524)
				(type default)
			)
			(layer "F.SilkS")
		)
		(fp_line
			(start 0.7874 -0.4064)
			(end 0.7874 0.4064)
			(stroke
				(width 0.1524)
				(type default)
			)
			(layer "F.SilkS")
		)
		(fp_poly
			(pts
				(xy -0.508 0.2794) (xy -0.508 0.2286) (xy -0.635 0.2286) (xy -0.635 -0.254) (xy -0.5334 -0.254)
				(xy -0.5334 -0.2794) (xy 0.5334 -0.2794) (xy 0.5334 -0.254) (xy 0.635 -0.254) (xy 0.635 0.254) (xy 0.5334 0.254)
				(xy 0.5334 0.2794)
			)
			(stroke
				(width 0)
				(type default)
			)
			(fill no)
			(layer "F.CrtYd")
		)
		(pad "1" smd rect
			(at 0.40005 0 270)
			(size 0.4572 0.508)
			(layers "F.Cu" "F.Mask" "F.Paste")
			(net "UART_T8_NODE3_RXD")
		)
		(pad "2" smd rect
			(at -0.40005 0 270)
			(size 0.4572 0.508)
			(layers "F.Cu" "F.Mask" "F.Paste")
			(net "UART_T8_NODE3_RXD_R")
		)
	)
	(footprint ""
		(layer "F.Cu")
		(at 70.1548 -101.397562 180)
		(property "Reference" "R1091"
			(at 1.169416 3.10642 0)
			(unlocked yes)
			(layer "F.SilkS")
			(effects
				(font
					(size 0.7874 0.5842)
					(thickness 0.1524)
				)
				(justify left)
			)
		)
		(property "Value" ""
			(at 0 0 180)
			(layer "F.Fab")
			(effects
				(font
					(size 1.27 1.27)
				)
			)
		)
		(duplicate_pad_numbers_are_jumpers no)
		(fp_line
			(start 0.7874 0.4064)
			(end -0.7874 0.4064)
			(stroke
				(width 0.1524)
				(type default)
			)
			(layer "F.SilkS")
		)
		(fp_line
			(start 0.7874 -0.4064)
			(end 0.7874 0.4064)
			(stroke
				(width 0.1524)
				(type default)
			)
			(layer "F.SilkS")
		)
		(fp_line
			(start -0.7874 0.4064)
			(end -0.7874 -0.4064)
			(stroke
				(width 0.1524)
				(type default)
			)
			(layer "F.SilkS")
		)
		(fp_line
			(start -0.7874 -0.4064)
			(end 0.7874 -0.4064)
			(stroke
				(width 0.1524)
				(type default)
			)
			(layer "F.SilkS")
		)
		(fp_poly
			(pts
				(xy -0.508 0.2794) (xy -0.508 0.2286) (xy -0.635 0.2286) (xy -0.635 -0.254) (xy -0.5334 -0.254)
				(xy -0.5334 -0.2794) (xy 0.5334 -0.2794) (xy 0.5334 -0.254) (xy 0.635 -0.254) (xy 0.635 0.254) (xy 0.5334 0.254)
				(xy 0.5334 0.2794)
			)
			(stroke
				(width 0)
				(type default)
			)
			(fill no)
			(layer "F.CrtYd")
		)
		(pad "1" smd rect
			(at 0.40005 0 180)
			(size 0.4572 0.508)
			(layers "F.Cu" "F.Mask" "F.Paste")
			(net "FM_CPLD_NODE1_P1V8_SUS_EN")
		)
		(pad "2" smd rect
			(at -0.40005 0 180)
			(size 0.4572 0.508)
			(layers "F.Cu" "F.Mask" "F.Paste")
			(net "P3V3_STB_NODE1")
		)
	)
	(footprint ""
		(layer "F.Cu")
		(at 124.85116 -188.126624 90)
		(property "Reference" "C626"
			(at 4.949444 -0.396748 90)
			(unlocked yes)
			(layer "F.SilkS")
			(effects
				(font
					(size 0.7874 0.5842)
					(thickness 0.1524)
				)
				(justify left)
			)
		)
		(property "Value" ""
			(at 0 0 90)
			(layer "F.Fab")
			(effects
				(font
					(size 1.27 1.27)
				)
			)
		)
		(duplicate_pad_numbers_are_jumpers no)
		(fp_line
			(start 0.7874 -0.4064)
			(end 0.7874 0.4064)
			(stroke
				(width 0.1524)
				(type default)
			)
			(layer "F.SilkS")
		)
		(fp_line
			(start -0.7874 -0.4064)
			(end 0.7874 -0.4064)
			(stroke
				(width 0.1524)
				(type default)
			)
			(layer "F.SilkS")
		)
		(fp_line
			(start 0 0.381)
			(end 0 -0.381)
			(stroke
				(width 0.1524)
				(type default)
			)
			(layer "F.SilkS")
		)
		(fp_line
			(start 0.7874 0.4064)
			(end -0.7874 0.4064)
			(stroke
				(width 0.1524)
				(type default)
			)
			(layer "F.SilkS")
		)
		(fp_line
			(start -0.7874 0.4064)
			(end -0.7874 -0.4064)
			(stroke
				(width 0.1524)
				(type default)
			)
			(layer "F.SilkS")
		)
		(fp_poly
			(pts
				(xy -0.5334 0.254) (xy -0.635 0.254) (xy -0.635 0.2286) (xy -0.635 -0.254) (xy -0.5334 -0.254) (xy -0.5334 -0.2794)
				(xy 0.5334 -0.2794) (xy 0.5334 -0.254) (xy 0.635 -0.254) (xy 0.635 0.254) (xy 0.5334 0.254) (xy 0.5334 0.2794)
				(xy -0.508 0.2794) (xy -0.5334 0.2794)
			)
			(stroke
				(width 0)
				(type default)
			)
			(fill no)
			(layer "F.CrtYd")
		)
		(pad "1" smd rect
			(at 0.40005 0 90)
			(size 0.4572 0.508)
			(layers "F.Cu" "F.Mask" "F.Paste")
			(net "T8_NODE2_EN_R")
		)
		(pad "2" smd rect
			(at -0.40005 0 90)
			(size 0.4572 0.508)
			(layers "F.Cu" "F.Mask" "F.Paste")
			(net "GND")
		)
	)
	(footprint ""
		(layer "F.Cu")
		(at 81.56194 -84.438744 -90)
		(property "Reference" "R64"
			(at 17.669764 -1.85166 90)
			(unlocked yes)
			(layer "F.SilkS")
			(effects
				(font
					(size 0.7874 0.5842)
					(thickness 0.1524)
				)
				(justify left)
			)
		)
		(property "Value" ""
			(at 0 0 270)
			(layer "F.Fab")
			(effects
				(font
					(size 1.27 1.27)
				)
			)
		)
		(duplicate_pad_numbers_are_jumpers no)
		(fp_line
			(start -0.7874 0.406146)
			(end -0.7874 -0.406146)
			(stroke
				(width 0.1524)
				(type default)
			)
			(layer "F.SilkS")
		)
		(fp_line
			(start 0.7874 0.406146)
			(end -0.7874 0.406146)
			(stroke
				(width 0.1524)
				(type default)
			)
			(layer "F.SilkS")
		)
		(fp_line
			(start -0.7874 -0.406146)
			(end 0.7874 -0.406146)
			(stroke
				(width 0.1524)
				(type default)
			)
			(layer "F.SilkS")
		)
		(fp_line
			(start 0.7874 -0.406146)
			(end 0.7874 0.406146)
			(stroke
				(width 0.1524)
				(type default)
			)
			(layer "F.SilkS")
		)
		(fp_poly
			(pts
				(xy -0.508 0.2794) (xy -0.508 0.2286) (xy -0.635 0.2286) (xy -0.635 -0.254) (xy -0.5334 -0.254)
				(xy -0.5334 -0.2794) (xy 0.5334 -0.2794) (xy 0.5334 -0.254) (xy 0.635 -0.254) (xy 0.635 0.254) (xy 0.5334 0.254)
				(xy 0.5334 0.2794)
			)
			(stroke
				(width 0)
				(type default)
			)
			(fill no)
			(layer "F.CrtYd")
		)
		(pad "1" smd rect
			(at 0.40005 0 270)
			(size 0.4572 0.508)
			(layers "F.Cu" "F.Mask" "F.Paste")
			(net "XTAL_CPU_NODE1_X1PAD")
		)
		(pad "2" smd rect
			(at -0.40005 0 270)
			(size 0.4572 0.508)
			(layers "F.Cu" "F.Mask" "F.Paste")
			(net "XTAL_CPU_NODE1_X2PAD")
		)
	)
	(footprint ""
		(layer "F.Cu")
		(at 110.727998 -29.030422 -90)
		(property "Reference" "C859"
			(at -2.0955 -0.369062 90)
			(unlocked yes)
			(layer "F.SilkS")
			(effects
				(font
					(size 0.7874 0.5842)
					(thickness 0.1524)
				)
				(justify left)
			)
		)
		(property "Value" ""
			(at 0 0 270)
			(layer "F.Fab")
			(effects
				(font
					(size 1.27 1.27)
				)
			)
		)
		(duplicate_pad_numbers_are_jumpers no)
		(fp_line
			(start -1.905 0.8636)
			(end -1.905 -0.8636)
			(stroke
				(width 0.1524)
				(type default)
			)
			(layer "F.SilkS")
		)
		(fp_line
			(start 1.905 0.8636)
			(end -1.905 0.8636)
			(stroke
				(width 0.1524)
				(type default)
			)
			(layer "F.SilkS")
		)
		(fp_line
			(start 0 0.8382)
			(end 0 -0.8382)
			(stroke
				(width 0.1524)
				(type default)
			)
			(layer "F.SilkS")
		)
		(fp_line
			(start -1.905 -0.8636)
			(end 1.905 -0.8636)
			(stroke
				(width 0.1524)
				(type default)
			)
			(layer "F.SilkS")
		)
		(fp_line
			(start 1.905 -0.8636)
			(end 1.905 0.8636)
			(stroke
				(width 0.1524)
				(type default)
			)
			(layer "F.SilkS")
		)
		(fp_rect
			(start -1.524 0.7366)
			(end 1.524 -0.7366)
			(stroke
				(width 0)
				(type default)
			)
			(fill no)
			(layer "F.CrtYd")
		)
		(pad "1" smd rect
			(at 0.94996 0 270)
			(size 1.1176 1.3716)
			(layers "F.Cu" "F.Mask" "F.Paste")
			(net "PV_VTT_DDR_NODE1")
		)
		(pad "2" smd rect
			(at -0.94996 0 270)
			(size 1.1176 1.3716)
			(layers "F.Cu" "F.Mask" "F.Paste")
			(net "GND")
		)
	)
	(footprint ""
		(layer "F.Cu")
		(at 51.310286 -119.368062 180)
		(property "Reference" "C247"
			(at 7.234428 -0.17526 0)
			(unlocked yes)
			(layer "F.SilkS")
			(effects
				(font
					(size 0.7874 0.5842)
					(thickness 0.1524)
				)
				(justify left)
			)
		)
		(property "Value" ""
			(at 0 0 180)
			(layer "F.Fab")
			(effects
				(font
					(size 1.27 1.27)
				)
			)
		)
		(duplicate_pad_numbers_are_jumpers no)
		(fp_line
			(start 0.7874 0.4064)
			(end -0.7874 0.4064)
			(stroke
				(width 0.1524)
				(type default)
			)
			(layer "F.SilkS")
		)
		(fp_line
			(start 0.7874 -0.4064)
			(end 0.7874 0.4064)
			(stroke
				(width 0.1524)
				(type default)
			)
			(layer "F.SilkS")
		)
		(fp_line
			(start 0 0.381)
			(end 0 -0.381)
			(stroke
				(width 0.1524)
				(type default)
			)
			(layer "F.SilkS")
		)
		(fp_line
			(start -0.7874 0.4064)
			(end -0.7874 -0.4064)
			(stroke
				(width 0.1524)
				(type default)
			)
			(layer "F.SilkS")
		)
		(fp_line
			(start -0.7874 -0.4064)
			(end 0.7874 -0.4064)
			(stroke
				(width 0.1524)
				(type default)
			)
			(layer "F.SilkS")
		)
		(fp_poly
			(pts
				(xy -0.5334 0.254) (xy -0.635 0.254) (xy -0.635 0.2286) (xy -0.635 -0.254) (xy -0.5334 -0.254) (xy -0.5334 -0.2794)
				(xy 0.5334 -0.2794) (xy 0.5334 -0.254) (xy 0.635 -0.254) (xy 0.635 0.254) (xy 0.5334 0.254) (xy 0.5334 0.2794)
				(xy -0.508 0.2794) (xy -0.5334 0.2794)
			)
			(stroke
				(width 0)
				(type default)
			)
			(fill no)
			(layer "F.CrtYd")
		)
		(pad "1" smd rect
			(at 0.40005 0 180)
			(size 0.4572 0.508)
			(layers "F.Cu" "F.Mask" "F.Paste")
			(net "GND")
		)
		(pad "2" smd rect
			(at -0.40005 0 180)
			(size 0.4572 0.508)
			(layers "F.Cu" "F.Mask" "F.Paste")
			(net "BMC_NODE1_OSC1_VDD")
		)
	)
	(footprint ""
		(layer "F.Cu")
		(at 164.905944 -93.840808 -90)
		(property "Reference" "R524"
			(at 1.224788 4.22402 90)
			(unlocked yes)
			(layer "F.SilkS")
			(effects
				(font
					(size 0.7874 0.5842)
					(thickness 0.1524)
				)
				(justify left)
			)
		)
		(property "Value" ""
			(at 0 0 270)
			(layer "F.Fab")
			(effects
				(font
					(size 1.27 1.27)
				)
			)
		)
		(duplicate_pad_numbers_are_jumpers no)
		(fp_line
			(start -0.7874 0.4064)
			(end -0.7874 -0.4064)
			(stroke
				(width 0.1524)
				(type default)
			)
			(layer "F.SilkS")
		)
		(fp_line
			(start 0.7874 0.4064)
			(end -0.7874 0.4064)
			(stroke
				(width 0.1524)
				(type default)
			)
			(layer "F.SilkS")
		)
		(fp_line
			(start -0.7874 -0.4064)
			(end 0.7874 -0.4064)
			(stroke
				(width 0.1524)
				(type default)
			)
			(layer "F.SilkS")
		)
		(fp_line
			(start 0.7874 -0.4064)
			(end 0.7874 0.4064)
			(stroke
				(width 0.1524)
				(type default)
			)
			(layer "F.SilkS")
		)
		(fp_poly
			(pts
				(xy -0.508 0.2794) (xy -0.508 0.2286) (xy -0.635 0.2286) (xy -0.635 -0.254) (xy -0.5334 -0.254)
				(xy -0.5334 -0.2794) (xy 0.5334 -0.2794) (xy 0.5334 -0.254) (xy 0.635 -0.254) (xy 0.635 0.254) (xy 0.5334 0.254)
				(xy 0.5334 0.2794)
			)
			(stroke
				(width 0)
				(type default)
			)
			(fill no)
			(layer "F.CrtYd")
		)
		(pad "1" smd rect
			(at 0.40005 0 270)
			(size 0.4572 0.508)
			(layers "F.Cu" "F.Mask" "F.Paste")
			(net "SPI_USB_NODE1_SO")
		)
		(pad "2" smd rect
			(at -0.40005 0 270)
			(size 0.4572 0.508)
			(layers "F.Cu" "F.Mask" "F.Paste")
			(net "SPI_USB_NODE1_R_SO")
		)
	)
	(footprint ""
		(layer "F.Cu")
		(at 50.90668 -94.920054 180)
		(property "Reference" "C136"
			(at 1.709928 -1.066546 0)
			(unlocked yes)
			(layer "F.SilkS")
			(effects
				(font
					(size 0.7874 0.5842)
					(thickness 0.1524)
				)
				(justify left)
			)
		)
		(property "Value" ""
			(at 0 0 180)
			(layer "F.Fab")
			(effects
				(font
					(size 1.27 1.27)
				)
			)
		)
		(duplicate_pad_numbers_are_jumpers no)
		(fp_line
			(start 0.7874 0.4064)
			(end -0.7874 0.4064)
			(stroke
				(width 0.1524)
				(type default)
			)
			(layer "F.SilkS")
		)
		(fp_line
			(start 0.7874 -0.4064)
			(end 0.7874 0.4064)
			(stroke
				(width 0.1524)
				(type default)
			)
			(layer "F.SilkS")
		)
		(fp_line
			(start 0 0.381)
			(end 0 -0.381)
			(stroke
				(width 0.1524)
				(type default)
			)
			(layer "F.SilkS")
		)
		(fp_line
			(start -0.7874 0.4064)
			(end -0.7874 -0.4064)
			(stroke
				(width 0.1524)
				(type default)
			)
			(layer "F.SilkS")
		)
		(fp_line
			(start -0.7874 -0.4064)
			(end 0.7874 -0.4064)
			(stroke
				(width 0.1524)
				(type default)
			)
			(layer "F.SilkS")
		)
		(fp_poly
			(pts
				(xy -0.5334 0.254) (xy -0.635 0.254) (xy -0.635 0.2286) (xy -0.635 -0.254) (xy -0.5334 -0.254) (xy -0.5334 -0.2794)
				(xy 0.5334 -0.2794) (xy 0.5334 -0.254) (xy 0.635 -0.254) (xy 0.635 0.254) (xy 0.5334 0.254) (xy 0.5334 0.2794)
				(xy -0.508 0.2794) (xy -0.5334 0.2794)
			)
			(stroke
				(width 0)
				(type default)
			)
			(fill no)
			(layer "F.CrtYd")
		)
		(pad "1" smd rect
			(at 0.40005 0 180)
			(size 0.4572 0.508)
			(layers "F.Cu" "F.Mask" "F.Paste")
			(net "P3V3_NODE1")
		)
		(pad "2" smd rect
			(at -0.40005 0 180)
			(size 0.4572 0.508)
			(layers "F.Cu" "F.Mask" "F.Paste")
			(net "GND")
		)
	)
	(footprint ""
		(layer "F.Cu")
		(at 58.869326 -155.710382)
		(property "Reference" "U36"
			(at -3.258312 1.102868 90)
			(unlocked yes)
			(layer "F.SilkS")
			(effects
				(font
					(size 0.7874 0.5842)
					(thickness 0.1524)
				)
				(justify left)
			)
		)
		(property "Value" ""
			(at 0 0 0)
			(layer "F.Fab")
			(effects
				(font
					(size 1.27 1.27)
				)
			)
		)
		(duplicate_pad_numbers_are_jumpers no)
		(fp_line
			(start -2.5146 -1.4224)
			(end 2.5146 -1.4224)
			(stroke
				(width 0.1524)
				(type default)
			)
			(layer "F.SilkS")
		)
		(fp_line
			(start -2.5146 -0.4572)
			(end -2.5146 -1.4224)
			(stroke
				(width 0.1524)
				(type default)
			)
			(layer "F.SilkS")
		)
		(fp_line
			(start -2.5146 0.4572)
			(end -2.0574 0)
			(stroke
				(width 0.1524)
				(type default)
			)
			(layer "F.SilkS")
		)
		(fp_line
			(start -2.5146 1.4224)
			(end -2.5146 0.4572)
			(stroke
				(width 0.1524)
				(type default)
			)
			(layer "F.SilkS")
		)
		(fp_line
			(start -2.0574 0)
			(end -2.5146 -0.4572)
			(stroke
				(width 0.1524)
				(type default)
			)
			(layer "F.SilkS")
		)
		(fp_line
			(start 2.5146 -1.4224)
			(end 2.5146 1.4224)
			(stroke
				(width 0.1524)
				(type default)
			)
			(layer "F.SilkS")
		)
		(fp_line
			(start 2.5146 1.4224)
			(end -2.5146 1.4224)
			(stroke
				(width 0.1524)
				(type default)
			)
			(layer "F.SilkS")
		)
		(fp_circle
			(center -1.905 0.889)
			(end -1.651 0.889)
			(stroke
				(width 0.1524)
				(type default)
			)
			(fill no)
			(layer "F.SilkS")
		)
		(fp_poly
			(pts
				(xy -2.1844 3.5052) (xy -2.1844 2.0066) (xy -2.5146 2.0066) (xy -2.5146 -2.0066) (xy -2.1844 -2.0066)
				(xy -2.1844 -3.5052) (xy 2.1844 -3.5052) (xy 2.1844 -2.0066) (xy 2.5146 -2.0066) (xy 2.5146 2.0066)
				(xy 2.1844 2.0066) (xy 2.1844 3.5052)
			)
			(stroke
				(width 0)
				(type default)
			)
			(fill no)
			(layer "F.CrtYd")
		)
		(pad "1" smd rect
			(at -1.905 2.6416)
			(size 0.5588 1.7272)
			(layers "F.Cu" "F.Mask" "F.Paste")
			(net "LAN1_NVM_CS_N_R")
		)
		(pad "2" smd rect
			(at -0.635 2.6416)
			(size 0.5588 1.7272)
			(layers "F.Cu" "F.Mask" "F.Paste")
			(net "LAN1_NVM_SO_R")
		)
		(pad "3" smd rect
			(at 0.635 2.6416)
			(size 0.5588 1.7272)
			(layers "F.Cu" "F.Mask" "F.Paste")
			(net "LAN1_NVM_WP_N")
		)
		(pad "4" smd rect
			(at 1.905 2.6416)
			(size 0.5588 1.7272)
			(layers "F.Cu" "F.Mask" "F.Paste")
			(net "GND")
		)
		(pad "5" smd rect
			(at 1.905 -2.6416)
			(size 0.5588 1.7272)
			(layers "F.Cu" "F.Mask" "F.Paste")
			(net "LAN1_NVM_SI_R")
		)
		(pad "6" smd rect
			(at 0.635 -2.6416)
			(size 0.5588 1.7272)
			(layers "F.Cu" "F.Mask" "F.Paste")
			(net "LAN1_NVM_SK_R")
		)
		(pad "7" smd rect
			(at -0.635 -2.6416)
			(size 0.5588 1.7272)
			(layers "F.Cu" "F.Mask" "F.Paste")
			(net "LAN1_NVM_HOLD_N")
		)
		(pad "8" smd rect
			(at -1.905 -2.6416)
			(size 0.5588 1.7272)
			(layers "F.Cu" "F.Mask" "F.Paste")
			(net "P3V3_NODE1")
		)
	)
	(footprint ""
		(layer "F.Cu")
		(at 64.069722 -161.722816 -90)
		(property "Reference" "C845"
			(at 1.128014 -8.378444 90)
			(unlocked yes)
			(layer "F.SilkS")
			(effects
				(font
					(size 0.7874 0.5842)
					(thickness 0.1524)
				)
				(justify left)
			)
		)
		(property "Value" ""
			(at 0 0 270)
			(layer "F.Fab")
			(effects
				(font
					(size 1.27 1.27)
				)
			)
		)
		(duplicate_pad_numbers_are_jumpers no)
		(fp_line
			(start -1.905 0.8636)
			(end -1.905 -0.8636)
			(stroke
				(width 0.1524)
				(type default)
			)
			(layer "F.SilkS")
		)
		(fp_line
			(start 1.905 0.8636)
			(end -1.905 0.8636)
			(stroke
				(width 0.1524)
				(type default)
			)
			(layer "F.SilkS")
		)
		(fp_line
			(start 0 0.8382)
			(end 0 -0.8382)
			(stroke
				(width 0.1524)
				(type default)
			)
			(layer "F.SilkS")
		)
		(fp_line
			(start -1.905 -0.8636)
			(end 1.905 -0.8636)
			(stroke
				(width 0.1524)
				(type default)
			)
			(layer "F.SilkS")
		)
		(fp_line
			(start 1.905 -0.8636)
			(end 1.905 0.8636)
			(stroke
				(width 0.1524)
				(type default)
			)
			(layer "F.SilkS")
		)
		(fp_rect
			(start -1.524 0.7366)
			(end 1.524 -0.7366)
			(stroke
				(width 0)
				(type default)
			)
			(fill no)
			(layer "F.CrtYd")
		)
		(pad "1" smd rect
			(at 0.94996 0 270)
			(size 1.1176 1.3716)
			(layers "F.Cu" "F.Mask" "F.Paste")
			(net "FM_CPLD_NODE1_P5V_EN_LV")
		)
		(pad "2" smd rect
			(at -0.94996 0 270)
			(size 1.1176 1.3716)
			(layers "F.Cu" "F.Mask" "F.Paste")
			(net "P5V_NODE1")
		)
	)
	(footprint ""
		(layer "F.Cu")
		(at 43.80357 -186.5249 90)
		(property "Reference" "R1007"
			(at 2.494788 0.24257 90)
			(unlocked yes)
			(layer "F.SilkS")
			(effects
				(font
					(size 0.7874 0.5842)
					(thickness 0.1524)
				)
				(justify left)
			)
		)
		(property "Value" ""
			(at 0 0 90)
			(layer "F.Fab")
			(effects
				(font
					(size 1.27 1.27)
				)
			)
		)
		(duplicate_pad_numbers_are_jumpers no)
		(fp_line
			(start 0.7874 -0.4064)
			(end 0.7874 0.4064)
			(stroke
				(width 0.1524)
				(type default)
			)
			(layer "F.SilkS")
		)
		(fp_line
			(start -0.7874 -0.4064)
			(end 0.7874 -0.4064)
			(stroke
				(width 0.1524)
				(type default)
			)
			(layer "F.SilkS")
		)
		(fp_line
			(start 0.7874 0.4064)
			(end -0.7874 0.4064)
			(stroke
				(width 0.1524)
				(type default)
			)
			(layer "F.SilkS")
		)
		(fp_line
			(start -0.7874 0.4064)
			(end -0.7874 -0.4064)
			(stroke
				(width 0.1524)
				(type default)
			)
			(layer "F.SilkS")
		)
		(fp_poly
			(pts
				(xy -0.508 0.2794) (xy -0.508 0.2286) (xy -0.635 0.2286) (xy -0.635 -0.254) (xy -0.5334 -0.254)
				(xy -0.5334 -0.2794) (xy 0.5334 -0.2794) (xy 0.5334 -0.254) (xy 0.635 -0.254) (xy 0.635 0.254) (xy 0.5334 0.254)
				(xy 0.5334 0.2794)
			)
			(stroke
				(width 0)
				(type default)
			)
			(fill no)
			(layer "F.CrtYd")
		)
		(pad "1" smd rect
			(at 0.40005 0 90)
			(size 0.4572 0.508)
			(layers "F.Cu" "F.Mask" "F.Paste")
			(net "P12V_PDB")
		)
		(pad "2" smd rect
			(at -0.40005 0 90)
			(size 0.4572 0.508)
			(layers "F.Cu" "F.Mask" "F.Paste")
			(net "MATE_N")
		)
	)
	(footprint ""
		(layer "F.Cu")
		(at 52.17414 -166.43985 90)
		(property "Reference" "R563"
			(at -130.36804 -3.432048 90)
			(unlocked yes)
			(layer "F.SilkS")
			(effects
				(font
					(size 0.7874 0.5842)
					(thickness 0.1524)
				)
				(justify left)
			)
		)
		(property "Value" ""
			(at 0 0 90)
			(layer "F.Fab")
			(effects
				(font
					(size 1.27 1.27)
				)
			)
		)
		(duplicate_pad_numbers_are_jumpers no)
		(fp_line
			(start 0.7874 -0.4064)
			(end 0.7874 0.4064)
			(stroke
				(width 0.1524)
				(type default)
			)
			(layer "F.SilkS")
		)
		(fp_line
			(start -0.7874 -0.4064)
			(end 0.7874 -0.4064)
			(stroke
				(width 0.1524)
				(type default)
			)
			(layer "F.SilkS")
		)
		(fp_line
			(start 0.7874 0.4064)
			(end -0.7874 0.4064)
			(stroke
				(width 0.1524)
				(type default)
			)
			(layer "F.SilkS")
		)
		(fp_line
			(start -0.7874 0.4064)
			(end -0.7874 -0.4064)
			(stroke
				(width 0.1524)
				(type default)
			)
			(layer "F.SilkS")
		)
		(fp_poly
			(pts
				(xy -0.508 0.2794) (xy -0.508 0.2286) (xy -0.635 0.2286) (xy -0.635 -0.254) (xy -0.5334 -0.254)
				(xy -0.5334 -0.2794) (xy 0.5334 -0.2794) (xy 0.5334 -0.254) (xy 0.635 -0.254) (xy 0.635 0.254) (xy 0.5334 0.254)
				(xy 0.5334 0.2794)
			)
			(stroke
				(width 0)
				(type default)
			)
			(fill no)
			(layer "F.CrtYd")
		)
		(pad "1" smd rect
			(at 0.40005 0 90)
			(size 0.4572 0.508)
			(layers "F.Cu" "F.Mask" "F.Paste")
			(net "SMB_PCH_SCL")
		)
		(pad "2" smd rect
			(at -0.40005 0 90)
			(size 0.4572 0.508)
			(layers "F.Cu" "F.Mask" "F.Paste")
			(net "SMB_LAN1_CLK")
		)
	)
	(footprint ""
		(layer "F.Cu")
		(at 153.872184 -44.41063 180)
		(property "Reference" "J7"
			(at -4.145026 2.643124 90)
			(unlocked yes)
			(layer "F.SilkS")
			(effects
				(font
					(size 0.7874 0.5842)
					(thickness 0.1524)
				)
				(justify left)
			)
		)
		(property "Value" ""
			(at 0 0 180)
			(layer "F.Fab")
			(effects
				(font
					(size 1.27 1.27)
				)
			)
		)
		(duplicate_pad_numbers_are_jumpers no)
		(fp_line
			(start 2.949956 11.73988)
			(end 2.949956 -4.260088)
			(stroke
				(width 0.1524)
				(type default)
			)
			(layer "F.SilkS")
		)
		(fp_line
			(start 0.145796 8.845296)
			(end 0.145796 8.464296)
			(stroke
				(width 0.1524)
				(type default)
			)
			(layer "F.SilkS")
		)
		(fp_line
			(start 0.145796 8.464296)
			(end -2.597404 8.464296)
			(stroke
				(width 0.1524)
				(type default)
			)
			(layer "F.SilkS")
		)
		(fp_line
			(start -2.597404 8.464296)
			(end -2.597404 -0.298704)
			(stroke
				(width 0.1524)
				(type default)
			)
			(layer "F.SilkS")
		)
		(fp_line
			(start -2.597404 -0.298704)
			(end -2.902204 -0.298704)
			(stroke
				(width 0.1524)
				(type default)
			)
			(layer "F.SilkS")
		)
		(fp_line
			(start -2.902204 8.845296)
			(end 0.145796 8.845296)
			(stroke
				(width 0.1524)
				(type default)
			)
			(layer "F.SilkS")
		)
		(fp_line
			(start -2.902204 -0.298704)
			(end -2.902204 8.845296)
			(stroke
				(width 0.1524)
				(type default)
			)
			(layer "F.SilkS")
		)
		(fp_line
			(start -3.50012 11.73988)
			(end 2.949956 11.73988)
			(stroke
				(width 0.1524)
				(type default)
			)
			(layer "F.SilkS")
		)
		(fp_line
			(start -3.50012 11.73988)
			(end -3.50012 -4.260088)
			(stroke
				(width 0.1524)
				(type default)
			)
			(layer "F.SilkS")
		)
		(fp_line
			(start -3.50012 -4.260088)
			(end 2.949956 -4.260088)
			(stroke
				(width 0.1524)
				(type default)
			)
			(layer "F.SilkS")
		)
		(fp_poly
			(pts
				(xy -2.050542 8.210296) (xy 0.591058 8.210296) (xy 0.591058 -0.603504) (xy -2.050542 -0.603504)
				(xy -2.101342 -0.603504) (xy -2.101342 8.210296)
			)
			(stroke
				(width 0)
				(type default)
			)
			(fill no)
			(layer "B.CrtYd")
		)
		(fp_poly
			(pts
				(arc
					(start -1.015492 -2.45999)
					(mid 1.015492 -2.45999)
					(end -1.015492 -2.45999)
				)
			)
			(stroke
				(width 0)
				(type default)
			)
			(fill no)
			(layer "B.CrtYd")
		)
		(fp_poly
			(pts
				(arc
					(start -2.016506 10.370058)
					(mid 0.01651 10.370058)
					(end -2.016506 10.370058)
				)
			)
			(stroke
				(width 0)
				(type default)
			)
			(fill no)
			(layer "B.CrtYd")
		)
		(fp_poly
			(pts
				(xy -0.020066 11.73988) (xy 2.949956 11.73988) (xy 2.949956 -4.260088) (xy -3.50012 -4.260088) (xy -3.50012 11.73988)
			)
			(stroke
				(width 0)
				(type default)
			)
			(fill no)
			(layer "F.CrtYd")
		)
		(fp_line
			(start 2.949956 11.73988)
			(end 2.949956 -4.260088)
			(stroke
				(width 0.1)
				(type default)
			)
			(layer "F.Fab")
		)
		(fp_line
			(start 2.949956 -4.260088)
			(end -3.50012 -4.260088)
			(stroke
				(width 0.1)
				(type default)
			)
			(layer "F.Fab")
		)
		(fp_line
			(start -0.020066 11.73988)
			(end 2.949956 11.73988)
			(stroke
				(width 0.1)
				(type default)
			)
			(layer "F.Fab")
		)
		(fp_line
			(start -3.50012 11.73988)
			(end -0.020066 11.73988)
			(stroke
				(width 0.1)
				(type default)
			)
			(layer "F.Fab")
		)
		(fp_line
			(start -3.50012 -4.260088)
			(end -3.50012 11.73988)
			(stroke
				(width 0.1)
				(type default)
			)
			(layer "F.Fab")
		)
		(fp_text user "1"
			(at -2.154936 -5.000244 0)
			(unlocked yes)
			(layer "F.SilkS")
			(effects
				(font
					(size 0.635 0.4064)
					(thickness 0.1524)
				)
				(justify left)
			)
		)
		(fp_text user "7"
			(at -3.864356 8.262874 0)
			(unlocked yes)
			(layer "F.SilkS")
			(effects
				(font
					(size 0.635 0.4064)
					(thickness 0.1524)
				)
				(justify left)
			)
		)
		(fp_text user "1"
			(at 1.365758 0.058674 0)
			(unlocked yes)
			(layer "B.SilkS")
			(effects
				(font
					(size 0.7874 0.5842)
					(thickness 0.1524)
				)
				(justify left mirror)
			)
		)
		(fp_text user "7"
			(at 0.956564 7.765034 0)
			(unlocked yes)
			(layer "B.SilkS")
			(effects
				(font
					(size 0.7874 0.5842)
					(thickness 0.1524)
				)
				(justify left mirror)
			)
		)
		(fp_text user "7"
			(at 1.15824 7.257796 270)
			(unlocked yes)
			(layer "B.Fab")
			(effects
				(font
					(size 0.7874 0.5842)
					(thickness 0.000001)
				)
				(justify left mirror)
			)
		)
		(fp_text user "1"
			(at 1.10744 -0.260604 270)
			(unlocked yes)
			(layer "B.Fab")
			(effects
				(font
					(size 0.7874 0.5842)
					(thickness 0.000001)
				)
				(justify left mirror)
			)
		)
		(fp_text user "7"
			(at -3.97256 7.841996 270)
			(unlocked yes)
			(layer "F.Fab")
			(effects
				(font
					(size 0.7874 0.5842)
					(thickness 0.000001)
				)
				(justify left)
			)
		)
		(fp_text user "1"
			(at -4.111498 0.755396 270)
			(unlocked yes)
			(layer "F.Fab")
			(effects
				(font
					(size 0.7874 0.5842)
					(thickness 0.000001)
				)
				(justify left)
			)
		)
		(pad "1" thru_hole rect
			(at 0 0 270)
			(size 1.0668 1.0668)
			(drill 0.6604)
			(layers "*.Cu" "*.Mask")
			(remove_unused_layers no)
			(net "GND")
			(clearance 0.0508)
			(thermal_gap 0.0508)
			(padstack
				(mode front_inner_back)
				(layer "Inner"
					(shape circle)
					(size 1.0668 1.0668)
					(clearance 0.0508)
				)
				(layer "B.Cu"
					(shape rect)
					(size 1.0668 1.0668)
					(clearance 0.0508)
				)
			)
		)
		(pad "2" thru_hole circle
			(at -1.500124 1.054608 270)
			(size 1.0668 1.0668)
			(drill 0.6604)
			(layers "*.Cu" "*.Mask")
			(remove_unused_layers no)
			(net "SATA_TX0_C_DP")
			(clearance 0.0508)
			(thermal_gap 0.0508)
		)
		(pad "3" thru_hole circle
			(at -1.500124 2.75463 270)
			(size 1.0668 1.0668)
			(drill 0.6604)
			(layers "*.Cu" "*.Mask")
			(remove_unused_layers no)
			(net "SATA_TX0_C_DN")
			(clearance 0.0508)
			(thermal_gap 0.0508)
		)
		(pad "4" thru_hole circle
			(at 0 3.81 270)
			(size 1.0668 1.0668)
			(drill 0.6604)
			(layers "*.Cu" "*.Mask")
			(remove_unused_layers no)
			(net "GND")
			(clearance 0.0508)
			(thermal_gap 0.0508)
		)
		(pad "5" thru_hole circle
			(at -1.500124 4.864608 270)
			(size 1.0668 1.0668)
			(drill 0.6604)
			(layers "*.Cu" "*.Mask")
			(remove_unused_layers no)
			(net "SATA_RX0_C_DN")
			(clearance 0.0508)
			(thermal_gap 0.0508)
		)
		(pad "6" thru_hole circle
			(at -1.500124 6.56463 270)
			(size 1.0668 1.0668)
			(drill 0.6604)
			(layers "*.Cu" "*.Mask")
			(remove_unused_layers no)
			(net "SATA_RX0_C_DP")
			(clearance 0.0508)
			(thermal_gap 0.0508)
		)
		(pad "7" thru_hole circle
			(at 0 7.62 270)
			(size 1.0668 1.0668)
			(drill 0.6604)
			(layers "*.Cu" "*.Mask")
			(remove_unused_layers no)
			(net "SATA_P7")
			(clearance 0.0508)
			(thermal_gap 0.0508)
		)
		(pad "8" thru_hole circle
			(at 0 -2.45999 270)
			(size 1.9304 1.9304)
			(drill 1.4224)
			(layers "*.Cu" "*.Mask")
			(remove_unused_layers no)
			(net "GND")
			(clearance 0)
		)
		(pad "9" thru_hole circle
			(at -0.999998 10.370058 270)
			(size 1.9304 1.9304)
			(drill 1.4224)
			(layers "*.Cu" "*.Mask")
			(remove_unused_layers no)
			(net "GND")
			(clearance 0)
		)
	)
	(footprint ""
		(layer "F.Cu")
		(at 62.558422 -164.289232 90)
		(property "Reference" "R1110"
			(at 1.75514 0.208026 90)
			(unlocked yes)
			(layer "F.SilkS")
			(effects
				(font
					(size 0.7874 0.5842)
					(thickness 0.1524)
				)
				(justify left)
			)
		)
		(property "Value" ""
			(at 0 0 90)
			(layer "F.Fab")
			(effects
				(font
					(size 1.27 1.27)
				)
			)
		)
		(duplicate_pad_numbers_are_jumpers no)
		(fp_line
			(start 0.7874 -0.4064)
			(end 0.7874 0.4064)
			(stroke
				(width 0.1524)
				(type default)
			)
			(layer "F.SilkS")
		)
		(fp_line
			(start -0.7874 -0.4064)
			(end 0.7874 -0.4064)
			(stroke
				(width 0.1524)
				(type default)
			)
			(layer "F.SilkS")
		)
		(fp_line
			(start 0.7874 0.4064)
			(end -0.7874 0.4064)
			(stroke
				(width 0.1524)
				(type default)
			)
			(layer "F.SilkS")
		)
		(fp_line
			(start -0.7874 0.4064)
			(end -0.7874 -0.4064)
			(stroke
				(width 0.1524)
				(type default)
			)
			(layer "F.SilkS")
		)
		(fp_poly
			(pts
				(xy -0.508 0.2794) (xy -0.508 0.2286) (xy -0.635 0.2286) (xy -0.635 -0.254) (xy -0.5334 -0.254)
				(xy -0.5334 -0.2794) (xy 0.5334 -0.2794) (xy 0.5334 -0.254) (xy 0.635 -0.254) (xy 0.635 0.254) (xy 0.5334 0.254)
				(xy 0.5334 0.2794)
			)
			(stroke
				(width 0)
				(type default)
			)
			(fill no)
			(layer "F.CrtYd")
		)
		(pad "1" smd rect
			(at 0.40005 0 90)
			(size 0.4572 0.508)
			(layers "F.Cu" "F.Mask" "F.Paste")
			(net "GND")
		)
		(pad "2" smd rect
			(at -0.40005 0 90)
			(size 0.4572 0.508)
			(layers "F.Cu" "F.Mask" "F.Paste")
			(net "P5V_NODE1")
		)
	)
	(footprint ""
		(layer "F.Cu")
		(at 139.68476 -181.506622 -90)
		(property "Reference" "C901"
			(at 0.479044 -1.142746 90)
			(unlocked yes)
			(layer "F.SilkS")
			(effects
				(font
					(size 0.7874 0.5842)
					(thickness 0.1524)
				)
				(justify left)
			)
		)
		(property "Value" ""
			(at 0 0 270)
			(layer "F.Fab")
			(effects
				(font
					(size 1.27 1.27)
				)
			)
		)
		(duplicate_pad_numbers_are_jumpers no)
		(fp_line
			(start -0.7874 0.4064)
			(end -0.7874 -0.4064)
			(stroke
				(width 0.1524)
				(type default)
			)
			(layer "F.SilkS")
		)
		(fp_line
			(start 0.7874 0.4064)
			(end -0.7874 0.4064)
			(stroke
				(width 0.1524)
				(type default)
			)
			(layer "F.SilkS")
		)
		(fp_line
			(start 0 0.381)
			(end 0 -0.381)
			(stroke
				(width 0.1524)
				(type default)
			)
			(layer "F.SilkS")
		)
		(fp_line
			(start -0.7874 -0.4064)
			(end 0.7874 -0.4064)
			(stroke
				(width 0.1524)
				(type default)
			)
			(layer "F.SilkS")
		)
		(fp_line
			(start 0.7874 -0.4064)
			(end 0.7874 0.4064)
			(stroke
				(width 0.1524)
				(type default)
			)
			(layer "F.SilkS")
		)
		(fp_poly
			(pts
				(xy -0.5334 0.254) (xy -0.635 0.254) (xy -0.635 0.2286) (xy -0.635 -0.254) (xy -0.5334 -0.254) (xy -0.5334 -0.2794)
				(xy 0.5334 -0.2794) (xy 0.5334 -0.254) (xy 0.635 -0.254) (xy 0.635 0.254) (xy 0.5334 0.254) (xy 0.5334 0.2794)
				(xy -0.508 0.2794) (xy -0.5334 0.2794)
			)
			(stroke
				(width 0)
				(type default)
			)
			(fill no)
			(layer "F.CrtYd")
		)
		(pad "1" smd rect
			(at 0.40005 0 270)
			(size 0.4572 0.508)
			(layers "F.Cu" "F.Mask" "F.Paste")
			(net "P3V3_NODE1")
		)
		(pad "2" smd rect
			(at -0.40005 0 270)
			(size 0.4572 0.508)
			(layers "F.Cu" "F.Mask" "F.Paste")
			(net "GND")
		)
	)
	(footprint ""
		(layer "F.Cu")
		(at 165.011354 -184.067196 180)
		(property "Reference" "R1170"
			(at 4.889754 0.614934 0)
			(unlocked yes)
			(layer "F.SilkS")
			(effects
				(font
					(size 0.7874 0.5842)
					(thickness 0.1524)
				)
				(justify left)
			)
		)
		(property "Value" ""
			(at 0 0 180)
			(layer "F.Fab")
			(effects
				(font
					(size 1.27 1.27)
				)
			)
		)
		(duplicate_pad_numbers_are_jumpers no)
		(fp_line
			(start 0.7874 0.4064)
			(end -0.7874 0.4064)
			(stroke
				(width 0.1524)
				(type default)
			)
			(layer "F.SilkS")
		)
		(fp_line
			(start 0.7874 -0.4064)
			(end 0.7874 0.4064)
			(stroke
				(width 0.1524)
				(type default)
			)
			(layer "F.SilkS")
		)
		(fp_line
			(start -0.7874 0.4064)
			(end -0.7874 -0.4064)
			(stroke
				(width 0.1524)
				(type default)
			)
			(layer "F.SilkS")
		)
		(fp_line
			(start -0.7874 -0.4064)
			(end 0.7874 -0.4064)
			(stroke
				(width 0.1524)
				(type default)
			)
			(layer "F.SilkS")
		)
		(fp_poly
			(pts
				(xy -0.508 0.2794) (xy -0.508 0.2286) (xy -0.635 0.2286) (xy -0.635 -0.254) (xy -0.5334 -0.254)
				(xy -0.5334 -0.2794) (xy 0.5334 -0.2794) (xy 0.5334 -0.254) (xy 0.635 -0.254) (xy 0.635 0.254) (xy 0.5334 0.254)
				(xy 0.5334 0.2794)
			)
			(stroke
				(width 0)
				(type default)
			)
			(fill no)
			(layer "F.CrtYd")
		)
		(pad "1" smd rect
			(at 0.40005 0 180)
			(size 0.4572 0.508)
			(layers "F.Cu" "F.Mask" "F.Paste")
			(net "CPLD_UART_DTR_P3_R_N")
		)
		(pad "2" smd rect
			(at -0.40005 0 180)
			(size 0.4572 0.508)
			(layers "F.Cu" "F.Mask" "F.Paste")
			(net "CPLD_UART_DTR_P3_N")
		)
	)
	(footprint ""
		(layer "F.Cu")
		(at 122.818652 -26.574242 90)
		(property "Reference" "R624"
			(at -5.330444 0.35687 90)
			(unlocked yes)
			(layer "F.SilkS")
			(effects
				(font
					(size 0.7874 0.5842)
					(thickness 0.1524)
				)
				(justify left)
			)
		)
		(property "Value" ""
			(at 0 0 90)
			(layer "F.Fab")
			(effects
				(font
					(size 1.27 1.27)
				)
			)
		)
		(duplicate_pad_numbers_are_jumpers no)
		(fp_line
			(start 0.7874 -0.4064)
			(end 0.7874 0.4064)
			(stroke
				(width 0.1524)
				(type default)
			)
			(layer "F.SilkS")
		)
		(fp_line
			(start -0.7874 -0.4064)
			(end 0.7874 -0.4064)
			(stroke
				(width 0.1524)
				(type default)
			)
			(layer "F.SilkS")
		)
		(fp_line
			(start 0.7874 0.4064)
			(end -0.7874 0.4064)
			(stroke
				(width 0.1524)
				(type default)
			)
			(layer "F.SilkS")
		)
		(fp_line
			(start -0.7874 0.4064)
			(end -0.7874 -0.4064)
			(stroke
				(width 0.1524)
				(type default)
			)
			(layer "F.SilkS")
		)
		(fp_poly
			(pts
				(xy -0.508 0.2794) (xy -0.508 0.2286) (xy -0.635 0.2286) (xy -0.635 -0.254) (xy -0.5334 -0.254)
				(xy -0.5334 -0.2794) (xy 0.5334 -0.2794) (xy 0.5334 -0.254) (xy 0.635 -0.254) (xy 0.635 0.254) (xy 0.5334 0.254)
				(xy 0.5334 0.2794)
			)
			(stroke
				(width 0)
				(type default)
			)
			(fill no)
			(layer "F.CrtYd")
		)
		(pad "1" smd rect
			(at 0.40005 0 90)
			(size 0.4572 0.508)
			(layers "F.Cu" "F.Mask" "F.Paste")
			(net "SIO_COPEN_N")
		)
		(pad "2" smd rect
			(at -0.40005 0 90)
			(size 0.4572 0.508)
			(layers "F.Cu" "F.Mask" "F.Paste")
			(net "GND")
		)
	)
	(footprint ""
		(layer "F.Cu")
		(at 50.53076 -185.205624 90)
		(property "Reference" "R836"
			(at 4.006088 0.055372 90)
			(unlocked yes)
			(layer "F.SilkS")
			(effects
				(font
					(size 0.7874 0.5842)
					(thickness 0.1524)
				)
				(justify left)
			)
		)
		(property "Value" ""
			(at 0 0 90)
			(layer "F.Fab")
			(effects
				(font
					(size 1.27 1.27)
				)
			)
		)
		(duplicate_pad_numbers_are_jumpers no)
		(fp_line
			(start 0.7874 -0.4064)
			(end 0.7874 0.4064)
			(stroke
				(width 0.1524)
				(type default)
			)
			(layer "F.SilkS")
		)
		(fp_line
			(start -0.7874 -0.4064)
			(end 0.7874 -0.4064)
			(stroke
				(width 0.1524)
				(type default)
			)
			(layer "F.SilkS")
		)
		(fp_line
			(start 0.7874 0.4064)
			(end -0.7874 0.4064)
			(stroke
				(width 0.1524)
				(type default)
			)
			(layer "F.SilkS")
		)
		(fp_line
			(start -0.7874 0.4064)
			(end -0.7874 -0.4064)
			(stroke
				(width 0.1524)
				(type default)
			)
			(layer "F.SilkS")
		)
		(fp_poly
			(pts
				(xy -0.508 0.2794) (xy -0.508 0.2286) (xy -0.635 0.2286) (xy -0.635 -0.254) (xy -0.5334 -0.254)
				(xy -0.5334 -0.2794) (xy 0.5334 -0.2794) (xy 0.5334 -0.254) (xy 0.635 -0.254) (xy 0.635 0.254) (xy 0.5334 0.254)
				(xy 0.5334 0.2794)
			)
			(stroke
				(width 0)
				(type default)
			)
			(fill no)
			(layer "F.CrtYd")
		)
		(pad "1" smd rect
			(at 0.40005 0 90)
			(size 0.4572 0.508)
			(layers "F.Cu" "F.Mask" "F.Paste")
			(net "PSU3_AC_OK_R")
		)
		(pad "2" smd rect
			(at -0.40005 0 90)
			(size 0.4572 0.508)
			(layers "F.Cu" "F.Mask" "F.Paste")
			(net "PSU3_AC_OK")
		)
	)
	(footprint ""
		(layer "F.Cu")
		(at 89.962228 -133.213094 -90)
		(property "Reference" "D37"
			(at -3.582162 1.343406 90)
			(unlocked yes)
			(layer "F.SilkS")
			(effects
				(font
					(size 0.7874 0.5842)
					(thickness 0.1524)
				)
				(justify left)
			)
		)
		(property "Value" ""
			(at 0 0 270)
			(layer "F.Fab")
			(effects
				(font
					(size 1.27 1.27)
				)
			)
		)
		(duplicate_pad_numbers_are_jumpers no)
		(fp_line
			(start -1.3208 0.5588)
			(end -1.3208 -0.5588)
			(stroke
				(width 0.1524)
				(type default)
			)
			(layer "F.SilkS")
		)
		(fp_line
			(start 1.3208 0.5588)
			(end -1.3208 0.5588)
			(stroke
				(width 0.1524)
				(type default)
			)
			(layer "F.SilkS")
		)
		(fp_line
			(start 1.6256 0.5588)
			(end 1.6256 -0.5588)
			(stroke
				(width 0.1524)
				(type default)
			)
			(layer "F.SilkS")
		)
		(fp_line
			(start 1.778 0.5588)
			(end 1.3208 0.5588)
			(stroke
				(width 0.1524)
				(type default)
			)
			(layer "F.SilkS")
		)
		(fp_line
			(start -1.3208 -0.5588)
			(end 1.3208 -0.5588)
			(stroke
				(width 0.1524)
				(type default)
			)
			(layer "F.SilkS")
		)
		(fp_line
			(start 1.3208 -0.5588)
			(end 1.3208 0.5588)
			(stroke
				(width 0.1524)
				(type default)
			)
			(layer "F.SilkS")
		)
		(fp_line
			(start 1.4732 -0.5588)
			(end 1.4732 0.5588)
			(stroke
				(width 0.1524)
				(type default)
			)
			(layer "F.SilkS")
		)
		(fp_line
			(start 1.778 -0.5588)
			(end 1.778 0.5588)
			(stroke
				(width 0.1524)
				(type default)
			)
			(layer "F.SilkS")
		)
		(fp_line
			(start 1.778 -0.5588)
			(end 1.3208 -0.5588)
			(stroke
				(width 0.1524)
				(type default)
			)
			(layer "F.SilkS")
		)
		(fp_circle
			(center 2.4384 0)
			(end 2.4384 -0.413512)
			(stroke
				(width 0.1524)
				(type default)
			)
			(fill no)
			(layer "F.SilkS")
		)
		(fp_rect
			(start -1.1684 0.508)
			(end 1.1684 -0.508)
			(stroke
				(width 0)
				(type default)
			)
			(fill no)
			(layer "F.CrtYd")
		)
		(fp_text user "-"
			(at 1.898396 0.67818 270)
			(unlocked yes)
			(layer "F.SilkS")
			(effects
				(font
					(size 0.7874 0.5842)
					(thickness 0.1524)
				)
				(justify left)
			)
		)
		(pad "A" smd rect
			(at -0.750062 0 270)
			(size 0.8128 0.8128)
			(layers "F.Cu" "F.Mask" "F.Paste")
			(net "P3V3_NODE1")
		)
		(pad "C" smd rect
			(at 0.750062 0 270)
			(size 0.8128 0.8128)
			(layers "F.Cu" "F.Mask" "F.Paste")
			(net "N53313577")
		)
	)
	(footprint ""
		(layer "F.Cu")
		(at 16.825468 -54.773322 90)
		(property "Reference" "L39"
			(at -1.449578 14.098016 90)
			(unlocked yes)
			(layer "F.SilkS")
			(effects
				(font
					(size 0.7874 0.5842)
					(thickness 0.1524)
				)
			)
		)
		(property "Value" ""
			(at 0 0 90)
			(layer "F.Fab")
			(effects
				(font
					(size 1.27 1.27)
				)
			)
		)
		(duplicate_pad_numbers_are_jumpers no)
		(fp_line
			(start 1.2954 -0.635)
			(end 1.2954 0.635)
			(stroke
				(width 0.1524)
				(type default)
			)
			(layer "F.SilkS")
		)
		(fp_line
			(start -1.2954 -0.635)
			(end 1.2954 -0.635)
			(stroke
				(width 0.1524)
				(type default)
			)
			(layer "F.SilkS")
		)
		(fp_line
			(start -1.2954 -0.635)
			(end -1.2954 0.635)
			(stroke
				(width 0.1524)
				(type default)
			)
			(layer "F.SilkS")
		)
		(fp_line
			(start 0.127 -0.5842)
			(end 0.127 0.5842)
			(stroke
				(width 0.1524)
				(type default)
			)
			(layer "F.SilkS")
		)
		(fp_line
			(start -0.127 -0.5842)
			(end -0.127 0.5842)
			(stroke
				(width 0.1524)
				(type default)
			)
			(layer "F.SilkS")
		)
		(fp_line
			(start 1.2954 0.635)
			(end -1.2954 0.635)
			(stroke
				(width 0.1524)
				(type default)
			)
			(layer "F.SilkS")
		)
		(fp_poly
			(pts
				(xy -0.9144 0.508) (xy -0.9144 0.3556) (xy -1.143 0.3556) (xy -1.143 -0.3556) (xy -0.9144 -0.3556)
				(xy -0.9144 -0.508) (xy 0.9144 -0.508) (xy 0.9144 -0.3556) (xy 1.143 -0.3556) (xy 1.143 0.3556)
				(xy 0.9144 0.3556) (xy 0.9144 0.508)
			)
			(stroke
				(width 0)
				(type default)
			)
			(fill no)
			(layer "F.CrtYd")
		)
		(pad "1" smd rect
			(at 0.7366 0 180)
			(size 0.7112 0.8128)
			(layers "F.Cu" "F.Mask" "F.Paste")
			(net "BMC_NODE1_GFX_BLUE")
		)
		(pad "2" smd rect
			(at -0.7366 0 180)
			(size 0.7112 0.8128)
			(layers "F.Cu" "F.Mask" "F.Paste")
			(net "CRT_B_L")
		)
	)
	(footprint ""
		(layer "F.Cu")
		(at 190.627 -124.079)
		(property "Reference" "R1267"
			(at 1.27 0.02667 0)
			(unlocked yes)
			(layer "F.SilkS")
			(effects
				(font
					(size 0.7874 0.5842)
					(thickness 0.1524)
				)
				(justify left)
			)
		)
		(property "Value" ""
			(at 0 0 0)
			(layer "F.Fab")
			(effects
				(font
					(size 1.27 1.27)
				)
			)
		)
		(duplicate_pad_numbers_are_jumpers no)
		(fp_line
			(start -0.7874 -0.4064)
			(end 0.7874 -0.4064)
			(stroke
				(width 0.1524)
				(type default)
			)
			(layer "F.SilkS")
		)
		(fp_line
			(start -0.7874 0.4064)
			(end -0.7874 -0.4064)
			(stroke
				(width 0.1524)
				(type default)
			)
			(layer "F.SilkS")
		)
		(fp_line
			(start 0.7874 -0.4064)
			(end 0.7874 0.4064)
			(stroke
				(width 0.1524)
				(type default)
			)
			(layer "F.SilkS")
		)
		(fp_line
			(start 0.7874 0.4064)
			(end -0.7874 0.4064)
			(stroke
				(width 0.1524)
				(type default)
			)
			(layer "F.SilkS")
		)
		(fp_poly
			(pts
				(xy -0.508 0.2794) (xy -0.508 0.2286) (xy -0.635 0.2286) (xy -0.635 -0.254) (xy -0.5334 -0.254)
				(xy -0.5334 -0.2794) (xy 0.5334 -0.2794) (xy 0.5334 -0.254) (xy 0.635 -0.254) (xy 0.635 0.254) (xy 0.5334 0.254)
				(xy 0.5334 0.2794)
			)
			(stroke
				(width 0)
				(type default)
			)
			(fill no)
			(layer "F.CrtYd")
		)
		(pad "1" smd rect
			(at 0.40005 0)
			(size 0.4572 0.508)
			(layers "F.Cu" "F.Mask" "F.Paste")
			(net "SIO_JTAG_CPLD1_TCK_R")
		)
		(pad "2" smd rect
			(at -0.40005 0)
			(size 0.4572 0.508)
			(layers "F.Cu" "F.Mask" "F.Paste")
			(net "SIO_JTAG_CPLD1_TCK")
		)
	)
	(footprint ""
		(layer "F.Cu")
		(at 79.984092 -75.146154 180)
		(property "Reference" "R114"
			(at 0.336296 -16.257524 0)
			(unlocked yes)
			(layer "F.SilkS")
			(effects
				(font
					(size 0.7874 0.5842)
					(thickness 0.1524)
				)
				(justify left)
			)
		)
		(property "Value" ""
			(at 0 0 180)
			(layer "F.Fab")
			(effects
				(font
					(size 1.27 1.27)
				)
			)
		)
		(duplicate_pad_numbers_are_jumpers no)
		(fp_line
			(start 0.7874 0.4064)
			(end -0.7874 0.4064)
			(stroke
				(width 0.1524)
				(type default)
			)
			(layer "F.SilkS")
		)
		(fp_line
			(start 0.7874 -0.4064)
			(end 0.7874 0.4064)
			(stroke
				(width 0.1524)
				(type default)
			)
			(layer "F.SilkS")
		)
		(fp_line
			(start -0.7874 0.4064)
			(end -0.7874 -0.4064)
			(stroke
				(width 0.1524)
				(type default)
			)
			(layer "F.SilkS")
		)
		(fp_line
			(start -0.7874 -0.4064)
			(end 0.7874 -0.4064)
			(stroke
				(width 0.1524)
				(type default)
			)
			(layer "F.SilkS")
		)
		(fp_poly
			(pts
				(xy -0.508 0.2794) (xy -0.508 0.2286) (xy -0.635 0.2286) (xy -0.635 -0.254) (xy -0.5334 -0.254)
				(xy -0.5334 -0.2794) (xy 0.5334 -0.2794) (xy 0.5334 -0.254) (xy 0.635 -0.254) (xy 0.635 0.254) (xy 0.5334 0.254)
				(xy 0.5334 0.2794)
			)
			(stroke
				(width 0)
				(type default)
			)
			(fill no)
			(layer "F.CrtYd")
		)
		(pad "1" smd rect
			(at 0.40005 0 180)
			(size 0.4572 0.508)
			(layers "F.Cu" "F.Mask" "F.Paste")
			(net "XDP_CPU_NODE1_PRDY_L")
		)
		(pad "2" smd rect
			(at -0.40005 0 180)
			(size 0.4572 0.508)
			(layers "F.Cu" "F.Mask" "F.Paste")
			(net "P1V05_NODE1")
		)
	)
	(footprint ""
		(layer "F.Cu")
		(at 172.701458 -12.474194 90)
		(property "Reference" "R1212"
			(at -0.981202 2.105152 90)
			(unlocked yes)
			(layer "F.SilkS")
			(effects
				(font
					(size 0.7874 0.5842)
					(thickness 0.1524)
				)
				(justify left)
			)
		)
		(property "Value" ""
			(at 0 0 90)
			(layer "F.Fab")
			(effects
				(font
					(size 1.27 1.27)
				)
			)
		)
		(duplicate_pad_numbers_are_jumpers no)
		(fp_line
			(start 0.7874 -0.4064)
			(end 0.7874 0.4064)
			(stroke
				(width 0.1524)
				(type default)
			)
			(layer "F.SilkS")
		)
		(fp_line
			(start -0.7874 -0.4064)
			(end 0.7874 -0.4064)
			(stroke
				(width 0.1524)
				(type default)
			)
			(layer "F.SilkS")
		)
		(fp_line
			(start 0.7874 0.4064)
			(end -0.7874 0.4064)
			(stroke
				(width 0.1524)
				(type default)
			)
			(layer "F.SilkS")
		)
		(fp_line
			(start -0.7874 0.4064)
			(end -0.7874 -0.4064)
			(stroke
				(width 0.1524)
				(type default)
			)
			(layer "F.SilkS")
		)
		(fp_poly
			(pts
				(xy -0.508 0.2794) (xy -0.508 0.2286) (xy -0.635 0.2286) (xy -0.635 -0.254) (xy -0.5334 -0.254)
				(xy -0.5334 -0.2794) (xy 0.5334 -0.2794) (xy 0.5334 -0.254) (xy 0.635 -0.254) (xy 0.635 0.254) (xy 0.5334 0.254)
				(xy 0.5334 0.2794)
			)
			(stroke
				(width 0)
				(type default)
			)
			(fill no)
			(layer "F.CrtYd")
		)
		(pad "1" smd rect
			(at 0.40005 0 90)
			(size 0.4572 0.508)
			(layers "F.Cu" "F.Mask" "F.Paste")
			(net "GND")
		)
		(pad "2" smd rect
			(at -0.40005 0 90)
			(size 0.4572 0.508)
			(layers "F.Cu" "F.Mask" "F.Paste")
			(net "JTAG_CPLD3_TCK")
		)
	)
	(footprint ""
		(layer "F.Cu")
		(at 136.822688 -64.480948 180)
		(property "Reference" "C329"
			(at 2.02565 0.37719 90)
			(unlocked yes)
			(layer "F.SilkS")
			(effects
				(font
					(size 0.7874 0.5842)
					(thickness 0.1524)
				)
			)
		)
		(property "Value" ""
			(at 0 0 180)
			(layer "F.Fab")
			(effects
				(font
					(size 1.27 1.27)
				)
			)
		)
		(duplicate_pad_numbers_are_jumpers no)
		(fp_line
			(start 1.2954 0.5842)
			(end -1.2954 0.5842)
			(stroke
				(width 0.1524)
				(type default)
			)
			(layer "F.SilkS")
		)
		(fp_line
			(start 1.2954 -0.5842)
			(end 1.2954 0.5842)
			(stroke
				(width 0.1524)
				(type default)
			)
			(layer "F.SilkS")
		)
		(fp_line
			(start 0 -0.5842)
			(end 0 0.5842)
			(stroke
				(width 0.1524)
				(type default)
			)
			(layer "F.SilkS")
		)
		(fp_line
			(start -1.2954 0.5842)
			(end -1.2954 -0.5842)
			(stroke
				(width 0.1524)
				(type default)
			)
			(layer "F.SilkS")
		)
		(fp_line
			(start -1.2954 -0.5842)
			(end 1.2954 -0.5842)
			(stroke
				(width 0.1524)
				(type default)
			)
			(layer "F.SilkS")
		)
		(fp_poly
			(pts
				(xy 0.8636 -0.4572) (xy 0.8636 -0.3556) (xy 1.143 -0.3556) (xy 1.143 0.3556) (xy 0.8636 0.3556)
				(xy 0.8636 0.4572) (xy -0.8636 0.4572) (xy -0.8636 0.3556) (xy -1.143 0.3556) (xy -1.143 -0.3556)
				(xy -0.8636 -0.3556) (xy -0.8636 -0.4572)
			)
			(stroke
				(width 0)
				(type default)
			)
			(fill no)
			(layer "F.CrtYd")
		)
		(fp_line
			(start 0.884936 0.504952)
			(end -0.884936 0.504952)
			(stroke
				(width 0.1)
				(type default)
			)
			(layer "F.Fab")
		)
		(fp_line
			(start 0.884936 -0.504952)
			(end 0.884936 0.504952)
			(stroke
				(width 0.1)
				(type default)
			)
			(layer "F.Fab")
		)
		(fp_line
			(start -0.884936 0.504952)
			(end -0.884936 -0.504952)
			(stroke
				(width 0.1)
				(type default)
			)
			(layer "F.Fab")
		)
		(fp_line
			(start -0.884936 -0.504952)
			(end 0.884936 -0.504952)
			(stroke
				(width 0.1)
				(type default)
			)
			(layer "F.Fab")
		)
		(pad "1" smd rect
			(at 0.7366 0 270)
			(size 0.7112 0.8128)
			(layers "F.Cu" "F.Mask" "F.Paste")
			(net "P1V8_NODE1")
		)
		(pad "2" smd rect
			(at -0.7366 0 270)
			(size 0.7112 0.8128)
			(layers "F.Cu" "F.Mask" "F.Paste")
			(net "GND")
		)
	)
	(footprint ""
		(layer "F.Cu")
		(at 138.303 -51.435 90)
		(property "Reference" "R777"
			(at 16.383 30.70987 90)
			(unlocked yes)
			(layer "F.SilkS")
			(effects
				(font
					(size 0.7874 0.5842)
					(thickness 0.1524)
				)
				(justify left)
			)
		)
		(property "Value" ""
			(at 0 0 90)
			(layer "F.Fab")
			(effects
				(font
					(size 1.27 1.27)
				)
			)
		)
		(duplicate_pad_numbers_are_jumpers no)
		(fp_line
			(start 0.7874 -0.4064)
			(end 0.7874 0.4064)
			(stroke
				(width 0.1524)
				(type default)
			)
			(layer "F.SilkS")
		)
		(fp_line
			(start -0.7874 -0.4064)
			(end 0.7874 -0.4064)
			(stroke
				(width 0.1524)
				(type default)
			)
			(layer "F.SilkS")
		)
		(fp_line
			(start 0.7874 0.4064)
			(end -0.7874 0.4064)
			(stroke
				(width 0.1524)
				(type default)
			)
			(layer "F.SilkS")
		)
		(fp_line
			(start -0.7874 0.4064)
			(end -0.7874 -0.4064)
			(stroke
				(width 0.1524)
				(type default)
			)
			(layer "F.SilkS")
		)
		(fp_poly
			(pts
				(xy -0.508 0.2794) (xy -0.508 0.2286) (xy -0.635 0.2286) (xy -0.635 -0.254) (xy -0.5334 -0.254)
				(xy -0.5334 -0.2794) (xy 0.5334 -0.2794) (xy 0.5334 -0.254) (xy 0.635 -0.254) (xy 0.635 0.254) (xy 0.5334 0.254)
				(xy 0.5334 0.2794)
			)
			(stroke
				(width 0)
				(type default)
			)
			(fill no)
			(layer "F.CrtYd")
		)
		(pad "1" smd rect
			(at 0.40005 0 90)
			(size 0.4572 0.508)
			(layers "F.Cu" "F.Mask" "F.Paste")
			(net "P5V_NODE1")
		)
		(pad "2" smd rect
			(at -0.40005 0 90)
			(size 0.4572 0.508)
			(layers "F.Cu" "F.Mask" "F.Paste")
			(net "UART_CTS_P3_N")
		)
	)
	(footprint ""
		(layer "F.Cu")
		(at 24.752046 -47.095664 180)
		(property "Reference" "Q18"
			(at -2.273046 0.212852 90)
			(unlocked yes)
			(layer "F.SilkS")
			(effects
				(font
					(size 0.7874 0.5842)
					(thickness 0.1524)
				)
			)
		)
		(property "Value" ""
			(at 0 0 180)
			(layer "F.Fab")
			(effects
				(font
					(size 1.27 1.27)
				)
			)
		)
		(duplicate_pad_numbers_are_jumpers no)
		(fp_line
			(start 1.651 1.905)
			(end -1.651 1.905)
			(stroke
				(width 0.1524)
				(type default)
			)
			(layer "F.SilkS")
		)
		(fp_line
			(start 1.651 -1.905)
			(end 1.651 1.905)
			(stroke
				(width 0.1524)
				(type default)
			)
			(layer "F.SilkS")
		)
		(fp_line
			(start -1.651 1.905)
			(end -1.651 -1.905)
			(stroke
				(width 0.1524)
				(type default)
			)
			(layer "F.SilkS")
		)
		(fp_line
			(start -1.651 -1.905)
			(end 1.651 -1.905)
			(stroke
				(width 0.1524)
				(type default)
			)
			(layer "F.SilkS")
		)
		(fp_poly
			(pts
				(xy -1.524 0.7112) (xy -1.524 1.7526) (xy -0.508 1.7526) (xy -0.508 0.6985) (xy 0.508 0.6985) (xy 0.508 1.7526)
				(xy 1.524 1.7526) (xy 1.524 0.6985) (xy 1.524 -0.6985) (xy 0.508 -0.6985) (xy 0.508 -1.7526) (xy -0.508 -1.7526)
				(xy -0.508 -0.6985) (xy -1.524 -0.6985) (xy -1.524 0.6985)
			)
			(stroke
				(width 0)
				(type default)
			)
			(fill no)
			(layer "F.CrtYd")
		)
		(fp_text user "S"
			(at 0.446278 2.465324 0)
			(unlocked yes)
			(layer "F.SilkS")
			(effects
				(font
					(size 0.635 0.4064)
					(thickness 0.1524)
				)
			)
		)
		(fp_text user "D"
			(at -2.043176 -1.641602 0)
			(unlocked yes)
			(layer "F.SilkS")
			(effects
				(font
					(size 0.635 0.4064)
					(thickness 0.1524)
				)
			)
		)
		(fp_text user "G"
			(at -2.293112 2.310892 0)
			(unlocked yes)
			(layer "F.SilkS")
			(effects
				(font
					(size 0.635 0.4064)
					(thickness 0.1524)
				)
			)
		)
		(pad "D" smd rect
			(at 0 -1.1176 180)
			(size 1.016 1.27)
			(layers "F.Cu" "F.Mask" "F.Paste")
			(net "I2C_VIDREAR_5V_SDA")
		)
		(pad "G" smd rect
			(at -1.016 1.1176 180)
			(size 1.016 1.27)
			(layers "F.Cu" "F.Mask" "F.Paste")
			(net "N21581283")
		)
		(pad "S" smd rect
			(at 1.016 1.1176 180)
			(size 1.016 1.27)
			(layers "F.Cu" "F.Mask" "F.Paste")
			(net "SMB_BMC_NODE1_DDC_DAT")
		)
	)
	(footprint ""
		(layer "F.Cu")
		(at 73.39076 -188.126624 -90)
		(property "Reference" "R944"
			(at -4.548886 1.038098 90)
			(unlocked yes)
			(layer "F.SilkS")
			(effects
				(font
					(size 0.7874 0.5842)
					(thickness 0.1524)
				)
				(justify left)
			)
		)
		(property "Value" ""
			(at 0 0 270)
			(layer "F.Fab")
			(effects
				(font
					(size 1.27 1.27)
				)
			)
		)
		(duplicate_pad_numbers_are_jumpers no)
		(fp_line
			(start -0.7874 0.4064)
			(end -0.7874 -0.4064)
			(stroke
				(width 0.1524)
				(type default)
			)
			(layer "F.SilkS")
		)
		(fp_line
			(start 0.7874 0.4064)
			(end -0.7874 0.4064)
			(stroke
				(width 0.1524)
				(type default)
			)
			(layer "F.SilkS")
		)
		(fp_line
			(start -0.7874 -0.4064)
			(end 0.7874 -0.4064)
			(stroke
				(width 0.1524)
				(type default)
			)
			(layer "F.SilkS")
		)
		(fp_line
			(start 0.7874 -0.4064)
			(end 0.7874 0.4064)
			(stroke
				(width 0.1524)
				(type default)
			)
			(layer "F.SilkS")
		)
		(fp_poly
			(pts
				(xy -0.508 0.2794) (xy -0.508 0.2286) (xy -0.635 0.2286) (xy -0.635 -0.254) (xy -0.5334 -0.254)
				(xy -0.5334 -0.2794) (xy 0.5334 -0.2794) (xy 0.5334 -0.254) (xy 0.635 -0.254) (xy 0.635 0.254) (xy 0.5334 0.254)
				(xy 0.5334 0.2794)
			)
			(stroke
				(width 0)
				(type default)
			)
			(fill no)
			(layer "F.CrtYd")
		)
		(pad "1" smd rect
			(at 0.40005 0 270)
			(size 0.4572 0.508)
			(layers "F.Cu" "F.Mask" "F.Paste")
			(net "UART_T4_NODE3_RXD")
		)
		(pad "2" smd rect
			(at -0.40005 0 270)
			(size 0.4572 0.508)
			(layers "F.Cu" "F.Mask" "F.Paste")
			(net "UART_T4_NODE3_RXD_R")
		)
	)
	(footprint ""
		(layer "F.Cu")
		(at 44.53509 -4.187952 90)
		(property "Reference" "PC71"
			(at -3.608324 -13.705586 90)
			(unlocked yes)
			(layer "F.SilkS")
			(effects
				(font
					(size 0.7874 0.5842)
					(thickness 0.1524)
				)
				(justify left)
			)
		)
		(property "Value" ""
			(at 0 0 90)
			(layer "F.Fab")
			(effects
				(font
					(size 1.27 1.27)
				)
			)
		)
		(duplicate_pad_numbers_are_jumpers no)
		(fp_line
			(start 0.7874 -0.4064)
			(end 0.7874 0.4064)
			(stroke
				(width 0.1524)
				(type default)
			)
			(layer "F.SilkS")
		)
		(fp_line
			(start -0.7874 -0.4064)
			(end 0.7874 -0.4064)
			(stroke
				(width 0.1524)
				(type default)
			)
			(layer "F.SilkS")
		)
		(fp_line
			(start 0 0.381)
			(end 0 -0.381)
			(stroke
				(width 0.1524)
				(type default)
			)
			(layer "F.SilkS")
		)
		(fp_line
			(start 0.7874 0.4064)
			(end -0.7874 0.4064)
			(stroke
				(width 0.1524)
				(type default)
			)
			(layer "F.SilkS")
		)
		(fp_line
			(start -0.7874 0.4064)
			(end -0.7874 -0.4064)
			(stroke
				(width 0.1524)
				(type default)
			)
			(layer "F.SilkS")
		)
		(fp_poly
			(pts
				(xy -0.5334 0.254) (xy -0.635 0.254) (xy -0.635 0.2286) (xy -0.635 -0.254) (xy -0.5334 -0.254) (xy -0.5334 -0.2794)
				(xy 0.5334 -0.2794) (xy 0.5334 -0.254) (xy 0.635 -0.254) (xy 0.635 0.254) (xy 0.5334 0.254) (xy 0.5334 0.2794)
				(xy -0.508 0.2794) (xy -0.5334 0.2794)
			)
			(stroke
				(width 0)
				(type default)
			)
			(fill no)
			(layer "F.CrtYd")
		)
		(pad "1" smd rect
			(at 0.40005 0 90)
			(size 0.4572 0.508)
			(layers "F.Cu" "F.Mask" "F.Paste")
			(net "SW_PV_VDDR_NODE1_VIN_FLT")
		)
		(pad "2" smd rect
			(at -0.40005 0 90)
			(size 0.4572 0.508)
			(layers "F.Cu" "F.Mask" "F.Paste")
			(net "GND")
		)
	)
	(footprint ""
		(layer "F.Cu")
		(at 49.88814 -163.89985 90)
		(property "Reference" "R540"
			(at -131.03606 -3.589528 90)
			(unlocked yes)
			(layer "F.SilkS")
			(effects
				(font
					(size 0.7874 0.5842)
					(thickness 0.1524)
				)
				(justify left)
			)
		)
		(property "Value" ""
			(at 0 0 90)
			(layer "F.Fab")
			(effects
				(font
					(size 1.27 1.27)
				)
			)
		)
		(duplicate_pad_numbers_are_jumpers no)
		(fp_line
			(start 0.7874 -0.4064)
			(end 0.7874 0.4064)
			(stroke
				(width 0.1524)
				(type default)
			)
			(layer "F.SilkS")
		)
		(fp_line
			(start -0.7874 -0.4064)
			(end 0.7874 -0.4064)
			(stroke
				(width 0.1524)
				(type default)
			)
			(layer "F.SilkS")
		)
		(fp_line
			(start 0.7874 0.4064)
			(end -0.7874 0.4064)
			(stroke
				(width 0.1524)
				(type default)
			)
			(layer "F.SilkS")
		)
		(fp_line
			(start -0.7874 0.4064)
			(end -0.7874 -0.4064)
			(stroke
				(width 0.1524)
				(type default)
			)
			(layer "F.SilkS")
		)
		(fp_poly
			(pts
				(xy -0.508 0.2794) (xy -0.508 0.2286) (xy -0.635 0.2286) (xy -0.635 -0.254) (xy -0.5334 -0.254)
				(xy -0.5334 -0.2794) (xy 0.5334 -0.2794) (xy 0.5334 -0.254) (xy 0.635 -0.254) (xy 0.635 0.254) (xy 0.5334 0.254)
				(xy 0.5334 0.2794)
			)
			(stroke
				(width 0)
				(type default)
			)
			(fill no)
			(layer "F.CrtYd")
		)
		(pad "1" smd rect
			(at 0.40005 0 90)
			(size 0.4572 0.508)
			(layers "F.Cu" "F.Mask" "F.Paste")
			(net "P3V3_NODE1")
		)
		(pad "2" smd rect
			(at -0.40005 0 90)
			(size 0.4572 0.508)
			(layers "F.Cu" "F.Mask" "F.Paste")
			(net "SMB_LAN1_DAT")
		)
	)
	(footprint ""
		(layer "F.Cu")
		(at 109.075474 -129.941574 180)
		(property "Reference" "PR51"
			(at 8.906764 -3.15849 0)
			(unlocked yes)
			(layer "F.SilkS")
			(effects
				(font
					(size 0.7874 0.5842)
					(thickness 0.1524)
				)
				(justify left)
			)
		)
		(property "Value" ""
			(at 0 0 180)
			(layer "F.Fab")
			(effects
				(font
					(size 1.27 1.27)
				)
			)
		)
		(duplicate_pad_numbers_are_jumpers no)
		(fp_line
			(start 0.7874 0.4064)
			(end -0.7874 0.4064)
			(stroke
				(width 0.1524)
				(type default)
			)
			(layer "F.SilkS")
		)
		(fp_line
			(start 0.7874 -0.4064)
			(end 0.7874 0.4064)
			(stroke
				(width 0.1524)
				(type default)
			)
			(layer "F.SilkS")
		)
		(fp_line
			(start -0.7874 0.4064)
			(end -0.7874 -0.4064)
			(stroke
				(width 0.1524)
				(type default)
			)
			(layer "F.SilkS")
		)
		(fp_line
			(start -0.7874 -0.4064)
			(end 0.7874 -0.4064)
			(stroke
				(width 0.1524)
				(type default)
			)
			(layer "F.SilkS")
		)
		(fp_poly
			(pts
				(xy -0.508 0.2794) (xy -0.508 0.2286) (xy -0.635 0.2286) (xy -0.635 -0.254) (xy -0.5334 -0.254)
				(xy -0.5334 -0.2794) (xy 0.5334 -0.2794) (xy 0.5334 -0.254) (xy 0.635 -0.254) (xy 0.635 0.254) (xy 0.5334 0.254)
				(xy 0.5334 0.2794)
			)
			(stroke
				(width 0)
				(type default)
			)
			(fill no)
			(layer "F.CrtYd")
		)
		(pad "1" smd rect
			(at 0.40005 0 180)
			(size 0.4572 0.508)
			(layers "F.Cu" "F.Mask" "F.Paste")
			(net "VR_PVCCP_NODE1_PHASE1")
		)
		(pad "2" smd rect
			(at -0.40005 0 180)
			(size 0.4572 0.508)
			(layers "F.Cu" "F.Mask" "F.Paste")
			(net "VR_PVCCP_NODE1_UGATE1")
		)
	)
	(footprint ""
		(layer "F.Cu")
		(at 114.046254 -60.239148 180)
		(property "Reference" "R225"
			(at -1.192022 -1.86944 0)
			(unlocked yes)
			(layer "F.SilkS")
			(effects
				(font
					(size 0.7874 0.5842)
					(thickness 0.1524)
				)
				(justify left)
			)
		)
		(property "Value" ""
			(at 0 0 180)
			(layer "F.Fab")
			(effects
				(font
					(size 1.27 1.27)
				)
			)
		)
		(duplicate_pad_numbers_are_jumpers no)
		(fp_line
			(start 0.7874 0.4064)
			(end -0.7874 0.4064)
			(stroke
				(width 0.1524)
				(type default)
			)
			(layer "F.SilkS")
		)
		(fp_line
			(start 0.7874 -0.4064)
			(end 0.7874 0.4064)
			(stroke
				(width 0.1524)
				(type default)
			)
			(layer "F.SilkS")
		)
		(fp_line
			(start -0.7874 0.4064)
			(end -0.7874 -0.4064)
			(stroke
				(width 0.1524)
				(type default)
			)
			(layer "F.SilkS")
		)
		(fp_line
			(start -0.7874 -0.4064)
			(end 0.7874 -0.4064)
			(stroke
				(width 0.1524)
				(type default)
			)
			(layer "F.SilkS")
		)
		(fp_poly
			(pts
				(xy -0.508 0.2794) (xy -0.508 0.2286) (xy -0.635 0.2286) (xy -0.635 -0.254) (xy -0.5334 -0.254)
				(xy -0.5334 -0.2794) (xy 0.5334 -0.2794) (xy 0.5334 -0.254) (xy 0.635 -0.254) (xy 0.635 0.254) (xy 0.5334 0.254)
				(xy 0.5334 0.2794)
			)
			(stroke
				(width 0)
				(type default)
			)
			(fill no)
			(layer "F.CrtYd")
		)
		(pad "1" smd rect
			(at 0.40005 0 180)
			(size 0.4572 0.508)
			(layers "F.Cu" "F.Mask" "F.Paste")
			(net "XDP_NODE1_P60")
		)
		(pad "2" smd rect
			(at -0.40005 0 180)
			(size 0.4572 0.508)
			(layers "F.Cu" "F.Mask" "F.Paste")
			(net "GND")
		)
	)
	(footprint ""
		(layer "F.Cu")
		(at 52.223162 -145.514822 180)
		(property "Reference" "R545"
			(at 2.169922 -6.390894 0)
			(unlocked yes)
			(layer "F.SilkS")
			(effects
				(font
					(size 0.7874 0.5842)
					(thickness 0.1524)
				)
				(justify left)
			)
		)
		(property "Value" ""
			(at 0 0 180)
			(layer "F.Fab")
			(effects
				(font
					(size 1.27 1.27)
				)
			)
		)
		(duplicate_pad_numbers_are_jumpers no)
		(fp_line
			(start 0.7874 0.4064)
			(end -0.7874 0.4064)
			(stroke
				(width 0.1524)
				(type default)
			)
			(layer "F.SilkS")
		)
		(fp_line
			(start 0.7874 -0.4064)
			(end 0.7874 0.4064)
			(stroke
				(width 0.1524)
				(type default)
			)
			(layer "F.SilkS")
		)
		(fp_line
			(start -0.7874 0.4064)
			(end -0.7874 -0.4064)
			(stroke
				(width 0.1524)
				(type default)
			)
			(layer "F.SilkS")
		)
		(fp_line
			(start -0.7874 -0.4064)
			(end 0.7874 -0.4064)
			(stroke
				(width 0.1524)
				(type default)
			)
			(layer "F.SilkS")
		)
		(fp_poly
			(pts
				(xy -0.508 0.2794) (xy -0.508 0.2286) (xy -0.635 0.2286) (xy -0.635 -0.254) (xy -0.5334 -0.254)
				(xy -0.5334 -0.2794) (xy 0.5334 -0.2794) (xy 0.5334 -0.254) (xy 0.635 -0.254) (xy 0.635 0.254) (xy 0.5334 0.254)
				(xy 0.5334 0.2794)
			)
			(stroke
				(width 0)
				(type default)
			)
			(fill no)
			(layer "F.CrtYd")
		)
		(pad "1" smd rect
			(at 0.40005 0 180)
			(size 0.4572 0.508)
			(layers "F.Cu" "F.Mask" "F.Paste")
			(net "SPI_LAN1_NVM_SK")
		)
		(pad "2" smd rect
			(at -0.40005 0 180)
			(size 0.4572 0.508)
			(layers "F.Cu" "F.Mask" "F.Paste")
			(net "LAN1_NVM_SK_R")
		)
	)
	(footprint ""
		(layer "F.Cu")
		(at 83.209384 -92.366338 180)
		(property "Reference" "C110"
			(at -3.768344 -1.0541 0)
			(unlocked yes)
			(layer "F.SilkS")
			(effects
				(font
					(size 0.7874 0.5842)
					(thickness 0.1524)
				)
			)
		)
		(property "Value" ""
			(at 0 0 180)
			(layer "F.Fab")
			(effects
				(font
					(size 1.27 1.27)
				)
			)
		)
		(duplicate_pad_numbers_are_jumpers no)
		(fp_line
			(start 1.2954 0.5842)
			(end -1.2954 0.5842)
			(stroke
				(width 0.1524)
				(type default)
			)
			(layer "F.SilkS")
		)
		(fp_line
			(start 1.2954 -0.5842)
			(end 1.2954 0.5842)
			(stroke
				(width 0.1524)
				(type default)
			)
			(layer "F.SilkS")
		)
		(fp_line
			(start 0 -0.5842)
			(end 0 0.5842)
			(stroke
				(width 0.1524)
				(type default)
			)
			(layer "F.SilkS")
		)
		(fp_line
			(start -1.2954 0.5842)
			(end -1.2954 -0.5842)
			(stroke
				(width 0.1524)
				(type default)
			)
			(layer "F.SilkS")
		)
		(fp_line
			(start -1.2954 -0.5842)
			(end 1.2954 -0.5842)
			(stroke
				(width 0.1524)
				(type default)
			)
			(layer "F.SilkS")
		)
		(fp_poly
			(pts
				(xy 0.8636 -0.4572) (xy 0.8636 -0.3556) (xy 1.143 -0.3556) (xy 1.143 0.3556) (xy 0.8636 0.3556)
				(xy 0.8636 0.4572) (xy -0.8636 0.4572) (xy -0.8636 0.3556) (xy -1.143 0.3556) (xy -1.143 -0.3556)
				(xy -0.8636 -0.3556) (xy -0.8636 -0.4572)
			)
			(stroke
				(width 0)
				(type default)
			)
			(fill no)
			(layer "F.CrtYd")
		)
		(fp_line
			(start 0.884936 0.504952)
			(end -0.884936 0.504952)
			(stroke
				(width 0.1)
				(type default)
			)
			(layer "F.Fab")
		)
		(fp_line
			(start 0.884936 -0.504952)
			(end 0.884936 0.504952)
			(stroke
				(width 0.1)
				(type default)
			)
			(layer "F.Fab")
		)
		(fp_line
			(start -0.884936 0.504952)
			(end -0.884936 -0.504952)
			(stroke
				(width 0.1)
				(type default)
			)
			(layer "F.Fab")
		)
		(fp_line
			(start -0.884936 -0.504952)
			(end 0.884936 -0.504952)
			(stroke
				(width 0.1)
				(type default)
			)
			(layer "F.Fab")
		)
		(pad "1" smd rect
			(at 0.7366 0 270)
			(size 0.7112 0.8128)
			(layers "F.Cu" "F.Mask" "F.Paste")
			(net "P3V3_SUS_NODE1")
		)
		(pad "2" smd rect
			(at -0.7366 0 270)
			(size 0.7112 0.8128)
			(layers "F.Cu" "F.Mask" "F.Paste")
			(net "GND")
		)
	)
	(footprint ""
		(layer "F.Cu")
		(at 82.190082 -162.055556 90)
		(property "Reference" "R935"
			(at -2.612136 1.126744 90)
			(unlocked yes)
			(layer "F.SilkS")
			(effects
				(font
					(size 0.7874 0.5842)
					(thickness 0.1524)
				)
				(justify left)
			)
		)
		(property "Value" ""
			(at 0 0 90)
			(layer "F.Fab")
			(effects
				(font
					(size 1.27 1.27)
				)
			)
		)
		(duplicate_pad_numbers_are_jumpers no)
		(fp_line
			(start 0.7874 -0.4064)
			(end 0.7874 0.4064)
			(stroke
				(width 0.1524)
				(type default)
			)
			(layer "F.SilkS")
		)
		(fp_line
			(start -0.7874 -0.4064)
			(end 0.7874 -0.4064)
			(stroke
				(width 0.1524)
				(type default)
			)
			(layer "F.SilkS")
		)
		(fp_line
			(start 0.7874 0.4064)
			(end -0.7874 0.4064)
			(stroke
				(width 0.1524)
				(type default)
			)
			(layer "F.SilkS")
		)
		(fp_line
			(start -0.7874 0.4064)
			(end -0.7874 -0.4064)
			(stroke
				(width 0.1524)
				(type default)
			)
			(layer "F.SilkS")
		)
		(fp_poly
			(pts
				(xy -0.508 0.2794) (xy -0.508 0.2286) (xy -0.635 0.2286) (xy -0.635 -0.254) (xy -0.5334 -0.254)
				(xy -0.5334 -0.2794) (xy 0.5334 -0.2794) (xy 0.5334 -0.254) (xy 0.635 -0.254) (xy 0.635 0.254) (xy 0.5334 0.254)
				(xy 0.5334 0.2794)
			)
			(stroke
				(width 0)
				(type default)
			)
			(fill no)
			(layer "F.CrtYd")
		)
		(pad "1" smd rect
			(at 0.40005 0 90)
			(size 0.4572 0.508)
			(layers "F.Cu" "F.Mask" "F.Paste")
			(net "UART_T4_NODE1_TXD")
		)
		(pad "2" smd rect
			(at -0.40005 0 90)
			(size 0.4572 0.508)
			(layers "F.Cu" "F.Mask" "F.Paste")
			(net "UART_T4_NODE1_TXD_R")
		)
	)
	(footprint ""
		(layer "F.Cu")
		(at 38.681152 -4.500372)
		(property "Reference" "C853"
			(at -14.711172 1.896364 0)
			(unlocked yes)
			(layer "F.SilkS")
			(effects
				(font
					(size 0.7874 0.5842)
					(thickness 0.1524)
				)
				(justify left)
			)
		)
		(property "Value" ""
			(at 0 0 0)
			(layer "F.Fab")
			(effects
				(font
					(size 1.27 1.27)
				)
			)
		)
		(duplicate_pad_numbers_are_jumpers no)
		(fp_line
			(start -0.7874 -0.4064)
			(end 0.7874 -0.4064)
			(stroke
				(width 0.1524)
				(type default)
			)
			(layer "F.SilkS")
		)
		(fp_line
			(start -0.7874 0.4064)
			(end -0.7874 -0.4064)
			(stroke
				(width 0.1524)
				(type default)
			)
			(layer "F.SilkS")
		)
		(fp_line
			(start 0 0.381)
			(end 0 -0.381)
			(stroke
				(width 0.1524)
				(type default)
			)
			(layer "F.SilkS")
		)
		(fp_line
			(start 0.7874 -0.4064)
			(end 0.7874 0.4064)
			(stroke
				(width 0.1524)
				(type default)
			)
			(layer "F.SilkS")
		)
		(fp_line
			(start 0.7874 0.4064)
			(end -0.7874 0.4064)
			(stroke
				(width 0.1524)
				(type default)
			)
			(layer "F.SilkS")
		)
		(fp_poly
			(pts
				(xy -0.5334 0.254) (xy -0.635 0.254) (xy -0.635 0.2286) (xy -0.635 -0.254) (xy -0.5334 -0.254) (xy -0.5334 -0.2794)
				(xy 0.5334 -0.2794) (xy 0.5334 -0.254) (xy 0.635 -0.254) (xy 0.635 0.254) (xy 0.5334 0.254) (xy 0.5334 0.2794)
				(xy -0.508 0.2794) (xy -0.5334 0.2794)
			)
			(stroke
				(width 0)
				(type default)
			)
			(fill no)
			(layer "F.CrtYd")
		)
		(pad "1" smd rect
			(at 0.40005 0)
			(size 0.4572 0.508)
			(layers "F.Cu" "F.Mask" "F.Paste")
			(net "GND")
		)
		(pad "2" smd rect
			(at -0.40005 0)
			(size 0.4572 0.508)
			(layers "F.Cu" "F.Mask" "F.Paste")
			(net "P3V3_STB_NODE1")
		)
	)
	(footprint ""
		(layer "F.Cu")
		(at 95.113094 -140.101066 180)
		(property "Reference" "C815"
			(at 1.865122 4.19989 0)
			(unlocked yes)
			(layer "F.SilkS")
			(effects
				(font
					(size 0.7874 0.5842)
					(thickness 0.1524)
				)
				(justify left)
			)
		)
		(property "Value" ""
			(at 0 0 180)
			(layer "F.Fab")
			(effects
				(font
					(size 1.27 1.27)
				)
			)
		)
		(duplicate_pad_numbers_are_jumpers no)
		(fp_line
			(start 0.7874 0.4064)
			(end -0.7874 0.4064)
			(stroke
				(width 0.1524)
				(type default)
			)
			(layer "F.SilkS")
		)
		(fp_line
			(start 0.7874 -0.4064)
			(end 0.7874 0.4064)
			(stroke
				(width 0.1524)
				(type default)
			)
			(layer "F.SilkS")
		)
		(fp_line
			(start 0 0.381)
			(end 0 -0.381)
			(stroke
				(width 0.1524)
				(type default)
			)
			(layer "F.SilkS")
		)
		(fp_line
			(start -0.7874 0.4064)
			(end -0.7874 -0.4064)
			(stroke
				(width 0.1524)
				(type default)
			)
			(layer "F.SilkS")
		)
		(fp_line
			(start -0.7874 -0.4064)
			(end 0.7874 -0.4064)
			(stroke
				(width 0.1524)
				(type default)
			)
			(layer "F.SilkS")
		)
		(fp_poly
			(pts
				(xy -0.5334 0.254) (xy -0.635 0.254) (xy -0.635 0.2286) (xy -0.635 -0.254) (xy -0.5334 -0.254) (xy -0.5334 -0.2794)
				(xy 0.5334 -0.2794) (xy 0.5334 -0.254) (xy 0.635 -0.254) (xy 0.635 0.254) (xy 0.5334 0.254) (xy 0.5334 0.2794)
				(xy -0.508 0.2794) (xy -0.5334 0.2794)
			)
			(stroke
				(width 0)
				(type default)
			)
			(fill no)
			(layer "F.CrtYd")
		)
		(pad "1" smd rect
			(at 0.40005 0 180)
			(size 0.4572 0.508)
			(layers "F.Cu" "F.Mask" "F.Paste")
			(net "P1V05_SUS_NODE1_ADJ")
		)
		(pad "2" smd rect
			(at -0.40005 0 180)
			(size 0.4572 0.508)
			(layers "F.Cu" "F.Mask" "F.Paste")
			(net "P1V05_SUS_NODE1_ADJ_S")
		)
	)
	(footprint ""
		(layer "F.Cu")
		(at 70.639686 -148.476462 90)
		(property "Reference" "R304"
			(at 1.233932 -0.125984 90)
			(unlocked yes)
			(layer "F.SilkS")
			(effects
				(font
					(size 0.7874 0.5842)
					(thickness 0.1524)
				)
				(justify left)
			)
		)
		(property "Value" ""
			(at 0 0 90)
			(layer "F.Fab")
			(effects
				(font
					(size 1.27 1.27)
				)
			)
		)
		(duplicate_pad_numbers_are_jumpers no)
		(fp_line
			(start 0.7874 -0.4064)
			(end 0.7874 0.4064)
			(stroke
				(width 0.1524)
				(type default)
			)
			(layer "F.SilkS")
		)
		(fp_line
			(start -0.7874 -0.4064)
			(end 0.7874 -0.4064)
			(stroke
				(width 0.1524)
				(type default)
			)
			(layer "F.SilkS")
		)
		(fp_line
			(start 0.7874 0.4064)
			(end -0.7874 0.4064)
			(stroke
				(width 0.1524)
				(type default)
			)
			(layer "F.SilkS")
		)
		(fp_line
			(start -0.7874 0.4064)
			(end -0.7874 -0.4064)
			(stroke
				(width 0.1524)
				(type default)
			)
			(layer "F.SilkS")
		)
		(fp_poly
			(pts
				(xy -0.508 0.2794) (xy -0.508 0.2286) (xy -0.635 0.2286) (xy -0.635 -0.254) (xy -0.5334 -0.254)
				(xy -0.5334 -0.2794) (xy 0.5334 -0.2794) (xy 0.5334 -0.254) (xy 0.635 -0.254) (xy 0.635 0.254) (xy 0.5334 0.254)
				(xy 0.5334 0.2794)
			)
			(stroke
				(width 0)
				(type default)
			)
			(fill no)
			(layer "F.CrtYd")
		)
		(pad "1" smd rect
			(at 0.40005 0 90)
			(size 0.4572 0.508)
			(layers "F.Cu" "F.Mask" "F.Paste")
			(net "P3V3_NODE1")
		)
		(pad "2" smd rect
			(at -0.40005 0 90)
			(size 0.4572 0.508)
			(layers "F.Cu" "F.Mask" "F.Paste")
			(net "BMC_NODE1_JTAG_TCK")
		)
	)
	(footprint ""
		(layer "F.Cu")
		(at 148.19376 -188.126624 90)
		(property "Reference" "C753"
			(at 5.519674 -2.554732 90)
			(unlocked yes)
			(layer "F.SilkS")
			(effects
				(font
					(size 0.7874 0.5842)
					(thickness 0.1524)
				)
				(justify left)
			)
		)
		(property "Value" ""
			(at 0 0 90)
			(layer "F.Fab")
			(effects
				(font
					(size 1.27 1.27)
				)
			)
		)
		(duplicate_pad_numbers_are_jumpers no)
		(fp_line
			(start 0.7874 -0.4064)
			(end 0.7874 0.4064)
			(stroke
				(width 0.1524)
				(type default)
			)
			(layer "F.SilkS")
		)
		(fp_line
			(start -0.7874 -0.4064)
			(end 0.7874 -0.4064)
			(stroke
				(width 0.1524)
				(type default)
			)
			(layer "F.SilkS")
		)
		(fp_line
			(start 0 0.381)
			(end 0 -0.381)
			(stroke
				(width 0.1524)
				(type default)
			)
			(layer "F.SilkS")
		)
		(fp_line
			(start 0.7874 0.4064)
			(end -0.7874 0.4064)
			(stroke
				(width 0.1524)
				(type default)
			)
			(layer "F.SilkS")
		)
		(fp_line
			(start -0.7874 0.4064)
			(end -0.7874 -0.4064)
			(stroke
				(width 0.1524)
				(type default)
			)
			(layer "F.SilkS")
		)
		(fp_poly
			(pts
				(xy -0.5334 0.254) (xy -0.635 0.254) (xy -0.635 0.2286) (xy -0.635 -0.254) (xy -0.5334 -0.254) (xy -0.5334 -0.2794)
				(xy 0.5334 -0.2794) (xy 0.5334 -0.254) (xy 0.635 -0.254) (xy 0.635 0.254) (xy 0.5334 0.254) (xy 0.5334 0.2794)
				(xy -0.508 0.2794) (xy -0.5334 0.2794)
			)
			(stroke
				(width 0)
				(type default)
			)
			(fill no)
			(layer "F.CrtYd")
		)
		(pad "1" smd rect
			(at 0.40005 0 90)
			(size 0.4572 0.508)
			(layers "F.Cu" "F.Mask" "F.Paste")
			(net "UART_T12_NODE2_TXD_R")
		)
		(pad "2" smd rect
			(at -0.40005 0 90)
			(size 0.4572 0.508)
			(layers "F.Cu" "F.Mask" "F.Paste")
			(net "GND")
		)
	)
	(footprint ""
		(layer "F.Cu")
		(at 32.3596 -132.81533 90)
		(property "Reference" "J22"
			(at 0.906018 0.44958 0)
			(unlocked yes)
			(layer "F.SilkS")
			(effects
				(font
					(size 0.7874 0.5842)
					(thickness 0.1524)
				)
				(justify left)
			)
		)
		(property "Value" ""
			(at 0 0 90)
			(layer "F.Fab")
			(effects
				(font
					(size 1.27 1.27)
				)
			)
		)
		(duplicate_pad_numbers_are_jumpers no)
		(fp_poly
			(pts
				(xy 0.2794 0.907796) (xy 0.254 0.907796) (xy 0.254 1.0414) (xy -0.254 1.0414) (xy -0.254 1.034796)
				(xy -0.254 0.933196) (xy -0.2794 0.933196) (xy -0.2794 -0.133604) (xy -0.254 -0.133604) (xy -0.254 -0.235204)
				(xy 0.254 -0.235204) (xy 0.254 -0.133604) (xy 0.2794 -0.133604)
			)
			(stroke
				(width 0)
				(type default)
			)
			(fill no)
			(layer "F.CrtYd")
		)
		(pad "1" smd custom
			(at 0 -0.000254 90)
			(size 0.127 0.127)
			(layers "F.Cu" "F.Mask" "F.Paste")
			(net "P1V538_STB_NODE1_ADJ_S")
			(options
				(clearance outline)
				(anchor circle)
			)
			(primitives
				(gr_poly
					(pts
						(xy -0.127 0.508) (xy -0.127 -0.0508) (xy -0.254 -0.0508) (xy -0.254 -0.508) (xy 0.254 -0.508)
						(xy 0.254 -0.0508) (xy 0.127 -0.0508) (xy 0.127 0.508)
					)
					(width 0)
					(fill yes)
				)
			)
		)
		(pad "2" smd rect
			(at 0 0.799846 180)
			(size 0.4572 0.508)
			(layers "F.Cu" "F.Mask" "F.Paste")
			(net "P1V538_BMC_NODE1")
		)
		(zone
			(layer "F.Cu")
			(hatch none 0.5)
			(connect_pads
				(clearance 0)
			)
			(min_thickness 0.25)
			(keepout
				(tracks allowed)
				(vias not_allowed)
				(pads allowed)
				(copperpour not_allowed)
				(footprints allowed)
			)
			(placement
				(enabled no)
				(sheetname "")
			)
			(fill
				(thermal_gap 0.5)
				(thermal_bridge_width 0.5)
				(island_removal_mode 0)
			)
			(polygon
				(pts
					(xy 33.445196 -132.51053) (xy 33.445196 -133.12013) (xy 32.073596 -133.12013) (xy 32.073596 -132.51053)
				)
			)
		)
	)
	(footprint ""
		(layer "F.Cu")
		(at 112.17021 -153.688034)
		(property "Reference" "R802"
			(at 0 1.257554 0)
			(unlocked yes)
			(layer "F.SilkS")
			(effects
				(font
					(size 0.635 0.4064)
					(thickness 0.1524)
				)
				(justify left)
			)
		)
		(property "Value" ""
			(at 0 0 0)
			(layer "F.Fab")
			(effects
				(font
					(size 1.27 1.27)
				)
			)
		)
		(duplicate_pad_numbers_are_jumpers no)
		(fp_line
			(start -0.7874 -0.4064)
			(end 0.7874 -0.4064)
			(stroke
				(width 0.1524)
				(type default)
			)
			(layer "F.SilkS")
		)
		(fp_line
			(start -0.7874 0.4064)
			(end -0.7874 -0.4064)
			(stroke
				(width 0.1524)
				(type default)
			)
			(layer "F.SilkS")
		)
		(fp_line
			(start 0.7874 -0.4064)
			(end 0.7874 0.4064)
			(stroke
				(width 0.1524)
				(type default)
			)
			(layer "F.SilkS")
		)
		(fp_line
			(start 0.7874 0.4064)
			(end -0.7874 0.4064)
			(stroke
				(width 0.1524)
				(type default)
			)
			(layer "F.SilkS")
		)
		(fp_poly
			(pts
				(xy -0.508 0.2794) (xy -0.508 0.2286) (xy -0.635 0.2286) (xy -0.635 -0.254) (xy -0.5334 -0.254)
				(xy -0.5334 -0.2794) (xy 0.5334 -0.2794) (xy 0.5334 -0.254) (xy 0.635 -0.254) (xy 0.635 0.254) (xy 0.5334 0.254)
				(xy 0.5334 0.2794)
			)
			(stroke
				(width 0)
				(type default)
			)
			(fill no)
			(layer "F.CrtYd")
		)
		(pad "1" smd rect
			(at 0.40005 0)
			(size 0.4572 0.508)
			(layers "F.Cu" "F.Mask" "F.Paste")
			(net "N52410978")
		)
		(pad "2" smd rect
			(at -0.40005 0)
			(size 0.4572 0.508)
			(layers "F.Cu" "F.Mask" "F.Paste")
			(net "P3V3_STB_NODE1")
		)
	)
	(footprint ""
		(layer "F.Cu")
		(at 100.461572 -177.458624 -90)
		(property "Reference" "U67"
			(at 77.037946 -86.148164 0)
			(unlocked yes)
			(layer "F.SilkS")
			(effects
				(font
					(size 0.7874 0.5842)
					(thickness 0.1524)
				)
				(justify left)
			)
		)
		(property "Value" ""
			(at 0 0 270)
			(layer "F.Fab")
			(effects
				(font
					(size 1.27 1.27)
				)
			)
		)
		(duplicate_pad_numbers_are_jumpers no)
		(fp_line
			(start -2.5146 1.4224)
			(end -2.5146 0.4572)
			(stroke
				(width 0.1524)
				(type default)
			)
			(layer "F.SilkS")
		)
		(fp_line
			(start 2.5146 1.4224)
			(end -2.5146 1.4224)
			(stroke
				(width 0.1524)
				(type default)
			)
			(layer "F.SilkS")
		)
		(fp_line
			(start -2.5146 0.4572)
			(end -2.0574 0)
			(stroke
				(width 0.1524)
				(type default)
			)
			(layer "F.SilkS")
		)
		(fp_line
			(start -2.0574 0)
			(end -2.5146 -0.4572)
			(stroke
				(width 0.1524)
				(type default)
			)
			(layer "F.SilkS")
		)
		(fp_line
			(start -2.5146 -0.4572)
			(end -2.5146 -1.4224)
			(stroke
				(width 0.1524)
				(type default)
			)
			(layer "F.SilkS")
		)
		(fp_line
			(start -2.5146 -1.4224)
			(end 2.5146 -1.4224)
			(stroke
				(width 0.1524)
				(type default)
			)
			(layer "F.SilkS")
		)
		(fp_line
			(start 2.5146 -1.4224)
			(end 2.5146 1.4224)
			(stroke
				(width 0.1524)
				(type default)
			)
			(layer "F.SilkS")
		)
		(fp_circle
			(center -1.905 0.889)
			(end -1.905 0.635)
			(stroke
				(width 0.1524)
				(type default)
			)
			(fill no)
			(layer "F.SilkS")
		)
		(fp_poly
			(pts
				(xy -2.1844 3.5052) (xy -2.1844 2.0066) (xy -2.5146 2.0066) (xy -2.5146 -2.0066) (xy -2.1844 -2.0066)
				(xy -2.1844 -3.5052) (xy 2.1844 -3.5052) (xy 2.1844 -2.0066) (xy 2.5146 -2.0066) (xy 2.5146 2.0066)
				(xy 2.1844 2.0066) (xy 2.1844 3.5052)
			)
			(stroke
				(width 0)
				(type default)
			)
			(fill no)
			(layer "F.CrtYd")
		)
		(pad "1" smd rect
			(at -1.905 2.6416 270)
			(size 0.5588 1.7272)
			(layers "F.Cu" "F.Mask" "F.Paste")
			(net "N21700941")
		)
		(pad "2" smd rect
			(at -0.635 2.6416 270)
			(size 0.5588 1.7272)
			(layers "F.Cu" "F.Mask" "F.Paste")
			(net "N21698939")
		)
		(pad "3" smd rect
			(at 0.635 2.6416 270)
			(size 0.5588 1.7272)
			(layers "F.Cu" "F.Mask" "F.Paste")
			(net "N21698906")
		)
		(pad "4" smd rect
			(at 1.905 2.6416 270)
			(size 0.5588 1.7272)
			(layers "F.Cu" "F.Mask" "F.Paste")
			(net "GND")
		)
		(pad "5" smd rect
			(at 1.905 -2.6416 270)
			(size 0.5588 1.7272)
			(layers "F.Cu" "F.Mask" "F.Paste")
			(net "I2C_COM3_SDA")
		)
		(pad "6" smd rect
			(at 0.635 -2.6416 270)
			(size 0.5588 1.7272)
			(layers "F.Cu" "F.Mask" "F.Paste")
			(net "I2C_COM3_SCL")
		)
		(pad "7" smd rect
			(at -0.635 -2.6416 270)
			(size 0.5588 1.7272)
			(layers "F.Cu" "F.Mask" "F.Paste")
			(net "N21700943")
		)
		(pad "8" smd rect
			(at -1.905 -2.6416 270)
			(size 0.5588 1.7272)
			(layers "F.Cu" "F.Mask" "F.Paste")
			(net "P3V3_NODE1")
		)
	)
	(footprint ""
		(layer "F.Cu")
		(at 110.799626 -142.419832 90)
		(property "Reference" "PR57"
			(at 1.927352 0.092964 90)
			(unlocked yes)
			(layer "F.SilkS")
			(effects
				(font
					(size 0.635 0.4064)
					(thickness 0.1524)
				)
				(justify left)
			)
		)
		(property "Value" ""
			(at 0 0 90)
			(layer "F.Fab")
			(effects
				(font
					(size 1.27 1.27)
				)
			)
		)
		(duplicate_pad_numbers_are_jumpers no)
		(fp_line
			(start 0.7874 -0.4064)
			(end 0.7874 0.4064)
			(stroke
				(width 0.1524)
				(type default)
			)
			(layer "F.SilkS")
		)
		(fp_line
			(start -0.7874 -0.4064)
			(end 0.7874 -0.4064)
			(stroke
				(width 0.1524)
				(type default)
			)
			(layer "F.SilkS")
		)
		(fp_line
			(start 0.7874 0.4064)
			(end -0.7874 0.4064)
			(stroke
				(width 0.1524)
				(type default)
			)
			(layer "F.SilkS")
		)
		(fp_line
			(start -0.7874 0.4064)
			(end -0.7874 -0.4064)
			(stroke
				(width 0.1524)
				(type default)
			)
			(layer "F.SilkS")
		)
		(fp_poly
			(pts
				(xy -0.508 0.2794) (xy -0.508 0.2286) (xy -0.635 0.2286) (xy -0.635 -0.254) (xy -0.5334 -0.254)
				(xy -0.5334 -0.2794) (xy 0.5334 -0.2794) (xy 0.5334 -0.254) (xy 0.635 -0.254) (xy 0.635 0.254) (xy 0.5334 0.254)
				(xy 0.5334 0.2794)
			)
			(stroke
				(width 0)
				(type default)
			)
			(fill no)
			(layer "F.CrtYd")
		)
		(pad "1" smd rect
			(at 0.40005 0 90)
			(size 0.4572 0.508)
			(layers "F.Cu" "F.Mask" "F.Paste")
			(net "VR_PVCCP_NODE1_VCC")
		)
		(pad "2" smd rect
			(at -0.40005 0 90)
			(size 0.4572 0.508)
			(layers "F.Cu" "F.Mask" "F.Paste")
			(net "VR_PVCCP_NODE1_SETINI")
		)
	)
	(footprint ""
		(layer "F.Cu")
		(at 123.00712 -50.035714 90)
		(property "Reference" "R617"
			(at -1.527556 -1.042162 90)
			(unlocked yes)
			(layer "F.SilkS")
			(effects
				(font
					(size 0.7874 0.5842)
					(thickness 0.1524)
				)
				(justify left)
			)
		)
		(property "Value" ""
			(at 0 0 90)
			(layer "F.Fab")
			(effects
				(font
					(size 1.27 1.27)
				)
			)
		)
		(duplicate_pad_numbers_are_jumpers no)
		(fp_line
			(start 0.7874 -0.4064)
			(end 0.7874 0.4064)
			(stroke
				(width 0.1524)
				(type default)
			)
			(layer "F.SilkS")
		)
		(fp_line
			(start -0.7874 -0.4064)
			(end 0.7874 -0.4064)
			(stroke
				(width 0.1524)
				(type default)
			)
			(layer "F.SilkS")
		)
		(fp_line
			(start 0.7874 0.4064)
			(end -0.7874 0.4064)
			(stroke
				(width 0.1524)
				(type default)
			)
			(layer "F.SilkS")
		)
		(fp_line
			(start -0.7874 0.4064)
			(end -0.7874 -0.4064)
			(stroke
				(width 0.1524)
				(type default)
			)
			(layer "F.SilkS")
		)
		(fp_poly
			(pts
				(xy -0.508 0.2794) (xy -0.508 0.2286) (xy -0.635 0.2286) (xy -0.635 -0.254) (xy -0.5334 -0.254)
				(xy -0.5334 -0.2794) (xy 0.5334 -0.2794) (xy 0.5334 -0.254) (xy 0.635 -0.254) (xy 0.635 0.254) (xy 0.5334 0.254)
				(xy 0.5334 0.2794)
			)
			(stroke
				(width 0)
				(type default)
			)
			(fill no)
			(layer "F.CrtYd")
		)
		(pad "1" smd rect
			(at 0.40005 0 90)
			(size 0.4572 0.508)
			(layers "F.Cu" "F.Mask" "F.Paste")
			(net "P3V3_NODE1")
		)
		(pad "2" smd rect
			(at -0.40005 0 90)
			(size 0.4572 0.508)
			(layers "F.Cu" "F.Mask" "F.Paste")
			(net "SIO_PIN38")
		)
	)
	(footprint ""
		(layer "F.Cu")
		(at 136.38657 -26.569416 90)
		(property "Reference" "C485"
			(at -5.325618 0.26543 90)
			(unlocked yes)
			(layer "F.SilkS")
			(effects
				(font
					(size 0.7874 0.5842)
					(thickness 0.1524)
				)
				(justify left)
			)
		)
		(property "Value" ""
			(at 0 0 90)
			(layer "F.Fab")
			(effects
				(font
					(size 1.27 1.27)
				)
			)
		)
		(duplicate_pad_numbers_are_jumpers no)
		(fp_line
			(start 0.7874 -0.4064)
			(end 0.7874 0.4064)
			(stroke
				(width 0.1524)
				(type default)
			)
			(layer "F.SilkS")
		)
		(fp_line
			(start -0.7874 -0.4064)
			(end 0.7874 -0.4064)
			(stroke
				(width 0.1524)
				(type default)
			)
			(layer "F.SilkS")
		)
		(fp_line
			(start 0 0.381)
			(end 0 -0.381)
			(stroke
				(width 0.1524)
				(type default)
			)
			(layer "F.SilkS")
		)
		(fp_line
			(start 0.7874 0.4064)
			(end -0.7874 0.4064)
			(stroke
				(width 0.1524)
				(type default)
			)
			(layer "F.SilkS")
		)
		(fp_line
			(start -0.7874 0.4064)
			(end -0.7874 -0.4064)
			(stroke
				(width 0.1524)
				(type default)
			)
			(layer "F.SilkS")
		)
		(fp_poly
			(pts
				(xy -0.5334 0.254) (xy -0.635 0.254) (xy -0.635 0.2286) (xy -0.635 -0.254) (xy -0.5334 -0.254) (xy -0.5334 -0.2794)
				(xy 0.5334 -0.2794) (xy 0.5334 -0.254) (xy 0.635 -0.254) (xy 0.635 0.254) (xy 0.5334 0.254) (xy 0.5334 0.2794)
				(xy -0.508 0.2794) (xy -0.5334 0.2794)
			)
			(stroke
				(width 0)
				(type default)
			)
			(fill no)
			(layer "F.CrtYd")
		)
		(pad "1" smd rect
			(at 0.40005 0 90)
			(size 0.4572 0.508)
			(layers "F.Cu" "F.Mask" "F.Paste")
			(net "SIO_VREF")
		)
		(pad "2" smd rect
			(at -0.40005 0 90)
			(size 0.4572 0.508)
			(layers "F.Cu" "F.Mask" "F.Paste")
			(net "GNDA")
		)
	)
	(footprint ""
		(layer "F.Cu")
		(at 72.159114 -182.186326 180)
		(property "Reference" "R1074"
			(at 4.849368 0.458978 0)
			(unlocked yes)
			(layer "F.SilkS")
			(effects
				(font
					(size 0.7874 0.5842)
					(thickness 0.1524)
				)
				(justify left)
			)
		)
		(property "Value" ""
			(at 0 0 180)
			(layer "F.Fab")
			(effects
				(font
					(size 1.27 1.27)
				)
			)
		)
		(duplicate_pad_numbers_are_jumpers no)
		(fp_line
			(start 0.7874 0.4064)
			(end -0.7874 0.4064)
			(stroke
				(width 0.1524)
				(type default)
			)
			(layer "F.SilkS")
		)
		(fp_line
			(start 0.7874 -0.4064)
			(end 0.7874 0.4064)
			(stroke
				(width 0.1524)
				(type default)
			)
			(layer "F.SilkS")
		)
		(fp_line
			(start -0.7874 0.4064)
			(end -0.7874 -0.4064)
			(stroke
				(width 0.1524)
				(type default)
			)
			(layer "F.SilkS")
		)
		(fp_line
			(start -0.7874 -0.4064)
			(end 0.7874 -0.4064)
			(stroke
				(width 0.1524)
				(type default)
			)
			(layer "F.SilkS")
		)
		(fp_poly
			(pts
				(xy -0.508 0.2794) (xy -0.508 0.2286) (xy -0.635 0.2286) (xy -0.635 -0.254) (xy -0.5334 -0.254)
				(xy -0.5334 -0.2794) (xy 0.5334 -0.2794) (xy 0.5334 -0.254) (xy 0.635 -0.254) (xy 0.635 0.254) (xy 0.5334 0.254)
				(xy 0.5334 0.2794)
			)
			(stroke
				(width 0)
				(type default)
			)
			(fill no)
			(layer "F.CrtYd")
		)
		(pad "1" smd rect
			(at 0.40005 0 180)
			(size 0.4572 0.508)
			(layers "F.Cu" "F.Mask" "F.Paste")
			(net "GND")
		)
		(pad "2" smd rect
			(at -0.40005 0 180)
			(size 0.4572 0.508)
			(layers "F.Cu" "F.Mask" "F.Paste")
			(net "JTAG_CPLD2_TCK")
		)
	)
	(footprint ""
		(layer "F.Cu")
		(at 116.529104 -63.422784 180)
		(property "Reference" "R223"
			(at -0.95123 -0.010414 0)
			(unlocked yes)
			(layer "F.SilkS")
			(effects
				(font
					(size 0.7874 0.5842)
					(thickness 0.1524)
				)
				(justify left)
			)
		)
		(property "Value" ""
			(at 0 0 180)
			(layer "F.Fab")
			(effects
				(font
					(size 1.27 1.27)
				)
			)
		)
		(duplicate_pad_numbers_are_jumpers no)
		(fp_line
			(start 0.7874 0.4064)
			(end -0.7874 0.4064)
			(stroke
				(width 0.1524)
				(type default)
			)
			(layer "F.SilkS")
		)
		(fp_line
			(start 0.7874 -0.4064)
			(end 0.7874 0.4064)
			(stroke
				(width 0.1524)
				(type default)
			)
			(layer "F.SilkS")
		)
		(fp_line
			(start -0.7874 0.4064)
			(end -0.7874 -0.4064)
			(stroke
				(width 0.1524)
				(type default)
			)
			(layer "F.SilkS")
		)
		(fp_line
			(start -0.7874 -0.4064)
			(end 0.7874 -0.4064)
			(stroke
				(width 0.1524)
				(type default)
			)
			(layer "F.SilkS")
		)
		(fp_poly
			(pts
				(xy -0.508 0.2794) (xy -0.508 0.2286) (xy -0.635 0.2286) (xy -0.635 -0.254) (xy -0.5334 -0.254)
				(xy -0.5334 -0.2794) (xy 0.5334 -0.2794) (xy 0.5334 -0.254) (xy 0.635 -0.254) (xy 0.635 0.254) (xy 0.5334 0.254)
				(xy 0.5334 0.2794)
			)
			(stroke
				(width 0)
				(type default)
			)
			(fill no)
			(layer "F.CrtYd")
		)
		(pad "1" smd rect
			(at 0.40005 0 180)
			(size 0.4572 0.508)
			(layers "F.Cu" "F.Mask" "F.Paste")
			(net "RST_NODE1_CPU_XDP_RSTIN_L")
		)
		(pad "2" smd rect
			(at -0.40005 0 180)
			(size 0.4572 0.508)
			(layers "F.Cu" "F.Mask" "F.Paste")
			(net "P3V3_STB_NODE1")
		)
	)
	(footprint ""
		(layer "F.Cu")
		(at 70.1548 -102.413562 180)
		(property "Reference" "C826"
			(at 1.169416 3.161792 0)
			(unlocked yes)
			(layer "F.SilkS")
			(effects
				(font
					(size 0.7874 0.5842)
					(thickness 0.1524)
				)
				(justify left)
			)
		)
		(property "Value" ""
			(at 0 0 180)
			(layer "F.Fab")
			(effects
				(font
					(size 1.27 1.27)
				)
			)
		)
		(duplicate_pad_numbers_are_jumpers no)
		(fp_line
			(start 0.7874 0.4064)
			(end -0.7874 0.4064)
			(stroke
				(width 0.1524)
				(type default)
			)
			(layer "F.SilkS")
		)
		(fp_line
			(start 0.7874 -0.4064)
			(end 0.7874 0.4064)
			(stroke
				(width 0.1524)
				(type default)
			)
			(layer "F.SilkS")
		)
		(fp_line
			(start 0 0.381)
			(end 0 -0.381)
			(stroke
				(width 0.1524)
				(type default)
			)
			(layer "F.SilkS")
		)
		(fp_line
			(start -0.7874 0.4064)
			(end -0.7874 -0.4064)
			(stroke
				(width 0.1524)
				(type default)
			)
			(layer "F.SilkS")
		)
		(fp_line
			(start -0.7874 -0.4064)
			(end 0.7874 -0.4064)
			(stroke
				(width 0.1524)
				(type default)
			)
			(layer "F.SilkS")
		)
		(fp_poly
			(pts
				(xy -0.5334 0.254) (xy -0.635 0.254) (xy -0.635 0.2286) (xy -0.635 -0.254) (xy -0.5334 -0.254) (xy -0.5334 -0.2794)
				(xy 0.5334 -0.2794) (xy 0.5334 -0.254) (xy 0.635 -0.254) (xy 0.635 0.254) (xy 0.5334 0.254) (xy 0.5334 0.2794)
				(xy -0.508 0.2794) (xy -0.5334 0.2794)
			)
			(stroke
				(width 0)
				(type default)
			)
			(fill no)
			(layer "F.CrtYd")
		)
		(pad "1" smd rect
			(at 0.40005 0 180)
			(size 0.4572 0.508)
			(layers "F.Cu" "F.Mask" "F.Paste")
			(net "FM_CPLD_NODE1_P1V8_SUS_EN")
		)
		(pad "2" smd rect
			(at -0.40005 0 180)
			(size 0.4572 0.508)
			(layers "F.Cu" "F.Mask" "F.Paste")
			(net "GND")
		)
	)
	(footprint ""
		(layer "F.Cu")
		(at 183.485282 -130.602228 -90)
		(property "Reference" "R1121"
			(at 1.053338 -14.029436 90)
			(unlocked yes)
			(layer "F.SilkS")
			(effects
				(font
					(size 0.7874 0.5842)
					(thickness 0.1524)
				)
				(justify left)
			)
		)
		(property "Value" ""
			(at 0 0 270)
			(layer "F.Fab")
			(effects
				(font
					(size 1.27 1.27)
				)
			)
		)
		(duplicate_pad_numbers_are_jumpers no)
		(fp_line
			(start -0.7874 0.4064)
			(end -0.7874 -0.4064)
			(stroke
				(width 0.1524)
				(type default)
			)
			(layer "F.SilkS")
		)
		(fp_line
			(start 0.7874 0.4064)
			(end -0.7874 0.4064)
			(stroke
				(width 0.1524)
				(type default)
			)
			(layer "F.SilkS")
		)
		(fp_line
			(start -0.7874 -0.4064)
			(end 0.7874 -0.4064)
			(stroke
				(width 0.1524)
				(type default)
			)
			(layer "F.SilkS")
		)
		(fp_line
			(start 0.7874 -0.4064)
			(end 0.7874 0.4064)
			(stroke
				(width 0.1524)
				(type default)
			)
			(layer "F.SilkS")
		)
		(fp_poly
			(pts
				(xy -0.508 0.2794) (xy -0.508 0.2286) (xy -0.635 0.2286) (xy -0.635 -0.254) (xy -0.5334 -0.254)
				(xy -0.5334 -0.2794) (xy 0.5334 -0.2794) (xy 0.5334 -0.254) (xy 0.635 -0.254) (xy 0.635 0.254) (xy 0.5334 0.254)
				(xy 0.5334 0.2794)
			)
			(stroke
				(width 0)
				(type default)
			)
			(fill no)
			(layer "F.CrtYd")
		)
		(pad "1" smd rect
			(at 0.40005 0 270)
			(size 0.4572 0.508)
			(layers "F.Cu" "F.Mask" "F.Paste")
			(net "SYS_AUTO_POWER_ON_N")
		)
		(pad "2" smd rect
			(at -0.40005 0 270)
			(size 0.4572 0.508)
			(layers "F.Cu" "F.Mask" "F.Paste")
			(net "P3V3_STB_NODE1")
		)
	)
	(footprint ""
		(layer "F.Cu")
		(at 157.065472 -105.98277 -90)
		(property "Reference" "R274"
			(at -1.588262 -0.00381 90)
			(unlocked yes)
			(layer "F.SilkS")
			(effects
				(font
					(size 0.7874 0.5842)
					(thickness 0.1524)
				)
				(justify left)
			)
		)
		(property "Value" ""
			(at 0 0 270)
			(layer "F.Fab")
			(effects
				(font
					(size 1.27 1.27)
				)
			)
		)
		(duplicate_pad_numbers_are_jumpers no)
		(fp_line
			(start -0.7874 0.4064)
			(end -0.7874 -0.4064)
			(stroke
				(width 0.1524)
				(type default)
			)
			(layer "F.SilkS")
		)
		(fp_line
			(start 0.7874 0.4064)
			(end -0.7874 0.4064)
			(stroke
				(width 0.1524)
				(type default)
			)
			(layer "F.SilkS")
		)
		(fp_line
			(start -0.7874 -0.4064)
			(end 0.7874 -0.4064)
			(stroke
				(width 0.1524)
				(type default)
			)
			(layer "F.SilkS")
		)
		(fp_line
			(start 0.7874 -0.4064)
			(end 0.7874 0.4064)
			(stroke
				(width 0.1524)
				(type default)
			)
			(layer "F.SilkS")
		)
		(fp_poly
			(pts
				(xy -0.508 0.2794) (xy -0.508 0.2286) (xy -0.635 0.2286) (xy -0.635 -0.254) (xy -0.5334 -0.254)
				(xy -0.5334 -0.2794) (xy 0.5334 -0.2794) (xy 0.5334 -0.254) (xy 0.635 -0.254) (xy 0.635 0.254) (xy 0.5334 0.254)
				(xy 0.5334 0.2794)
			)
			(stroke
				(width 0)
				(type default)
			)
			(fill no)
			(layer "F.CrtYd")
		)
		(pad "1" smd rect
			(at 0.40005 0 270)
			(size 0.4572 0.508)
			(layers "F.Cu" "F.Mask" "F.Paste")
			(net "FM_CPLD_NODE1_USB_PERST_L")
		)
		(pad "2" smd rect
			(at -0.40005 0 270)
			(size 0.4572 0.508)
			(layers "F.Cu" "F.Mask" "F.Paste")
			(net "N34379705")
		)
	)
	(footprint ""
		(layer "F.Cu")
		(at 116.894864 -26.094944 180)
		(property "Reference" "R1124"
			(at -1.468882 0.263398 90)
			(unlocked yes)
			(layer "F.SilkS")
			(effects
				(font
					(size 0.7874 0.5842)
					(thickness 0.1524)
				)
				(justify left)
			)
		)
		(property "Value" ""
			(at 0 0 180)
			(layer "F.Fab")
			(effects
				(font
					(size 1.27 1.27)
				)
			)
		)
		(duplicate_pad_numbers_are_jumpers no)
		(fp_line
			(start 0.7874 0.4064)
			(end -0.7874 0.4064)
			(stroke
				(width 0.1524)
				(type default)
			)
			(layer "F.SilkS")
		)
		(fp_line
			(start 0.7874 -0.4064)
			(end 0.7874 0.4064)
			(stroke
				(width 0.1524)
				(type default)
			)
			(layer "F.SilkS")
		)
		(fp_line
			(start -0.7874 0.4064)
			(end -0.7874 -0.4064)
			(stroke
				(width 0.1524)
				(type default)
			)
			(layer "F.SilkS")
		)
		(fp_line
			(start -0.7874 -0.4064)
			(end 0.7874 -0.4064)
			(stroke
				(width 0.1524)
				(type default)
			)
			(layer "F.SilkS")
		)
		(fp_poly
			(pts
				(xy -0.508 0.2794) (xy -0.508 0.2286) (xy -0.635 0.2286) (xy -0.635 -0.254) (xy -0.5334 -0.254)
				(xy -0.5334 -0.2794) (xy 0.5334 -0.2794) (xy 0.5334 -0.254) (xy 0.635 -0.254) (xy 0.635 0.254) (xy 0.5334 0.254)
				(xy 0.5334 0.2794)
			)
			(stroke
				(width 0)
				(type default)
			)
			(fill no)
			(layer "F.CrtYd")
		)
		(pad "1" smd rect
			(at 0.40005 0 180)
			(size 0.4572 0.508)
			(layers "F.Cu" "F.Mask" "F.Paste")
			(net "PV_VDDR_NODE1")
		)
		(pad "2" smd rect
			(at -0.40005 0 180)
			(size 0.4572 0.508)
			(layers "F.Cu" "F.Mask" "F.Paste")
			(net "PV_VTT_DDR_NODE1_REFIN")
		)
	)
	(footprint ""
		(layer "F.Cu")
		(at 155.05176 -188.126624 90)
		(property "Reference" "C660"
			(at 5.519674 -3.327908 90)
			(unlocked yes)
			(layer "F.SilkS")
			(effects
				(font
					(size 0.7874 0.5842)
					(thickness 0.1524)
				)
				(justify left)
			)
		)
		(property "Value" ""
			(at 0 0 90)
			(layer "F.Fab")
			(effects
				(font
					(size 1.27 1.27)
				)
			)
		)
		(duplicate_pad_numbers_are_jumpers no)
		(fp_line
			(start 0.7874 -0.4064)
			(end 0.7874 0.4064)
			(stroke
				(width 0.1524)
				(type default)
			)
			(layer "F.SilkS")
		)
		(fp_line
			(start -0.7874 -0.4064)
			(end 0.7874 -0.4064)
			(stroke
				(width 0.1524)
				(type default)
			)
			(layer "F.SilkS")
		)
		(fp_line
			(start 0 0.381)
			(end 0 -0.381)
			(stroke
				(width 0.1524)
				(type default)
			)
			(layer "F.SilkS")
		)
		(fp_line
			(start 0.7874 0.4064)
			(end -0.7874 0.4064)
			(stroke
				(width 0.1524)
				(type default)
			)
			(layer "F.SilkS")
		)
		(fp_line
			(start -0.7874 0.4064)
			(end -0.7874 -0.4064)
			(stroke
				(width 0.1524)
				(type default)
			)
			(layer "F.SilkS")
		)
		(fp_poly
			(pts
				(xy -0.5334 0.254) (xy -0.635 0.254) (xy -0.635 0.2286) (xy -0.635 -0.254) (xy -0.5334 -0.254) (xy -0.5334 -0.2794)
				(xy 0.5334 -0.2794) (xy 0.5334 -0.254) (xy 0.635 -0.254) (xy 0.635 0.254) (xy 0.5334 0.254) (xy 0.5334 0.2794)
				(xy -0.508 0.2794) (xy -0.5334 0.2794)
			)
			(stroke
				(width 0)
				(type default)
			)
			(fill no)
			(layer "F.CrtYd")
		)
		(pad "1" smd rect
			(at 0.40005 0 90)
			(size 0.4572 0.508)
			(layers "F.Cu" "F.Mask" "F.Paste")
			(net "T12_NODE1_EN_R")
		)
		(pad "2" smd rect
			(at -0.40005 0 90)
			(size 0.4572 0.508)
			(layers "F.Cu" "F.Mask" "F.Paste")
			(net "GND")
		)
	)
	(footprint ""
		(layer "F.Cu")
		(at 77.841602 -5.105654 90)
		(property "Reference" "PL17"
			(at 4.08686 1.526794 0)
			(unlocked yes)
			(layer "F.SilkS")
			(effects
				(font
					(size 0.7874 0.5842)
					(thickness 0.1524)
				)
				(justify left)
			)
		)
		(property "Value" ""
			(at 0 0 90)
			(layer "F.Fab")
			(effects
				(font
					(size 1.27 1.27)
				)
			)
		)
		(duplicate_pad_numbers_are_jumpers no)
		(fp_line
			(start 3.350006 -4.1656)
			(end 3.350006 4.1656)
			(stroke
				(width 0.1524)
				(type default)
			)
			(layer "F.SilkS")
		)
		(fp_line
			(start -3.350006 -4.1656)
			(end 3.350006 -4.1656)
			(stroke
				(width 0.1524)
				(type default)
			)
			(layer "F.SilkS")
		)
		(fp_line
			(start 3.350006 4.1656)
			(end -3.350006 4.1656)
			(stroke
				(width 0.1524)
				(type default)
			)
			(layer "F.SilkS")
		)
		(fp_line
			(start -3.350006 4.1656)
			(end -3.350006 -4.1656)
			(stroke
				(width 0.1524)
				(type default)
			)
			(layer "F.SilkS")
		)
		(fp_poly
			(pts
				(xy -3.350006 -3.64998) (xy -1.7018 -3.64998) (xy -1.7018 -4.05257) (xy 1.7018 -4.05257) (xy 1.7018 -3.64998)
				(xy 3.350006 -3.64998) (xy 3.350006 3.64998) (xy 1.7018 3.64998) (xy 1.7018 4.05257) (xy -1.7018 4.05257)
				(xy -1.7018 3.64998) (xy -3.350006 3.64998)
			)
			(stroke
				(width 0)
				(type default)
			)
			(fill no)
			(layer "F.CrtYd")
		)
		(fp_line
			(start 3.350006 -3.64998)
			(end 3.350006 3.64998)
			(stroke
				(width 0.1)
				(type default)
			)
			(layer "F.Fab")
		)
		(fp_line
			(start -3.350006 -3.64998)
			(end 3.350006 -3.64998)
			(stroke
				(width 0.1)
				(type default)
			)
			(layer "F.Fab")
		)
		(fp_line
			(start 3.350006 3.64998)
			(end -3.350006 3.64998)
			(stroke
				(width 0.1)
				(type default)
			)
			(layer "F.Fab")
		)
		(fp_line
			(start -3.350006 3.64998)
			(end -3.350006 -3.64998)
			(stroke
				(width 0.1)
				(type default)
			)
			(layer "F.Fab")
		)
		(pad "1" smd rect
			(at 0 -2.92481)
			(size 2.15392 3.302)
			(layers "F.Cu" "F.Mask" "F.Paste")
			(net "SW_P3V3_NODE1_PH")
		)
		(pad "2" smd rect
			(at 0 2.92481)
			(size 2.15392 3.302)
			(layers "F.Cu" "F.Mask" "F.Paste")
			(net "P3V3_NODE1")
		)
	)
	(footprint ""
		(layer "F.Cu")
		(at 91.102434 -188.858398 180)
		(property "Reference" "C672"
			(at 1.437894 7.241032 0)
			(unlocked yes)
			(layer "F.SilkS")
			(effects
				(font
					(size 0.7874 0.5842)
					(thickness 0.1524)
				)
				(justify left)
			)
		)
		(property "Value" ""
			(at 0 0 180)
			(layer "F.Fab")
			(effects
				(font
					(size 1.27 1.27)
				)
			)
		)
		(duplicate_pad_numbers_are_jumpers no)
		(fp_line
			(start 0.7874 0.4064)
			(end -0.7874 0.4064)
			(stroke
				(width 0.1524)
				(type default)
			)
			(layer "F.SilkS")
		)
		(fp_line
			(start 0.7874 -0.4064)
			(end 0.7874 0.4064)
			(stroke
				(width 0.1524)
				(type default)
			)
			(layer "F.SilkS")
		)
		(fp_line
			(start 0 0.381)
			(end 0 -0.381)
			(stroke
				(width 0.1524)
				(type default)
			)
			(layer "F.SilkS")
		)
		(fp_line
			(start -0.7874 0.4064)
			(end -0.7874 -0.4064)
			(stroke
				(width 0.1524)
				(type default)
			)
			(layer "F.SilkS")
		)
		(fp_line
			(start -0.7874 -0.4064)
			(end 0.7874 -0.4064)
			(stroke
				(width 0.1524)
				(type default)
			)
			(layer "F.SilkS")
		)
		(fp_poly
			(pts
				(xy -0.5334 0.254) (xy -0.635 0.254) (xy -0.635 0.2286) (xy -0.635 -0.254) (xy -0.5334 -0.254) (xy -0.5334 -0.2794)
				(xy 0.5334 -0.2794) (xy 0.5334 -0.254) (xy 0.635 -0.254) (xy 0.635 0.254) (xy 0.5334 0.254) (xy 0.5334 0.2794)
				(xy -0.508 0.2794) (xy -0.5334 0.2794)
			)
			(stroke
				(width 0)
				(type default)
			)
			(fill no)
			(layer "F.CrtYd")
		)
		(pad "1" smd rect
			(at 0.40005 0 180)
			(size 0.4572 0.508)
			(layers "F.Cu" "F.Mask" "F.Paste")
			(net "UART_T5_NODE1_RXD")
		)
		(pad "2" smd rect
			(at -0.40005 0 180)
			(size 0.4572 0.508)
			(layers "F.Cu" "F.Mask" "F.Paste")
			(net "GND")
		)
	)
	(footprint ""
		(layer "F.Cu")
		(at 10.640568 -167.373554)
		(property "Reference" "C542"
			(at 0.4699 -1.475486 0)
			(unlocked yes)
			(layer "F.SilkS")
			(effects
				(font
					(size 0.7874 0.5842)
					(thickness 0.1524)
				)
				(justify left)
			)
		)
		(property "Value" ""
			(at 0 0 0)
			(layer "F.Fab")
			(effects
				(font
					(size 1.27 1.27)
				)
			)
		)
		(duplicate_pad_numbers_are_jumpers no)
		(fp_line
			(start -0.7874 -0.4064)
			(end 0.7874 -0.4064)
			(stroke
				(width 0.1524)
				(type default)
			)
			(layer "F.SilkS")
		)
		(fp_line
			(start -0.7874 0.4064)
			(end -0.7874 -0.4064)
			(stroke
				(width 0.1524)
				(type default)
			)
			(layer "F.SilkS")
		)
		(fp_line
			(start 0 0.381)
			(end 0 -0.381)
			(stroke
				(width 0.1524)
				(type default)
			)
			(layer "F.SilkS")
		)
		(fp_line
			(start 0.7874 -0.4064)
			(end 0.7874 0.4064)
			(stroke
				(width 0.1524)
				(type default)
			)
			(layer "F.SilkS")
		)
		(fp_line
			(start 0.7874 0.4064)
			(end -0.7874 0.4064)
			(stroke
				(width 0.1524)
				(type default)
			)
			(layer "F.SilkS")
		)
		(fp_poly
			(pts
				(xy -0.5334 0.254) (xy -0.635 0.254) (xy -0.635 0.2286) (xy -0.635 -0.254) (xy -0.5334 -0.254) (xy -0.5334 -0.2794)
				(xy 0.5334 -0.2794) (xy 0.5334 -0.254) (xy 0.635 -0.254) (xy 0.635 0.254) (xy 0.5334 0.254) (xy 0.5334 0.2794)
				(xy -0.508 0.2794) (xy -0.5334 0.2794)
			)
			(stroke
				(width 0)
				(type default)
			)
			(fill no)
			(layer "F.CrtYd")
		)
		(pad "1" smd rect
			(at 0.40005 0)
			(size 0.4572 0.508)
			(layers "F.Cu" "F.Mask" "F.Paste")
			(net "N54258523")
		)
		(pad "2" smd rect
			(at -0.40005 0)
			(size 0.4572 0.508)
			(layers "F.Cu" "F.Mask" "F.Paste")
			(net "N54258525")
		)
	)
	(footprint ""
		(layer "F.Cu")
		(at 187.7695 -166.072566)
		(property "Reference" "R1280"
			(at -1.634744 5.208778 0)
			(unlocked yes)
			(layer "F.SilkS")
			(effects
				(font
					(size 0.7874 0.5842)
					(thickness 0.1524)
				)
				(justify left)
			)
		)
		(property "Value" ""
			(at 0 0 0)
			(layer "F.Fab")
			(effects
				(font
					(size 1.27 1.27)
				)
			)
		)
		(duplicate_pad_numbers_are_jumpers no)
		(fp_line
			(start -0.7874 -0.4064)
			(end 0.7874 -0.4064)
			(stroke
				(width 0.1524)
				(type default)
			)
			(layer "F.SilkS")
		)
		(fp_line
			(start -0.7874 0.4064)
			(end -0.7874 -0.4064)
			(stroke
				(width 0.1524)
				(type default)
			)
			(layer "F.SilkS")
		)
		(fp_line
			(start 0.7874 -0.4064)
			(end 0.7874 0.4064)
			(stroke
				(width 0.1524)
				(type default)
			)
			(layer "F.SilkS")
		)
		(fp_line
			(start 0.7874 0.4064)
			(end -0.7874 0.4064)
			(stroke
				(width 0.1524)
				(type default)
			)
			(layer "F.SilkS")
		)
		(fp_poly
			(pts
				(xy -0.508 0.2794) (xy -0.508 0.2286) (xy -0.635 0.2286) (xy -0.635 -0.254) (xy -0.5334 -0.254)
				(xy -0.5334 -0.2794) (xy 0.5334 -0.2794) (xy 0.5334 -0.254) (xy 0.635 -0.254) (xy 0.635 0.254) (xy 0.5334 0.254)
				(xy 0.5334 0.2794)
			)
			(stroke
				(width 0)
				(type default)
			)
			(fill no)
			(layer "F.CrtYd")
		)
		(pad "1" smd rect
			(at 0.40005 0)
			(size 0.4572 0.508)
			(layers "F.Cu" "F.Mask" "F.Paste")
			(net "N54134271")
		)
		(pad "2" smd rect
			(at -0.40005 0)
			(size 0.4572 0.508)
			(layers "F.Cu" "F.Mask" "F.Paste")
			(net "LAN2_P4_R")
		)
	)
	(footprint ""
		(layer "F.Cu")
		(at 57.081166 -96.709992 90)
		(property "Reference" "R82"
			(at -54.98719 28.432252 90)
			(unlocked yes)
			(layer "F.SilkS")
			(effects
				(font
					(size 0.7874 0.5842)
					(thickness 0.1524)
				)
				(justify left)
			)
		)
		(property "Value" ""
			(at 0 0 90)
			(layer "F.Fab")
			(effects
				(font
					(size 1.27 1.27)
				)
			)
		)
		(duplicate_pad_numbers_are_jumpers no)
		(fp_line
			(start 0.7874 -0.4064)
			(end 0.7874 0.4064)
			(stroke
				(width 0.1524)
				(type default)
			)
			(layer "F.SilkS")
		)
		(fp_line
			(start -0.7874 -0.4064)
			(end 0.7874 -0.4064)
			(stroke
				(width 0.1524)
				(type default)
			)
			(layer "F.SilkS")
		)
		(fp_line
			(start 0.7874 0.4064)
			(end -0.7874 0.4064)
			(stroke
				(width 0.1524)
				(type default)
			)
			(layer "F.SilkS")
		)
		(fp_line
			(start -0.7874 0.4064)
			(end -0.7874 -0.4064)
			(stroke
				(width 0.1524)
				(type default)
			)
			(layer "F.SilkS")
		)
		(fp_poly
			(pts
				(xy -0.508 0.2794) (xy -0.508 0.2286) (xy -0.635 0.2286) (xy -0.635 -0.254) (xy -0.5334 -0.254)
				(xy -0.5334 -0.2794) (xy 0.5334 -0.2794) (xy 0.5334 -0.254) (xy 0.635 -0.254) (xy 0.635 0.254) (xy 0.5334 0.254)
				(xy 0.5334 0.2794)
			)
			(stroke
				(width 0)
				(type default)
			)
			(fill no)
			(layer "F.CrtYd")
		)
		(pad "1" smd rect
			(at 0.40005 0 90)
			(size 0.4572 0.508)
			(layers "F.Cu" "F.Mask" "F.Paste")
			(net "GND")
		)
		(pad "2" smd rect
			(at -0.40005 0 90)
			(size 0.4572 0.508)
			(layers "F.Cu" "F.Mask" "F.Paste")
			(net "PD_CPU_NODE1_DFX_GPIO_GRP0_3")
		)
	)
	(footprint ""
		(layer "F.Cu")
		(at 14.052804 -164.700712 180)
		(property "Reference" "R1276"
			(at 1.765808 2.226056 0)
			(unlocked yes)
			(layer "F.SilkS")
			(effects
				(font
					(size 0.7874 0.5842)
					(thickness 0.1524)
				)
				(justify left)
			)
		)
		(property "Value" ""
			(at 0 0 180)
			(layer "F.Fab")
			(effects
				(font
					(size 1.27 1.27)
				)
			)
		)
		(duplicate_pad_numbers_are_jumpers no)
		(fp_line
			(start 0.7874 0.4064)
			(end -0.7874 0.4064)
			(stroke
				(width 0.1524)
				(type default)
			)
			(layer "F.SilkS")
		)
		(fp_line
			(start 0.7874 -0.4064)
			(end 0.7874 0.4064)
			(stroke
				(width 0.1524)
				(type default)
			)
			(layer "F.SilkS")
		)
		(fp_line
			(start -0.7874 0.4064)
			(end -0.7874 -0.4064)
			(stroke
				(width 0.1524)
				(type default)
			)
			(layer "F.SilkS")
		)
		(fp_line
			(start -0.7874 -0.4064)
			(end 0.7874 -0.4064)
			(stroke
				(width 0.1524)
				(type default)
			)
			(layer "F.SilkS")
		)
		(fp_poly
			(pts
				(xy -0.508 0.2794) (xy -0.508 0.2286) (xy -0.635 0.2286) (xy -0.635 -0.254) (xy -0.5334 -0.254)
				(xy -0.5334 -0.2794) (xy 0.5334 -0.2794) (xy 0.5334 -0.254) (xy 0.635 -0.254) (xy 0.635 0.254) (xy 0.5334 0.254)
				(xy 0.5334 0.2794)
			)
			(stroke
				(width 0)
				(type default)
			)
			(fill no)
			(layer "F.CrtYd")
		)
		(pad "1" smd rect
			(at 0.40005 0 180)
			(size 0.4572 0.508)
			(layers "F.Cu" "F.Mask" "F.Paste")
			(net "N54065132")
		)
		(pad "2" smd rect
			(at -0.40005 0 180)
			(size 0.4572 0.508)
			(layers "F.Cu" "F.Mask" "F.Paste")
			(net "LAN1_P4_R")
		)
	)
	(footprint ""
		(layer "F.Cu")
		(at 34.457894 -9.954514)
		(property "Reference" "PR38"
			(at -10.749788 -0.098044 0)
			(unlocked yes)
			(layer "F.SilkS")
			(effects
				(font
					(size 0.7874 0.5842)
					(thickness 0.1524)
				)
				(justify left)
			)
		)
		(property "Value" ""
			(at 0 0 0)
			(layer "F.Fab")
			(effects
				(font
					(size 1.27 1.27)
				)
			)
		)
		(duplicate_pad_numbers_are_jumpers no)
		(fp_line
			(start -0.7874 -0.4064)
			(end 0.7874 -0.4064)
			(stroke
				(width 0.1524)
				(type default)
			)
			(layer "F.SilkS")
		)
		(fp_line
			(start -0.7874 0.4064)
			(end -0.7874 -0.4064)
			(stroke
				(width 0.1524)
				(type default)
			)
			(layer "F.SilkS")
		)
		(fp_line
			(start 0.7874 -0.4064)
			(end 0.7874 0.4064)
			(stroke
				(width 0.1524)
				(type default)
			)
			(layer "F.SilkS")
		)
		(fp_line
			(start 0.7874 0.4064)
			(end -0.7874 0.4064)
			(stroke
				(width 0.1524)
				(type default)
			)
			(layer "F.SilkS")
		)
		(fp_poly
			(pts
				(xy -0.508 0.2794) (xy -0.508 0.2286) (xy -0.635 0.2286) (xy -0.635 -0.254) (xy -0.5334 -0.254)
				(xy -0.5334 -0.2794) (xy 0.5334 -0.2794) (xy 0.5334 -0.254) (xy 0.635 -0.254) (xy 0.635 0.254) (xy 0.5334 0.254)
				(xy 0.5334 0.2794)
			)
			(stroke
				(width 0)
				(type default)
			)
			(fill no)
			(layer "F.CrtYd")
		)
		(pad "1" smd rect
			(at 0.40005 0)
			(size 0.4572 0.508)
			(layers "F.Cu" "F.Mask" "F.Paste")
			(net "PV_VDDR_NODE1_V1")
		)
		(pad "2" smd rect
			(at -0.40005 0)
			(size 0.4572 0.508)
			(layers "F.Cu" "F.Mask" "F.Paste")
			(net "PV_VDDR_NODE1_V0")
		)
	)
	(footprint ""
		(layer "F.Cu")
		(at 165.011354 -185.083196 180)
		(property "Reference" "R1171"
			(at 4.864354 0.538734 0)
			(unlocked yes)
			(layer "F.SilkS")
			(effects
				(font
					(size 0.7874 0.5842)
					(thickness 0.1524)
				)
				(justify left)
			)
		)
		(property "Value" ""
			(at 0 0 180)
			(layer "F.Fab")
			(effects
				(font
					(size 1.27 1.27)
				)
			)
		)
		(duplicate_pad_numbers_are_jumpers no)
		(fp_line
			(start 0.7874 0.4064)
			(end -0.7874 0.4064)
			(stroke
				(width 0.1524)
				(type default)
			)
			(layer "F.SilkS")
		)
		(fp_line
			(start 0.7874 -0.4064)
			(end 0.7874 0.4064)
			(stroke
				(width 0.1524)
				(type default)
			)
			(layer "F.SilkS")
		)
		(fp_line
			(start -0.7874 0.4064)
			(end -0.7874 -0.4064)
			(stroke
				(width 0.1524)
				(type default)
			)
			(layer "F.SilkS")
		)
		(fp_line
			(start -0.7874 -0.4064)
			(end 0.7874 -0.4064)
			(stroke
				(width 0.1524)
				(type default)
			)
			(layer "F.SilkS")
		)
		(fp_poly
			(pts
				(xy -0.508 0.2794) (xy -0.508 0.2286) (xy -0.635 0.2286) (xy -0.635 -0.254) (xy -0.5334 -0.254)
				(xy -0.5334 -0.2794) (xy 0.5334 -0.2794) (xy 0.5334 -0.254) (xy 0.635 -0.254) (xy 0.635 0.254) (xy 0.5334 0.254)
				(xy 0.5334 0.2794)
			)
			(stroke
				(width 0)
				(type default)
			)
			(fill no)
			(layer "F.CrtYd")
		)
		(pad "1" smd rect
			(at 0.40005 0 180)
			(size 0.4572 0.508)
			(layers "F.Cu" "F.Mask" "F.Paste")
			(net "CPLD_UART_DTR_P3_N")
		)
		(pad "2" smd rect
			(at -0.40005 0 180)
			(size 0.4572 0.508)
			(layers "F.Cu" "F.Mask" "F.Paste")
			(net "GND")
		)
	)
	(footprint ""
		(layer "F.Cu")
		(at 9.550146 -11.613896 90)
		(property "Reference" "C181"
			(at -0.984758 -4.7117 90)
			(unlocked yes)
			(layer "F.SilkS")
			(effects
				(font
					(size 0.7874 0.5842)
					(thickness 0.1524)
				)
				(justify left)
			)
		)
		(property "Value" ""
			(at 0 0 90)
			(layer "F.Fab")
			(effects
				(font
					(size 1.27 1.27)
				)
			)
		)
		(duplicate_pad_numbers_are_jumpers no)
		(fp_line
			(start 0.7874 -0.4064)
			(end 0.7874 0.4064)
			(stroke
				(width 0.1524)
				(type default)
			)
			(layer "F.SilkS")
		)
		(fp_line
			(start -0.7874 -0.4064)
			(end 0.7874 -0.4064)
			(stroke
				(width 0.1524)
				(type default)
			)
			(layer "F.SilkS")
		)
		(fp_line
			(start 0 0.381)
			(end 0 -0.381)
			(stroke
				(width 0.1524)
				(type default)
			)
			(layer "F.SilkS")
		)
		(fp_line
			(start 0.7874 0.4064)
			(end -0.7874 0.4064)
			(stroke
				(width 0.1524)
				(type default)
			)
			(layer "F.SilkS")
		)
		(fp_line
			(start -0.7874 0.4064)
			(end -0.7874 -0.4064)
			(stroke
				(width 0.1524)
				(type default)
			)
			(layer "F.SilkS")
		)
		(fp_poly
			(pts
				(xy -0.5334 0.254) (xy -0.635 0.254) (xy -0.635 0.2286) (xy -0.635 -0.254) (xy -0.5334 -0.254) (xy -0.5334 -0.2794)
				(xy 0.5334 -0.2794) (xy 0.5334 -0.254) (xy 0.635 -0.254) (xy 0.635 0.254) (xy 0.5334 0.254) (xy 0.5334 0.2794)
				(xy -0.508 0.2794) (xy -0.5334 0.2794)
			)
			(stroke
				(width 0)
				(type default)
			)
			(fill no)
			(layer "F.CrtYd")
		)
		(pad "1" smd rect
			(at 0.40005 0 90)
			(size 0.4572 0.508)
			(layers "F.Cu" "F.Mask" "F.Paste")
			(net "PV_VDDR_NODE1_VREF_LM321")
		)
		(pad "2" smd rect
			(at -0.40005 0 90)
			(size 0.4572 0.508)
			(layers "F.Cu" "F.Mask" "F.Paste")
			(net "GND")
		)
	)
	(footprint ""
		(layer "F.Cu")
		(at 58.753756 -14.910054 -90)
		(property "Reference" "PC84"
			(at 0.031242 6.692646 90)
			(unlocked yes)
			(layer "F.SilkS")
			(effects
				(font
					(size 0.7874 0.5842)
					(thickness 0.1524)
				)
				(justify left)
			)
		)
		(property "Value" ""
			(at 0 0 270)
			(layer "F.Fab")
			(effects
				(font
					(size 1.27 1.27)
				)
			)
		)
		(duplicate_pad_numbers_are_jumpers no)
		(fp_line
			(start -1.905 0.8636)
			(end -1.905 -0.8636)
			(stroke
				(width 0.1524)
				(type default)
			)
			(layer "F.SilkS")
		)
		(fp_line
			(start 1.905 0.8636)
			(end -1.905 0.8636)
			(stroke
				(width 0.1524)
				(type default)
			)
			(layer "F.SilkS")
		)
		(fp_line
			(start 0 0.8382)
			(end 0 -0.8382)
			(stroke
				(width 0.1524)
				(type default)
			)
			(layer "F.SilkS")
		)
		(fp_line
			(start -1.905 -0.8636)
			(end 1.905 -0.8636)
			(stroke
				(width 0.1524)
				(type default)
			)
			(layer "F.SilkS")
		)
		(fp_line
			(start 1.905 -0.8636)
			(end 1.905 0.8636)
			(stroke
				(width 0.1524)
				(type default)
			)
			(layer "F.SilkS")
		)
		(fp_rect
			(start -1.524 0.7366)
			(end 1.524 -0.7366)
			(stroke
				(width 0)
				(type default)
			)
			(fill no)
			(layer "F.CrtYd")
		)
		(pad "1" smd rect
			(at 0.94996 0 270)
			(size 1.1176 1.3716)
			(layers "F.Cu" "F.Mask" "F.Paste")
			(net "PV_VDDR_NODE1")
		)
		(pad "2" smd rect
			(at -0.94996 0 270)
			(size 1.1176 1.3716)
			(layers "F.Cu" "F.Mask" "F.Paste")
			(net "GND")
		)
	)
	(footprint ""
		(layer "F.Cu")
		(at 72.24776 -185.205624 -90)
		(property "Reference" "R947"
			(at -4.006088 1.07188 90)
			(unlocked yes)
			(layer "F.SilkS")
			(effects
				(font
					(size 0.7874 0.5842)
					(thickness 0.1524)
				)
				(justify left)
			)
		)
		(property "Value" ""
			(at 0 0 270)
			(layer "F.Fab")
			(effects
				(font
					(size 1.27 1.27)
				)
			)
		)
		(duplicate_pad_numbers_are_jumpers no)
		(fp_line
			(start -0.7874 0.4064)
			(end -0.7874 -0.4064)
			(stroke
				(width 0.1524)
				(type default)
			)
			(layer "F.SilkS")
		)
		(fp_line
			(start 0.7874 0.4064)
			(end -0.7874 0.4064)
			(stroke
				(width 0.1524)
				(type default)
			)
			(layer "F.SilkS")
		)
		(fp_line
			(start -0.7874 -0.4064)
			(end 0.7874 -0.4064)
			(stroke
				(width 0.1524)
				(type default)
			)
			(layer "F.SilkS")
		)
		(fp_line
			(start 0.7874 -0.4064)
			(end 0.7874 0.4064)
			(stroke
				(width 0.1524)
				(type default)
			)
			(layer "F.SilkS")
		)
		(fp_poly
			(pts
				(xy -0.508 0.2794) (xy -0.508 0.2286) (xy -0.635 0.2286) (xy -0.635 -0.254) (xy -0.5334 -0.254)
				(xy -0.5334 -0.2794) (xy 0.5334 -0.2794) (xy 0.5334 -0.254) (xy 0.635 -0.254) (xy 0.635 0.254) (xy 0.5334 0.254)
				(xy 0.5334 0.2794)
			)
			(stroke
				(width 0)
				(type default)
			)
			(fill no)
			(layer "F.CrtYd")
		)
		(pad "1" smd rect
			(at 0.40005 0 270)
			(size 0.4572 0.508)
			(layers "F.Cu" "F.Mask" "F.Paste")
			(net "UART_T4_NODE3_TXD")
		)
		(pad "2" smd rect
			(at -0.40005 0 270)
			(size 0.4572 0.508)
			(layers "F.Cu" "F.Mask" "F.Paste")
			(net "UART_T4_NODE3_TXD_R")
		)
	)
	(footprint ""
		(layer "F.Cu")
		(at 35.243008 -188.652404)
		(property "Reference" "C769"
			(at -1.53162 -5.211064 0)
			(unlocked yes)
			(layer "F.SilkS")
			(effects
				(font
					(size 0.7874 0.5842)
					(thickness 0.1524)
				)
				(justify left)
			)
		)
		(property "Value" ""
			(at 0 0 0)
			(layer "F.Fab")
			(effects
				(font
					(size 1.27 1.27)
				)
			)
		)
		(duplicate_pad_numbers_are_jumpers no)
		(fp_line
			(start -0.7874 -0.4064)
			(end 0.7874 -0.4064)
			(stroke
				(width 0.1524)
				(type default)
			)
			(layer "F.SilkS")
		)
		(fp_line
			(start -0.7874 0.4064)
			(end -0.7874 -0.4064)
			(stroke
				(width 0.1524)
				(type default)
			)
			(layer "F.SilkS")
		)
		(fp_line
			(start 0 0.381)
			(end 0 -0.381)
			(stroke
				(width 0.1524)
				(type default)
			)
			(layer "F.SilkS")
		)
		(fp_line
			(start 0.7874 -0.4064)
			(end 0.7874 0.4064)
			(stroke
				(width 0.1524)
				(type default)
			)
			(layer "F.SilkS")
		)
		(fp_line
			(start 0.7874 0.4064)
			(end -0.7874 0.4064)
			(stroke
				(width 0.1524)
				(type default)
			)
			(layer "F.SilkS")
		)
		(fp_poly
			(pts
				(xy -0.5334 0.254) (xy -0.635 0.254) (xy -0.635 0.2286) (xy -0.635 -0.254) (xy -0.5334 -0.254) (xy -0.5334 -0.2794)
				(xy 0.5334 -0.2794) (xy 0.5334 -0.254) (xy 0.635 -0.254) (xy 0.635 0.254) (xy 0.5334 0.254) (xy 0.5334 0.2794)
				(xy -0.508 0.2794) (xy -0.5334 0.2794)
			)
			(stroke
				(width 0)
				(type default)
			)
			(fill no)
			(layer "F.CrtYd")
		)
		(pad "1" smd rect
			(at 0.40005 0)
			(size 0.4572 0.508)
			(layers "F.Cu" "F.Mask" "F.Paste")
			(net "P12V_PDB")
		)
		(pad "2" smd rect
			(at -0.40005 0)
			(size 0.4572 0.508)
			(layers "F.Cu" "F.Mask" "F.Paste")
			(net "GND")
		)
	)
	(footprint ""
		(layer "F.Cu")
		(at 117.023388 -135.617204 90)
		(property "Reference" "PR69"
			(at 2.566416 5.091938 90)
			(unlocked yes)
			(layer "F.SilkS")
			(effects
				(font
					(size 0.635 0.4064)
					(thickness 0.1524)
				)
				(justify left)
			)
		)
		(property "Value" ""
			(at 0 0 90)
			(layer "F.Fab")
			(effects
				(font
					(size 1.27 1.27)
				)
			)
		)
		(duplicate_pad_numbers_are_jumpers no)
		(fp_line
			(start 0.7874 -0.4064)
			(end 0.7874 0.4064)
			(stroke
				(width 0.1524)
				(type default)
			)
			(layer "F.SilkS")
		)
		(fp_line
			(start -0.7874 -0.4064)
			(end 0.7874 -0.4064)
			(stroke
				(width 0.1524)
				(type default)
			)
			(layer "F.SilkS")
		)
		(fp_line
			(start 0.7874 0.4064)
			(end -0.7874 0.4064)
			(stroke
				(width 0.1524)
				(type default)
			)
			(layer "F.SilkS")
		)
		(fp_line
			(start -0.7874 0.4064)
			(end -0.7874 -0.4064)
			(stroke
				(width 0.1524)
				(type default)
			)
			(layer "F.SilkS")
		)
		(fp_poly
			(pts
				(xy -0.508 0.2794) (xy -0.508 0.2286) (xy -0.635 0.2286) (xy -0.635 -0.254) (xy -0.5334 -0.254)
				(xy -0.5334 -0.2794) (xy 0.5334 -0.2794) (xy 0.5334 -0.254) (xy 0.635 -0.254) (xy 0.635 0.254) (xy 0.5334 0.254)
				(xy 0.5334 0.2794)
			)
			(stroke
				(width 0)
				(type default)
			)
			(fill no)
			(layer "F.CrtYd")
		)
		(pad "1" smd rect
			(at 0.40005 0 90)
			(size 0.4572 0.508)
			(layers "F.Cu" "F.Mask" "F.Paste")
			(net "VR_PVCCP_NODE1_FB")
		)
		(pad "2" smd rect
			(at -0.40005 0 90)
			(size 0.4572 0.508)
			(layers "F.Cu" "F.Mask" "F.Paste")
			(net "VR_PVCCP_NODE1_FB_RR")
		)
	)
	(footprint ""
		(layer "F.Cu")
		(at 94.451932 -164.123624)
		(property "Reference" "R770"
			(at 86.632288 73.221596 0)
			(unlocked yes)
			(layer "F.SilkS")
			(effects
				(font
					(size 0.7874 0.5842)
					(thickness 0.1524)
				)
				(justify left)
			)
		)
		(property "Value" ""
			(at 0 0 0)
			(layer "F.Fab")
			(effects
				(font
					(size 1.27 1.27)
				)
			)
		)
		(duplicate_pad_numbers_are_jumpers no)
		(fp_line
			(start -0.7874 -0.4064)
			(end 0.7874 -0.4064)
			(stroke
				(width 0.1524)
				(type default)
			)
			(layer "F.SilkS")
		)
		(fp_line
			(start -0.7874 0.4064)
			(end -0.7874 -0.4064)
			(stroke
				(width 0.1524)
				(type default)
			)
			(layer "F.SilkS")
		)
		(fp_line
			(start 0.7874 -0.4064)
			(end 0.7874 0.4064)
			(stroke
				(width 0.1524)
				(type default)
			)
			(layer "F.SilkS")
		)
		(fp_line
			(start 0.7874 0.4064)
			(end -0.7874 0.4064)
			(stroke
				(width 0.1524)
				(type default)
			)
			(layer "F.SilkS")
		)
		(fp_poly
			(pts
				(xy -0.508 0.2794) (xy -0.508 0.2286) (xy -0.635 0.2286) (xy -0.635 -0.254) (xy -0.5334 -0.254)
				(xy -0.5334 -0.2794) (xy 0.5334 -0.2794) (xy 0.5334 -0.254) (xy 0.635 -0.254) (xy 0.635 0.254) (xy 0.5334 0.254)
				(xy 0.5334 0.2794)
			)
			(stroke
				(width 0)
				(type default)
			)
			(fill no)
			(layer "F.CrtYd")
		)
		(pad "1" smd rect
			(at 0.40005 0)
			(size 0.4572 0.508)
			(layers "F.Cu" "F.Mask" "F.Paste")
			(net "FAN6_TACH_IN")
		)
		(pad "2" smd rect
			(at -0.40005 0)
			(size 0.4572 0.508)
			(layers "F.Cu" "F.Mask" "F.Paste")
			(net "FAN6_TACH")
		)
	)
	(footprint ""
		(layer "F.Cu")
		(at 20.15744 -10.541254 -90)
		(property "Reference" "R808"
			(at 1.17094 -1.56591 90)
			(unlocked yes)
			(layer "F.SilkS")
			(effects
				(font
					(size 0.7874 0.5842)
					(thickness 0.1524)
				)
				(justify left)
			)
		)
		(property "Value" ""
			(at 0 0 270)
			(layer "F.Fab")
			(effects
				(font
					(size 1.27 1.27)
				)
			)
		)
		(duplicate_pad_numbers_are_jumpers no)
		(fp_line
			(start -0.7874 0.4064)
			(end -0.7874 -0.4064)
			(stroke
				(width 0.1524)
				(type default)
			)
			(layer "F.SilkS")
		)
		(fp_line
			(start 0.7874 0.4064)
			(end -0.7874 0.4064)
			(stroke
				(width 0.1524)
				(type default)
			)
			(layer "F.SilkS")
		)
		(fp_line
			(start -0.7874 -0.4064)
			(end 0.7874 -0.4064)
			(stroke
				(width 0.1524)
				(type default)
			)
			(layer "F.SilkS")
		)
		(fp_line
			(start 0.7874 -0.4064)
			(end 0.7874 0.4064)
			(stroke
				(width 0.1524)
				(type default)
			)
			(layer "F.SilkS")
		)
		(fp_poly
			(pts
				(xy -0.508 0.2794) (xy -0.508 0.2286) (xy -0.635 0.2286) (xy -0.635 -0.254) (xy -0.5334 -0.254)
				(xy -0.5334 -0.2794) (xy 0.5334 -0.2794) (xy 0.5334 -0.254) (xy 0.635 -0.254) (xy 0.635 0.254) (xy 0.5334 0.254)
				(xy 0.5334 0.2794)
			)
			(stroke
				(width 0)
				(type default)
			)
			(fill no)
			(layer "F.CrtYd")
		)
		(pad "1" smd rect
			(at 0.40005 0 270)
			(size 0.4572 0.508)
			(layers "F.Cu" "F.Mask" "F.Paste")
			(net "N53608934")
		)
		(pad "2" smd rect
			(at -0.40005 0 270)
			(size 0.4572 0.508)
			(layers "F.Cu" "F.Mask" "F.Paste")
			(net "GND")
		)
	)
	(footprint ""
		(layer "F.Cu")
		(at 48.24476 -185.205624 90)
		(property "Reference" "R842"
			(at 4.006088 0.055372 90)
			(unlocked yes)
			(layer "F.SilkS")
			(effects
				(font
					(size 0.7874 0.5842)
					(thickness 0.1524)
				)
				(justify left)
			)
		)
		(property "Value" ""
			(at 0 0 90)
			(layer "F.Fab")
			(effects
				(font
					(size 1.27 1.27)
				)
			)
		)
		(duplicate_pad_numbers_are_jumpers no)
		(fp_line
			(start 0.7874 -0.4064)
			(end 0.7874 0.4064)
			(stroke
				(width 0.1524)
				(type default)
			)
			(layer "F.SilkS")
		)
		(fp_line
			(start -0.7874 -0.4064)
			(end 0.7874 -0.4064)
			(stroke
				(width 0.1524)
				(type default)
			)
			(layer "F.SilkS")
		)
		(fp_line
			(start 0.7874 0.4064)
			(end -0.7874 0.4064)
			(stroke
				(width 0.1524)
				(type default)
			)
			(layer "F.SilkS")
		)
		(fp_line
			(start -0.7874 0.4064)
			(end -0.7874 -0.4064)
			(stroke
				(width 0.1524)
				(type default)
			)
			(layer "F.SilkS")
		)
		(fp_poly
			(pts
				(xy -0.508 0.2794) (xy -0.508 0.2286) (xy -0.635 0.2286) (xy -0.635 -0.254) (xy -0.5334 -0.254)
				(xy -0.5334 -0.2794) (xy 0.5334 -0.2794) (xy 0.5334 -0.254) (xy 0.635 -0.254) (xy 0.635 0.254) (xy 0.5334 0.254)
				(xy 0.5334 0.2794)
			)
			(stroke
				(width 0)
				(type default)
			)
			(fill no)
			(layer "F.CrtYd")
		)
		(pad "1" smd rect
			(at 0.40005 0 90)
			(size 0.4572 0.508)
			(layers "F.Cu" "F.Mask" "F.Paste")
			(net "PSU5_AC_OK_R")
		)
		(pad "2" smd rect
			(at -0.40005 0 90)
			(size 0.4572 0.508)
			(layers "F.Cu" "F.Mask" "F.Paste")
			(net "PSU5_AC_OK")
		)
	)
	(footprint ""
		(layer "F.Cu")
		(at 80.91297 -96.665034 180)
		(property "Reference" "R1102"
			(at 0.336804 -3.213354 90)
			(unlocked yes)
			(layer "F.SilkS")
			(effects
				(font
					(size 0.635 0.4064)
					(thickness 0.1524)
				)
				(justify left)
			)
		)
		(property "Value" ""
			(at 0 0 180)
			(layer "F.Fab")
			(effects
				(font
					(size 1.27 1.27)
				)
			)
		)
		(duplicate_pad_numbers_are_jumpers no)
		(fp_line
			(start 0.7874 0.4064)
			(end -0.7874 0.4064)
			(stroke
				(width 0.1524)
				(type default)
			)
			(layer "F.SilkS")
		)
		(fp_line
			(start 0.7874 -0.4064)
			(end 0.7874 0.4064)
			(stroke
				(width 0.1524)
				(type default)
			)
			(layer "F.SilkS")
		)
		(fp_line
			(start -0.7874 0.4064)
			(end -0.7874 -0.4064)
			(stroke
				(width 0.1524)
				(type default)
			)
			(layer "F.SilkS")
		)
		(fp_line
			(start -0.7874 -0.4064)
			(end 0.7874 -0.4064)
			(stroke
				(width 0.1524)
				(type default)
			)
			(layer "F.SilkS")
		)
		(fp_poly
			(pts
				(xy -0.508 0.2794) (xy -0.508 0.2286) (xy -0.635 0.2286) (xy -0.635 -0.254) (xy -0.5334 -0.254)
				(xy -0.5334 -0.2794) (xy 0.5334 -0.2794) (xy 0.5334 -0.254) (xy 0.635 -0.254) (xy 0.635 0.254) (xy 0.5334 0.254)
				(xy 0.5334 0.2794)
			)
			(stroke
				(width 0)
				(type default)
			)
			(fill no)
			(layer "F.CrtYd")
		)
		(pad "1" smd rect
			(at 0.40005 0 180)
			(size 0.4572 0.508)
			(layers "F.Cu" "F.Mask" "F.Paste")
			(net "GND")
		)
		(pad "2" smd rect
			(at -0.40005 0 180)
			(size 0.4572 0.508)
			(layers "F.Cu" "F.Mask" "F.Paste")
			(net "P3V3_SUS_NODE1")
		)
	)
	(footprint ""
		(layer "F.Cu")
		(at 107.17276 -185.205624 90)
		(property "Reference" "C696"
			(at 4.768088 0.857758 90)
			(unlocked yes)
			(layer "F.SilkS")
			(effects
				(font
					(size 0.7874 0.5842)
					(thickness 0.1524)
				)
				(justify left)
			)
		)
		(property "Value" ""
			(at 0 0 90)
			(layer "F.Fab")
			(effects
				(font
					(size 1.27 1.27)
				)
			)
		)
		(duplicate_pad_numbers_are_jumpers no)
		(fp_line
			(start 0.7874 -0.4064)
			(end 0.7874 0.4064)
			(stroke
				(width 0.1524)
				(type default)
			)
			(layer "F.SilkS")
		)
		(fp_line
			(start -0.7874 -0.4064)
			(end 0.7874 -0.4064)
			(stroke
				(width 0.1524)
				(type default)
			)
			(layer "F.SilkS")
		)
		(fp_line
			(start 0 0.381)
			(end 0 -0.381)
			(stroke
				(width 0.1524)
				(type default)
			)
			(layer "F.SilkS")
		)
		(fp_line
			(start 0.7874 0.4064)
			(end -0.7874 0.4064)
			(stroke
				(width 0.1524)
				(type default)
			)
			(layer "F.SilkS")
		)
		(fp_line
			(start -0.7874 0.4064)
			(end -0.7874 -0.4064)
			(stroke
				(width 0.1524)
				(type default)
			)
			(layer "F.SilkS")
		)
		(fp_poly
			(pts
				(xy -0.5334 0.254) (xy -0.635 0.254) (xy -0.635 0.2286) (xy -0.635 -0.254) (xy -0.5334 -0.254) (xy -0.5334 -0.2794)
				(xy 0.5334 -0.2794) (xy 0.5334 -0.254) (xy 0.635 -0.254) (xy 0.635 0.254) (xy 0.5334 0.254) (xy 0.5334 0.2794)
				(xy -0.508 0.2794) (xy -0.5334 0.2794)
			)
			(stroke
				(width 0)
				(type default)
			)
			(fill no)
			(layer "F.CrtYd")
		)
		(pad "1" smd rect
			(at 0.40005 0 90)
			(size 0.4572 0.508)
			(layers "F.Cu" "F.Mask" "F.Paste")
			(net "UART_T6_NODE1_RXD")
		)
		(pad "2" smd rect
			(at -0.40005 0 90)
			(size 0.4572 0.508)
			(layers "F.Cu" "F.Mask" "F.Paste")
			(net "GND")
		)
	)
	(footprint ""
		(layer "F.Cu")
		(at 160.81502 -188.08192 90)
		(property "Reference" "R1223"
			(at 1.106932 0.545338 90)
			(unlocked yes)
			(layer "F.SilkS")
			(effects
				(font
					(size 0.7874 0.5842)
					(thickness 0.1524)
				)
				(justify left)
			)
		)
		(property "Value" ""
			(at 0 0 90)
			(layer "F.Fab")
			(effects
				(font
					(size 1.27 1.27)
				)
			)
		)
		(duplicate_pad_numbers_are_jumpers no)
		(fp_line
			(start 0.7874 -0.4064)
			(end 0.7874 0.4064)
			(stroke
				(width 0.1524)
				(type default)
			)
			(layer "F.SilkS")
		)
		(fp_line
			(start -0.7874 -0.4064)
			(end 0.7874 -0.4064)
			(stroke
				(width 0.1524)
				(type default)
			)
			(layer "F.SilkS")
		)
		(fp_line
			(start 0.7874 0.4064)
			(end -0.7874 0.4064)
			(stroke
				(width 0.1524)
				(type default)
			)
			(layer "F.SilkS")
		)
		(fp_line
			(start -0.7874 0.4064)
			(end -0.7874 -0.4064)
			(stroke
				(width 0.1524)
				(type default)
			)
			(layer "F.SilkS")
		)
		(fp_poly
			(pts
				(xy -0.508 0.2794) (xy -0.508 0.2286) (xy -0.635 0.2286) (xy -0.635 -0.254) (xy -0.5334 -0.254)
				(xy -0.5334 -0.2794) (xy 0.5334 -0.2794) (xy 0.5334 -0.254) (xy 0.635 -0.254) (xy 0.635 0.254) (xy 0.5334 0.254)
				(xy 0.5334 0.2794)
			)
			(stroke
				(width 0)
				(type default)
			)
			(fill no)
			(layer "F.CrtYd")
		)
		(pad "1" smd rect
			(at 0.40005 0 90)
			(size 0.4572 0.508)
			(layers "F.Cu" "F.Mask" "F.Paste")
			(net "FAN5_TACH_R")
		)
		(pad "2" smd rect
			(at -0.40005 0 90)
			(size 0.4572 0.508)
			(layers "F.Cu" "F.Mask" "F.Paste")
			(net "GND")
		)
	)
	(footprint ""
		(layer "F.Cu")
		(at 45.604176 -106.255312 180)
		(property "Reference" "PJ2"
			(at 3.070098 -2.106676 90)
			(unlocked yes)
			(layer "F.SilkS")
			(effects
				(font
					(size 0.7874 0.5842)
					(thickness 0.1524)
				)
				(justify left)
			)
		)
		(property "Value" ""
			(at 0 0 180)
			(layer "F.Fab")
			(effects
				(font
					(size 1.27 1.27)
				)
			)
		)
		(duplicate_pad_numbers_are_jumpers no)
		(fp_poly
			(pts
				(xy 0.2794 0.907796) (xy 0.254 0.907796) (xy 0.254 1.0414) (xy -0.254 1.0414) (xy -0.254 1.034796)
				(xy -0.254 0.933196) (xy -0.2794 0.933196) (xy -0.2794 -0.133604) (xy -0.254 -0.133604) (xy -0.254 -0.235204)
				(xy 0.254 -0.235204) (xy 0.254 -0.133604) (xy 0.2794 -0.133604)
			)
			(stroke
				(width 0)
				(type default)
			)
			(fill no)
			(layer "F.CrtYd")
		)
		(pad "1" smd custom
			(at 0 -0.000254 180)
			(size 0.127 0.127)
			(layers "F.Cu" "F.Mask" "F.Paste")
			(net "PWRGD_NODE1_P5V_STB_PG")
			(options
				(clearance outline)
				(anchor circle)
			)
			(primitives
				(gr_poly
					(pts
						(xy -0.127 0.508) (xy -0.127 -0.0508) (xy -0.254 -0.0508) (xy -0.254 -0.508) (xy 0.254 -0.508)
						(xy 0.254 -0.0508) (xy 0.127 -0.0508) (xy 0.127 0.508)
					)
					(width 0)
					(fill yes)
				)
			)
		)
		(pad "2" smd rect
			(at 0 0.799846 270)
			(size 0.4572 0.508)
			(layers "F.Cu" "F.Mask" "F.Paste")
			(net "P3V3_STB_NODE1_EN")
		)
		(zone
			(layer "F.Cu")
			(hatch none 0.5)
			(connect_pads
				(clearance 0)
			)
			(min_thickness 0.25)
			(keepout
				(tracks allowed)
				(vias not_allowed)
				(pads allowed)
				(copperpour not_allowed)
				(footprints allowed)
			)
			(placement
				(enabled no)
				(sheetname "")
			)
			(fill
				(thermal_gap 0.5)
				(thermal_bridge_width 0.5)
				(island_removal_mode 0)
			)
			(polygon
				(pts
					(xy 45.908976 -107.340908) (xy 45.299376 -107.340908) (xy 45.299376 -105.969308) (xy 45.908976 -105.969308)
				)
			)
		)
	)
	(footprint ""
		(layer "F.Cu")
		(at 24.826722 -57.362344 180)
		(property "Reference" "R658"
			(at -12.358878 -3.551936 0)
			(unlocked yes)
			(layer "F.SilkS")
			(effects
				(font
					(size 0.7874 0.5842)
					(thickness 0.1524)
				)
				(justify left)
			)
		)
		(property "Value" ""
			(at 0 0 180)
			(layer "F.Fab")
			(effects
				(font
					(size 1.27 1.27)
				)
			)
		)
		(duplicate_pad_numbers_are_jumpers no)
		(fp_line
			(start 0.7874 0.4064)
			(end -0.7874 0.4064)
			(stroke
				(width 0.1524)
				(type default)
			)
			(layer "F.SilkS")
		)
		(fp_line
			(start 0.7874 -0.4064)
			(end 0.7874 0.4064)
			(stroke
				(width 0.1524)
				(type default)
			)
			(layer "F.SilkS")
		)
		(fp_line
			(start -0.7874 0.4064)
			(end -0.7874 -0.4064)
			(stroke
				(width 0.1524)
				(type default)
			)
			(layer "F.SilkS")
		)
		(fp_line
			(start -0.7874 -0.4064)
			(end 0.7874 -0.4064)
			(stroke
				(width 0.1524)
				(type default)
			)
			(layer "F.SilkS")
		)
		(fp_poly
			(pts
				(xy -0.508 0.2794) (xy -0.508 0.2286) (xy -0.635 0.2286) (xy -0.635 -0.254) (xy -0.5334 -0.254)
				(xy -0.5334 -0.2794) (xy 0.5334 -0.2794) (xy 0.5334 -0.254) (xy 0.635 -0.254) (xy 0.635 0.254) (xy 0.5334 0.254)
				(xy 0.5334 0.2794)
			)
			(stroke
				(width 0)
				(type default)
			)
			(fill no)
			(layer "F.CrtYd")
		)
		(pad "1" smd rect
			(at 0.40005 0 180)
			(size 0.4572 0.508)
			(layers "F.Cu" "F.Mask" "F.Paste")
			(net "GND")
		)
		(pad "2" smd rect
			(at -0.40005 0 180)
			(size 0.4572 0.508)
			(layers "F.Cu" "F.Mask" "F.Paste")
			(net "GFX_BUF_EN_N")
		)
	)
	(footprint ""
		(layer "F.Cu")
		(at 152.755854 -137.187432)
		(property "Reference" "R1063"
			(at -5.190236 1.965198 0)
			(unlocked yes)
			(layer "F.SilkS")
			(effects
				(font
					(size 0.7874 0.5842)
					(thickness 0.1524)
				)
				(justify left)
			)
		)
		(property "Value" ""
			(at 0 0 0)
			(layer "F.Fab")
			(effects
				(font
					(size 1.27 1.27)
				)
			)
		)
		(duplicate_pad_numbers_are_jumpers no)
		(fp_line
			(start -0.7874 -0.4064)
			(end 0.7874 -0.4064)
			(stroke
				(width 0.1524)
				(type default)
			)
			(layer "F.SilkS")
		)
		(fp_line
			(start -0.7874 0.4064)
			(end -0.7874 -0.4064)
			(stroke
				(width 0.1524)
				(type default)
			)
			(layer "F.SilkS")
		)
		(fp_line
			(start 0.7874 -0.4064)
			(end 0.7874 0.4064)
			(stroke
				(width 0.1524)
				(type default)
			)
			(layer "F.SilkS")
		)
		(fp_line
			(start 0.7874 0.4064)
			(end -0.7874 0.4064)
			(stroke
				(width 0.1524)
				(type default)
			)
			(layer "F.SilkS")
		)
		(fp_poly
			(pts
				(xy -0.508 0.2794) (xy -0.508 0.2286) (xy -0.635 0.2286) (xy -0.635 -0.254) (xy -0.5334 -0.254)
				(xy -0.5334 -0.2794) (xy 0.5334 -0.2794) (xy 0.5334 -0.254) (xy 0.635 -0.254) (xy 0.635 0.254) (xy 0.5334 0.254)
				(xy 0.5334 0.2794)
			)
			(stroke
				(width 0)
				(type default)
			)
			(fill no)
			(layer "F.CrtYd")
		)
		(pad "1" smd rect
			(at 0.40005 0)
			(size 0.4572 0.508)
			(layers "F.Cu" "F.Mask" "F.Paste")
			(net "RST_BTN_NODE1_C_L")
		)
		(pad "2" smd rect
			(at -0.40005 0)
			(size 0.4572 0.508)
			(layers "F.Cu" "F.Mask" "F.Paste")
			(net "RST_BTN_L")
		)
	)
	(footprint ""
		(layer "F.Cu")
		(at 149.277578 -57.249822 -90)
		(property "Reference" "R502"
			(at -14.50213 -26.0858 90)
			(unlocked yes)
			(layer "F.SilkS")
			(effects
				(font
					(size 0.7874 0.5842)
					(thickness 0.1524)
				)
				(justify left)
			)
		)
		(property "Value" ""
			(at 0 0 270)
			(layer "F.Fab")
			(effects
				(font
					(size 1.27 1.27)
				)
			)
		)
		(duplicate_pad_numbers_are_jumpers no)
		(fp_line
			(start -0.7874 0.4064)
			(end -0.7874 -0.4064)
			(stroke
				(width 0.1524)
				(type default)
			)
			(layer "F.SilkS")
		)
		(fp_line
			(start 0.7874 0.4064)
			(end -0.7874 0.4064)
			(stroke
				(width 0.1524)
				(type default)
			)
			(layer "F.SilkS")
		)
		(fp_line
			(start -0.7874 -0.4064)
			(end 0.7874 -0.4064)
			(stroke
				(width 0.1524)
				(type default)
			)
			(layer "F.SilkS")
		)
		(fp_line
			(start 0.7874 -0.4064)
			(end 0.7874 0.4064)
			(stroke
				(width 0.1524)
				(type default)
			)
			(layer "F.SilkS")
		)
		(fp_poly
			(pts
				(xy -0.508 0.2794) (xy -0.508 0.2286) (xy -0.635 0.2286) (xy -0.635 -0.254) (xy -0.5334 -0.254)
				(xy -0.5334 -0.2794) (xy 0.5334 -0.2794) (xy 0.5334 -0.254) (xy 0.635 -0.254) (xy 0.635 0.254) (xy 0.5334 0.254)
				(xy 0.5334 0.2794)
			)
			(stroke
				(width 0)
				(type default)
			)
			(fill no)
			(layer "F.CrtYd")
		)
		(pad "1" smd rect
			(at 0.40005 0 270)
			(size 0.4572 0.508)
			(layers "F.Cu" "F.Mask" "F.Paste")
			(net "P3V3_NODE1")
		)
		(pad "2" smd rect
			(at -0.40005 0 270)
			(size 0.4572 0.508)
			(layers "F.Cu" "F.Mask" "F.Paste")
			(net "PU_SATA_NODE1_GPIO4")
		)
	)
	(footprint ""
		(layer "F.Cu")
		(at 115.382802 -22.305264 180)
		(property "Reference" "U123"
			(at 2.883154 -1.497584 90)
			(unlocked yes)
			(layer "F.SilkS")
			(effects
				(font
					(size 0.7874 0.5842)
					(thickness 0.1524)
				)
				(justify left)
			)
		)
		(property "Value" ""
			(at 0 0 180)
			(layer "F.Fab")
			(effects
				(font
					(size 1.27 1.27)
				)
			)
		)
		(duplicate_pad_numbers_are_jumpers no)
		(fp_line
			(start 1.625092 1.625092)
			(end 1.27 1.625092)
			(stroke
				(width 0.1524)
				(type default)
			)
			(layer "F.SilkS")
		)
		(fp_line
			(start 1.625092 1.016)
			(end 1.625092 1.625092)
			(stroke
				(width 0.1524)
				(type default)
			)
			(layer "F.SilkS")
		)
		(fp_line
			(start 1.625092 -1.625092)
			(end 1.625092 -1.016)
			(stroke
				(width 0.1524)
				(type default)
			)
			(layer "F.SilkS")
		)
		(fp_line
			(start 1.27 -1.625092)
			(end 1.625092 -1.625092)
			(stroke
				(width 0.1524)
				(type default)
			)
			(layer "F.SilkS")
		)
		(fp_line
			(start -1.27 1.625092)
			(end -1.625092 1.625092)
			(stroke
				(width 0.1524)
				(type default)
			)
			(layer "F.SilkS")
		)
		(fp_line
			(start -1.625092 1.625092)
			(end -1.625092 1.016)
			(stroke
				(width 0.1524)
				(type default)
			)
			(layer "F.SilkS")
		)
		(fp_line
			(start -1.625092 -1.016)
			(end -1.625092 -1.625092)
			(stroke
				(width 0.1524)
				(type default)
			)
			(layer "F.SilkS")
		)
		(fp_line
			(start -1.625092 -1.625092)
			(end -1.27 -1.625092)
			(stroke
				(width 0.1524)
				(type default)
			)
			(layer "F.SilkS")
		)
		(fp_poly
			(pts
				(xy -0.999998 2.0701) (xy -1.299972 2.970276) (xy -0.700024 2.970276)
			)
			(stroke
				(width 0)
				(type default)
			)
			(fill yes)
			(layer "F.SilkS")
		)
		(fp_poly
			(pts
				(xy -1.625092 1.625092) (xy -1.1938 1.625092) (xy -1.1938 2.0574) (xy 1.1938 2.0574) (xy 1.1938 1.625092)
				(xy 1.625092 1.625092) (xy 1.625092 0.9398) (xy 1.6764 0.9398) (xy 1.6764 -0.9398) (xy 1.625092 -0.9398)
				(xy 1.625092 -1.625092) (xy 1.1938 -1.625092) (xy 1.1938 -2.0574) (xy -1.1938 -2.0574) (xy -1.1938 -1.625092)
				(xy -1.625092 -1.625092) (xy -1.625092 -0.9398) (xy -1.6764 -0.9398) (xy -1.6764 0.9398) (xy -1.625092 0.9398)
			)
			(stroke
				(width 0)
				(type default)
			)
			(fill no)
			(layer "F.CrtYd")
		)
		(fp_line
			(start 1.625092 1.625092)
			(end -1.625092 1.625092)
			(stroke
				(width 0.1)
				(type default)
			)
			(layer "F.Fab")
		)
		(fp_line
			(start 1.625092 -1.625092)
			(end 1.625092 1.625092)
			(stroke
				(width 0.1)
				(type default)
			)
			(layer "F.Fab")
		)
		(fp_line
			(start -1.625092 1.625092)
			(end -1.625092 -1.625092)
			(stroke
				(width 0.1)
				(type default)
			)
			(layer "F.Fab")
		)
		(fp_line
			(start -1.625092 -1.625092)
			(end 1.625092 -1.625092)
			(stroke
				(width 0.1)
				(type default)
			)
			(layer "F.Fab")
		)
		(fp_poly
			(pts
				(xy -0.999998 2.0701) (xy -1.302512 2.977896) (xy -0.697484 2.977896)
			)
			(stroke
				(width 0)
				(type default)
			)
			(fill yes)
			(layer "F.Fab")
		)
		(fp_text user "5"
			(at 2.31013 1.737868 0)
			(unlocked yes)
			(layer "F.SilkS")
			(effects
				(font
					(size 0.635 0.4064)
					(thickness 0.1524)
				)
				(justify left)
			)
		)
		(fp_text user "6"
			(at 1.888236 -1.62306 180)
			(unlocked yes)
			(layer "F.SilkS")
			(effects
				(font
					(size 0.635 0.4064)
					(thickness 0.1524)
				)
				(justify left)
			)
		)
		(fp_text user "1"
			(at -1.525778 2.101596 0)
			(unlocked yes)
			(layer "F.SilkS")
			(effects
				(font
					(size 0.635 0.4064)
					(thickness 0.1524)
				)
				(justify left)
			)
		)
		(fp_text user "10"
			(at -1.846072 -1.77673 0)
			(unlocked yes)
			(layer "F.SilkS")
			(effects
				(font
					(size 0.635 0.4064)
					(thickness 0.1524)
				)
				(justify left)
			)
		)
		(fp_text user "5"
			(at 1.1557 2.245868 180)
			(unlocked yes)
			(layer "F.Fab")
			(effects
				(font
					(size 0.7874 0.5842)
					(thickness 0.000001)
				)
				(justify left)
			)
		)
		(fp_text user "6"
			(at 1.1557 -2.17551 180)
			(unlocked yes)
			(layer "F.Fab")
			(effects
				(font
					(size 0.7874 0.5842)
					(thickness 0.000001)
				)
				(justify left)
			)
		)
		(fp_text user "1"
			(at -1.7907 2.245868 180)
			(unlocked yes)
			(layer "F.Fab")
			(effects
				(font
					(size 0.7874 0.5842)
					(thickness 0.000001)
				)
				(justify left)
			)
		)
		(fp_text user "10"
			(at -2.5654 -2.15011 180)
			(unlocked yes)
			(layer "F.Fab")
			(effects
				(font
					(size 0.7874 0.5842)
					(thickness 0.000001)
				)
				(justify left)
			)
		)
		(pad "1" smd rect
			(at -0.999998 1.550162 180)
			(size 0.2794 0.9144)
			(layers "F.Cu" "F.Mask" "F.Paste")
			(net "PV_VTT_DDR_NODE1_REFIN")
		)
		(pad "2" smd rect
			(at -0.500126 1.550162 180)
			(size 0.2794 0.9144)
			(layers "F.Cu" "F.Mask" "F.Paste")
			(net "PV_VDDR_NODE1")
		)
		(pad "3" smd rect
			(at 0 1.550162 180)
			(size 0.2794 0.9144)
			(layers "F.Cu" "F.Mask" "F.Paste")
			(net "PV_VTT_DDR_NODE1")
		)
		(pad "4" smd rect
			(at 0.500126 1.550162 180)
			(size 0.2794 0.9144)
			(layers "F.Cu" "F.Mask" "F.Paste")
			(net "GND")
		)
		(pad "5" smd rect
			(at 0.999998 1.550162)
			(size 0.2794 0.9144)
			(layers "F.Cu" "F.Mask" "F.Paste")
			(net "PV_VTT_DDR_NODE1_VOSNS")
		)
		(pad "6" smd rect
			(at 0.999998 -1.550162)
			(size 0.2794 0.9144)
			(layers "F.Cu" "F.Mask" "F.Paste")
			(net "PV_VTT_DDR_NODE1_REFOUT")
		)
		(pad "7" smd rect
			(at 0.500126 -1.550162 180)
			(size 0.2794 0.9144)
			(layers "F.Cu" "F.Mask" "F.Paste")
			(net "FM_CPLD_NODE1_PVTT_DDR_EN")
		)
		(pad "8" smd rect
			(at 0 -1.550162 180)
			(size 0.2794 0.9144)
			(layers "F.Cu" "F.Mask" "F.Paste")
			(net "GND")
		)
		(pad "9" smd rect
			(at -0.500126 -1.550162 180)
			(size 0.2794 0.9144)
			(layers "F.Cu" "F.Mask" "F.Paste")
			(net "PWRGD_NODE1_PVTT_DDR_PG")
		)
		(pad "10" smd rect
			(at -0.999998 -1.550162 180)
			(size 0.2794 0.9144)
			(layers "F.Cu" "F.Mask" "F.Paste")
			(net "P3V3_STB_NODE1")
		)
		(pad "TH" smd rect
			(at 0 0 270)
			(size 1.7526 3.2512)
			(layers "F.Cu" "F.Mask" "F.Paste")
			(net "GND")
		)
	)
	(footprint ""
		(layer "F.Cu")
		(at 147.98548 -158.594552 -90)
		(property "Reference" "C191"
			(at 0.138684 -0.475488 0)
			(unlocked yes)
			(layer "F.SilkS")
			(effects
				(font
					(size 0.7874 0.5842)
					(thickness 0.1524)
				)
				(justify left)
			)
		)
		(property "Value" ""
			(at 0 0 270)
			(layer "F.Fab")
			(effects
				(font
					(size 1.27 1.27)
				)
			)
		)
		(duplicate_pad_numbers_are_jumpers no)
		(fp_line
			(start -0.7874 0.4064)
			(end -0.7874 -0.4064)
			(stroke
				(width 0.1524)
				(type default)
			)
			(layer "F.SilkS")
		)
		(fp_line
			(start 0.7874 0.4064)
			(end -0.7874 0.4064)
			(stroke
				(width 0.1524)
				(type default)
			)
			(layer "F.SilkS")
		)
		(fp_line
			(start 0 0.381)
			(end 0 -0.381)
			(stroke
				(width 0.1524)
				(type default)
			)
			(layer "F.SilkS")
		)
		(fp_line
			(start -0.7874 -0.4064)
			(end 0.7874 -0.4064)
			(stroke
				(width 0.1524)
				(type default)
			)
			(layer "F.SilkS")
		)
		(fp_line
			(start 0.7874 -0.4064)
			(end 0.7874 0.4064)
			(stroke
				(width 0.1524)
				(type default)
			)
			(layer "F.SilkS")
		)
		(fp_poly
			(pts
				(xy -0.5334 0.254) (xy -0.635 0.254) (xy -0.635 0.2286) (xy -0.635 -0.254) (xy -0.5334 -0.254) (xy -0.5334 -0.2794)
				(xy 0.5334 -0.2794) (xy 0.5334 -0.254) (xy 0.635 -0.254) (xy 0.635 0.254) (xy 0.5334 0.254) (xy 0.5334 0.2794)
				(xy -0.508 0.2794) (xy -0.5334 0.2794)
			)
			(stroke
				(width 0)
				(type default)
			)
			(fill no)
			(layer "F.CrtYd")
		)
		(pad "1" smd rect
			(at 0.40005 0 270)
			(size 0.4572 0.508)
			(layers "F.Cu" "F.Mask" "F.Paste")
			(net "P3V3_NODE1")
		)
		(pad "2" smd rect
			(at -0.40005 0 270)
			(size 0.4572 0.508)
			(layers "F.Cu" "F.Mask" "F.Paste")
			(net "GND")
		)
	)
	(footprint ""
		(layer "F.Cu")
		(at 154.551126 -165.245288)
		(property "Reference" "R585"
			(at -5.148834 -4.59359 0)
			(unlocked yes)
			(layer "F.SilkS")
			(effects
				(font
					(size 0.7874 0.5842)
					(thickness 0.1524)
				)
				(justify left)
			)
		)
		(property "Value" ""
			(at 0 0 0)
			(layer "F.Fab")
			(effects
				(font
					(size 1.27 1.27)
				)
			)
		)
		(duplicate_pad_numbers_are_jumpers no)
		(fp_line
			(start -0.7874 -0.4064)
			(end 0.7874 -0.4064)
			(stroke
				(width 0.1524)
				(type default)
			)
			(layer "F.SilkS")
		)
		(fp_line
			(start -0.7874 0.4064)
			(end -0.7874 -0.4064)
			(stroke
				(width 0.1524)
				(type default)
			)
			(layer "F.SilkS")
		)
		(fp_line
			(start 0.7874 -0.4064)
			(end 0.7874 0.4064)
			(stroke
				(width 0.1524)
				(type default)
			)
			(layer "F.SilkS")
		)
		(fp_line
			(start 0.7874 0.4064)
			(end -0.7874 0.4064)
			(stroke
				(width 0.1524)
				(type default)
			)
			(layer "F.SilkS")
		)
		(fp_poly
			(pts
				(xy -0.508 0.2794) (xy -0.508 0.2286) (xy -0.635 0.2286) (xy -0.635 -0.254) (xy -0.5334 -0.254)
				(xy -0.5334 -0.2794) (xy 0.5334 -0.2794) (xy 0.5334 -0.254) (xy 0.635 -0.254) (xy 0.635 0.254) (xy 0.5334 0.254)
				(xy 0.5334 0.2794)
			)
			(stroke
				(width 0)
				(type default)
			)
			(fill no)
			(layer "F.CrtYd")
		)
		(pad "1" smd rect
			(at 0.40005 0)
			(size 0.4572 0.508)
			(layers "F.Cu" "F.Mask" "F.Paste")
			(net "LAN2_NVM_WP_N")
		)
		(pad "2" smd rect
			(at -0.40005 0)
			(size 0.4572 0.508)
			(layers "F.Cu" "F.Mask" "F.Paste")
			(net "P3V3_NODE1")
		)
	)
	(footprint ""
		(layer "F.Cu")
		(at 130.108452 -158.641796 180)
		(property "Reference" "U139"
			(at 61.408818 -109.092746 90)
			(unlocked yes)
			(layer "F.SilkS")
			(effects
				(font
					(size 0.7874 0.5842)
					(thickness 0.1524)
				)
			)
		)
		(property "Value" ""
			(at 0 0 180)
			(layer "F.Fab")
			(effects
				(font
					(size 1.27 1.27)
				)
			)
		)
		(duplicate_pad_numbers_are_jumpers no)
		(fp_line
			(start 1.651 1.905)
			(end -1.651 1.905)
			(stroke
				(width 0.1524)
				(type default)
			)
			(layer "F.SilkS")
		)
		(fp_line
			(start 1.651 -1.905)
			(end 1.651 1.905)
			(stroke
				(width 0.1524)
				(type default)
			)
			(layer "F.SilkS")
		)
		(fp_line
			(start -1.651 1.905)
			(end -1.651 -1.905)
			(stroke
				(width 0.1524)
				(type default)
			)
			(layer "F.SilkS")
		)
		(fp_line
			(start -1.651 -1.905)
			(end 1.651 -1.905)
			(stroke
				(width 0.1524)
				(type default)
			)
			(layer "F.SilkS")
		)
		(fp_poly
			(pts
				(xy -1.524 0.7112) (xy -1.524 1.7526) (xy -0.508 1.7526) (xy -0.508 0.6985) (xy 0.508 0.6985) (xy 0.508 1.7526)
				(xy 1.524 1.7526) (xy 1.524 0.6985) (xy 1.524 -0.6985) (xy 0.508 -0.6985) (xy 0.508 -1.7526) (xy -0.508 -1.7526)
				(xy -0.508 -0.6985) (xy -1.524 -0.6985) (xy -1.524 0.6985)
			)
			(stroke
				(width 0)
				(type default)
			)
			(fill no)
			(layer "F.CrtYd")
		)
		(fp_text user "S"
			(at 0.499618 -0.030226 0)
			(unlocked yes)
			(layer "F.SilkS")
			(effects
				(font
					(size 0.635 0.4064)
					(thickness 0.1524)
				)
			)
		)
		(fp_text user "D"
			(at 0.172466 -2.761488 0)
			(unlocked yes)
			(layer "F.SilkS")
			(effects
				(font
					(size 0.635 0.4064)
					(thickness 0.1524)
				)
			)
		)
		(fp_text user "G"
			(at -2.52222 2.676398 0)
			(unlocked yes)
			(layer "F.SilkS")
			(effects
				(font
					(size 0.635 0.4064)
					(thickness 0.1524)
				)
			)
		)
		(pad "D" smd rect
			(at 0 -1.1176 180)
			(size 1.016 1.27)
			(layers "F.Cu" "F.Mask" "F.Paste")
			(net "I2C_PSU3_SCL")
		)
		(pad "G" smd rect
			(at -1.016 1.1176 180)
			(size 1.016 1.27)
			(layers "F.Cu" "F.Mask" "F.Paste")
			(net "PMBUS3_EN")
		)
		(pad "S" smd rect
			(at 1.016 1.1176 180)
			(size 1.016 1.27)
			(layers "F.Cu" "F.Mask" "F.Paste")
			(net "I2C_PSU3_SCL_MOS")
		)
	)
	(footprint ""
		(layer "F.Cu")
		(at 137.52576 -110.783624 -90)
		(property "Reference" "R26"
			(at 5.835904 -0.850646 90)
			(unlocked yes)
			(layer "F.SilkS")
			(effects
				(font
					(size 0.7874 0.5842)
					(thickness 0.1524)
				)
				(justify left)
			)
		)
		(property "Value" ""
			(at 0 0 270)
			(layer "F.Fab")
			(effects
				(font
					(size 1.27 1.27)
				)
			)
		)
		(duplicate_pad_numbers_are_jumpers no)
		(fp_line
			(start -0.7874 0.4064)
			(end -0.7874 -0.4064)
			(stroke
				(width 0.1524)
				(type default)
			)
			(layer "F.SilkS")
		)
		(fp_line
			(start 0.7874 0.4064)
			(end -0.7874 0.4064)
			(stroke
				(width 0.1524)
				(type default)
			)
			(layer "F.SilkS")
		)
		(fp_line
			(start -0.7874 -0.4064)
			(end 0.7874 -0.4064)
			(stroke
				(width 0.1524)
				(type default)
			)
			(layer "F.SilkS")
		)
		(fp_line
			(start 0.7874 -0.4064)
			(end 0.7874 0.4064)
			(stroke
				(width 0.1524)
				(type default)
			)
			(layer "F.SilkS")
		)
		(fp_poly
			(pts
				(xy -0.508 0.2794) (xy -0.508 0.2286) (xy -0.635 0.2286) (xy -0.635 -0.254) (xy -0.5334 -0.254)
				(xy -0.5334 -0.2794) (xy 0.5334 -0.2794) (xy 0.5334 -0.254) (xy 0.635 -0.254) (xy 0.635 0.254) (xy 0.5334 0.254)
				(xy 0.5334 0.2794)
			)
			(stroke
				(width 0)
				(type default)
			)
			(fill no)
			(layer "F.CrtYd")
		)
		(pad "1" smd rect
			(at 0.40005 0 270)
			(size 0.4572 0.508)
			(layers "F.Cu" "F.Mask" "F.Paste")
			(net "GND")
		)
		(pad "2" smd rect
			(at -0.40005 0 270)
			(size 0.4572 0.508)
			(layers "F.Cu" "F.Mask" "F.Paste")
			(net "CLK_14M_CPU_NODE1_R")
		)
	)
	(footprint ""
		(layer "F.Cu")
		(at 35.669728 -79.893922)
		(property "Reference" "R40"
			(at -4.58851 -0.106934 0)
			(unlocked yes)
			(layer "F.SilkS")
			(effects
				(font
					(size 0.7874 0.5842)
					(thickness 0.1524)
				)
				(justify left)
			)
		)
		(property "Value" ""
			(at 0 0 0)
			(layer "F.Fab")
			(effects
				(font
					(size 1.27 1.27)
				)
			)
		)
		(duplicate_pad_numbers_are_jumpers no)
		(fp_line
			(start -0.7874 -0.4064)
			(end 0.7874 -0.4064)
			(stroke
				(width 0.1524)
				(type default)
			)
			(layer "F.SilkS")
		)
		(fp_line
			(start -0.7874 0.4064)
			(end -0.7874 -0.4064)
			(stroke
				(width 0.1524)
				(type default)
			)
			(layer "F.SilkS")
		)
		(fp_line
			(start 0.7874 -0.4064)
			(end 0.7874 0.4064)
			(stroke
				(width 0.1524)
				(type default)
			)
			(layer "F.SilkS")
		)
		(fp_line
			(start 0.7874 0.4064)
			(end -0.7874 0.4064)
			(stroke
				(width 0.1524)
				(type default)
			)
			(layer "F.SilkS")
		)
		(fp_poly
			(pts
				(xy -0.508 0.2794) (xy -0.508 0.2286) (xy -0.635 0.2286) (xy -0.635 -0.254) (xy -0.5334 -0.254)
				(xy -0.5334 -0.2794) (xy 0.5334 -0.2794) (xy 0.5334 -0.254) (xy 0.635 -0.254) (xy 0.635 0.254) (xy 0.5334 0.254)
				(xy 0.5334 0.2794)
			)
			(stroke
				(width 0)
				(type default)
			)
			(fill no)
			(layer "F.CrtYd")
		)
		(pad "1" smd rect
			(at 0.40005 0)
			(size 0.4572 0.508)
			(layers "F.Cu" "F.Mask" "F.Paste")
			(net "PD_CPU_NODE1_Y2")
		)
		(pad "2" smd rect
			(at -0.40005 0)
			(size 0.4572 0.508)
			(layers "F.Cu" "F.Mask" "F.Paste")
			(net "GND")
		)
	)
	(footprint ""
		(layer "F.Cu")
		(at -74.811128 -265.390884)
		(property "Reference" "H10_NUT"
			(at -1.157732 0.435102 0)
			(unlocked yes)
			(layer "B.SilkS")
			(effects
				(font
					(size 0.7874 0.5842)
					(thickness 0.1524)
				)
				(justify left mirror)
			)
		)
		(property "Value" ""
			(at 0 0 0)
			(layer "F.Fab")
			(effects
				(font
					(size 1.27 1.27)
				)
			)
		)
		(duplicate_pad_numbers_are_jumpers no)
		(fp_poly
			(pts
				(arc
					(start 0.3302 0)
					(mid -0.3302 0)
					(end 0.3302 0)
				)
			)
			(stroke
				(width 0)
				(type default)
			)
			(fill no)
			(layer "B.CrtYd")
		)
		(pad "1" thru_hole circle
			(at 0 0)
			(size 0.508 0.508)
			(drill 0.254)
			(layers "*.Cu" "*.Mask")
			(remove_unused_layers no)
			(net "Net_218")
			(clearance 0.127)
			(thermal_gap 0.127)
			(padstack
				(mode front_inner_back)
				(layer "Inner"
					(shape circle)
					(size 0.508 0.508)
					(clearance 0.127)
				)
				(layer "B.Cu"
					(shape circle)
					(size 0.6604 0.6604)
					(clearance 0.0508)
				)
			)
		)
	)
	(footprint ""
		(layer "F.Cu")
		(at 80.527398 -138.786616)
		(property "Reference" "C838"
			(at -2.036318 3.04927 0)
			(unlocked yes)
			(layer "F.SilkS")
			(effects
				(font
					(size 0.635 0.4064)
					(thickness 0.1524)
				)
				(justify left)
			)
		)
		(property "Value" ""
			(at 0 0 0)
			(layer "F.Fab")
			(effects
				(font
					(size 1.27 1.27)
				)
			)
		)
		(duplicate_pad_numbers_are_jumpers no)
		(fp_line
			(start -1.905 -0.8636)
			(end 1.905 -0.8636)
			(stroke
				(width 0.1524)
				(type default)
			)
			(layer "F.SilkS")
		)
		(fp_line
			(start -1.905 0.8636)
			(end -1.905 -0.8636)
			(stroke
				(width 0.1524)
				(type default)
			)
			(layer "F.SilkS")
		)
		(fp_line
			(start 0 0.8382)
			(end 0 -0.8382)
			(stroke
				(width 0.1524)
				(type default)
			)
			(layer "F.SilkS")
		)
		(fp_line
			(start 1.905 -0.8636)
			(end 1.905 0.8636)
			(stroke
				(width 0.1524)
				(type default)
			)
			(layer "F.SilkS")
		)
		(fp_line
			(start 1.905 0.8636)
			(end -1.905 0.8636)
			(stroke
				(width 0.1524)
				(type default)
			)
			(layer "F.SilkS")
		)
		(fp_rect
			(start -1.524 0.7366)
			(end 1.524 -0.7366)
			(stroke
				(width 0)
				(type default)
			)
			(fill no)
			(layer "F.CrtYd")
		)
		(pad "1" smd rect
			(at 0.94996 0)
			(size 1.1176 1.3716)
			(layers "F.Cu" "F.Mask" "F.Paste")
			(net "P1V26_BMC_NODE1")
		)
		(pad "2" smd rect
			(at -0.94996 0)
			(size 1.1176 1.3716)
			(layers "F.Cu" "F.Mask" "F.Paste")
			(net "GND")
		)
	)
	(footprint ""
		(layer "F.Cu")
		(at 69.96176 -185.205624 -90)
		(property "Reference" "R953"
			(at -4.006088 0.889762 90)
			(unlocked yes)
			(layer "F.SilkS")
			(effects
				(font
					(size 0.7874 0.5842)
					(thickness 0.1524)
				)
				(justify left)
			)
		)
		(property "Value" ""
			(at 0 0 270)
			(layer "F.Fab")
			(effects
				(font
					(size 1.27 1.27)
				)
			)
		)
		(duplicate_pad_numbers_are_jumpers no)
		(fp_line
			(start -0.7874 0.4064)
			(end -0.7874 -0.4064)
			(stroke
				(width 0.1524)
				(type default)
			)
			(layer "F.SilkS")
		)
		(fp_line
			(start 0.7874 0.4064)
			(end -0.7874 0.4064)
			(stroke
				(width 0.1524)
				(type default)
			)
			(layer "F.SilkS")
		)
		(fp_line
			(start -0.7874 -0.4064)
			(end 0.7874 -0.4064)
			(stroke
				(width 0.1524)
				(type default)
			)
			(layer "F.SilkS")
		)
		(fp_line
			(start 0.7874 -0.4064)
			(end 0.7874 0.4064)
			(stroke
				(width 0.1524)
				(type default)
			)
			(layer "F.SilkS")
		)
		(fp_poly
			(pts
				(xy -0.508 0.2794) (xy -0.508 0.2286) (xy -0.635 0.2286) (xy -0.635 -0.254) (xy -0.5334 -0.254)
				(xy -0.5334 -0.2794) (xy 0.5334 -0.2794) (xy 0.5334 -0.254) (xy 0.635 -0.254) (xy 0.635 0.254) (xy 0.5334 0.254)
				(xy 0.5334 0.2794)
			)
			(stroke
				(width 0)
				(type default)
			)
			(fill no)
			(layer "F.CrtYd")
		)
		(pad "1" smd rect
			(at 0.40005 0 270)
			(size 0.4572 0.508)
			(layers "F.Cu" "F.Mask" "F.Paste")
			(net "UART_T4_NODE4_TXD")
		)
		(pad "2" smd rect
			(at -0.40005 0 270)
			(size 0.4572 0.508)
			(layers "F.Cu" "F.Mask" "F.Paste")
			(net "UART_T4_NODE4_TXD_R")
		)
	)
	(footprint ""
		(layer "F.Cu")
		(at 63.10376 -185.205624 -90)
		(property "Reference" "R934"
			(at -4.006088 0.728218 90)
			(unlocked yes)
			(layer "F.SilkS")
			(effects
				(font
					(size 0.7874 0.5842)
					(thickness 0.1524)
				)
				(justify left)
			)
		)
		(property "Value" ""
			(at 0 0 270)
			(layer "F.Fab")
			(effects
				(font
					(size 1.27 1.27)
				)
			)
		)
		(duplicate_pad_numbers_are_jumpers no)
		(fp_line
			(start -0.7874 0.4064)
			(end -0.7874 -0.4064)
			(stroke
				(width 0.1524)
				(type default)
			)
			(layer "F.SilkS")
		)
		(fp_line
			(start 0.7874 0.4064)
			(end -0.7874 0.4064)
			(stroke
				(width 0.1524)
				(type default)
			)
			(layer "F.SilkS")
		)
		(fp_line
			(start -0.7874 -0.4064)
			(end 0.7874 -0.4064)
			(stroke
				(width 0.1524)
				(type default)
			)
			(layer "F.SilkS")
		)
		(fp_line
			(start 0.7874 -0.4064)
			(end 0.7874 0.4064)
			(stroke
				(width 0.1524)
				(type default)
			)
			(layer "F.SilkS")
		)
		(fp_poly
			(pts
				(xy -0.508 0.2794) (xy -0.508 0.2286) (xy -0.635 0.2286) (xy -0.635 -0.254) (xy -0.5334 -0.254)
				(xy -0.5334 -0.2794) (xy 0.5334 -0.2794) (xy 0.5334 -0.254) (xy 0.635 -0.254) (xy 0.635 0.254) (xy 0.5334 0.254)
				(xy 0.5334 0.2794)
			)
			(stroke
				(width 0)
				(type default)
			)
			(fill no)
			(layer "F.CrtYd")
		)
		(pad "1" smd rect
			(at 0.40005 0 270)
			(size 0.4572 0.508)
			(layers "F.Cu" "F.Mask" "F.Paste")
			(net "UART_T2_NODE1_TXD")
		)
		(pad "2" smd rect
			(at -0.40005 0 270)
			(size 0.4572 0.508)
			(layers "F.Cu" "F.Mask" "F.Paste")
			(net "UART_T2_NODE1_TXD_R")
		)
	)
	(footprint ""
		(layer "F.Cu")
		(at 171.151042 -136.335008 180)
		(property "Reference" "R1053"
			(at 2.942082 9.40308 0)
			(unlocked yes)
			(layer "F.SilkS")
			(effects
				(font
					(size 0.7874 0.5842)
					(thickness 0.1524)
				)
				(justify left)
			)
		)
		(property "Value" ""
			(at 0 0 180)
			(layer "F.Fab")
			(effects
				(font
					(size 1.27 1.27)
				)
			)
		)
		(duplicate_pad_numbers_are_jumpers no)
		(fp_line
			(start 0.7874 0.4064)
			(end -0.7874 0.4064)
			(stroke
				(width 0.1524)
				(type default)
			)
			(layer "F.SilkS")
		)
		(fp_line
			(start 0.7874 -0.4064)
			(end 0.7874 0.4064)
			(stroke
				(width 0.1524)
				(type default)
			)
			(layer "F.SilkS")
		)
		(fp_line
			(start -0.7874 0.4064)
			(end -0.7874 -0.4064)
			(stroke
				(width 0.1524)
				(type default)
			)
			(layer "F.SilkS")
		)
		(fp_line
			(start -0.7874 -0.4064)
			(end 0.7874 -0.4064)
			(stroke
				(width 0.1524)
				(type default)
			)
			(layer "F.SilkS")
		)
		(fp_poly
			(pts
				(xy -0.508 0.2794) (xy -0.508 0.2286) (xy -0.635 0.2286) (xy -0.635 -0.254) (xy -0.5334 -0.254)
				(xy -0.5334 -0.2794) (xy 0.5334 -0.2794) (xy 0.5334 -0.254) (xy 0.635 -0.254) (xy 0.635 0.254) (xy 0.5334 0.254)
				(xy 0.5334 0.2794)
			)
			(stroke
				(width 0)
				(type default)
			)
			(fill no)
			(layer "F.CrtYd")
		)
		(pad "1" smd rect
			(at 0.40005 0 180)
			(size 0.4572 0.508)
			(layers "F.Cu" "F.Mask" "F.Paste")
			(net "PWR_BTN_NODE1_L")
		)
		(pad "2" smd rect
			(at -0.40005 0 180)
			(size 0.4572 0.508)
			(layers "F.Cu" "F.Mask" "F.Paste")
			(net "P3V3_STB_NODE1")
		)
	)
	(footprint ""
		(layer "F.Cu")
		(at 94.060772 -94.109032)
		(property "Reference" "R178"
			(at -0.432816 1.176782 0)
			(unlocked yes)
			(layer "F.SilkS")
			(effects
				(font
					(size 0.7874 0.5842)
					(thickness 0.1524)
				)
				(justify left)
			)
		)
		(property "Value" ""
			(at 0 0 0)
			(layer "F.Fab")
			(effects
				(font
					(size 1.27 1.27)
				)
			)
		)
		(duplicate_pad_numbers_are_jumpers no)
		(fp_line
			(start -0.7874 -0.4064)
			(end 0.7874 -0.4064)
			(stroke
				(width 0.1524)
				(type default)
			)
			(layer "F.SilkS")
		)
		(fp_line
			(start -0.7874 0.4064)
			(end -0.7874 -0.4064)
			(stroke
				(width 0.1524)
				(type default)
			)
			(layer "F.SilkS")
		)
		(fp_line
			(start 0.7874 -0.4064)
			(end 0.7874 0.4064)
			(stroke
				(width 0.1524)
				(type default)
			)
			(layer "F.SilkS")
		)
		(fp_line
			(start 0.7874 0.4064)
			(end -0.7874 0.4064)
			(stroke
				(width 0.1524)
				(type default)
			)
			(layer "F.SilkS")
		)
		(fp_poly
			(pts
				(xy -0.508 0.2794) (xy -0.508 0.2286) (xy -0.635 0.2286) (xy -0.635 -0.254) (xy -0.5334 -0.254)
				(xy -0.5334 -0.2794) (xy 0.5334 -0.2794) (xy 0.5334 -0.254) (xy 0.635 -0.254) (xy 0.635 0.254) (xy 0.5334 0.254)
				(xy 0.5334 0.2794)
			)
			(stroke
				(width 0)
				(type default)
			)
			(fill no)
			(layer "F.CrtYd")
		)
		(pad "1" smd rect
			(at 0.40005 0)
			(size 0.4572 0.508)
			(layers "F.Cu" "F.Mask" "F.Paste")
			(net "SPI_CPU_NODE1_MISO")
		)
		(pad "2" smd rect
			(at -0.40005 0)
			(size 0.4572 0.508)
			(layers "F.Cu" "F.Mask" "F.Paste")
			(net "SPI_CPU_NODE1_MISO_R")
		)
	)
	(footprint ""
		(layer "F.Cu")
		(at 130.79476 -185.205624 90)
		(property "Reference" "C734"
			(at 4.510786 1.00838 90)
			(unlocked yes)
			(layer "F.SilkS")
			(effects
				(font
					(size 0.7874 0.5842)
					(thickness 0.1524)
				)
				(justify left)
			)
		)
		(property "Value" ""
			(at 0 0 90)
			(layer "F.Fab")
			(effects
				(font
					(size 1.27 1.27)
				)
			)
		)
		(duplicate_pad_numbers_are_jumpers no)
		(fp_line
			(start 0.7874 -0.4064)
			(end 0.7874 0.4064)
			(stroke
				(width 0.1524)
				(type default)
			)
			(layer "F.SilkS")
		)
		(fp_line
			(start -0.7874 -0.4064)
			(end 0.7874 -0.4064)
			(stroke
				(width 0.1524)
				(type default)
			)
			(layer "F.SilkS")
		)
		(fp_line
			(start 0 0.381)
			(end 0 -0.381)
			(stroke
				(width 0.1524)
				(type default)
			)
			(layer "F.SilkS")
		)
		(fp_line
			(start 0.7874 0.4064)
			(end -0.7874 0.4064)
			(stroke
				(width 0.1524)
				(type default)
			)
			(layer "F.SilkS")
		)
		(fp_line
			(start -0.7874 0.4064)
			(end -0.7874 -0.4064)
			(stroke
				(width 0.1524)
				(type default)
			)
			(layer "F.SilkS")
		)
		(fp_poly
			(pts
				(xy -0.5334 0.254) (xy -0.635 0.254) (xy -0.635 0.2286) (xy -0.635 -0.254) (xy -0.5334 -0.254) (xy -0.5334 -0.2794)
				(xy 0.5334 -0.2794) (xy 0.5334 -0.254) (xy 0.635 -0.254) (xy 0.635 0.254) (xy 0.5334 0.254) (xy 0.5334 0.2794)
				(xy -0.508 0.2794) (xy -0.5334 0.2794)
			)
			(stroke
				(width 0)
				(type default)
			)
			(fill no)
			(layer "F.CrtYd")
		)
		(pad "1" smd rect
			(at 0.40005 0 90)
			(size 0.4572 0.508)
			(layers "F.Cu" "F.Mask" "F.Paste")
			(net "UART_T9_NODE3_TXD_R")
		)
		(pad "2" smd rect
			(at -0.40005 0 90)
			(size 0.4572 0.508)
			(layers "F.Cu" "F.Mask" "F.Paste")
			(net "GND")
		)
	)
	(footprint ""
		(layer "F.Cu")
		(at 62.267338 -6.726682)
		(property "Reference" "PC79"
			(at -1.87706 5.312156 0)
			(unlocked yes)
			(layer "F.SilkS")
			(effects
				(font
					(size 0.7874 0.5842)
					(thickness 0.1524)
				)
				(justify left)
			)
		)
		(property "Value" ""
			(at 0 0 0)
			(layer "F.Fab")
			(effects
				(font
					(size 1.27 1.27)
				)
			)
		)
		(duplicate_pad_numbers_are_jumpers no)
		(fp_line
			(start -2.249932 -4.533392)
			(end 2.249932 -4.533392)
			(stroke
				(width 0.1524)
				(type default)
			)
			(layer "F.SilkS")
		)
		(fp_line
			(start -2.249932 4.533392)
			(end -2.249932 -4.533392)
			(stroke
				(width 0.1524)
				(type default)
			)
			(layer "F.SilkS")
		)
		(fp_line
			(start 2.249932 -4.533392)
			(end 2.249932 4.533392)
			(stroke
				(width 0.1524)
				(type default)
			)
			(layer "F.SilkS")
		)
		(fp_line
			(start 2.249932 4.533392)
			(end -2.249932 4.533392)
			(stroke
				(width 0.1524)
				(type default)
			)
			(layer "F.SilkS")
		)
		(fp_poly
			(pts
				(xy 2.326132 -4.533392) (xy 2.326132 -5.39242) (xy -2.326132 -5.39242) (xy -2.326132 -4.533392)
			)
			(stroke
				(width 0)
				(type default)
			)
			(fill yes)
			(layer "F.SilkS")
		)
		(fp_poly
			(pts
				(xy -1.4605 4.457192) (xy -1.4605 3.750056) (xy -2.249932 3.750056) (xy -2.249932 -3.750056) (xy -1.4605 -3.750056)
				(xy -1.4605 -4.457192) (xy 1.4605 -4.457192) (xy 1.4605 -3.750056) (xy 2.249932 -3.750056) (xy 2.249932 3.750056)
				(xy 1.4605 3.750056) (xy 1.4605 4.457192)
			)
			(stroke
				(width 0)
				(type default)
			)
			(fill no)
			(layer "F.CrtYd")
		)
		(fp_line
			(start -2.249932 -3.750056)
			(end 2.249932 -3.750056)
			(stroke
				(width 0.1)
				(type default)
			)
			(layer "F.Fab")
		)
		(fp_line
			(start -2.249932 3.750056)
			(end -2.249932 -3.750056)
			(stroke
				(width 0.1)
				(type default)
			)
			(layer "F.Fab")
		)
		(fp_line
			(start 2.249932 -3.750056)
			(end 2.249932 3.750056)
			(stroke
				(width 0.1)
				(type default)
			)
			(layer "F.Fab")
		)
		(fp_line
			(start 2.249932 3.750056)
			(end -2.249932 3.750056)
			(stroke
				(width 0.1)
				(type default)
			)
			(layer "F.Fab")
		)
		(fp_text user "+"
			(at 1.884426 -5.438902 90)
			(unlocked yes)
			(layer "F.SilkS")
			(effects
				(font
					(size 1.6002 1.1938)
					(thickness 0.1524)
				)
				(justify left)
			)
		)
		(fp_text user "+"
			(at -0.786384 -6.322314 0)
			(unlocked yes)
			(layer "F.Fab")
			(effects
				(font
					(size 1.905 1.4224)
					(thickness 0.000001)
				)
				(justify left)
			)
		)
		(pad "1" smd rect
			(at 0 -3.199892 270)
			(size 2.413 2.8194)
			(layers "F.Cu" "F.Mask" "F.Paste")
			(net "PV_VDDR_NODE1")
		)
		(pad "2" smd rect
			(at 0 3.199892 270)
			(size 2.413 2.8194)
			(layers "F.Cu" "F.Mask" "F.Paste")
			(net "GND")
		)
	)
	(footprint ""
		(layer "F.Cu")
		(at 155.987242 -136.718802 -90)
		(property "Reference" "U58"
			(at -2.787904 2.153158 0)
			(unlocked yes)
			(layer "F.SilkS")
			(effects
				(font
					(size 0.7874 0.5842)
					(thickness 0.1524)
				)
				(justify left)
			)
		)
		(property "Value" ""
			(at 0 0 270)
			(layer "F.Fab")
			(effects
				(font
					(size 1.27 1.27)
				)
			)
		)
		(duplicate_pad_numbers_are_jumpers no)
		(fp_line
			(start -1.549908 2.032)
			(end -1.549908 -2.032)
			(stroke
				(width 0.1524)
				(type default)
			)
			(layer "F.SilkS")
		)
		(fp_line
			(start 1.549908 2.032)
			(end -1.549908 2.032)
			(stroke
				(width 0.1524)
				(type default)
			)
			(layer "F.SilkS")
		)
		(fp_line
			(start -1.549908 -2.032)
			(end 1.549908 -2.032)
			(stroke
				(width 0.1524)
				(type default)
			)
			(layer "F.SilkS")
		)
		(fp_line
			(start 1.549908 -2.032)
			(end 1.549908 2.032)
			(stroke
				(width 0.1524)
				(type default)
			)
			(layer "F.SilkS")
		)
		(fp_poly
			(pts
				(xy -2.47142 1.319276) (xy -2.47142 1.827276) (xy -1.70942 1.573276)
			)
			(stroke
				(width 0)
				(type default)
			)
			(fill yes)
			(layer "F.SilkS")
		)
		(fp_poly
			(pts
				(xy -1.549908 0.849884) (xy -1.2319 0.849884) (xy -1.2319 1.9431) (xy -1.1811 1.9431) (xy 1.1811 1.9431)
				(xy 1.2319 1.9431) (xy 1.2319 0.849884) (xy 1.549908 0.849884) (xy 1.549908 -0.849884) (xy 1.2319 -0.849884)
				(xy 1.2319 -1.9431) (xy 1.1811 -1.9431) (xy -1.1811 -1.9431) (xy -1.2319 -1.9431) (xy -1.2319 -0.849884)
				(xy -1.549908 -0.849884)
			)
			(stroke
				(width 0)
				(type default)
			)
			(fill no)
			(layer "F.CrtYd")
		)
		(fp_line
			(start -1.549908 0.849884)
			(end 1.549908 0.849884)
			(stroke
				(width 0.1)
				(type default)
			)
			(layer "F.Fab")
		)
		(fp_line
			(start 1.549908 0.849884)
			(end 1.549908 -0.849884)
			(stroke
				(width 0.1)
				(type default)
			)
			(layer "F.Fab")
		)
		(fp_line
			(start -1.549908 -0.849884)
			(end -1.549908 0.849884)
			(stroke
				(width 0.1)
				(type default)
			)
			(layer "F.Fab")
		)
		(fp_line
			(start 1.549908 -0.849884)
			(end -1.549908 -0.849884)
			(stroke
				(width 0.1)
				(type default)
			)
			(layer "F.Fab")
		)
		(fp_text user "3"
			(at 2.156714 2.46761 0)
			(unlocked yes)
			(layer "F.SilkS")
			(effects
				(font
					(size 0.635 0.4064)
					(thickness 0.1524)
				)
				(justify left)
			)
		)
		(fp_text user "1"
			(at -2.05867 2.27584 0)
			(unlocked yes)
			(layer "F.SilkS")
			(effects
				(font
					(size 0.635 0.4064)
					(thickness 0.1524)
				)
				(justify left)
			)
		)
		(fp_text user "4"
			(at 0.36322 -2.219198 0)
			(unlocked yes)
			(layer "F.SilkS")
			(effects
				(font
					(size 0.635 0.4064)
					(thickness 0.1524)
				)
				(justify left)
			)
		)
		(fp_text user "5"
			(at -1.195832 -2.232914 0)
			(unlocked yes)
			(layer "F.SilkS")
			(effects
				(font
					(size 0.635 0.4064)
					(thickness 0.1524)
				)
				(justify left)
			)
		)
		(pad "1" smd rect
			(at -0.94996 1.225042 270)
			(size 0.4572 1.3208)
			(layers "F.Cu" "F.Mask" "F.Paste")
			(net "Net_1704")
		)
		(pad "2" smd rect
			(at 0 1.225042 270)
			(size 0.4572 1.3208)
			(layers "F.Cu" "F.Mask" "F.Paste")
			(net "RST_BTN_NODE1_C_L")
		)
		(pad "3" smd rect
			(at 0.94996 1.225042 270)
			(size 0.4572 1.3208)
			(layers "F.Cu" "F.Mask" "F.Paste")
			(net "GND")
		)
		(pad "4" smd rect
			(at 0.94996 -1.225042 270)
			(size 0.4572 1.3208)
			(layers "F.Cu" "F.Mask" "F.Paste")
			(net "RST_BTN_NODE1_L")
		)
		(pad "5" smd rect
			(at -0.94996 -1.225042 270)
			(size 0.4572 1.3208)
			(layers "F.Cu" "F.Mask" "F.Paste")
			(net "P3V3_STB_NODE1")
		)
	)
	(footprint ""
		(layer "F.Cu")
		(at 123.70816 -169.571416)
		(property "Reference" "R672"
			(at 30.127448 47.889922 0)
			(unlocked yes)
			(layer "F.SilkS")
			(effects
				(font
					(size 0.7874 0.5842)
					(thickness 0.1524)
				)
				(justify left)
			)
		)
		(property "Value" ""
			(at 0 0 0)
			(layer "F.Fab")
			(effects
				(font
					(size 1.27 1.27)
				)
			)
		)
		(duplicate_pad_numbers_are_jumpers no)
		(fp_line
			(start -0.7874 -0.4064)
			(end 0.7874 -0.4064)
			(stroke
				(width 0.1524)
				(type default)
			)
			(layer "F.SilkS")
		)
		(fp_line
			(start -0.7874 0.4064)
			(end -0.7874 -0.4064)
			(stroke
				(width 0.1524)
				(type default)
			)
			(layer "F.SilkS")
		)
		(fp_line
			(start 0.7874 -0.4064)
			(end 0.7874 0.4064)
			(stroke
				(width 0.1524)
				(type default)
			)
			(layer "F.SilkS")
		)
		(fp_line
			(start 0.7874 0.4064)
			(end -0.7874 0.4064)
			(stroke
				(width 0.1524)
				(type default)
			)
			(layer "F.SilkS")
		)
		(fp_poly
			(pts
				(xy -0.508 0.2794) (xy -0.508 0.2286) (xy -0.635 0.2286) (xy -0.635 -0.254) (xy -0.5334 -0.254)
				(xy -0.5334 -0.2794) (xy 0.5334 -0.2794) (xy 0.5334 -0.254) (xy 0.635 -0.254) (xy 0.635 0.254) (xy 0.5334 0.254)
				(xy 0.5334 0.2794)
			)
			(stroke
				(width 0)
				(type default)
			)
			(fill no)
			(layer "F.CrtYd")
		)
		(pad "1" smd rect
			(at 0.40005 0)
			(size 0.4572 0.508)
			(layers "F.Cu" "F.Mask" "F.Paste")
			(net "P3V3_NODE1")
		)
		(pad "2" smd rect
			(at -0.40005 0)
			(size 0.4572 0.508)
			(layers "F.Cu" "F.Mask" "F.Paste")
			(net "PU_I2C_SCL4")
		)
	)
	(footprint ""
		(layer "F.Cu")
		(at 125.735588 -182.519828 180)
		(property "Reference" "R720"
			(at -1.568704 -3.327908 0)
			(unlocked yes)
			(layer "F.SilkS")
			(effects
				(font
					(size 0.7874 0.5842)
					(thickness 0.1524)
				)
				(justify left)
			)
		)
		(property "Value" ""
			(at 0 0 180)
			(layer "F.Fab")
			(effects
				(font
					(size 1.27 1.27)
				)
			)
		)
		(duplicate_pad_numbers_are_jumpers no)
		(fp_line
			(start 0.7874 0.4064)
			(end -0.7874 0.4064)
			(stroke
				(width 0.1524)
				(type default)
			)
			(layer "F.SilkS")
		)
		(fp_line
			(start 0.7874 -0.4064)
			(end 0.7874 0.4064)
			(stroke
				(width 0.1524)
				(type default)
			)
			(layer "F.SilkS")
		)
		(fp_line
			(start -0.7874 0.4064)
			(end -0.7874 -0.4064)
			(stroke
				(width 0.1524)
				(type default)
			)
			(layer "F.SilkS")
		)
		(fp_line
			(start -0.7874 -0.4064)
			(end 0.7874 -0.4064)
			(stroke
				(width 0.1524)
				(type default)
			)
			(layer "F.SilkS")
		)
		(fp_poly
			(pts
				(xy -0.508 0.2794) (xy -0.508 0.2286) (xy -0.635 0.2286) (xy -0.635 -0.254) (xy -0.5334 -0.254)
				(xy -0.5334 -0.2794) (xy 0.5334 -0.2794) (xy 0.5334 -0.254) (xy 0.635 -0.254) (xy 0.635 0.254) (xy 0.5334 0.254)
				(xy 0.5334 0.2794)
			)
			(stroke
				(width 0)
				(type default)
			)
			(fill no)
			(layer "F.CrtYd")
		)
		(pad "1" smd rect
			(at 0.40005 0 180)
			(size 0.4572 0.508)
			(layers "F.Cu" "F.Mask" "F.Paste")
			(net "T7_NODE1_EN")
		)
		(pad "2" smd rect
			(at -0.40005 0 180)
			(size 0.4572 0.508)
			(layers "F.Cu" "F.Mask" "F.Paste")
			(net "P5V_NODE1")
		)
	)
	(footprint ""
		(layer "F.Cu")
		(at 75.766168 -183.15432)
		(property "Reference" "R1076"
			(at -4.691634 -0.262382 0)
			(unlocked yes)
			(layer "F.SilkS")
			(effects
				(font
					(size 0.7874 0.5842)
					(thickness 0.1524)
				)
				(justify left)
			)
		)
		(property "Value" ""
			(at 0 0 0)
			(layer "F.Fab")
			(effects
				(font
					(size 1.27 1.27)
				)
			)
		)
		(duplicate_pad_numbers_are_jumpers no)
		(fp_line
			(start -0.7874 -0.4064)
			(end 0.7874 -0.4064)
			(stroke
				(width 0.1524)
				(type default)
			)
			(layer "F.SilkS")
		)
		(fp_line
			(start -0.7874 0.4064)
			(end -0.7874 -0.4064)
			(stroke
				(width 0.1524)
				(type default)
			)
			(layer "F.SilkS")
		)
		(fp_line
			(start 0.7874 -0.4064)
			(end 0.7874 0.4064)
			(stroke
				(width 0.1524)
				(type default)
			)
			(layer "F.SilkS")
		)
		(fp_line
			(start 0.7874 0.4064)
			(end -0.7874 0.4064)
			(stroke
				(width 0.1524)
				(type default)
			)
			(layer "F.SilkS")
		)
		(fp_poly
			(pts
				(xy -0.508 0.2794) (xy -0.508 0.2286) (xy -0.635 0.2286) (xy -0.635 -0.254) (xy -0.5334 -0.254)
				(xy -0.5334 -0.2794) (xy 0.5334 -0.2794) (xy 0.5334 -0.254) (xy 0.635 -0.254) (xy 0.635 0.254) (xy 0.5334 0.254)
				(xy 0.5334 0.2794)
			)
			(stroke
				(width 0)
				(type default)
			)
			(fill no)
			(layer "F.CrtYd")
		)
		(pad "1" smd rect
			(at 0.40005 0)
			(size 0.4572 0.508)
			(layers "F.Cu" "F.Mask" "F.Paste")
			(net "P3V3_NODE1")
		)
		(pad "2" smd rect
			(at -0.40005 0)
			(size 0.4572 0.508)
			(layers "F.Cu" "F.Mask" "F.Paste")
			(net "JTAG_CPLD2_TDI")
		)
	)
	(footprint ""
		(layer "F.Cu")
		(at 43.41622 -145.83029 -90)
		(property "Reference" "R556"
			(at 0.886968 6.618732 90)
			(unlocked yes)
			(layer "F.SilkS")
			(effects
				(font
					(size 0.7874 0.5842)
					(thickness 0.1524)
				)
				(justify left)
			)
		)
		(property "Value" ""
			(at 0 0 270)
			(layer "F.Fab")
			(effects
				(font
					(size 1.27 1.27)
				)
			)
		)
		(duplicate_pad_numbers_are_jumpers no)
		(fp_line
			(start -0.7874 0.4064)
			(end -0.7874 -0.4064)
			(stroke
				(width 0.1524)
				(type default)
			)
			(layer "F.SilkS")
		)
		(fp_line
			(start 0.7874 0.4064)
			(end -0.7874 0.4064)
			(stroke
				(width 0.1524)
				(type default)
			)
			(layer "F.SilkS")
		)
		(fp_line
			(start -0.7874 -0.4064)
			(end 0.7874 -0.4064)
			(stroke
				(width 0.1524)
				(type default)
			)
			(layer "F.SilkS")
		)
		(fp_line
			(start 0.7874 -0.4064)
			(end 0.7874 0.4064)
			(stroke
				(width 0.1524)
				(type default)
			)
			(layer "F.SilkS")
		)
		(fp_poly
			(pts
				(xy -0.508 0.2794) (xy -0.508 0.2286) (xy -0.635 0.2286) (xy -0.635 -0.254) (xy -0.5334 -0.254)
				(xy -0.5334 -0.2794) (xy 0.5334 -0.2794) (xy 0.5334 -0.254) (xy 0.635 -0.254) (xy 0.635 0.254) (xy 0.5334 0.254)
				(xy 0.5334 0.2794)
			)
			(stroke
				(width 0)
				(type default)
			)
			(fill no)
			(layer "F.CrtYd")
		)
		(pad "1" smd rect
			(at 0.40005 0 270)
			(size 0.4572 0.508)
			(layers "F.Cu" "F.Mask" "F.Paste")
			(net "GND")
		)
		(pad "2" smd rect
			(at -0.40005 0 270)
			(size 0.4572 0.508)
			(layers "F.Cu" "F.Mask" "F.Paste")
			(net "LAN1_NC_SI_TX_EN")
		)
	)
	(footprint ""
		(layer "F.Cu")
		(at 182.234586 -143.06042)
		(property "Reference" "C448"
			(at 0.304292 1.81102 0)
			(unlocked yes)
			(layer "F.SilkS")
			(effects
				(font
					(size 0.7874 0.5842)
					(thickness 0.1524)
				)
			)
		)
		(property "Value" ""
			(at 0 0 0)
			(layer "F.Fab")
			(effects
				(font
					(size 1.27 1.27)
				)
			)
		)
		(duplicate_pad_numbers_are_jumpers no)
		(fp_line
			(start -1.2954 -0.5842)
			(end 1.2954 -0.5842)
			(stroke
				(width 0.1524)
				(type default)
			)
			(layer "F.SilkS")
		)
		(fp_line
			(start -1.2954 0.5842)
			(end -1.2954 -0.5842)
			(stroke
				(width 0.1524)
				(type default)
			)
			(layer "F.SilkS")
		)
		(fp_line
			(start 0 -0.5842)
			(end 0 0.5842)
			(stroke
				(width 0.1524)
				(type default)
			)
			(layer "F.SilkS")
		)
		(fp_line
			(start 1.2954 -0.5842)
			(end 1.2954 0.5842)
			(stroke
				(width 0.1524)
				(type default)
			)
			(layer "F.SilkS")
		)
		(fp_line
			(start 1.2954 0.5842)
			(end -1.2954 0.5842)
			(stroke
				(width 0.1524)
				(type default)
			)
			(layer "F.SilkS")
		)
		(fp_poly
			(pts
				(xy 0.8636 -0.4572) (xy 0.8636 -0.3556) (xy 1.143 -0.3556) (xy 1.143 0.3556) (xy 0.8636 0.3556)
				(xy 0.8636 0.4572) (xy -0.8636 0.4572) (xy -0.8636 0.3556) (xy -1.143 0.3556) (xy -1.143 -0.3556)
				(xy -0.8636 -0.3556) (xy -0.8636 -0.4572)
			)
			(stroke
				(width 0)
				(type default)
			)
			(fill no)
			(layer "F.CrtYd")
		)
		(fp_line
			(start -0.884936 -0.504952)
			(end 0.884936 -0.504952)
			(stroke
				(width 0.1)
				(type default)
			)
			(layer "F.Fab")
		)
		(fp_line
			(start -0.884936 0.504952)
			(end -0.884936 -0.504952)
			(stroke
				(width 0.1)
				(type default)
			)
			(layer "F.Fab")
		)
		(fp_line
			(start 0.884936 -0.504952)
			(end 0.884936 0.504952)
			(stroke
				(width 0.1)
				(type default)
			)
			(layer "F.Fab")
		)
		(fp_line
			(start 0.884936 0.504952)
			(end -0.884936 0.504952)
			(stroke
				(width 0.1)
				(type default)
			)
			(layer "F.Fab")
		)
		(pad "1" smd rect
			(at 0.7366 0 90)
			(size 0.7112 0.8128)
			(layers "F.Cu" "F.Mask" "F.Paste")
			(net "P3V3_NODE1")
		)
		(pad "2" smd rect
			(at -0.7366 0 90)
			(size 0.7112 0.8128)
			(layers "F.Cu" "F.Mask" "F.Paste")
			(net "GND")
		)
	)
	(footprint ""
		(layer "F.Cu")
		(at 125.94336 -188.126624 90)
		(property "Reference" "C623"
			(at 4.949444 -0.396748 90)
			(unlocked yes)
			(layer "F.SilkS")
			(effects
				(font
					(size 0.7874 0.5842)
					(thickness 0.1524)
				)
				(justify left)
			)
		)
		(property "Value" ""
			(at 0 0 90)
			(layer "F.Fab")
			(effects
				(font
					(size 1.27 1.27)
				)
			)
		)
		(duplicate_pad_numbers_are_jumpers no)
		(fp_line
			(start 0.7874 -0.4064)
			(end 0.7874 0.4064)
			(stroke
				(width 0.1524)
				(type default)
			)
			(layer "F.SilkS")
		)
		(fp_line
			(start -0.7874 -0.4064)
			(end 0.7874 -0.4064)
			(stroke
				(width 0.1524)
				(type default)
			)
			(layer "F.SilkS")
		)
		(fp_line
			(start 0 0.381)
			(end 0 -0.381)
			(stroke
				(width 0.1524)
				(type default)
			)
			(layer "F.SilkS")
		)
		(fp_line
			(start 0.7874 0.4064)
			(end -0.7874 0.4064)
			(stroke
				(width 0.1524)
				(type default)
			)
			(layer "F.SilkS")
		)
		(fp_line
			(start -0.7874 0.4064)
			(end -0.7874 -0.4064)
			(stroke
				(width 0.1524)
				(type default)
			)
			(layer "F.SilkS")
		)
		(fp_poly
			(pts
				(xy -0.5334 0.254) (xy -0.635 0.254) (xy -0.635 0.2286) (xy -0.635 -0.254) (xy -0.5334 -0.254) (xy -0.5334 -0.2794)
				(xy 0.5334 -0.2794) (xy 0.5334 -0.254) (xy 0.635 -0.254) (xy 0.635 0.254) (xy 0.5334 0.254) (xy 0.5334 0.2794)
				(xy -0.508 0.2794) (xy -0.5334 0.2794)
			)
			(stroke
				(width 0)
				(type default)
			)
			(fill no)
			(layer "F.CrtYd")
		)
		(pad "1" smd rect
			(at 0.40005 0 90)
			(size 0.4572 0.508)
			(layers "F.Cu" "F.Mask" "F.Paste")
			(net "T8_NODE1_EN_R")
		)
		(pad "2" smd rect
			(at -0.40005 0 90)
			(size 0.4572 0.508)
			(layers "F.Cu" "F.Mask" "F.Paste")
			(net "GND")
		)
	)
	(footprint ""
		(layer "F.Cu")
		(at 140.90396 -121.324624 90)
		(property "Reference" "L1"
			(at 2.205482 -0.094742 90)
			(unlocked yes)
			(layer "F.SilkS")
			(effects
				(font
					(size 0.7874 0.5842)
					(thickness 0.1524)
				)
				(justify left)
			)
		)
		(property "Value" ""
			(at 0 0 90)
			(layer "F.Fab")
			(effects
				(font
					(size 1.27 1.27)
				)
			)
		)
		(duplicate_pad_numbers_are_jumpers no)
		(fp_line
			(start -1.905 -0.8636)
			(end 1.905 -0.8636)
			(stroke
				(width 0.1524)
				(type default)
			)
			(layer "F.SilkS")
		)
		(fp_line
			(start 1.905 0.8382)
			(end 1.905 -0.8382)
			(stroke
				(width 0.1524)
				(type default)
			)
			(layer "F.SilkS")
		)
		(fp_line
			(start 0.127 0.8382)
			(end 0.127 -0.8382)
			(stroke
				(width 0.1524)
				(type default)
			)
			(layer "F.SilkS")
		)
		(fp_line
			(start -0.127 0.8382)
			(end -0.127 -0.8382)
			(stroke
				(width 0.1524)
				(type default)
			)
			(layer "F.SilkS")
		)
		(fp_line
			(start -1.905 0.8382)
			(end -1.905 -0.8382)
			(stroke
				(width 0.1524)
				(type default)
			)
			(layer "F.SilkS")
		)
		(fp_line
			(start 1.905 0.8636)
			(end -1.905 0.8636)
			(stroke
				(width 0.1524)
				(type default)
			)
			(layer "F.SilkS")
		)
		(fp_rect
			(start -1.524 0.7112)
			(end 1.524 -0.7366)
			(stroke
				(width 0)
				(type default)
			)
			(fill no)
			(layer "F.CrtYd")
		)
		(pad "1" smd rect
			(at 0.94996 0 90)
			(size 1.1176 1.3716)
			(layers "F.Cu" "F.Mask" "F.Paste")
			(net "P1V5_CLK_NODE1_R")
		)
		(pad "2" smd rect
			(at -0.94996 0 90)
			(size 1.1176 1.3716)
			(layers "F.Cu" "F.Mask" "F.Paste")
			(net "P1V5_CLK_NODE1")
		)
	)
	(footprint ""
		(layer "F.Cu")
		(at 112.73663 -129.84734 90)
		(property "Reference" "PR43"
			(at -2.08026 1.034796 90)
			(unlocked yes)
			(layer "F.SilkS")
			(effects
				(font
					(size 0.7874 0.5842)
					(thickness 0.1524)
				)
				(justify left)
			)
		)
		(property "Value" ""
			(at 0 0 90)
			(layer "F.Fab")
			(effects
				(font
					(size 1.27 1.27)
				)
			)
		)
		(duplicate_pad_numbers_are_jumpers no)
		(fp_line
			(start 0.7874 -0.4064)
			(end 0.7874 0.4064)
			(stroke
				(width 0.1524)
				(type default)
			)
			(layer "F.SilkS")
		)
		(fp_line
			(start -0.7874 -0.4064)
			(end 0.7874 -0.4064)
			(stroke
				(width 0.1524)
				(type default)
			)
			(layer "F.SilkS")
		)
		(fp_line
			(start 0.7874 0.4064)
			(end -0.7874 0.4064)
			(stroke
				(width 0.1524)
				(type default)
			)
			(layer "F.SilkS")
		)
		(fp_line
			(start -0.7874 0.4064)
			(end -0.7874 -0.4064)
			(stroke
				(width 0.1524)
				(type default)
			)
			(layer "F.SilkS")
		)
		(fp_poly
			(pts
				(xy -0.508 0.2794) (xy -0.508 0.2286) (xy -0.635 0.2286) (xy -0.635 -0.254) (xy -0.5334 -0.254)
				(xy -0.5334 -0.2794) (xy 0.5334 -0.2794) (xy 0.5334 -0.254) (xy 0.635 -0.254) (xy 0.635 0.254) (xy 0.5334 0.254)
				(xy 0.5334 0.2794)
			)
			(stroke
				(width 0)
				(type default)
			)
			(fill no)
			(layer "F.CrtYd")
		)
		(pad "1" smd rect
			(at 0.40005 0 90)
			(size 0.4572 0.508)
			(layers "F.Cu" "F.Mask" "F.Paste")
			(net "VR_PVCCP_NODE1_TONSET_R")
		)
		(pad "2" smd rect
			(at -0.40005 0 90)
			(size 0.4572 0.508)
			(layers "F.Cu" "F.Mask" "F.Paste")
			(net "SW_VR_PVCCP_NODE1_VIN_FLT")
		)
	)
	(footprint ""
		(layer "F.Cu")
		(at 80.845152 -133.211062 -90)
		(property "Reference" "D31"
			(at 5.319268 1.866646 90)
			(unlocked yes)
			(layer "F.SilkS")
			(effects
				(font
					(size 0.7874 0.5842)
					(thickness 0.1524)
				)
				(justify left)
			)
		)
		(property "Value" ""
			(at 0 0 270)
			(layer "F.Fab")
			(effects
				(font
					(size 1.27 1.27)
				)
			)
		)
		(duplicate_pad_numbers_are_jumpers no)
		(fp_line
			(start -1.3208 0.5588)
			(end -1.3208 -0.5588)
			(stroke
				(width 0.1524)
				(type default)
			)
			(layer "F.SilkS")
		)
		(fp_line
			(start 1.3208 0.5588)
			(end -1.3208 0.5588)
			(stroke
				(width 0.1524)
				(type default)
			)
			(layer "F.SilkS")
		)
		(fp_line
			(start 1.6256 0.5588)
			(end 1.6256 -0.5588)
			(stroke
				(width 0.1524)
				(type default)
			)
			(layer "F.SilkS")
		)
		(fp_line
			(start 1.778 0.5588)
			(end 1.3208 0.5588)
			(stroke
				(width 0.1524)
				(type default)
			)
			(layer "F.SilkS")
		)
		(fp_line
			(start -1.3208 -0.5588)
			(end 1.3208 -0.5588)
			(stroke
				(width 0.1524)
				(type default)
			)
			(layer "F.SilkS")
		)
		(fp_line
			(start 1.3208 -0.5588)
			(end 1.3208 0.5588)
			(stroke
				(width 0.1524)
				(type default)
			)
			(layer "F.SilkS")
		)
		(fp_line
			(start 1.4732 -0.5588)
			(end 1.4732 0.5588)
			(stroke
				(width 0.1524)
				(type default)
			)
			(layer "F.SilkS")
		)
		(fp_line
			(start 1.778 -0.5588)
			(end 1.778 0.5588)
			(stroke
				(width 0.1524)
				(type default)
			)
			(layer "F.SilkS")
		)
		(fp_line
			(start 1.778 -0.5588)
			(end 1.3208 -0.5588)
			(stroke
				(width 0.1524)
				(type default)
			)
			(layer "F.SilkS")
		)
		(fp_circle
			(center 2.4384 0)
			(end 2.4384 -0.413512)
			(stroke
				(width 0.1524)
				(type default)
			)
			(fill no)
			(layer "F.SilkS")
		)
		(fp_rect
			(start -1.1684 0.508)
			(end 1.1684 -0.508)
			(stroke
				(width 0)
				(type default)
			)
			(fill no)
			(layer "F.CrtYd")
		)
		(fp_text user "-"
			(at 1.199642 0.946404 270)
			(unlocked yes)
			(layer "F.SilkS")
			(effects
				(font
					(size 0.7874 0.5842)
					(thickness 0.1524)
				)
				(justify left)
			)
		)
		(pad "A" smd rect
			(at -0.750062 0 270)
			(size 0.8128 0.8128)
			(layers "F.Cu" "F.Mask" "F.Paste")
			(net "P3V3_NODE1")
		)
		(pad "C" smd rect
			(at 0.750062 0 270)
			(size 0.8128 0.8128)
			(layers "F.Cu" "F.Mask" "F.Paste")
			(net "N53313646")
		)
	)
	(footprint ""
		(layer "F.Cu")
		(at 118.47576 -188.126624 -90)
		(property "Reference" "R985"
			(at -4.912868 -0.016002 90)
			(unlocked yes)
			(layer "F.SilkS")
			(effects
				(font
					(size 0.7874 0.5842)
					(thickness 0.1524)
				)
				(justify left)
			)
		)
		(property "Value" ""
			(at 0 0 270)
			(layer "F.Fab")
			(effects
				(font
					(size 1.27 1.27)
				)
			)
		)
		(duplicate_pad_numbers_are_jumpers no)
		(fp_line
			(start -0.7874 0.4064)
			(end -0.7874 -0.4064)
			(stroke
				(width 0.1524)
				(type default)
			)
			(layer "F.SilkS")
		)
		(fp_line
			(start 0.7874 0.4064)
			(end -0.7874 0.4064)
			(stroke
				(width 0.1524)
				(type default)
			)
			(layer "F.SilkS")
		)
		(fp_line
			(start -0.7874 -0.4064)
			(end 0.7874 -0.4064)
			(stroke
				(width 0.1524)
				(type default)
			)
			(layer "F.SilkS")
		)
		(fp_line
			(start 0.7874 -0.4064)
			(end 0.7874 0.4064)
			(stroke
				(width 0.1524)
				(type default)
			)
			(layer "F.SilkS")
		)
		(fp_poly
			(pts
				(xy -0.508 0.2794) (xy -0.508 0.2286) (xy -0.635 0.2286) (xy -0.635 -0.254) (xy -0.5334 -0.254)
				(xy -0.5334 -0.2794) (xy 0.5334 -0.2794) (xy 0.5334 -0.254) (xy 0.635 -0.254) (xy 0.635 0.254) (xy 0.5334 0.254)
				(xy 0.5334 0.2794)
			)
			(stroke
				(width 0)
				(type default)
			)
			(fill no)
			(layer "F.CrtYd")
		)
		(pad "1" smd rect
			(at 0.40005 0 270)
			(size 0.4572 0.508)
			(layers "F.Cu" "F.Mask" "F.Paste")
			(net "UART_T8_NODE2_RXD")
		)
		(pad "2" smd rect
			(at -0.40005 0 270)
			(size 0.4572 0.508)
			(layers "F.Cu" "F.Mask" "F.Paste")
			(net "UART_T8_NODE2_RXD_R")
		)
	)
	(footprint ""
		(layer "F.Cu")
		(at 154.252168 -172.67555 -90)
		(property "Reference" "C912"
			(at 3.873754 0.049276 90)
			(unlocked yes)
			(layer "F.SilkS")
			(effects
				(font
					(size 0.7874 0.5842)
					(thickness 0.1524)
				)
				(justify left)
			)
		)
		(property "Value" ""
			(at 0 0 270)
			(layer "F.Fab")
			(effects
				(font
					(size 1.27 1.27)
				)
			)
		)
		(duplicate_pad_numbers_are_jumpers no)
		(fp_line
			(start -0.7874 0.4064)
			(end -0.7874 -0.4064)
			(stroke
				(width 0.1524)
				(type default)
			)
			(layer "F.SilkS")
		)
		(fp_line
			(start 0.7874 0.4064)
			(end -0.7874 0.4064)
			(stroke
				(width 0.1524)
				(type default)
			)
			(layer "F.SilkS")
		)
		(fp_line
			(start 0 0.381)
			(end 0 -0.381)
			(stroke
				(width 0.1524)
				(type default)
			)
			(layer "F.SilkS")
		)
		(fp_line
			(start -0.7874 -0.4064)
			(end 0.7874 -0.4064)
			(stroke
				(width 0.1524)
				(type default)
			)
			(layer "F.SilkS")
		)
		(fp_line
			(start 0.7874 -0.4064)
			(end 0.7874 0.4064)
			(stroke
				(width 0.1524)
				(type default)
			)
			(layer "F.SilkS")
		)
		(fp_poly
			(pts
				(xy -0.5334 0.254) (xy -0.635 0.254) (xy -0.635 0.2286) (xy -0.635 -0.254) (xy -0.5334 -0.254) (xy -0.5334 -0.2794)
				(xy 0.5334 -0.2794) (xy 0.5334 -0.254) (xy 0.635 -0.254) (xy 0.635 0.254) (xy 0.5334 0.254) (xy 0.5334 0.2794)
				(xy -0.508 0.2794) (xy -0.5334 0.2794)
			)
			(stroke
				(width 0)
				(type default)
			)
			(fill no)
			(layer "F.CrtYd")
		)
		(pad "1" smd rect
			(at 0.40005 0 270)
			(size 0.4572 0.508)
			(layers "F.Cu" "F.Mask" "F.Paste")
			(net "N54365601")
		)
		(pad "2" smd rect
			(at -0.40005 0 270)
			(size 0.4572 0.508)
			(layers "F.Cu" "F.Mask" "F.Paste")
			(net "N54365603")
		)
	)
	(footprint ""
		(layer "F.Cu")
		(at 59.260486 -121.044462 -90)
		(property "Reference" "R340"
			(at 4.642612 -8.471916 90)
			(unlocked yes)
			(layer "F.SilkS")
			(effects
				(font
					(size 0.7874 0.5842)
					(thickness 0.1524)
				)
				(justify left)
			)
		)
		(property "Value" ""
			(at 0 0 270)
			(layer "F.Fab")
			(effects
				(font
					(size 1.27 1.27)
				)
			)
		)
		(duplicate_pad_numbers_are_jumpers no)
		(fp_line
			(start -0.7874 0.4064)
			(end -0.7874 -0.4064)
			(stroke
				(width 0.1524)
				(type default)
			)
			(layer "F.SilkS")
		)
		(fp_line
			(start 0.7874 0.4064)
			(end -0.7874 0.4064)
			(stroke
				(width 0.1524)
				(type default)
			)
			(layer "F.SilkS")
		)
		(fp_line
			(start -0.7874 -0.4064)
			(end 0.7874 -0.4064)
			(stroke
				(width 0.1524)
				(type default)
			)
			(layer "F.SilkS")
		)
		(fp_line
			(start 0.7874 -0.4064)
			(end 0.7874 0.4064)
			(stroke
				(width 0.1524)
				(type default)
			)
			(layer "F.SilkS")
		)
		(fp_poly
			(pts
				(xy -0.508 0.2794) (xy -0.508 0.2286) (xy -0.635 0.2286) (xy -0.635 -0.254) (xy -0.5334 -0.254)
				(xy -0.5334 -0.2794) (xy 0.5334 -0.2794) (xy 0.5334 -0.254) (xy 0.635 -0.254) (xy 0.635 0.254) (xy 0.5334 0.254)
				(xy 0.5334 0.2794)
			)
			(stroke
				(width 0)
				(type default)
			)
			(fill no)
			(layer "F.CrtYd")
		)
		(pad "1" smd rect
			(at 0.40005 0 270)
			(size 0.4572 0.508)
			(layers "F.Cu" "F.Mask" "F.Paste")
			(net "P3V3_NODE1")
		)
		(pad "2" smd rect
			(at -0.40005 0 270)
			(size 0.4572 0.508)
			(layers "F.Cu" "F.Mask" "F.Paste")
			(net "BMC_ROMD0")
		)
	)
	(footprint ""
		(layer "F.Cu")
		(at 105.191814 -110.95482 180)
		(property "Reference" "PC107"
			(at 5.79247 -0.103886 0)
			(unlocked yes)
			(layer "F.SilkS")
			(effects
				(font
					(size 0.7874 0.5842)
					(thickness 0.1524)
				)
				(justify left)
			)
		)
		(property "Value" ""
			(at 0 0 180)
			(layer "F.Fab")
			(effects
				(font
					(size 1.27 1.27)
				)
			)
		)
		(duplicate_pad_numbers_are_jumpers no)
		(fp_line
			(start 1.905 0.8636)
			(end -1.905 0.8636)
			(stroke
				(width 0.1524)
				(type default)
			)
			(layer "F.SilkS")
		)
		(fp_line
			(start 1.905 -0.8636)
			(end 1.905 0.8636)
			(stroke
				(width 0.1524)
				(type default)
			)
			(layer "F.SilkS")
		)
		(fp_line
			(start 0 0.8382)
			(end 0 -0.8382)
			(stroke
				(width 0.1524)
				(type default)
			)
			(layer "F.SilkS")
		)
		(fp_line
			(start -1.905 0.8636)
			(end -1.905 -0.8636)
			(stroke
				(width 0.1524)
				(type default)
			)
			(layer "F.SilkS")
		)
		(fp_line
			(start -1.905 -0.8636)
			(end 1.905 -0.8636)
			(stroke
				(width 0.1524)
				(type default)
			)
			(layer "F.SilkS")
		)
		(fp_rect
			(start -1.524 0.7366)
			(end 1.524 -0.7366)
			(stroke
				(width 0)
				(type default)
			)
			(fill no)
			(layer "F.CrtYd")
		)
		(pad "1" smd rect
			(at 0.94996 0 180)
			(size 1.1176 1.3716)
			(layers "F.Cu" "F.Mask" "F.Paste")
			(net "GND")
		)
		(pad "2" smd rect
			(at -0.94996 0 180)
			(size 1.1176 1.3716)
			(layers "F.Cu" "F.Mask" "F.Paste")
			(net "PV_VCCP_NODE1")
		)
	)
	(footprint ""
		(layer "F.Cu")
		(at 139.36218 -76.485496 180)
		(property "Reference" "R506"
			(at -0.939038 1.9685 0)
			(unlocked yes)
			(layer "F.SilkS")
			(effects
				(font
					(size 0.7874 0.5842)
					(thickness 0.1524)
				)
				(justify left)
			)
		)
		(property "Value" ""
			(at 0 0 180)
			(layer "F.Fab")
			(effects
				(font
					(size 1.27 1.27)
				)
			)
		)
		(duplicate_pad_numbers_are_jumpers no)
		(fp_line
			(start 0.7874 0.4064)
			(end -0.7874 0.4064)
			(stroke
				(width 0.1524)
				(type default)
			)
			(layer "F.SilkS")
		)
		(fp_line
			(start 0.7874 -0.4064)
			(end 0.7874 0.4064)
			(stroke
				(width 0.1524)
				(type default)
			)
			(layer "F.SilkS")
		)
		(fp_line
			(start -0.7874 0.4064)
			(end -0.7874 -0.4064)
			(stroke
				(width 0.1524)
				(type default)
			)
			(layer "F.SilkS")
		)
		(fp_line
			(start -0.7874 -0.4064)
			(end 0.7874 -0.4064)
			(stroke
				(width 0.1524)
				(type default)
			)
			(layer "F.SilkS")
		)
		(fp_poly
			(pts
				(xy -0.508 0.2794) (xy -0.508 0.2286) (xy -0.635 0.2286) (xy -0.635 -0.254) (xy -0.5334 -0.254)
				(xy -0.5334 -0.2794) (xy 0.5334 -0.2794) (xy 0.5334 -0.254) (xy 0.635 -0.254) (xy 0.635 0.254) (xy 0.5334 0.254)
				(xy 0.5334 0.2794)
			)
			(stroke
				(width 0)
				(type default)
			)
			(fill no)
			(layer "F.CrtYd")
		)
		(pad "1" smd rect
			(at 0.40005 0 180)
			(size 0.4572 0.508)
			(layers "F.Cu" "F.Mask" "F.Paste")
			(net "SATA_SPI_DO_NODE1")
		)
		(pad "2" smd rect
			(at -0.40005 0 180)
			(size 0.4572 0.508)
			(layers "F.Cu" "F.Mask" "F.Paste")
			(net "SATA_SPI_DO_NODE1_R")
		)
	)
	(footprint ""
		(layer "F.Cu")
		(at 132.32257 -26.569416 -90)
		(property "Reference" "R1146"
			(at 5.325618 -0.117348 90)
			(unlocked yes)
			(layer "F.SilkS")
			(effects
				(font
					(size 0.7874 0.5842)
					(thickness 0.1524)
				)
				(justify left)
			)
		)
		(property "Value" ""
			(at 0 0 270)
			(layer "F.Fab")
			(effects
				(font
					(size 1.27 1.27)
				)
			)
		)
		(duplicate_pad_numbers_are_jumpers no)
		(fp_line
			(start -0.7874 0.4064)
			(end -0.7874 -0.4064)
			(stroke
				(width 0.1524)
				(type default)
			)
			(layer "F.SilkS")
		)
		(fp_line
			(start 0.7874 0.4064)
			(end -0.7874 0.4064)
			(stroke
				(width 0.1524)
				(type default)
			)
			(layer "F.SilkS")
		)
		(fp_line
			(start -0.7874 -0.4064)
			(end 0.7874 -0.4064)
			(stroke
				(width 0.1524)
				(type default)
			)
			(layer "F.SilkS")
		)
		(fp_line
			(start 0.7874 -0.4064)
			(end 0.7874 0.4064)
			(stroke
				(width 0.1524)
				(type default)
			)
			(layer "F.SilkS")
		)
		(fp_poly
			(pts
				(xy -0.508 0.2794) (xy -0.508 0.2286) (xy -0.635 0.2286) (xy -0.635 -0.254) (xy -0.5334 -0.254)
				(xy -0.5334 -0.2794) (xy 0.5334 -0.2794) (xy 0.5334 -0.254) (xy 0.635 -0.254) (xy 0.635 0.254) (xy 0.5334 0.254)
				(xy 0.5334 0.2794)
			)
			(stroke
				(width 0)
				(type default)
			)
			(fill no)
			(layer "F.CrtYd")
		)
		(pad "1" smd rect
			(at 0.40005 0 270)
			(size 0.4572 0.508)
			(layers "F.Cu" "F.Mask" "F.Paste")
			(net "P3V3_STB_NODE1")
		)
		(pad "2" smd rect
			(at -0.40005 0 270)
			(size 0.4572 0.508)
			(layers "F.Cu" "F.Mask" "F.Paste")
			(net "SIO_PIN81")
		)
	)
	(footprint ""
		(layer "F.Cu")
		(at 188.849 -126.1872 180)
		(property "Reference" "R1269"
			(at -6.477 -18.89887 0)
			(unlocked yes)
			(layer "F.SilkS")
			(effects
				(font
					(size 0.7874 0.5842)
					(thickness 0.1524)
				)
				(justify left)
			)
		)
		(property "Value" ""
			(at 0 0 180)
			(layer "F.Fab")
			(effects
				(font
					(size 1.27 1.27)
				)
			)
		)
		(duplicate_pad_numbers_are_jumpers no)
		(fp_line
			(start 0.7874 0.4064)
			(end -0.7874 0.4064)
			(stroke
				(width 0.1524)
				(type default)
			)
			(layer "F.SilkS")
		)
		(fp_line
			(start 0.7874 -0.4064)
			(end 0.7874 0.4064)
			(stroke
				(width 0.1524)
				(type default)
			)
			(layer "F.SilkS")
		)
		(fp_line
			(start -0.7874 0.4064)
			(end -0.7874 -0.4064)
			(stroke
				(width 0.1524)
				(type default)
			)
			(layer "F.SilkS")
		)
		(fp_line
			(start -0.7874 -0.4064)
			(end 0.7874 -0.4064)
			(stroke
				(width 0.1524)
				(type default)
			)
			(layer "F.SilkS")
		)
		(fp_poly
			(pts
				(xy -0.508 0.2794) (xy -0.508 0.2286) (xy -0.635 0.2286) (xy -0.635 -0.254) (xy -0.5334 -0.254)
				(xy -0.5334 -0.2794) (xy 0.5334 -0.2794) (xy 0.5334 -0.254) (xy 0.635 -0.254) (xy 0.635 0.254) (xy 0.5334 0.254)
				(xy 0.5334 0.2794)
			)
			(stroke
				(width 0)
				(type default)
			)
			(fill no)
			(layer "F.CrtYd")
		)
		(pad "1" smd rect
			(at 0.40005 0 180)
			(size 0.4572 0.508)
			(layers "F.Cu" "F.Mask" "F.Paste")
			(net "SIO_JTAG_CPLD1_TMS")
		)
		(pad "2" smd rect
			(at -0.40005 0 180)
			(size 0.4572 0.508)
			(layers "F.Cu" "F.Mask" "F.Paste")
			(net "GND")
		)
	)
	(footprint ""
		(layer "F.Cu")
		(at 162.696906 -118.335552 180)
		(property "Reference" "R134"
			(at 4.487672 -0.390398 0)
			(unlocked yes)
			(layer "F.SilkS")
			(effects
				(font
					(size 0.7874 0.5842)
					(thickness 0.1524)
				)
				(justify left)
			)
		)
		(property "Value" ""
			(at 0 0 180)
			(layer "F.Fab")
			(effects
				(font
					(size 1.27 1.27)
				)
			)
		)
		(duplicate_pad_numbers_are_jumpers no)
		(fp_line
			(start 0.7874 0.4064)
			(end -0.7874 0.4064)
			(stroke
				(width 0.1524)
				(type default)
			)
			(layer "F.SilkS")
		)
		(fp_line
			(start 0.7874 -0.4064)
			(end 0.7874 0.4064)
			(stroke
				(width 0.1524)
				(type default)
			)
			(layer "F.SilkS")
		)
		(fp_line
			(start -0.7874 0.4064)
			(end -0.7874 -0.4064)
			(stroke
				(width 0.1524)
				(type default)
			)
			(layer "F.SilkS")
		)
		(fp_line
			(start -0.7874 -0.4064)
			(end 0.7874 -0.4064)
			(stroke
				(width 0.1524)
				(type default)
			)
			(layer "F.SilkS")
		)
		(fp_poly
			(pts
				(xy -0.508 0.2794) (xy -0.508 0.2286) (xy -0.635 0.2286) (xy -0.635 -0.254) (xy -0.5334 -0.254)
				(xy -0.5334 -0.2794) (xy 0.5334 -0.2794) (xy 0.5334 -0.254) (xy 0.635 -0.254) (xy 0.635 0.254) (xy 0.5334 0.254)
				(xy 0.5334 0.2794)
			)
			(stroke
				(width 0)
				(type default)
			)
			(fill no)
			(layer "F.CrtYd")
		)
		(pad "1" smd rect
			(at 0.40005 0 180)
			(size 0.4572 0.508)
			(layers "F.Cu" "F.Mask" "F.Paste")
			(net "GND")
		)
		(pad "2" smd rect
			(at -0.40005 0 180)
			(size 0.4572 0.508)
			(layers "F.Cu" "F.Mask" "F.Paste")
			(net "FM_CPU_NODE1_RSTWARN")
		)
	)
	(footprint ""
		(layer "F.Cu")
		(at 69.273166 -96.709992 90)
		(property "Reference" "R69"
			(at -54.98719 28.346146 90)
			(unlocked yes)
			(layer "F.SilkS")
			(effects
				(font
					(size 0.7874 0.5842)
					(thickness 0.1524)
				)
				(justify left)
			)
		)
		(property "Value" ""
			(at 0 0 90)
			(layer "F.Fab")
			(effects
				(font
					(size 1.27 1.27)
				)
			)
		)
		(duplicate_pad_numbers_are_jumpers no)
		(fp_line
			(start 0.7874 -0.4064)
			(end 0.7874 0.4064)
			(stroke
				(width 0.1524)
				(type default)
			)
			(layer "F.SilkS")
		)
		(fp_line
			(start -0.7874 -0.4064)
			(end 0.7874 -0.4064)
			(stroke
				(width 0.1524)
				(type default)
			)
			(layer "F.SilkS")
		)
		(fp_line
			(start 0.7874 0.4064)
			(end -0.7874 0.4064)
			(stroke
				(width 0.1524)
				(type default)
			)
			(layer "F.SilkS")
		)
		(fp_line
			(start -0.7874 0.4064)
			(end -0.7874 -0.4064)
			(stroke
				(width 0.1524)
				(type default)
			)
			(layer "F.SilkS")
		)
		(fp_poly
			(pts
				(xy -0.508 0.2794) (xy -0.508 0.2286) (xy -0.635 0.2286) (xy -0.635 -0.254) (xy -0.5334 -0.254)
				(xy -0.5334 -0.2794) (xy 0.5334 -0.2794) (xy 0.5334 -0.254) (xy 0.635 -0.254) (xy 0.635 0.254) (xy 0.5334 0.254)
				(xy 0.5334 0.2794)
			)
			(stroke
				(width 0)
				(type default)
			)
			(fill no)
			(layer "F.CrtYd")
		)
		(pad "1" smd rect
			(at 0.40005 0 90)
			(size 0.4572 0.508)
			(layers "F.Cu" "F.Mask" "F.Paste")
			(net "SPC_CPU_NODE1_DTR_L")
		)
		(pad "2" smd rect
			(at -0.40005 0 90)
			(size 0.4572 0.508)
			(layers "F.Cu" "F.Mask" "F.Paste")
			(net "SPC_CPU_NODE1_DSR_L")
		)
	)
	(footprint ""
		(layer "F.Cu")
		(at 169.664888 -37.455856 90)
		(property "Reference" "L42"
			(at -3.408172 -2.057654 90)
			(unlocked yes)
			(layer "F.SilkS")
			(effects
				(font
					(size 0.7874 0.5842)
					(thickness 0.1524)
				)
				(justify left)
			)
		)
		(property "Value" ""
			(at 0 0 90)
			(layer "F.Fab")
			(effects
				(font
					(size 1.27 1.27)
				)
			)
		)
		(duplicate_pad_numbers_are_jumpers no)
		(fp_line
			(start 0.989838 -2.0066)
			(end 0.989838 2.0066)
			(stroke
				(width 0.1524)
				(type default)
			)
			(layer "F.SilkS")
		)
		(fp_line
			(start -1.015238 -2.0066)
			(end 0.989838 -2.0066)
			(stroke
				(width 0.1524)
				(type default)
			)
			(layer "F.SilkS")
		)
		(fp_line
			(start 0.989838 2.0066)
			(end -1.015238 2.0066)
			(stroke
				(width 0.1524)
				(type default)
			)
			(layer "F.SilkS")
		)
		(fp_line
			(start -1.015238 2.0066)
			(end -1.015238 -2.0066)
			(stroke
				(width 0.1524)
				(type default)
			)
			(layer "F.SilkS")
		)
		(fp_poly
			(pts
				(xy -0.899922 -1.700022) (xy -0.899922 1.700022) (xy -0.8636 1.700022) (xy -0.8636 1.9304) (xy -0.127 1.9304)
				(xy -0.127 1.700022) (xy 0.127 1.700022) (xy 0.127 1.9304) (xy 0.8636 1.9304) (xy 0.8636 1.700022)
				(xy 0.899922 1.700022) (xy 0.899922 -1.700022) (xy 0.8636 -1.700022) (xy 0.8636 -1.9304) (xy 0.127 -1.9304)
				(xy 0.127 -1.700022) (xy -0.127 -1.700022) (xy -0.127 -1.9304) (xy -0.8636 -1.9304) (xy -0.8636 -1.700022)
			)
			(stroke
				(width 0)
				(type default)
			)
			(fill no)
			(layer "F.CrtYd")
		)
		(fp_line
			(start 0.899922 -1.700022)
			(end 0.899922 1.700022)
			(stroke
				(width 0.1)
				(type default)
			)
			(layer "F.Fab")
		)
		(fp_line
			(start -0.899922 -1.700022)
			(end 0.899922 -1.700022)
			(stroke
				(width 0.1)
				(type default)
			)
			(layer "F.Fab")
		)
		(fp_line
			(start 0.899922 1.700022)
			(end -0.899922 1.700022)
			(stroke
				(width 0.1)
				(type default)
			)
			(layer "F.Fab")
		)
		(fp_line
			(start -0.899922 1.700022)
			(end -0.899922 -1.700022)
			(stroke
				(width 0.1)
				(type default)
			)
			(layer "F.Fab")
		)
		(pad "1" smd rect
			(at -0.499872 -1.400048 90)
			(size 0.6096 0.9144)
			(layers "F.Cu" "F.Mask" "F.Paste")
			(net "USB0_DN")
		)
		(pad "2" smd rect
			(at -0.499872 1.400048 90)
			(size 0.6096 0.9144)
			(layers "F.Cu" "F.Mask" "F.Paste")
			(net "USB0_L_DN")
		)
		(pad "3" smd rect
			(at 0.499872 1.400048 90)
			(size 0.6096 0.9144)
			(layers "F.Cu" "F.Mask" "F.Paste")
			(net "USB0_L_DP")
		)
		(pad "4" smd rect
			(at 0.499872 -1.400048 90)
			(size 0.6096 0.9144)
			(layers "F.Cu" "F.Mask" "F.Paste")
			(net "USB0_DP")
		)
	)
	(footprint ""
		(layer "F.Cu")
		(at 118.977918 -155.754578 180)
		(property "Reference" "R1059"
			(at 0.913638 2.237486 0)
			(unlocked yes)
			(layer "F.SilkS")
			(effects
				(font
					(size 0.635 0.4064)
					(thickness 0.1524)
				)
				(justify left)
			)
		)
		(property "Value" ""
			(at 0 0 180)
			(layer "F.Fab")
			(effects
				(font
					(size 1.27 1.27)
				)
			)
		)
		(duplicate_pad_numbers_are_jumpers no)
		(fp_line
			(start 0.7874 0.4064)
			(end -0.7874 0.4064)
			(stroke
				(width 0.1524)
				(type default)
			)
			(layer "F.SilkS")
		)
		(fp_line
			(start 0.7874 -0.4064)
			(end 0.7874 0.4064)
			(stroke
				(width 0.1524)
				(type default)
			)
			(layer "F.SilkS")
		)
		(fp_line
			(start -0.7874 0.4064)
			(end -0.7874 -0.4064)
			(stroke
				(width 0.1524)
				(type default)
			)
			(layer "F.SilkS")
		)
		(fp_line
			(start -0.7874 -0.4064)
			(end 0.7874 -0.4064)
			(stroke
				(width 0.1524)
				(type default)
			)
			(layer "F.SilkS")
		)
		(fp_poly
			(pts
				(xy -0.508 0.2794) (xy -0.508 0.2286) (xy -0.635 0.2286) (xy -0.635 -0.254) (xy -0.5334 -0.254)
				(xy -0.5334 -0.2794) (xy 0.5334 -0.2794) (xy 0.5334 -0.254) (xy 0.635 -0.254) (xy 0.635 0.254) (xy 0.5334 0.254)
				(xy 0.5334 0.2794)
			)
			(stroke
				(width 0)
				(type default)
			)
			(fill no)
			(layer "F.CrtYd")
		)
		(pad "1" smd rect
			(at 0.40005 0 180)
			(size 0.4572 0.508)
			(layers "F.Cu" "F.Mask" "F.Paste")
			(net "N52998261")
		)
		(pad "2" smd rect
			(at -0.40005 0 180)
			(size 0.4572 0.508)
			(layers "F.Cu" "F.Mask" "F.Paste")
			(net "P3V3_STB_NODE1")
		)
	)
	(footprint ""
		(layer "F.Cu")
		(at 22.15261 -69.986652 180)
		(property "Reference" "D7"
			(at -0.788162 2.805938 90)
			(unlocked yes)
			(layer "F.SilkS")
			(effects
				(font
					(size 0.7874 0.5842)
					(thickness 0.1524)
				)
			)
		)
		(property "Value" ""
			(at 0 0 180)
			(layer "F.Fab")
			(effects
				(font
					(size 1.27 1.27)
				)
			)
		)
		(duplicate_pad_numbers_are_jumpers no)
		(fp_line
			(start 1.519936 1.6002)
			(end -1.519936 1.6002)
			(stroke
				(width 0.1524)
				(type default)
			)
			(layer "F.SilkS")
		)
		(fp_line
			(start 1.519936 -1.6002)
			(end 1.519936 1.6002)
			(stroke
				(width 0.1524)
				(type default)
			)
			(layer "F.SilkS")
		)
		(fp_line
			(start -1.519936 1.6002)
			(end -1.519936 -1.5748)
			(stroke
				(width 0.1524)
				(type default)
			)
			(layer "F.SilkS")
		)
		(fp_line
			(start -1.519936 -1.6002)
			(end 1.519936 -1.6002)
			(stroke
				(width 0.1524)
				(type default)
			)
			(layer "F.SilkS")
		)
		(fp_poly
			(pts
				(xy -1.519936 0.700024) (xy -1.3716 0.700024) (xy -1.3716 1.4732) (xy -0.5334 1.4732) (xy -0.5334 0.700024)
				(xy 0.5334 0.700024) (xy 0.5334 1.4732) (xy 1.3716 1.4732) (xy 1.3716 0.700024) (xy 1.519936 0.700024)
				(xy 1.519936 -0.700024) (xy 0.4064 -0.700024) (xy 0.4064 -1.4732) (xy -0.4064 -1.4732) (xy -0.4064 -0.700024)
				(xy -1.519936 -0.700024)
			)
			(stroke
				(width 0)
				(type default)
			)
			(fill no)
			(layer "F.CrtYd")
		)
		(fp_line
			(start 1.519936 0.700024)
			(end -1.519936 0.700024)
			(stroke
				(width 0.1)
				(type default)
			)
			(layer "F.Fab")
		)
		(fp_line
			(start 1.519936 -0.700024)
			(end 1.519936 0.700024)
			(stroke
				(width 0.1)
				(type default)
			)
			(layer "F.Fab")
		)
		(fp_line
			(start -1.519936 0.700024)
			(end -1.519936 -0.700024)
			(stroke
				(width 0.1)
				(type default)
			)
			(layer "F.Fab")
		)
		(fp_line
			(start -1.519936 -0.700024)
			(end 1.519936 -0.700024)
			(stroke
				(width 0.1)
				(type default)
			)
			(layer "F.Fab")
		)
		(fp_text user "2"
			(at 1.78816 1.171956 0)
			(unlocked yes)
			(layer "F.SilkS")
			(effects
				(font
					(size 0.635 0.4064)
					(thickness 0.1524)
				)
			)
		)
		(fp_text user "3"
			(at 0.730758 -2.16662 0)
			(unlocked yes)
			(layer "F.SilkS")
			(effects
				(font
					(size 0.635 0.4064)
					(thickness 0.1524)
				)
			)
		)
		(fp_text user "1"
			(at -1.754378 0.227076 180)
			(unlocked yes)
			(layer "F.SilkS")
			(effects
				(font
					(size 0.635 0.4064)
					(thickness 0.1524)
				)
			)
		)
		(pad "1" smd rect
			(at -0.94996 0.999998 180)
			(size 0.8128 0.9144)
			(layers "F.Cu" "F.Mask" "F.Paste")
			(net "SMB_BMC_NODE1_DDC_CLK")
		)
		(pad "2" smd rect
			(at 0.94996 0.999998 180)
			(size 0.8128 0.9144)
			(layers "F.Cu" "F.Mask" "F.Paste")
			(net "Net_1679")
		)
		(pad "3" smd rect
			(at 0 -0.999998 180)
			(size 0.8128 0.9144)
			(layers "F.Cu" "F.Mask" "F.Paste")
			(net "I2C_VIDREAR_5V_SCL")
		)
	)
	(footprint ""
		(layer "F.Cu")
		(at 70.100698 -17.679416 90)
		(property "Reference" "C152"
			(at -4.786884 6.313678 90)
			(unlocked yes)
			(layer "F.SilkS")
			(effects
				(font
					(size 0.7874 0.5842)
					(thickness 0.1524)
				)
				(justify left)
			)
		)
		(property "Value" ""
			(at 0 0 90)
			(layer "F.Fab")
			(effects
				(font
					(size 1.27 1.27)
				)
			)
		)
		(duplicate_pad_numbers_are_jumpers no)
		(fp_line
			(start 0.7874 -0.4064)
			(end 0.7874 0.4064)
			(stroke
				(width 0.1524)
				(type default)
			)
			(layer "F.SilkS")
		)
		(fp_line
			(start -0.7874 -0.4064)
			(end 0.7874 -0.4064)
			(stroke
				(width 0.1524)
				(type default)
			)
			(layer "F.SilkS")
		)
		(fp_line
			(start 0 0.381)
			(end 0 -0.381)
			(stroke
				(width 0.1524)
				(type default)
			)
			(layer "F.SilkS")
		)
		(fp_line
			(start 0.7874 0.4064)
			(end -0.7874 0.4064)
			(stroke
				(width 0.1524)
				(type default)
			)
			(layer "F.SilkS")
		)
		(fp_line
			(start -0.7874 0.4064)
			(end -0.7874 -0.4064)
			(stroke
				(width 0.1524)
				(type default)
			)
			(layer "F.SilkS")
		)
		(fp_poly
			(pts
				(xy -0.5334 0.254) (xy -0.635 0.254) (xy -0.635 0.2286) (xy -0.635 -0.254) (xy -0.5334 -0.254) (xy -0.5334 -0.2794)
				(xy 0.5334 -0.2794) (xy 0.5334 -0.254) (xy 0.635 -0.254) (xy 0.635 0.254) (xy 0.5334 0.254) (xy 0.5334 0.2794)
				(xy -0.508 0.2794) (xy -0.5334 0.2794)
			)
			(stroke
				(width 0)
				(type default)
			)
			(fill no)
			(layer "F.CrtYd")
		)
		(pad "1" smd rect
			(at 0.40005 0 90)
			(size 0.4572 0.508)
			(layers "F.Cu" "F.Mask" "F.Paste")
			(net "PV_VDDR_NODE1")
		)
		(pad "2" smd rect
			(at -0.40005 0 90)
			(size 0.4572 0.508)
			(layers "F.Cu" "F.Mask" "F.Paste")
			(net "GND")
		)
	)
	(footprint ""
		(layer "F.Cu")
		(at 96.338644 -136.238488)
		(property "Reference" "U119"
			(at -3.788918 1.90881 90)
			(unlocked yes)
			(layer "F.SilkS")
			(effects
				(font
					(size 0.635 0.4064)
					(thickness 0.1524)
				)
				(justify left)
			)
		)
		(property "Value" ""
			(at 0 0 0)
			(layer "F.Fab")
			(effects
				(font
					(size 1.27 1.27)
				)
			)
		)
		(duplicate_pad_numbers_are_jumpers no)
		(fp_line
			(start -2.525014 0.025146)
			(end -2.525014 0.661162)
			(stroke
				(width 0.1524)
				(type default)
			)
			(layer "F.SilkS")
		)
		(fp_line
			(start -2.525014 2.540762)
			(end -2.525014 3.075178)
			(stroke
				(width 0.1524)
				(type default)
			)
			(layer "F.SilkS")
		)
		(fp_line
			(start -2.525014 3.075178)
			(end -2.525014 0.025146)
			(stroke
				(width 0.1524)
				(type default)
			)
			(layer "F.SilkS")
		)
		(fp_line
			(start -2.525014 3.075178)
			(end -2.320798 3.075178)
			(stroke
				(width 0.1524)
				(type default)
			)
			(layer "F.SilkS")
		)
		(fp_line
			(start -2.320798 0.025146)
			(end -2.525014 0.025146)
			(stroke
				(width 0.1524)
				(type default)
			)
			(layer "F.SilkS")
		)
		(fp_line
			(start 0.320802 3.075178)
			(end 0.525018 3.075178)
			(stroke
				(width 0.1524)
				(type default)
			)
			(layer "F.SilkS")
		)
		(fp_line
			(start 0.525018 0.025146)
			(end 0.320802 0.025146)
			(stroke
				(width 0.1524)
				(type default)
			)
			(layer "F.SilkS")
		)
		(fp_line
			(start 0.525018 0.686562)
			(end 0.525018 0.025146)
			(stroke
				(width 0.1524)
				(type default)
			)
			(layer "F.SilkS")
		)
		(fp_line
			(start 0.525018 3.075178)
			(end 0.525018 0.025146)
			(stroke
				(width 0.1524)
				(type default)
			)
			(layer "F.SilkS")
		)
		(fp_line
			(start 0.525018 3.075178)
			(end 0.525018 2.489962)
			(stroke
				(width 0.1524)
				(type default)
			)
			(layer "F.SilkS")
		)
		(fp_poly
			(pts
				(xy 0 -0.519938) (xy 0.299974 -1.420114) (xy -0.299974 -1.420114)
			)
			(stroke
				(width 0)
				(type default)
			)
			(fill yes)
			(layer "F.SilkS")
		)
		(fp_poly
			(pts
				(xy 0.525018 0.025146) (xy 0.244602 0.025146) (xy 0.244602 -0.532638) (xy -2.244598 -0.532638) (xy -2.244598 0.025146)
				(xy -2.525014 0.025146) (xy -2.525014 3.075178) (xy -2.244598 3.075178) (xy -2.244598 3.632962)
				(xy 0.244602 3.632962) (xy 0.244602 3.075178) (xy 0.525018 3.075178)
			)
			(stroke
				(width 0)
				(type default)
			)
			(fill no)
			(layer "F.CrtYd")
		)
		(fp_line
			(start -2.525014 0.025146)
			(end 0.525018 0.025146)
			(stroke
				(width 0.1)
				(type default)
			)
			(layer "F.Fab")
		)
		(fp_line
			(start -2.525014 3.075178)
			(end -2.525014 0.025146)
			(stroke
				(width 0.1)
				(type default)
			)
			(layer "F.Fab")
		)
		(fp_line
			(start 0.525018 0.025146)
			(end 0.525018 3.075178)
			(stroke
				(width 0.1)
				(type default)
			)
			(layer "F.Fab")
		)
		(fp_line
			(start 0.525018 3.075178)
			(end -2.525014 3.075178)
			(stroke
				(width 0.1)
				(type default)
			)
			(layer "F.Fab")
		)
		(fp_poly
			(pts
				(xy 0 -0.519938) (xy 0.302514 -1.427734) (xy -0.302514 -1.427734)
			)
			(stroke
				(width 0)
				(type default)
			)
			(fill yes)
			(layer "F.Fab")
		)
		(fp_text user "6"
			(at -3.643884 2.99974 0)
			(unlocked yes)
			(layer "F.SilkS")
			(effects
				(font
					(size 0.7874 0.5842)
					(thickness 0.1524)
				)
				(justify left)
			)
		)
		(fp_text user "5"
			(at -2.589784 -0.674878 0)
			(unlocked yes)
			(layer "F.SilkS")
			(effects
				(font
					(size 0.635 0.4064)
					(thickness 0.1524)
				)
				(justify left)
			)
		)
		(fp_text user "10"
			(at 0.119888 3.764026 0)
			(unlocked yes)
			(layer "F.SilkS")
			(effects
				(font
					(size 0.635 0.4064)
					(thickness 0.1524)
				)
				(justify left)
			)
		)
		(fp_text user "1"
			(at 0.160274 -0.722376 0)
			(unlocked yes)
			(layer "F.SilkS")
			(effects
				(font
					(size 0.7874 0.5842)
					(thickness 0.1524)
				)
				(justify left)
			)
		)
		(fp_text user "5"
			(at -2.155698 -0.695706 180)
			(unlocked yes)
			(layer "F.Fab")
			(effects
				(font
					(size 0.7874 0.5842)
					(thickness 0.000001)
				)
				(justify left)
			)
		)
		(fp_text user "6"
			(at -2.155698 3.725672 180)
			(unlocked yes)
			(layer "F.Fab")
			(effects
				(font
					(size 0.7874 0.5842)
					(thickness 0.000001)
				)
				(justify left)
			)
		)
		(fp_text user "1"
			(at 0.790702 -0.695706 180)
			(unlocked yes)
			(layer "F.Fab")
			(effects
				(font
					(size 0.7874 0.5842)
					(thickness 0.000001)
				)
				(justify left)
			)
		)
		(fp_text user "10"
			(at 1.565402 3.700272 180)
			(unlocked yes)
			(layer "F.Fab")
			(effects
				(font
					(size 0.7874 0.5842)
					(thickness 0.000001)
				)
				(justify left)
			)
		)
		(pad "1" smd rect
			(at 0 0 180)
			(size 0.2794 0.9144)
			(layers "F.Cu" "F.Mask" "F.Paste")
			(net "P1V05_SUS_NODE1")
		)
		(pad "2" smd rect
			(at -0.499872 0 180)
			(size 0.2794 0.9144)
			(layers "F.Cu" "F.Mask" "F.Paste")
			(net "P1V05_SUS_NODE1")
		)
		(pad "3" smd rect
			(at -0.999998 0 180)
			(size 0.2794 0.9144)
			(layers "F.Cu" "F.Mask" "F.Paste")
			(net "P1V05_SUS_NODE1")
		)
		(pad "4" smd rect
			(at -1.500124 0 180)
			(size 0.2794 0.9144)
			(layers "F.Cu" "F.Mask" "F.Paste")
			(net "P1V05_SUS_NODE1_ADJ")
		)
		(pad "5" smd rect
			(at -1.999996 0)
			(size 0.2794 0.9144)
			(layers "F.Cu" "F.Mask" "F.Paste")
			(net "PWRGD_NODE1_P1V05_SUS_PG")
		)
		(pad "6" smd rect
			(at -1.999996 3.100324)
			(size 0.2794 0.9144)
			(layers "F.Cu" "F.Mask" "F.Paste")
			(net "FM_CPLD_NODE1_P1V05_SUS_EN")
		)
		(pad "7" smd rect
			(at -1.500124 3.100324 180)
			(size 0.2794 0.9144)
			(layers "F.Cu" "F.Mask" "F.Paste")
			(net "P1V8_STB_NODE1")
		)
		(pad "8" smd rect
			(at -0.999998 3.100324 180)
			(size 0.2794 0.9144)
			(layers "F.Cu" "F.Mask" "F.Paste")
			(net "P1V8_STB_NODE1")
		)
		(pad "9" smd rect
			(at -0.499872 3.100324 180)
			(size 0.2794 0.9144)
			(layers "F.Cu" "F.Mask" "F.Paste")
			(net "P1V8_STB_NODE1")
		)
		(pad "10" smd rect
			(at 0 3.100324 180)
			(size 0.2794 0.9144)
			(layers "F.Cu" "F.Mask" "F.Paste")
			(net "P5V_STB_NODE1")
		)
		(pad "TH" smd rect
			(at -0.999998 1.550162 270)
			(size 1.7526 2.667)
			(layers "F.Cu" "F.Mask" "F.Paste")
			(net "GND")
		)
		(zone
			(layer "F.Cu")
			(hatch none 0.5)
			(connect_pads
				(clearance 0)
			)
			(min_thickness 0.25)
			(keepout
				(tracks allowed)
				(vias not_allowed)
				(pads allowed)
				(copperpour not_allowed)
				(footprints allowed)
			)
			(placement
				(enabled no)
				(sheetname "")
			)
			(fill
				(thermal_gap 0.5)
				(thermal_bridge_width 0.5)
				(island_removal_mode 0)
			)
			(polygon
				(pts
					(xy 96.872044 -135.705088) (xy 93.824044 -135.705088) (xy 93.824044 -133.673088) (xy 96.872044 -133.673088)
					(xy 96.872044 -135.603488) (xy 96.745044 -135.603488) (xy 96.745044 -133.749288) (xy 93.925644 -133.749288)
					(xy 93.925644 -135.628888) (xy 96.872044 -135.628888)
				)
			)
		)
	)
	(footprint ""
		(layer "F.Cu")
		(at 152.76576 -188.126624 90)
		(property "Reference" "C666"
			(at 5.519674 -3.062732 90)
			(unlocked yes)
			(layer "F.SilkS")
			(effects
				(font
					(size 0.7874 0.5842)
					(thickness 0.1524)
				)
				(justify left)
			)
		)
		(property "Value" ""
			(at 0 0 90)
			(layer "F.Fab")
			(effects
				(font
					(size 1.27 1.27)
				)
			)
		)
		(duplicate_pad_numbers_are_jumpers no)
		(fp_line
			(start 0.7874 -0.4064)
			(end 0.7874 0.4064)
			(stroke
				(width 0.1524)
				(type default)
			)
			(layer "F.SilkS")
		)
		(fp_line
			(start -0.7874 -0.4064)
			(end 0.7874 -0.4064)
			(stroke
				(width 0.1524)
				(type default)
			)
			(layer "F.SilkS")
		)
		(fp_line
			(start 0 0.381)
			(end 0 -0.381)
			(stroke
				(width 0.1524)
				(type default)
			)
			(layer "F.SilkS")
		)
		(fp_line
			(start 0.7874 0.4064)
			(end -0.7874 0.4064)
			(stroke
				(width 0.1524)
				(type default)
			)
			(layer "F.SilkS")
		)
		(fp_line
			(start -0.7874 0.4064)
			(end -0.7874 -0.4064)
			(stroke
				(width 0.1524)
				(type default)
			)
			(layer "F.SilkS")
		)
		(fp_poly
			(pts
				(xy -0.5334 0.254) (xy -0.635 0.254) (xy -0.635 0.2286) (xy -0.635 -0.254) (xy -0.5334 -0.254) (xy -0.5334 -0.2794)
				(xy 0.5334 -0.2794) (xy 0.5334 -0.254) (xy 0.635 -0.254) (xy 0.635 0.254) (xy 0.5334 0.254) (xy 0.5334 0.2794)
				(xy -0.508 0.2794) (xy -0.5334 0.2794)
			)
			(stroke
				(width 0)
				(type default)
			)
			(fill no)
			(layer "F.CrtYd")
		)
		(pad "1" smd rect
			(at 0.40005 0 90)
			(size 0.4572 0.508)
			(layers "F.Cu" "F.Mask" "F.Paste")
			(net "T12_NODE3_EN_R")
		)
		(pad "2" smd rect
			(at -0.40005 0 90)
			(size 0.4572 0.508)
			(layers "F.Cu" "F.Mask" "F.Paste")
			(net "GND")
		)
	)
	(footprint ""
		(layer "F.Cu")
		(at 34.976816 -104.248712 90)
		(property "Reference" "R1089"
			(at -6.011672 -0.00381 90)
			(unlocked yes)
			(layer "F.SilkS")
			(effects
				(font
					(size 0.7874 0.5842)
					(thickness 0.1524)
				)
				(justify left)
			)
		)
		(property "Value" ""
			(at 0 0 90)
			(layer "F.Fab")
			(effects
				(font
					(size 1.27 1.27)
				)
			)
		)
		(duplicate_pad_numbers_are_jumpers no)
		(fp_line
			(start 0.7874 -0.4064)
			(end 0.7874 0.4064)
			(stroke
				(width 0.1524)
				(type default)
			)
			(layer "F.SilkS")
		)
		(fp_line
			(start -0.7874 -0.4064)
			(end 0.7874 -0.4064)
			(stroke
				(width 0.1524)
				(type default)
			)
			(layer "F.SilkS")
		)
		(fp_line
			(start 0.7874 0.4064)
			(end -0.7874 0.4064)
			(stroke
				(width 0.1524)
				(type default)
			)
			(layer "F.SilkS")
		)
		(fp_line
			(start -0.7874 0.4064)
			(end -0.7874 -0.4064)
			(stroke
				(width 0.1524)
				(type default)
			)
			(layer "F.SilkS")
		)
		(fp_poly
			(pts
				(xy -0.508 0.2794) (xy -0.508 0.2286) (xy -0.635 0.2286) (xy -0.635 -0.254) (xy -0.5334 -0.254)
				(xy -0.5334 -0.2794) (xy 0.5334 -0.2794) (xy 0.5334 -0.254) (xy 0.635 -0.254) (xy 0.635 0.254) (xy 0.5334 0.254)
				(xy 0.5334 0.2794)
			)
			(stroke
				(width 0)
				(type default)
			)
			(fill no)
			(layer "F.CrtYd")
		)
		(pad "1" smd rect
			(at 0.40005 0 90)
			(size 0.4572 0.508)
			(layers "F.Cu" "F.Mask" "F.Paste")
			(net "GND")
		)
		(pad "2" smd rect
			(at -0.40005 0 90)
			(size 0.4572 0.508)
			(layers "F.Cu" "F.Mask" "F.Paste")
			(net "P1V5_SUS_NODE1_ADJ")
		)
	)
	(footprint ""
		(layer "F.Cu")
		(at 80.382364 -17.679416 90)
		(property "Reference" "C145"
			(at -4.546854 5.52323 90)
			(unlocked yes)
			(layer "F.SilkS")
			(effects
				(font
					(size 0.7874 0.5842)
					(thickness 0.1524)
				)
				(justify left)
			)
		)
		(property "Value" ""
			(at 0 0 90)
			(layer "F.Fab")
			(effects
				(font
					(size 1.27 1.27)
				)
			)
		)
		(duplicate_pad_numbers_are_jumpers no)
		(fp_line
			(start 0.7874 -0.4064)
			(end 0.7874 0.4064)
			(stroke
				(width 0.1524)
				(type default)
			)
			(layer "F.SilkS")
		)
		(fp_line
			(start -0.7874 -0.4064)
			(end 0.7874 -0.4064)
			(stroke
				(width 0.1524)
				(type default)
			)
			(layer "F.SilkS")
		)
		(fp_line
			(start 0 0.381)
			(end 0 -0.381)
			(stroke
				(width 0.1524)
				(type default)
			)
			(layer "F.SilkS")
		)
		(fp_line
			(start 0.7874 0.4064)
			(end -0.7874 0.4064)
			(stroke
				(width 0.1524)
				(type default)
			)
			(layer "F.SilkS")
		)
		(fp_line
			(start -0.7874 0.4064)
			(end -0.7874 -0.4064)
			(stroke
				(width 0.1524)
				(type default)
			)
			(layer "F.SilkS")
		)
		(fp_poly
			(pts
				(xy -0.5334 0.254) (xy -0.635 0.254) (xy -0.635 0.2286) (xy -0.635 -0.254) (xy -0.5334 -0.254) (xy -0.5334 -0.2794)
				(xy 0.5334 -0.2794) (xy 0.5334 -0.254) (xy 0.635 -0.254) (xy 0.635 0.254) (xy 0.5334 0.254) (xy 0.5334 0.2794)
				(xy -0.508 0.2794) (xy -0.5334 0.2794)
			)
			(stroke
				(width 0)
				(type default)
			)
			(fill no)
			(layer "F.CrtYd")
		)
		(pad "1" smd rect
			(at 0.40005 0 90)
			(size 0.4572 0.508)
			(layers "F.Cu" "F.Mask" "F.Paste")
			(net "PV_VDDR_NODE1")
		)
		(pad "2" smd rect
			(at -0.40005 0 90)
			(size 0.4572 0.508)
			(layers "F.Cu" "F.Mask" "F.Paste")
			(net "GND")
		)
	)
	(footprint ""
		(layer "F.Cu")
		(at 79.98714 -158.242508 -90)
		(property "Reference" "PR2"
			(at 0.960628 -4.381246 90)
			(unlocked yes)
			(layer "F.SilkS")
			(effects
				(font
					(size 0.7874 0.5842)
					(thickness 0.1524)
				)
				(justify left)
			)
		)
		(property "Value" ""
			(at 0 0 270)
			(layer "F.Fab")
			(effects
				(font
					(size 1.27 1.27)
				)
			)
		)
		(duplicate_pad_numbers_are_jumpers no)
		(fp_line
			(start -0.7874 0.4064)
			(end -0.7874 -0.4064)
			(stroke
				(width 0.1524)
				(type default)
			)
			(layer "F.SilkS")
		)
		(fp_line
			(start 0.7874 0.4064)
			(end -0.7874 0.4064)
			(stroke
				(width 0.1524)
				(type default)
			)
			(layer "F.SilkS")
		)
		(fp_line
			(start -0.7874 -0.4064)
			(end 0.7874 -0.4064)
			(stroke
				(width 0.1524)
				(type default)
			)
			(layer "F.SilkS")
		)
		(fp_line
			(start 0.7874 -0.4064)
			(end 0.7874 0.4064)
			(stroke
				(width 0.1524)
				(type default)
			)
			(layer "F.SilkS")
		)
		(fp_poly
			(pts
				(xy -0.508 0.2794) (xy -0.508 0.2286) (xy -0.635 0.2286) (xy -0.635 -0.254) (xy -0.5334 -0.254)
				(xy -0.5334 -0.2794) (xy 0.5334 -0.2794) (xy 0.5334 -0.254) (xy 0.635 -0.254) (xy 0.635 0.254) (xy 0.5334 0.254)
				(xy 0.5334 0.2794)
			)
			(stroke
				(width 0)
				(type default)
			)
			(fill no)
			(layer "F.CrtYd")
		)
		(pad "1" smd rect
			(at 0.40005 0 270)
			(size 0.4572 0.508)
			(layers "F.Cu" "F.Mask" "F.Paste")
			(net "PWRGD_NODE1_P5V_STB_PG")
		)
		(pad "2" smd rect
			(at -0.40005 0 270)
			(size 0.4572 0.508)
			(layers "F.Cu" "F.Mask" "F.Paste")
			(net "GND")
		)
	)
	(footprint ""
		(layer "F.Cu")
		(at 153.439114 -89.199466 -90)
		(property "Reference" "R530"
			(at -0.437134 3.434588 0)
			(unlocked yes)
			(layer "F.SilkS")
			(effects
				(font
					(size 0.7874 0.5842)
					(thickness 0.1524)
				)
				(justify left)
			)
		)
		(property "Value" ""
			(at 0 0 270)
			(layer "F.Fab")
			(effects
				(font
					(size 1.27 1.27)
				)
			)
		)
		(duplicate_pad_numbers_are_jumpers no)
		(fp_line
			(start -0.7874 0.4064)
			(end -0.7874 -0.4064)
			(stroke
				(width 0.1524)
				(type default)
			)
			(layer "F.SilkS")
		)
		(fp_line
			(start 0.7874 0.4064)
			(end -0.7874 0.4064)
			(stroke
				(width 0.1524)
				(type default)
			)
			(layer "F.SilkS")
		)
		(fp_line
			(start -0.7874 -0.4064)
			(end 0.7874 -0.4064)
			(stroke
				(width 0.1524)
				(type default)
			)
			(layer "F.SilkS")
		)
		(fp_line
			(start 0.7874 -0.4064)
			(end 0.7874 0.4064)
			(stroke
				(width 0.1524)
				(type default)
			)
			(layer "F.SilkS")
		)
		(fp_poly
			(pts
				(xy -0.508 0.2794) (xy -0.508 0.2286) (xy -0.635 0.2286) (xy -0.635 -0.254) (xy -0.5334 -0.254)
				(xy -0.5334 -0.2794) (xy 0.5334 -0.2794) (xy 0.5334 -0.254) (xy 0.635 -0.254) (xy 0.635 0.254) (xy 0.5334 0.254)
				(xy 0.5334 0.2794)
			)
			(stroke
				(width 0)
				(type default)
			)
			(fill no)
			(layer "F.CrtYd")
		)
		(pad "1" smd rect
			(at 0.40005 0 270)
			(size 0.4572 0.508)
			(layers "F.Cu" "F.Mask" "F.Paste")
			(net "SPI_USB_NODE1_SI_R")
		)
		(pad "2" smd rect
			(at -0.40005 0 270)
			(size 0.4572 0.508)
			(layers "F.Cu" "F.Mask" "F.Paste")
			(net "SPI_USB_NODE1_SI")
		)
	)
	(footprint ""
		(layer "F.Cu")
		(at 165.011354 -182.035196 180)
		(property "Reference" "R1169"
			(at 5.214366 -0.616966 0)
			(unlocked yes)
			(layer "F.SilkS")
			(effects
				(font
					(size 0.7874 0.5842)
					(thickness 0.1524)
				)
				(justify left)
			)
		)
		(property "Value" ""
			(at 0 0 180)
			(layer "F.Fab")
			(effects
				(font
					(size 1.27 1.27)
				)
			)
		)
		(duplicate_pad_numbers_are_jumpers no)
		(fp_line
			(start 0.7874 0.406146)
			(end -0.7874 0.406146)
			(stroke
				(width 0.1524)
				(type default)
			)
			(layer "F.SilkS")
		)
		(fp_line
			(start 0.7874 -0.406146)
			(end 0.7874 0.406146)
			(stroke
				(width 0.1524)
				(type default)
			)
			(layer "F.SilkS")
		)
		(fp_line
			(start -0.7874 0.406146)
			(end -0.7874 -0.406146)
			(stroke
				(width 0.1524)
				(type default)
			)
			(layer "F.SilkS")
		)
		(fp_line
			(start -0.7874 -0.406146)
			(end 0.7874 -0.406146)
			(stroke
				(width 0.1524)
				(type default)
			)
			(layer "F.SilkS")
		)
		(fp_poly
			(pts
				(xy -0.508 0.2794) (xy -0.508 0.2286) (xy -0.635 0.2286) (xy -0.635 -0.254) (xy -0.5334 -0.254)
				(xy -0.5334 -0.2794) (xy 0.5334 -0.2794) (xy 0.5334 -0.254) (xy 0.635 -0.254) (xy 0.635 0.254) (xy 0.5334 0.254)
				(xy 0.5334 0.2794)
			)
			(stroke
				(width 0)
				(type default)
			)
			(fill no)
			(layer "F.CrtYd")
		)
		(pad "1" smd rect
			(at 0.40005 0 180)
			(size 0.4572 0.508)
			(layers "F.Cu" "F.Mask" "F.Paste")
			(net "CPLD_UART_RTS_P3_R_N")
		)
		(pad "2" smd rect
			(at -0.40005 0 180)
			(size 0.4572 0.508)
			(layers "F.Cu" "F.Mask" "F.Paste")
			(net "CPLD_UART_RTS_P3_N")
		)
	)
	(footprint ""
		(layer "F.Cu")
		(at 119.444262 -156.94152)
		(property "Reference" "C934"
			(at -0.785622 -1.895602 0)
			(unlocked yes)
			(layer "F.SilkS")
			(effects
				(font
					(size 0.635 0.4064)
					(thickness 0.1524)
				)
			)
		)
		(property "Value" ""
			(at 0 0 0)
			(layer "F.Fab")
			(effects
				(font
					(size 1.27 1.27)
				)
			)
		)
		(duplicate_pad_numbers_are_jumpers no)
		(fp_line
			(start -1.2954 -0.5842)
			(end 1.2954 -0.5842)
			(stroke
				(width 0.1524)
				(type default)
			)
			(layer "F.SilkS")
		)
		(fp_line
			(start -1.2954 0.5842)
			(end -1.2954 -0.5842)
			(stroke
				(width 0.1524)
				(type default)
			)
			(layer "F.SilkS")
		)
		(fp_line
			(start 0 -0.5842)
			(end 0 0.5842)
			(stroke
				(width 0.1524)
				(type default)
			)
			(layer "F.SilkS")
		)
		(fp_line
			(start 1.2954 -0.5842)
			(end 1.2954 0.5842)
			(stroke
				(width 0.1524)
				(type default)
			)
			(layer "F.SilkS")
		)
		(fp_line
			(start 1.2954 0.5842)
			(end -1.2954 0.5842)
			(stroke
				(width 0.1524)
				(type default)
			)
			(layer "F.SilkS")
		)
		(fp_poly
			(pts
				(xy 0.8636 -0.4572) (xy 0.8636 -0.3556) (xy 1.143 -0.3556) (xy 1.143 0.3556) (xy 0.8636 0.3556)
				(xy 0.8636 0.4572) (xy -0.8636 0.4572) (xy -0.8636 0.3556) (xy -1.143 0.3556) (xy -1.143 -0.3556)
				(xy -0.8636 -0.3556) (xy -0.8636 -0.4572)
			)
			(stroke
				(width 0)
				(type default)
			)
			(fill no)
			(layer "F.CrtYd")
		)
		(fp_line
			(start -0.884936 -0.504952)
			(end 0.884936 -0.504952)
			(stroke
				(width 0.1)
				(type default)
			)
			(layer "F.Fab")
		)
		(fp_line
			(start -0.884936 0.504952)
			(end -0.884936 -0.504952)
			(stroke
				(width 0.1)
				(type default)
			)
			(layer "F.Fab")
		)
		(fp_line
			(start 0.884936 -0.504952)
			(end 0.884936 0.504952)
			(stroke
				(width 0.1)
				(type default)
			)
			(layer "F.Fab")
		)
		(fp_line
			(start 0.884936 0.504952)
			(end -0.884936 0.504952)
			(stroke
				(width 0.1)
				(type default)
			)
			(layer "F.Fab")
		)
		(pad "1" smd rect
			(at 0.7366 0 90)
			(size 0.7112 0.8128)
			(layers "F.Cu" "F.Mask" "F.Paste")
			(net "GND")
		)
		(pad "2" smd rect
			(at -0.7366 0 90)
			(size 0.7112 0.8128)
			(layers "F.Cu" "F.Mask" "F.Paste")
			(net "N52998261")
		)
	)
	(footprint ""
		(layer "F.Cu")
		(at 159.62376 -185.205624 -90)
		(property "Reference" "R819"
			(at -4.768088 -0.272288 90)
			(unlocked yes)
			(layer "F.SilkS")
			(effects
				(font
					(size 0.7874 0.5842)
					(thickness 0.1524)
				)
				(justify left)
			)
		)
		(property "Value" ""
			(at 0 0 270)
			(layer "F.Fab")
			(effects
				(font
					(size 1.27 1.27)
				)
			)
		)
		(duplicate_pad_numbers_are_jumpers no)
		(fp_line
			(start -0.7874 0.4064)
			(end -0.7874 -0.4064)
			(stroke
				(width 0.1524)
				(type default)
			)
			(layer "F.SilkS")
		)
		(fp_line
			(start 0.7874 0.4064)
			(end -0.7874 0.4064)
			(stroke
				(width 0.1524)
				(type default)
			)
			(layer "F.SilkS")
		)
		(fp_line
			(start -0.7874 -0.4064)
			(end 0.7874 -0.4064)
			(stroke
				(width 0.1524)
				(type default)
			)
			(layer "F.SilkS")
		)
		(fp_line
			(start 0.7874 -0.4064)
			(end 0.7874 0.4064)
			(stroke
				(width 0.1524)
				(type default)
			)
			(layer "F.SilkS")
		)
		(fp_poly
			(pts
				(xy -0.508 0.2794) (xy -0.508 0.2286) (xy -0.635 0.2286) (xy -0.635 -0.254) (xy -0.5334 -0.254)
				(xy -0.5334 -0.2794) (xy 0.5334 -0.2794) (xy 0.5334 -0.254) (xy 0.635 -0.254) (xy 0.635 0.254) (xy 0.5334 0.254)
				(xy 0.5334 0.2794)
			)
			(stroke
				(width 0)
				(type default)
			)
			(fill no)
			(layer "F.CrtYd")
		)
		(pad "1" smd rect
			(at 0.40005 0 270)
			(size 0.4572 0.508)
			(layers "F.Cu" "F.Mask" "F.Paste")
			(net "FAN_PWM")
		)
		(pad "2" smd rect
			(at -0.40005 0 270)
			(size 0.4572 0.508)
			(layers "F.Cu" "F.Mask" "F.Paste")
			(net "FAN_PWM_R")
		)
	)
	(footprint ""
		(layer "F.Cu")
		(at 98.161856 -162.227768 -90)
		(property "Reference" "R655"
			(at 73.441814 -87.743792 90)
			(unlocked yes)
			(layer "F.SilkS")
			(effects
				(font
					(size 0.7874 0.5842)
					(thickness 0.1524)
				)
				(justify left)
			)
		)
		(property "Value" ""
			(at 0 0 270)
			(layer "F.Fab")
			(effects
				(font
					(size 1.27 1.27)
				)
			)
		)
		(duplicate_pad_numbers_are_jumpers no)
		(fp_line
			(start -0.7874 0.4064)
			(end -0.7874 -0.4064)
			(stroke
				(width 0.1524)
				(type default)
			)
			(layer "F.SilkS")
		)
		(fp_line
			(start 0.7874 0.4064)
			(end -0.7874 0.4064)
			(stroke
				(width 0.1524)
				(type default)
			)
			(layer "F.SilkS")
		)
		(fp_line
			(start -0.7874 -0.4064)
			(end 0.7874 -0.4064)
			(stroke
				(width 0.1524)
				(type default)
			)
			(layer "F.SilkS")
		)
		(fp_line
			(start 0.7874 -0.4064)
			(end 0.7874 0.4064)
			(stroke
				(width 0.1524)
				(type default)
			)
			(layer "F.SilkS")
		)
		(fp_poly
			(pts
				(xy -0.508 0.2794) (xy -0.508 0.2286) (xy -0.635 0.2286) (xy -0.635 -0.254) (xy -0.5334 -0.254)
				(xy -0.5334 -0.2794) (xy 0.5334 -0.2794) (xy 0.5334 -0.254) (xy 0.635 -0.254) (xy 0.635 0.254) (xy 0.5334 0.254)
				(xy 0.5334 0.2794)
			)
			(stroke
				(width 0)
				(type default)
			)
			(fill no)
			(layer "F.CrtYd")
		)
		(pad "1" smd rect
			(at 0.40005 0 270)
			(size 0.4572 0.508)
			(layers "F.Cu" "F.Mask" "F.Paste")
			(net "N52411040")
		)
		(pad "2" smd rect
			(at -0.40005 0 270)
			(size 0.4572 0.508)
			(layers "F.Cu" "F.Mask" "F.Paste")
			(net "P12V_AUX")
		)
	)
	(footprint ""
		(layer "F.Cu")
		(at 102.016306 -134.11581 180)
		(property "Reference" "PR46"
			(at 4.393692 8.411972 0)
			(unlocked yes)
			(layer "F.SilkS")
			(effects
				(font
					(size 0.7874 0.5842)
					(thickness 0.1524)
				)
				(justify left)
			)
		)
		(property "Value" ""
			(at 0 0 180)
			(layer "F.Fab")
			(effects
				(font
					(size 1.27 1.27)
				)
			)
		)
		(duplicate_pad_numbers_are_jumpers no)
		(fp_line
			(start 0.7874 0.4064)
			(end -0.7874 0.4064)
			(stroke
				(width 0.1524)
				(type default)
			)
			(layer "F.SilkS")
		)
		(fp_line
			(start 0.7874 -0.4064)
			(end 0.7874 0.4064)
			(stroke
				(width 0.1524)
				(type default)
			)
			(layer "F.SilkS")
		)
		(fp_line
			(start -0.7874 0.4064)
			(end -0.7874 -0.4064)
			(stroke
				(width 0.1524)
				(type default)
			)
			(layer "F.SilkS")
		)
		(fp_line
			(start -0.7874 -0.4064)
			(end 0.7874 -0.4064)
			(stroke
				(width 0.1524)
				(type default)
			)
			(layer "F.SilkS")
		)
		(fp_poly
			(pts
				(xy -0.508 0.2794) (xy -0.508 0.2286) (xy -0.635 0.2286) (xy -0.635 -0.254) (xy -0.5334 -0.254)
				(xy -0.5334 -0.2794) (xy 0.5334 -0.2794) (xy 0.5334 -0.254) (xy 0.635 -0.254) (xy 0.635 0.254) (xy 0.5334 0.254)
				(xy 0.5334 0.2794)
			)
			(stroke
				(width 0)
				(type default)
			)
			(fill no)
			(layer "F.CrtYd")
		)
		(pad "1" smd rect
			(at 0.40005 0 180)
			(size 0.4572 0.508)
			(layers "F.Cu" "F.Mask" "F.Paste")
			(net "SVID_CPU_NODE1_PVCCP_DAT")
		)
		(pad "2" smd rect
			(at -0.40005 0 180)
			(size 0.4572 0.508)
			(layers "F.Cu" "F.Mask" "F.Paste")
			(net "SVID_CPU_NODE1_DAT_R")
		)
	)
	(footprint ""
		(layer "F.Cu")
		(at 125.800104 -50.070512 -90)
		(property "Reference" "C536"
			(at -17.625822 -32.187134 90)
			(unlocked yes)
			(layer "F.SilkS")
			(effects
				(font
					(size 0.7874 0.5842)
					(thickness 0.1524)
				)
				(justify left)
			)
		)
		(property "Value" ""
			(at 0 0 270)
			(layer "F.Fab")
			(effects
				(font
					(size 1.27 1.27)
				)
			)
		)
		(duplicate_pad_numbers_are_jumpers no)
		(fp_line
			(start -0.7874 0.4064)
			(end -0.7874 -0.4064)
			(stroke
				(width 0.1524)
				(type default)
			)
			(layer "F.SilkS")
		)
		(fp_line
			(start 0.7874 0.4064)
			(end -0.7874 0.4064)
			(stroke
				(width 0.1524)
				(type default)
			)
			(layer "F.SilkS")
		)
		(fp_line
			(start 0 0.381)
			(end 0 -0.381)
			(stroke
				(width 0.1524)
				(type default)
			)
			(layer "F.SilkS")
		)
		(fp_line
			(start -0.7874 -0.4064)
			(end 0.7874 -0.4064)
			(stroke
				(width 0.1524)
				(type default)
			)
			(layer "F.SilkS")
		)
		(fp_line
			(start 0.7874 -0.4064)
			(end 0.7874 0.4064)
			(stroke
				(width 0.1524)
				(type default)
			)
			(layer "F.SilkS")
		)
		(fp_poly
			(pts
				(xy -0.5334 0.254) (xy -0.635 0.254) (xy -0.635 0.2286) (xy -0.635 -0.254) (xy -0.5334 -0.254) (xy -0.5334 -0.2794)
				(xy 0.5334 -0.2794) (xy 0.5334 -0.254) (xy 0.635 -0.254) (xy 0.635 0.254) (xy 0.5334 0.254) (xy 0.5334 0.2794)
				(xy -0.508 0.2794) (xy -0.5334 0.2794)
			)
			(stroke
				(width 0)
				(type default)
			)
			(fill no)
			(layer "F.CrtYd")
		)
		(pad "1" smd rect
			(at 0.40005 0 270)
			(size 0.4572 0.508)
			(layers "F.Cu" "F.Mask" "F.Paste")
			(net "P5V_NODE1")
		)
		(pad "2" smd rect
			(at -0.40005 0 270)
			(size 0.4572 0.508)
			(layers "F.Cu" "F.Mask" "F.Paste")
			(net "GND")
		)
	)
	(footprint ""
		(layer "F.Cu")
		(at 130.429 -56.652922 90)
		(property "Reference" "C539"
			(at -0.518922 1.19507 90)
			(unlocked yes)
			(layer "F.SilkS")
			(effects
				(font
					(size 0.7874 0.5842)
					(thickness 0.1524)
				)
				(justify left)
			)
		)
		(property "Value" ""
			(at 0 0 90)
			(layer "F.Fab")
			(effects
				(font
					(size 1.27 1.27)
				)
			)
		)
		(duplicate_pad_numbers_are_jumpers no)
		(fp_line
			(start 0.7874 -0.4064)
			(end 0.7874 0.4064)
			(stroke
				(width 0.1524)
				(type default)
			)
			(layer "F.SilkS")
		)
		(fp_line
			(start -0.7874 -0.4064)
			(end 0.7874 -0.4064)
			(stroke
				(width 0.1524)
				(type default)
			)
			(layer "F.SilkS")
		)
		(fp_line
			(start 0 0.381)
			(end 0 -0.381)
			(stroke
				(width 0.1524)
				(type default)
			)
			(layer "F.SilkS")
		)
		(fp_line
			(start 0.7874 0.4064)
			(end -0.7874 0.4064)
			(stroke
				(width 0.1524)
				(type default)
			)
			(layer "F.SilkS")
		)
		(fp_line
			(start -0.7874 0.4064)
			(end -0.7874 -0.4064)
			(stroke
				(width 0.1524)
				(type default)
			)
			(layer "F.SilkS")
		)
		(fp_poly
			(pts
				(xy -0.5334 0.254) (xy -0.635 0.254) (xy -0.635 0.2286) (xy -0.635 -0.254) (xy -0.5334 -0.254) (xy -0.5334 -0.2794)
				(xy 0.5334 -0.2794) (xy 0.5334 -0.254) (xy 0.635 -0.254) (xy 0.635 0.254) (xy 0.5334 0.254) (xy 0.5334 0.2794)
				(xy -0.508 0.2794) (xy -0.5334 0.2794)
			)
			(stroke
				(width 0)
				(type default)
			)
			(fill no)
			(layer "F.CrtYd")
		)
		(pad "1" smd rect
			(at 0.40005 0 90)
			(size 0.4572 0.508)
			(layers "F.Cu" "F.Mask" "F.Paste")
			(net "P3V3_NODE1")
		)
		(pad "2" smd rect
			(at -0.40005 0 90)
			(size 0.4572 0.508)
			(layers "F.Cu" "F.Mask" "F.Paste")
			(net "GND")
		)
	)
	(footprint ""
		(layer "F.Cu")
		(at 81.95056 -80.683608 -90)
		(property "Reference" "C89"
			(at 17.592294 -1.189482 90)
			(unlocked yes)
			(layer "F.SilkS")
			(effects
				(font
					(size 0.7874 0.5842)
					(thickness 0.1524)
				)
				(justify left)
			)
		)
		(property "Value" ""
			(at 0 0 270)
			(layer "F.Fab")
			(effects
				(font
					(size 1.27 1.27)
				)
			)
		)
		(duplicate_pad_numbers_are_jumpers no)
		(fp_line
			(start -0.7874 0.4064)
			(end -0.7874 -0.4064)
			(stroke
				(width 0.1524)
				(type default)
			)
			(layer "F.SilkS")
		)
		(fp_line
			(start 0.7874 0.4064)
			(end -0.7874 0.4064)
			(stroke
				(width 0.1524)
				(type default)
			)
			(layer "F.SilkS")
		)
		(fp_line
			(start 0 0.381)
			(end 0 -0.381)
			(stroke
				(width 0.1524)
				(type default)
			)
			(layer "F.SilkS")
		)
		(fp_line
			(start -0.7874 -0.4064)
			(end 0.7874 -0.4064)
			(stroke
				(width 0.1524)
				(type default)
			)
			(layer "F.SilkS")
		)
		(fp_line
			(start 0.7874 -0.4064)
			(end 0.7874 0.4064)
			(stroke
				(width 0.1524)
				(type default)
			)
			(layer "F.SilkS")
		)
		(fp_poly
			(pts
				(xy -0.5334 0.254) (xy -0.635 0.254) (xy -0.635 0.2286) (xy -0.635 -0.254) (xy -0.5334 -0.254) (xy -0.5334 -0.2794)
				(xy 0.5334 -0.2794) (xy 0.5334 -0.254) (xy 0.635 -0.254) (xy 0.635 0.254) (xy 0.5334 0.254) (xy 0.5334 0.2794)
				(xy -0.508 0.2794) (xy -0.5334 0.2794)
			)
			(stroke
				(width 0)
				(type default)
			)
			(fill no)
			(layer "F.CrtYd")
		)
		(pad "1" smd rect
			(at 0.40005 0 270)
			(size 0.4572 0.508)
			(layers "F.Cu" "F.Mask" "F.Paste")
			(net "PV_VCCP_NODE1")
		)
		(pad "2" smd rect
			(at -0.40005 0 270)
			(size 0.4572 0.508)
			(layers "F.Cu" "F.Mask" "F.Paste")
			(net "GND")
		)
	)
	(footprint ""
		(layer "F.Cu")
		(at 92.6084 -3.993134 180)
		(property "Reference" "R179"
			(at 1.88722 -1.2954 0)
			(unlocked yes)
			(layer "F.SilkS")
			(effects
				(font
					(size 0.7874 0.5842)
					(thickness 0.1524)
				)
				(justify left)
			)
		)
		(property "Value" ""
			(at 0 0 180)
			(layer "F.Fab")
			(effects
				(font
					(size 1.27 1.27)
				)
			)
		)
		(duplicate_pad_numbers_are_jumpers no)
		(fp_line
			(start 0.7874 0.4064)
			(end -0.7874 0.4064)
			(stroke
				(width 0.1524)
				(type default)
			)
			(layer "F.SilkS")
		)
		(fp_line
			(start 0.7874 -0.4064)
			(end 0.7874 0.4064)
			(stroke
				(width 0.1524)
				(type default)
			)
			(layer "F.SilkS")
		)
		(fp_line
			(start -0.7874 0.4064)
			(end -0.7874 -0.4064)
			(stroke
				(width 0.1524)
				(type default)
			)
			(layer "F.SilkS")
		)
		(fp_line
			(start -0.7874 -0.4064)
			(end 0.7874 -0.4064)
			(stroke
				(width 0.1524)
				(type default)
			)
			(layer "F.SilkS")
		)
		(fp_poly
			(pts
				(xy -0.508 0.2794) (xy -0.508 0.2286) (xy -0.635 0.2286) (xy -0.635 -0.254) (xy -0.5334 -0.254)
				(xy -0.5334 -0.2794) (xy 0.5334 -0.2794) (xy 0.5334 -0.254) (xy 0.635 -0.254) (xy 0.635 0.254) (xy 0.5334 0.254)
				(xy 0.5334 0.2794)
			)
			(stroke
				(width 0)
				(type default)
			)
			(fill no)
			(layer "F.CrtYd")
		)
		(pad "1" smd rect
			(at 0.40005 0 180)
			(size 0.4572 0.508)
			(layers "F.Cu" "F.Mask" "F.Paste")
			(net "IRQ_CPU_NODE1_SERIAL")
		)
		(pad "2" smd rect
			(at -0.40005 0 180)
			(size 0.4572 0.508)
			(layers "F.Cu" "F.Mask" "F.Paste")
			(net "TPM_LPC_SERIRQ_PORT80_NODE1")
		)
	)
	(footprint ""
		(layer "F.Cu")
		(at 164.271198 -161.395918 90)
		(property "Reference" "R580"
			(at -8.091678 17.572736 90)
			(unlocked yes)
			(layer "F.SilkS")
			(effects
				(font
					(size 0.7874 0.5842)
					(thickness 0.1524)
				)
				(justify left)
			)
		)
		(property "Value" ""
			(at 0 0 90)
			(layer "F.Fab")
			(effects
				(font
					(size 1.27 1.27)
				)
			)
		)
		(duplicate_pad_numbers_are_jumpers no)
		(fp_line
			(start 0.7874 -0.4064)
			(end 0.7874 0.4064)
			(stroke
				(width 0.1524)
				(type default)
			)
			(layer "F.SilkS")
		)
		(fp_line
			(start -0.7874 -0.4064)
			(end 0.7874 -0.4064)
			(stroke
				(width 0.1524)
				(type default)
			)
			(layer "F.SilkS")
		)
		(fp_line
			(start 0.7874 0.4064)
			(end -0.7874 0.4064)
			(stroke
				(width 0.1524)
				(type default)
			)
			(layer "F.SilkS")
		)
		(fp_line
			(start -0.7874 0.4064)
			(end -0.7874 -0.4064)
			(stroke
				(width 0.1524)
				(type default)
			)
			(layer "F.SilkS")
		)
		(fp_poly
			(pts
				(xy -0.508 0.2794) (xy -0.508 0.2286) (xy -0.635 0.2286) (xy -0.635 -0.254) (xy -0.5334 -0.254)
				(xy -0.5334 -0.2794) (xy 0.5334 -0.2794) (xy 0.5334 -0.254) (xy 0.635 -0.254) (xy 0.635 0.254) (xy 0.5334 0.254)
				(xy 0.5334 0.2794)
			)
			(stroke
				(width 0)
				(type default)
			)
			(fill no)
			(layer "F.CrtYd")
		)
		(pad "1" smd rect
			(at 0.40005 0 90)
			(size 0.4572 0.508)
			(layers "F.Cu" "F.Mask" "F.Paste")
			(net "P3V3_NODE1")
		)
		(pad "2" smd rect
			(at -0.40005 0 90)
			(size 0.4572 0.508)
			(layers "F.Cu" "F.Mask" "F.Paste")
			(net "LAN2_NC_SI_RXD1")
		)
	)
	(footprint ""
		(layer "F.Cu")
		(at 108.721906 -140.341096 90)
		(property "Reference" "PR65"
			(at 2.647696 4.129532 90)
			(unlocked yes)
			(layer "F.SilkS")
			(effects
				(font
					(size 0.635 0.4064)
					(thickness 0.1524)
				)
				(justify left)
			)
		)
		(property "Value" ""
			(at 0 0 90)
			(layer "F.Fab")
			(effects
				(font
					(size 1.27 1.27)
				)
			)
		)
		(duplicate_pad_numbers_are_jumpers no)
		(fp_line
			(start 0.7874 -0.4064)
			(end 0.7874 0.4064)
			(stroke
				(width 0.1524)
				(type default)
			)
			(layer "F.SilkS")
		)
		(fp_line
			(start -0.7874 -0.4064)
			(end 0.7874 -0.4064)
			(stroke
				(width 0.1524)
				(type default)
			)
			(layer "F.SilkS")
		)
		(fp_line
			(start 0.7874 0.4064)
			(end -0.7874 0.4064)
			(stroke
				(width 0.1524)
				(type default)
			)
			(layer "F.SilkS")
		)
		(fp_line
			(start -0.7874 0.4064)
			(end -0.7874 -0.4064)
			(stroke
				(width 0.1524)
				(type default)
			)
			(layer "F.SilkS")
		)
		(fp_poly
			(pts
				(xy -0.508 0.2794) (xy -0.508 0.2286) (xy -0.635 0.2286) (xy -0.635 -0.254) (xy -0.5334 -0.254)
				(xy -0.5334 -0.2794) (xy 0.5334 -0.2794) (xy 0.5334 -0.254) (xy 0.635 -0.254) (xy 0.635 0.254) (xy 0.5334 0.254)
				(xy 0.5334 0.2794)
			)
			(stroke
				(width 0)
				(type default)
			)
			(fill no)
			(layer "F.CrtYd")
		)
		(pad "1" smd rect
			(at 0.40005 0 90)
			(size 0.4572 0.508)
			(layers "F.Cu" "F.Mask" "F.Paste")
			(net "AGND_PVCCP_NODE1")
		)
		(pad "2" smd rect
			(at -0.40005 0 90)
			(size 0.4572 0.508)
			(layers "F.Cu" "F.Mask" "F.Paste")
			(net "VR_PVCCP_NODE1_ICCMAX")
		)
	)
	(footprint ""
		(layer "F.Cu")
		(at 106.066844 -139.786868 180)
		(property "Reference" "PR76"
			(at 1.291844 3.15214 0)
			(unlocked yes)
			(layer "F.SilkS")
			(effects
				(font
					(size 0.635 0.4064)
					(thickness 0.1524)
				)
				(justify left)
			)
		)
		(property "Value" ""
			(at 0 0 180)
			(layer "F.Fab")
			(effects
				(font
					(size 1.27 1.27)
				)
			)
		)
		(duplicate_pad_numbers_are_jumpers no)
		(fp_line
			(start 0.7874 0.4064)
			(end -0.7874 0.4064)
			(stroke
				(width 0.1524)
				(type default)
			)
			(layer "F.SilkS")
		)
		(fp_line
			(start 0.7874 -0.4064)
			(end 0.7874 0.4064)
			(stroke
				(width 0.1524)
				(type default)
			)
			(layer "F.SilkS")
		)
		(fp_line
			(start -0.7874 0.4064)
			(end -0.7874 -0.4064)
			(stroke
				(width 0.1524)
				(type default)
			)
			(layer "F.SilkS")
		)
		(fp_line
			(start -0.7874 -0.4064)
			(end 0.7874 -0.4064)
			(stroke
				(width 0.1524)
				(type default)
			)
			(layer "F.SilkS")
		)
		(fp_poly
			(pts
				(xy -0.508 0.2794) (xy -0.508 0.2286) (xy -0.635 0.2286) (xy -0.635 -0.254) (xy -0.5334 -0.254)
				(xy -0.5334 -0.2794) (xy 0.5334 -0.2794) (xy 0.5334 -0.254) (xy 0.635 -0.254) (xy 0.635 0.254) (xy 0.5334 0.254)
				(xy 0.5334 0.2794)
			)
			(stroke
				(width 0)
				(type default)
			)
			(fill no)
			(layer "F.CrtYd")
		)
		(pad "1" smd rect
			(at 0.40005 0 180)
			(size 0.4572 0.508)
			(layers "F.Cu" "F.Mask" "F.Paste")
			(net "VR_PVCCP_NODE1_VCC")
		)
		(pad "2" smd rect
			(at -0.40005 0 180)
			(size 0.4572 0.508)
			(layers "F.Cu" "F.Mask" "F.Paste")
			(net "VR_PVCCP_NODE1_OCSET")
		)
	)
	(footprint ""
		(layer "F.Cu")
		(at 152.545796 -60.01893)
		(property "Reference" "R503"
			(at -1.094994 -1.79451 0)
			(unlocked yes)
			(layer "F.SilkS")
			(effects
				(font
					(size 0.7874 0.5842)
					(thickness 0.1524)
				)
				(justify left)
			)
		)
		(property "Value" ""
			(at 0 0 0)
			(layer "F.Fab")
			(effects
				(font
					(size 1.27 1.27)
				)
			)
		)
		(duplicate_pad_numbers_are_jumpers no)
		(fp_line
			(start -0.7874 -0.4064)
			(end 0.7874 -0.4064)
			(stroke
				(width 0.1524)
				(type default)
			)
			(layer "F.SilkS")
		)
		(fp_line
			(start -0.7874 0.4064)
			(end -0.7874 -0.4064)
			(stroke
				(width 0.1524)
				(type default)
			)
			(layer "F.SilkS")
		)
		(fp_line
			(start 0.7874 -0.4064)
			(end 0.7874 0.4064)
			(stroke
				(width 0.1524)
				(type default)
			)
			(layer "F.SilkS")
		)
		(fp_line
			(start 0.7874 0.4064)
			(end -0.7874 0.4064)
			(stroke
				(width 0.1524)
				(type default)
			)
			(layer "F.SilkS")
		)
		(fp_poly
			(pts
				(xy -0.508 0.2794) (xy -0.508 0.2286) (xy -0.635 0.2286) (xy -0.635 -0.254) (xy -0.5334 -0.254)
				(xy -0.5334 -0.2794) (xy 0.5334 -0.2794) (xy 0.5334 -0.254) (xy 0.635 -0.254) (xy 0.635 0.254) (xy 0.5334 0.254)
				(xy 0.5334 0.2794)
			)
			(stroke
				(width 0)
				(type default)
			)
			(fill no)
			(layer "F.CrtYd")
		)
		(pad "1" smd rect
			(at 0.40005 0)
			(size 0.4572 0.508)
			(layers "F.Cu" "F.Mask" "F.Paste")
			(net "GND")
		)
		(pad "2" smd rect
			(at -0.40005 0)
			(size 0.4572 0.508)
			(layers "F.Cu" "F.Mask" "F.Paste")
			(net "NODE1_USB_TESTMODE")
		)
	)
	(footprint ""
		(layer "F.Cu")
		(at 32.022288 -123.274582 90)
		(property "Reference" "C827"
			(at -2.647442 1.365758 90)
			(unlocked yes)
			(layer "F.SilkS")
			(effects
				(font
					(size 0.7874 0.5842)
					(thickness 0.1524)
				)
				(justify left)
			)
		)
		(property "Value" ""
			(at 0 0 90)
			(layer "F.Fab")
			(effects
				(font
					(size 1.27 1.27)
				)
			)
		)
		(duplicate_pad_numbers_are_jumpers no)
		(fp_line
			(start 0.7874 -0.4064)
			(end 0.7874 0.4064)
			(stroke
				(width 0.1524)
				(type default)
			)
			(layer "F.SilkS")
		)
		(fp_line
			(start -0.7874 -0.4064)
			(end 0.7874 -0.4064)
			(stroke
				(width 0.1524)
				(type default)
			)
			(layer "F.SilkS")
		)
		(fp_line
			(start 0 0.381)
			(end 0 -0.381)
			(stroke
				(width 0.1524)
				(type default)
			)
			(layer "F.SilkS")
		)
		(fp_line
			(start 0.7874 0.4064)
			(end -0.7874 0.4064)
			(stroke
				(width 0.1524)
				(type default)
			)
			(layer "F.SilkS")
		)
		(fp_line
			(start -0.7874 0.4064)
			(end -0.7874 -0.4064)
			(stroke
				(width 0.1524)
				(type default)
			)
			(layer "F.SilkS")
		)
		(fp_poly
			(pts
				(xy -0.5334 0.254) (xy -0.635 0.254) (xy -0.635 0.2286) (xy -0.635 -0.254) (xy -0.5334 -0.254) (xy -0.5334 -0.2794)
				(xy 0.5334 -0.2794) (xy 0.5334 -0.254) (xy 0.635 -0.254) (xy 0.635 0.254) (xy 0.5334 0.254) (xy 0.5334 0.2794)
				(xy -0.508 0.2794) (xy -0.5334 0.2794)
			)
			(stroke
				(width 0)
				(type default)
			)
			(fill no)
			(layer "F.CrtYd")
		)
		(pad "1" smd rect
			(at 0.40005 0 90)
			(size 0.4572 0.508)
			(layers "F.Cu" "F.Mask" "F.Paste")
			(net "P5V_STB_NODE1")
		)
		(pad "2" smd rect
			(at -0.40005 0 90)
			(size 0.4572 0.508)
			(layers "F.Cu" "F.Mask" "F.Paste")
			(net "GND")
		)
	)
	(footprint ""
		(layer "F.Cu")
		(at 184.7596 -175.4632 180)
		(property "Reference" "R1313"
			(at -9.9568 -17.40027 0)
			(unlocked yes)
			(layer "F.SilkS")
			(effects
				(font
					(size 0.7874 0.5842)
					(thickness 0.1524)
				)
				(justify left)
			)
		)
		(property "Value" ""
			(at 0 0 180)
			(layer "F.Fab")
			(effects
				(font
					(size 1.27 1.27)
				)
			)
		)
		(duplicate_pad_numbers_are_jumpers no)
		(fp_line
			(start 0.7874 0.4064)
			(end -0.7874 0.4064)
			(stroke
				(width 0.1524)
				(type default)
			)
			(layer "F.SilkS")
		)
		(fp_line
			(start 0.7874 -0.4064)
			(end 0.7874 0.4064)
			(stroke
				(width 0.1524)
				(type default)
			)
			(layer "F.SilkS")
		)
		(fp_line
			(start -0.7874 0.4064)
			(end -0.7874 -0.4064)
			(stroke
				(width 0.1524)
				(type default)
			)
			(layer "F.SilkS")
		)
		(fp_line
			(start -0.7874 -0.4064)
			(end 0.7874 -0.4064)
			(stroke
				(width 0.1524)
				(type default)
			)
			(layer "F.SilkS")
		)
		(fp_poly
			(pts
				(xy -0.508 0.2794) (xy -0.508 0.2286) (xy -0.635 0.2286) (xy -0.635 -0.254) (xy -0.5334 -0.254)
				(xy -0.5334 -0.2794) (xy 0.5334 -0.2794) (xy 0.5334 -0.254) (xy 0.635 -0.254) (xy 0.635 0.254) (xy 0.5334 0.254)
				(xy 0.5334 0.2794)
			)
			(stroke
				(width 0)
				(type default)
			)
			(fill no)
			(layer "F.CrtYd")
		)
		(pad "1" smd rect
			(at 0.40005 0 180)
			(size 0.4572 0.508)
			(layers "F.Cu" "F.Mask" "F.Paste")
			(net "POWER_SW2_PWR_CTR_12V")
		)
		(pad "2" smd rect
			(at -0.40005 0 180)
			(size 0.4572 0.508)
			(layers "F.Cu" "F.Mask" "F.Paste")
			(net "POWER_SW2_PWR_CTR_12V_R")
		)
	)
	(footprint ""
		(layer "F.Cu")
		(at 85.518752 -137.008362 90)
		(property "Reference" "R1096"
			(at 2.537714 4.13639 90)
			(unlocked yes)
			(layer "F.SilkS")
			(effects
				(font
					(size 0.7874 0.5842)
					(thickness 0.1524)
				)
				(justify left)
			)
		)
		(property "Value" ""
			(at 0 0 90)
			(layer "F.Fab")
			(effects
				(font
					(size 1.27 1.27)
				)
			)
		)
		(duplicate_pad_numbers_are_jumpers no)
		(fp_line
			(start 0.7874 -0.4064)
			(end 0.7874 0.4064)
			(stroke
				(width 0.1524)
				(type default)
			)
			(layer "F.SilkS")
		)
		(fp_line
			(start -0.7874 -0.4064)
			(end 0.7874 -0.4064)
			(stroke
				(width 0.1524)
				(type default)
			)
			(layer "F.SilkS")
		)
		(fp_line
			(start 0.7874 0.4064)
			(end -0.7874 0.4064)
			(stroke
				(width 0.1524)
				(type default)
			)
			(layer "F.SilkS")
		)
		(fp_line
			(start -0.7874 0.4064)
			(end -0.7874 -0.4064)
			(stroke
				(width 0.1524)
				(type default)
			)
			(layer "F.SilkS")
		)
		(fp_poly
			(pts
				(xy -0.508 0.2794) (xy -0.508 0.2286) (xy -0.635 0.2286) (xy -0.635 -0.254) (xy -0.5334 -0.254)
				(xy -0.5334 -0.2794) (xy 0.5334 -0.2794) (xy 0.5334 -0.254) (xy 0.635 -0.254) (xy 0.635 0.254) (xy 0.5334 0.254)
				(xy 0.5334 0.2794)
			)
			(stroke
				(width 0)
				(type default)
			)
			(fill no)
			(layer "F.CrtYd")
		)
		(pad "1" smd rect
			(at 0.40005 0 90)
			(size 0.4572 0.508)
			(layers "F.Cu" "F.Mask" "F.Paste")
			(net "PWRGD_NODE1_P1V26_BMC_PG")
		)
		(pad "2" smd rect
			(at -0.40005 0 90)
			(size 0.4572 0.508)
			(layers "F.Cu" "F.Mask" "F.Paste")
			(net "P3V3_STB_NODE1")
		)
	)
	(footprint ""
		(layer "F.Cu")
		(at 142.173452 -56.523382 180)
		(property "Reference" "R804"
			(at 1.742948 1.290066 0)
			(unlocked yes)
			(layer "F.SilkS")
			(effects
				(font
					(size 0.7874 0.5842)
					(thickness 0.1524)
				)
				(justify left)
			)
		)
		(property "Value" ""
			(at 0 0 180)
			(layer "F.Fab")
			(effects
				(font
					(size 1.27 1.27)
				)
			)
		)
		(duplicate_pad_numbers_are_jumpers no)
		(fp_line
			(start 1.905 0.8636)
			(end -1.905 0.8636)
			(stroke
				(width 0.1524)
				(type default)
			)
			(layer "F.SilkS")
		)
		(fp_line
			(start 1.905 -0.8636)
			(end 1.905 0.8636)
			(stroke
				(width 0.1524)
				(type default)
			)
			(layer "F.SilkS")
		)
		(fp_line
			(start -1.905 0.8636)
			(end -1.905 -0.8636)
			(stroke
				(width 0.1524)
				(type default)
			)
			(layer "F.SilkS")
		)
		(fp_line
			(start -1.905 -0.8636)
			(end 1.905 -0.8636)
			(stroke
				(width 0.1524)
				(type default)
			)
			(layer "F.SilkS")
		)
		(fp_poly
			(pts
				(xy 1.524 0.6858) (xy 1.524 -0.6858) (xy 1.524 -0.7366) (xy -1.524 -0.7366) (xy -1.524 -0.6858)
				(xy -1.524 0.6858) (xy -1.524 0.7366) (xy 1.524 0.7366)
			)
			(stroke
				(width 0)
				(type default)
			)
			(fill no)
			(layer "F.CrtYd")
		)
		(pad "1" smd rect
			(at 0.94996 0 180)
			(size 1.1176 1.3716)
			(layers "F.Cu" "F.Mask" "F.Paste")
			(net "P1V0_NODE1")
		)
		(pad "2" smd rect
			(at -0.94996 0 180)
			(size 1.1176 1.3716)
			(layers "F.Cu" "F.Mask" "F.Paste")
			(net "P1V0_SATA")
		)
	)
	(footprint ""
		(layer "F.Cu")
		(at 174.646336 -61.50991 180)
		(property "Reference" "U54"
			(at -2.29108 0.04191 90)
			(unlocked yes)
			(layer "F.SilkS")
			(effects
				(font
					(size 0.7874 0.5842)
					(thickness 0.1524)
				)
			)
		)
		(property "Value" ""
			(at 0 0 180)
			(layer "F.Fab")
			(effects
				(font
					(size 1.27 1.27)
				)
			)
		)
		(duplicate_pad_numbers_are_jumpers no)
		(fp_line
			(start 1.549908 2.032)
			(end -1.549908 2.032)
			(stroke
				(width 0.1524)
				(type default)
			)
			(layer "F.SilkS")
		)
		(fp_line
			(start 1.549908 -2.032)
			(end 1.549908 2.032)
			(stroke
				(width 0.1524)
				(type default)
			)
			(layer "F.SilkS")
		)
		(fp_line
			(start -1.549908 2.032)
			(end -1.549908 -2.032)
			(stroke
				(width 0.1524)
				(type default)
			)
			(layer "F.SilkS")
		)
		(fp_line
			(start -1.549908 -2.032)
			(end 1.549908 -2.032)
			(stroke
				(width 0.1524)
				(type default)
			)
			(layer "F.SilkS")
		)
		(fp_poly
			(pts
				(xy -0.94996 2.4765) (xy -1.33096 3.6195) (xy -0.56896 3.6195)
			)
			(stroke
				(width 0)
				(type default)
			)
			(fill yes)
			(layer "F.SilkS")
		)
		(fp_poly
			(pts
				(xy -1.1684 1.905) (xy -1.1684 0.8636) (xy -1.5494 0.8636) (xy -1.5494 -0.8636) (xy -1.1684 -0.8636)
				(xy -1.1684 -1.905) (xy 1.1684 -1.905) (xy 1.1684 -0.8636) (xy 1.5494 -0.8636) (xy 1.5494 0.8636)
				(xy 1.1684 0.8636) (xy 1.1684 1.905)
			)
			(stroke
				(width 0)
				(type default)
			)
			(fill no)
			(layer "F.CrtYd")
		)
		(pad "1" smd rect
			(at -0.94996 1.225042 180)
			(size 0.4064 1.3208)
			(layers "F.Cu" "F.Mask" "F.Paste")
			(net "USB3_L_DN")
		)
		(pad "2" smd rect
			(at 0 1.225042 180)
			(size 0.4064 1.3208)
			(layers "F.Cu" "F.Mask" "F.Paste")
			(net "GND")
		)
		(pad "3" smd rect
			(at 0.94996 1.225042 180)
			(size 0.4064 1.3208)
			(layers "F.Cu" "F.Mask" "F.Paste")
			(net "USB3_L_DP")
		)
		(pad "4" smd rect
			(at 0.94996 -1.225042 180)
			(size 0.4064 1.3208)
			(layers "F.Cu" "F.Mask" "F.Paste")
			(net "USB2_L_DP")
		)
		(pad "5" smd rect
			(at 0 -1.225042 180)
			(size 0.4064 1.3208)
			(layers "F.Cu" "F.Mask" "F.Paste")
			(net "USBPWR_P1")
		)
		(pad "6" smd rect
			(at -0.94996 -1.225042 180)
			(size 0.4064 1.3208)
			(layers "F.Cu" "F.Mask" "F.Paste")
			(net "USB2_L_DN")
		)
	)
	(footprint ""
		(layer "F.Cu")
		(at 168.509442 -156.827474)
		(property "Reference" "R582"
			(at -0.455422 2.314448 0)
			(unlocked yes)
			(layer "F.SilkS")
			(effects
				(font
					(size 0.7874 0.5842)
					(thickness 0.1524)
				)
				(justify left)
			)
		)
		(property "Value" ""
			(at 0 0 0)
			(layer "F.Fab")
			(effects
				(font
					(size 1.27 1.27)
				)
			)
		)
		(duplicate_pad_numbers_are_jumpers no)
		(fp_line
			(start -0.7874 -0.4064)
			(end 0.7874 -0.4064)
			(stroke
				(width 0.1524)
				(type default)
			)
			(layer "F.SilkS")
		)
		(fp_line
			(start -0.7874 0.4064)
			(end -0.7874 -0.4064)
			(stroke
				(width 0.1524)
				(type default)
			)
			(layer "F.SilkS")
		)
		(fp_line
			(start 0.7874 -0.4064)
			(end 0.7874 0.4064)
			(stroke
				(width 0.1524)
				(type default)
			)
			(layer "F.SilkS")
		)
		(fp_line
			(start 0.7874 0.4064)
			(end -0.7874 0.4064)
			(stroke
				(width 0.1524)
				(type default)
			)
			(layer "F.SilkS")
		)
		(fp_poly
			(pts
				(xy -0.508 0.2794) (xy -0.508 0.2286) (xy -0.635 0.2286) (xy -0.635 -0.254) (xy -0.5334 -0.254)
				(xy -0.5334 -0.2794) (xy 0.5334 -0.2794) (xy 0.5334 -0.254) (xy 0.635 -0.254) (xy 0.635 0.254) (xy 0.5334 0.254)
				(xy 0.5334 0.2794)
			)
			(stroke
				(width 0)
				(type default)
			)
			(fill no)
			(layer "F.CrtYd")
		)
		(pad "1" smd rect
			(at 0.40005 0)
			(size 0.4572 0.508)
			(layers "F.Cu" "F.Mask" "F.Paste")
			(net "GND")
		)
		(pad "2" smd rect
			(at -0.40005 0)
			(size 0.4572 0.508)
			(layers "F.Cu" "F.Mask" "F.Paste")
			(net "LAN2_DIS_REG10")
		)
	)
	(footprint ""
		(layer "F.Cu")
		(at 144.916652 -144.20215)
		(property "Reference" "R276"
			(at -0.704088 18.585688 0)
			(unlocked yes)
			(layer "F.SilkS")
			(effects
				(font
					(size 0.7874 0.5842)
					(thickness 0.1524)
				)
				(justify left)
			)
		)
		(property "Value" ""
			(at 0 0 0)
			(layer "F.Fab")
			(effects
				(font
					(size 1.27 1.27)
				)
			)
		)
		(duplicate_pad_numbers_are_jumpers no)
		(fp_line
			(start -0.7874 -0.4064)
			(end 0.7874 -0.4064)
			(stroke
				(width 0.1524)
				(type default)
			)
			(layer "F.SilkS")
		)
		(fp_line
			(start -0.7874 0.4064)
			(end -0.7874 -0.4064)
			(stroke
				(width 0.1524)
				(type default)
			)
			(layer "F.SilkS")
		)
		(fp_line
			(start 0.7874 -0.4064)
			(end 0.7874 0.4064)
			(stroke
				(width 0.1524)
				(type default)
			)
			(layer "F.SilkS")
		)
		(fp_line
			(start 0.7874 0.4064)
			(end -0.7874 0.4064)
			(stroke
				(width 0.1524)
				(type default)
			)
			(layer "F.SilkS")
		)
		(fp_poly
			(pts
				(xy -0.508 0.2794) (xy -0.508 0.2286) (xy -0.635 0.2286) (xy -0.635 -0.254) (xy -0.5334 -0.254)
				(xy -0.5334 -0.2794) (xy 0.5334 -0.2794) (xy 0.5334 -0.254) (xy 0.635 -0.254) (xy 0.635 0.254) (xy 0.5334 0.254)
				(xy 0.5334 0.2794)
			)
			(stroke
				(width 0)
				(type default)
			)
			(fill no)
			(layer "F.CrtYd")
		)
		(pad "1" smd rect
			(at 0.40005 0)
			(size 0.4572 0.508)
			(layers "F.Cu" "F.Mask" "F.Paste")
			(net "GND")
		)
		(pad "2" smd rect
			(at -0.40005 0)
			(size 0.4572 0.508)
			(layers "F.Cu" "F.Mask" "F.Paste")
			(net "PCIE_SW_PWR_SAV")
		)
	)
	(footprint ""
		(layer "F.Cu")
		(at 189.849506 -164.457888 -90)
		(property "Reference" "C541"
			(at 1.80086 -1.553464 90)
			(unlocked yes)
			(layer "F.SilkS")
			(effects
				(font
					(size 0.7874 0.5842)
					(thickness 0.1524)
				)
				(justify left)
			)
		)
		(property "Value" ""
			(at 0 0 270)
			(layer "F.Fab")
			(effects
				(font
					(size 1.27 1.27)
				)
			)
		)
		(duplicate_pad_numbers_are_jumpers no)
		(fp_line
			(start -2.2098 0.9398)
			(end -2.2098 -0.9398)
			(stroke
				(width 0.1524)
				(type default)
			)
			(layer "F.SilkS")
		)
		(fp_line
			(start 2.2098 0.9398)
			(end -2.2098 0.9398)
			(stroke
				(width 0.1524)
				(type default)
			)
			(layer "F.SilkS")
		)
		(fp_line
			(start -2.2098 -0.9398)
			(end 2.2098 -0.9398)
			(stroke
				(width 0.1524)
				(type default)
			)
			(layer "F.SilkS")
		)
		(fp_line
			(start 0 -0.9398)
			(end 0 0.9398)
			(stroke
				(width 0.1524)
				(type default)
			)
			(layer "F.SilkS")
		)
		(fp_line
			(start 2.2098 -0.9398)
			(end 2.2098 0.9398)
			(stroke
				(width 0.1524)
				(type default)
			)
			(layer "F.SilkS")
		)
		(fp_poly
			(pts
				(xy -1.6764 0.889) (xy -1.6764 0.7874) (xy -2.0574 0.7874) (xy -2.0574 -0.7874) (xy -1.6764 -0.7874)
				(xy -1.6764 -0.889) (xy -1.6764 -0.9398) (xy 1.6764 -0.9398) (xy 1.6764 -0.889) (xy 1.6764 -0.7874)
				(xy 2.0574 -0.7874) (xy 2.0574 0.7874) (xy 1.6764 0.7874) (xy 1.6764 0.889) (xy 1.6764 0.9398) (xy -1.6764 0.9398)
			)
			(stroke
				(width 0)
				(type default)
			)
			(fill no)
			(layer "F.CrtYd")
		)
		(pad "1" smd rect
			(at 1.4732 0 270)
			(size 1.1684 1.5748)
			(layers "F.Cu" "F.Mask" "F.Paste")
			(net "N54134271")
		)
		(pad "2" smd rect
			(at -1.4732 0 270)
			(size 1.1684 1.5748)
			(layers "F.Cu" "F.Mask" "F.Paste")
			(net "GND")
		)
	)
	(footprint ""
		(layer "F.Cu")
		(at 118.15191 -152.31364 180)
		(property "Reference" "U111"
			(at 4.17703 -1.70561 0)
			(unlocked yes)
			(layer "F.SilkS")
			(effects
				(font
					(size 0.635 0.4064)
					(thickness 0.1524)
				)
			)
		)
		(property "Value" ""
			(at 0 0 180)
			(layer "F.Fab")
			(effects
				(font
					(size 1.27 1.27)
				)
			)
		)
		(duplicate_pad_numbers_are_jumpers no)
		(fp_line
			(start 1.651 1.905)
			(end -1.651 1.905)
			(stroke
				(width 0.1524)
				(type default)
			)
			(layer "F.SilkS")
		)
		(fp_line
			(start 1.651 -1.905)
			(end 1.651 1.905)
			(stroke
				(width 0.1524)
				(type default)
			)
			(layer "F.SilkS")
		)
		(fp_line
			(start -1.651 1.905)
			(end -1.651 -1.905)
			(stroke
				(width 0.1524)
				(type default)
			)
			(layer "F.SilkS")
		)
		(fp_line
			(start -1.651 -1.905)
			(end 1.651 -1.905)
			(stroke
				(width 0.1524)
				(type default)
			)
			(layer "F.SilkS")
		)
		(fp_poly
			(pts
				(xy -1.524 0.7112) (xy -1.524 1.7526) (xy -0.508 1.7526) (xy -0.508 0.6985) (xy 0.508 0.6985) (xy 0.508 1.7526)
				(xy 1.524 1.7526) (xy 1.524 0.6985) (xy 1.524 -0.6985) (xy 0.508 -0.6985) (xy 0.508 -1.7526) (xy -0.508 -1.7526)
				(xy -0.508 -0.6985) (xy -1.524 -0.6985) (xy -1.524 0.6985)
			)
			(stroke
				(width 0)
				(type default)
			)
			(fill no)
			(layer "F.CrtYd")
		)
		(fp_text user "S"
			(at 2.032 1.23825 180)
			(unlocked yes)
			(layer "F.SilkS")
			(effects
				(font
					(size 0.635 0.4064)
					(thickness 0.1524)
				)
			)
		)
		(fp_text user "D"
			(at 1.96215 -1.274826 0)
			(unlocked yes)
			(layer "F.SilkS")
			(effects
				(font
					(size 0.635 0.4064)
					(thickness 0.1524)
				)
			)
		)
		(fp_text user "G"
			(at -0.0762 1.159256 180)
			(unlocked yes)
			(layer "F.SilkS")
			(effects
				(font
					(size 0.635 0.4064)
					(thickness 0.1524)
				)
			)
		)
		(pad "D" smd rect
			(at 0 -1.1176 180)
			(size 1.016 1.27)
			(layers "F.Cu" "F.Mask" "F.Paste")
			(net "N52998343")
		)
		(pad "G" smd rect
			(at -1.016 1.1176 180)
			(size 1.016 1.27)
			(layers "F.Cu" "F.Mask" "F.Paste")
			(net "N52998261")
		)
		(pad "S" smd rect
			(at 1.016 1.1176 180)
			(size 1.016 1.27)
			(layers "F.Cu" "F.Mask" "F.Paste")
			(net "GND")
		)
	)
	(footprint ""
		(layer "F.Cu")
		(at 137.779252 -154.79395 90)
		(property "Reference" "R287"
			(at -110.765082 -61.245496 90)
			(unlocked yes)
			(layer "F.SilkS")
			(effects
				(font
					(size 0.7874 0.5842)
					(thickness 0.1524)
				)
				(justify left)
			)
		)
		(property "Value" ""
			(at 0 0 90)
			(layer "F.Fab")
			(effects
				(font
					(size 1.27 1.27)
				)
			)
		)
		(duplicate_pad_numbers_are_jumpers no)
		(fp_line
			(start 0.7874 -0.4064)
			(end 0.7874 0.4064)
			(stroke
				(width 0.1524)
				(type default)
			)
			(layer "F.SilkS")
		)
		(fp_line
			(start -0.7874 -0.4064)
			(end 0.7874 -0.4064)
			(stroke
				(width 0.1524)
				(type default)
			)
			(layer "F.SilkS")
		)
		(fp_line
			(start 0.7874 0.4064)
			(end -0.7874 0.4064)
			(stroke
				(width 0.1524)
				(type default)
			)
			(layer "F.SilkS")
		)
		(fp_line
			(start -0.7874 0.4064)
			(end -0.7874 -0.4064)
			(stroke
				(width 0.1524)
				(type default)
			)
			(layer "F.SilkS")
		)
		(fp_poly
			(pts
				(xy -0.508 0.2794) (xy -0.508 0.2286) (xy -0.635 0.2286) (xy -0.635 -0.254) (xy -0.5334 -0.254)
				(xy -0.5334 -0.2794) (xy 0.5334 -0.2794) (xy 0.5334 -0.254) (xy 0.635 -0.254) (xy 0.635 0.254) (xy 0.5334 0.254)
				(xy 0.5334 0.2794)
			)
			(stroke
				(width 0)
				(type default)
			)
			(fill no)
			(layer "F.CrtYd")
		)
		(pad "1" smd rect
			(at 0.40005 0 90)
			(size 0.4572 0.508)
			(layers "F.Cu" "F.Mask" "F.Paste")
			(net "GND")
		)
		(pad "2" smd rect
			(at -0.40005 0 90)
			(size 0.4572 0.508)
			(layers "F.Cu" "F.Mask" "F.Paste")
			(net "PCIE_SW_TEST7")
		)
	)
	(footprint ""
		(layer "F.Cu")
		(at 191.369442 -113.419128 180)
		(property "Reference" "C781"
			(at -1.483614 -0.120142 0)
			(unlocked yes)
			(layer "F.SilkS")
			(effects
				(font
					(size 0.7874 0.5842)
					(thickness 0.1524)
				)
				(justify left)
			)
		)
		(property "Value" ""
			(at 0 0 180)
			(layer "F.Fab")
			(effects
				(font
					(size 1.27 1.27)
				)
			)
		)
		(duplicate_pad_numbers_are_jumpers no)
		(fp_line
			(start 0.7874 0.4064)
			(end -0.7874 0.4064)
			(stroke
				(width 0.1524)
				(type default)
			)
			(layer "F.SilkS")
		)
		(fp_line
			(start 0.7874 -0.4064)
			(end 0.7874 0.4064)
			(stroke
				(width 0.1524)
				(type default)
			)
			(layer "F.SilkS")
		)
		(fp_line
			(start 0 0.381)
			(end 0 -0.381)
			(stroke
				(width 0.1524)
				(type default)
			)
			(layer "F.SilkS")
		)
		(fp_line
			(start -0.7874 0.4064)
			(end -0.7874 -0.4064)
			(stroke
				(width 0.1524)
				(type default)
			)
			(layer "F.SilkS")
		)
		(fp_line
			(start -0.7874 -0.4064)
			(end 0.7874 -0.4064)
			(stroke
				(width 0.1524)
				(type default)
			)
			(layer "F.SilkS")
		)
		(fp_poly
			(pts
				(xy -0.5334 0.254) (xy -0.635 0.254) (xy -0.635 0.2286) (xy -0.635 -0.254) (xy -0.5334 -0.254) (xy -0.5334 -0.2794)
				(xy 0.5334 -0.2794) (xy 0.5334 -0.254) (xy 0.635 -0.254) (xy 0.635 0.254) (xy 0.5334 0.254) (xy 0.5334 0.2794)
				(xy -0.508 0.2794) (xy -0.5334 0.2794)
			)
			(stroke
				(width 0)
				(type default)
			)
			(fill no)
			(layer "F.CrtYd")
		)
		(pad "1" smd rect
			(at 0.40005 0 180)
			(size 0.4572 0.508)
			(layers "F.Cu" "F.Mask" "F.Paste")
			(net "P12V_NODE1_PWRGD_EN")
		)
		(pad "2" smd rect
			(at -0.40005 0 180)
			(size 0.4572 0.508)
			(layers "F.Cu" "F.Mask" "F.Paste")
			(net "GND")
		)
	)
	(footprint ""
		(layer "F.Cu")
		(at 79.963518 -86.974172)
		(property "Reference" "R112"
			(at -1.195578 19.010376 0)
			(unlocked yes)
			(layer "F.SilkS")
			(effects
				(font
					(size 0.7874 0.5842)
					(thickness 0.1524)
				)
				(justify left)
			)
		)
		(property "Value" ""
			(at 0 0 0)
			(layer "F.Fab")
			(effects
				(font
					(size 1.27 1.27)
				)
			)
		)
		(duplicate_pad_numbers_are_jumpers no)
		(fp_line
			(start -0.7874 -0.4064)
			(end 0.7874 -0.4064)
			(stroke
				(width 0.1524)
				(type default)
			)
			(layer "F.SilkS")
		)
		(fp_line
			(start -0.7874 0.4064)
			(end -0.7874 -0.4064)
			(stroke
				(width 0.1524)
				(type default)
			)
			(layer "F.SilkS")
		)
		(fp_line
			(start 0.7874 -0.4064)
			(end 0.7874 0.4064)
			(stroke
				(width 0.1524)
				(type default)
			)
			(layer "F.SilkS")
		)
		(fp_line
			(start 0.7874 0.4064)
			(end -0.7874 0.4064)
			(stroke
				(width 0.1524)
				(type default)
			)
			(layer "F.SilkS")
		)
		(fp_poly
			(pts
				(xy -0.508 0.2794) (xy -0.508 0.2286) (xy -0.635 0.2286) (xy -0.635 -0.254) (xy -0.5334 -0.254)
				(xy -0.5334 -0.2794) (xy 0.5334 -0.2794) (xy 0.5334 -0.254) (xy 0.635 -0.254) (xy 0.635 0.254) (xy 0.5334 0.254)
				(xy 0.5334 0.2794)
			)
			(stroke
				(width 0)
				(type default)
			)
			(fill no)
			(layer "F.CrtYd")
		)
		(pad "1" smd rect
			(at 0.40005 0)
			(size 0.4572 0.508)
			(layers "F.Cu" "F.Mask" "F.Paste")
			(net "P3V3_SUS_NODE1")
		)
		(pad "2" smd rect
			(at -0.40005 0)
			(size 0.4572 0.508)
			(layers "F.Cu" "F.Mask" "F.Paste")
			(net "SPI_CPU_NODE1_WP_R_L")
		)
	)
	(footprint ""
		(layer "F.Cu")
		(at 139.68476 -108.370624 90)
		(property "Reference" "R10"
			(at -6.585204 0.524002 90)
			(unlocked yes)
			(layer "F.SilkS")
			(effects
				(font
					(size 0.7874 0.5842)
					(thickness 0.1524)
				)
				(justify left)
			)
		)
		(property "Value" ""
			(at 0 0 90)
			(layer "F.Fab")
			(effects
				(font
					(size 1.27 1.27)
				)
			)
		)
		(duplicate_pad_numbers_are_jumpers no)
		(fp_line
			(start 0.7874 -0.4064)
			(end 0.7874 0.4064)
			(stroke
				(width 0.1524)
				(type default)
			)
			(layer "F.SilkS")
		)
		(fp_line
			(start -0.7874 -0.4064)
			(end 0.7874 -0.4064)
			(stroke
				(width 0.1524)
				(type default)
			)
			(layer "F.SilkS")
		)
		(fp_line
			(start 0.7874 0.4064)
			(end -0.7874 0.4064)
			(stroke
				(width 0.1524)
				(type default)
			)
			(layer "F.SilkS")
		)
		(fp_line
			(start -0.7874 0.4064)
			(end -0.7874 -0.4064)
			(stroke
				(width 0.1524)
				(type default)
			)
			(layer "F.SilkS")
		)
		(fp_poly
			(pts
				(xy -0.508 0.2794) (xy -0.508 0.2286) (xy -0.635 0.2286) (xy -0.635 -0.254) (xy -0.5334 -0.254)
				(xy -0.5334 -0.2794) (xy 0.5334 -0.2794) (xy 0.5334 -0.254) (xy 0.635 -0.254) (xy 0.635 0.254) (xy 0.5334 0.254)
				(xy 0.5334 0.2794)
			)
			(stroke
				(width 0)
				(type default)
			)
			(fill no)
			(layer "F.CrtYd")
		)
		(pad "1" smd rect
			(at 0.40005 0 90)
			(size 0.4572 0.508)
			(layers "F.Cu" "F.Mask" "F.Paste")
			(net "CLK_14M_CPU_NODE1_R")
		)
		(pad "2" smd rect
			(at -0.40005 0 90)
			(size 0.4572 0.508)
			(layers "F.Cu" "F.Mask" "F.Paste")
			(net "CLK_14M_CPU_NODE1")
		)
	)
	(footprint ""
		(layer "F.Cu")
		(at 126.22657 -26.569416 -90)
		(property "Reference" "R1143"
			(at 5.325618 -0.028448 90)
			(unlocked yes)
			(layer "F.SilkS")
			(effects
				(font
					(size 0.7874 0.5842)
					(thickness 0.1524)
				)
				(justify left)
			)
		)
		(property "Value" ""
			(at 0 0 270)
			(layer "F.Fab")
			(effects
				(font
					(size 1.27 1.27)
				)
			)
		)
		(duplicate_pad_numbers_are_jumpers no)
		(fp_line
			(start -0.7874 0.4064)
			(end -0.7874 -0.4064)
			(stroke
				(width 0.1524)
				(type default)
			)
			(layer "F.SilkS")
		)
		(fp_line
			(start 0.7874 0.4064)
			(end -0.7874 0.4064)
			(stroke
				(width 0.1524)
				(type default)
			)
			(layer "F.SilkS")
		)
		(fp_line
			(start -0.7874 -0.4064)
			(end 0.7874 -0.4064)
			(stroke
				(width 0.1524)
				(type default)
			)
			(layer "F.SilkS")
		)
		(fp_line
			(start 0.7874 -0.4064)
			(end 0.7874 0.4064)
			(stroke
				(width 0.1524)
				(type default)
			)
			(layer "F.SilkS")
		)
		(fp_poly
			(pts
				(xy -0.508 0.2794) (xy -0.508 0.2286) (xy -0.635 0.2286) (xy -0.635 -0.254) (xy -0.5334 -0.254)
				(xy -0.5334 -0.2794) (xy 0.5334 -0.2794) (xy 0.5334 -0.254) (xy 0.635 -0.254) (xy 0.635 0.254) (xy 0.5334 0.254)
				(xy 0.5334 0.2794)
			)
			(stroke
				(width 0)
				(type default)
			)
			(fill no)
			(layer "F.CrtYd")
		)
		(pad "1" smd rect
			(at 0.40005 0 270)
			(size 0.4572 0.508)
			(layers "F.Cu" "F.Mask" "F.Paste")
			(net "P3V3_STB_NODE1")
		)
		(pad "2" smd rect
			(at -0.40005 0 270)
			(size 0.4572 0.508)
			(layers "F.Cu" "F.Mask" "F.Paste")
			(net "SIO_PIN72")
		)
	)
	(footprint ""
		(layer "F.Cu")
		(at 79.457296 -98.917252 90)
		(property "Reference" "C795"
			(at 4.889754 -0.33528 90)
			(unlocked yes)
			(layer "F.SilkS")
			(effects
				(font
					(size 0.7874 0.5842)
					(thickness 0.1524)
				)
				(justify left)
			)
		)
		(property "Value" ""
			(at 0 0 90)
			(layer "F.Fab")
			(effects
				(font
					(size 1.27 1.27)
				)
			)
		)
		(duplicate_pad_numbers_are_jumpers no)
		(fp_line
			(start 0.7874 -0.4064)
			(end 0.7874 0.4064)
			(stroke
				(width 0.1524)
				(type default)
			)
			(layer "F.SilkS")
		)
		(fp_line
			(start -0.7874 -0.4064)
			(end 0.7874 -0.4064)
			(stroke
				(width 0.1524)
				(type default)
			)
			(layer "F.SilkS")
		)
		(fp_line
			(start 0 0.381)
			(end 0 -0.381)
			(stroke
				(width 0.1524)
				(type default)
			)
			(layer "F.SilkS")
		)
		(fp_line
			(start 0.7874 0.4064)
			(end -0.7874 0.4064)
			(stroke
				(width 0.1524)
				(type default)
			)
			(layer "F.SilkS")
		)
		(fp_line
			(start -0.7874 0.4064)
			(end -0.7874 -0.4064)
			(stroke
				(width 0.1524)
				(type default)
			)
			(layer "F.SilkS")
		)
		(fp_poly
			(pts
				(xy -0.5334 0.254) (xy -0.635 0.254) (xy -0.635 0.2286) (xy -0.635 -0.254) (xy -0.5334 -0.254) (xy -0.5334 -0.2794)
				(xy 0.5334 -0.2794) (xy 0.5334 -0.254) (xy 0.635 -0.254) (xy 0.635 0.254) (xy 0.5334 0.254) (xy 0.5334 0.2794)
				(xy -0.508 0.2794) (xy -0.5334 0.2794)
			)
			(stroke
				(width 0)
				(type default)
			)
			(fill no)
			(layer "F.CrtYd")
		)
		(pad "1" smd rect
			(at 0.40005 0 90)
			(size 0.4572 0.508)
			(layers "F.Cu" "F.Mask" "F.Paste")
			(net "P3V3_STB_NODE1")
		)
		(pad "2" smd rect
			(at -0.40005 0 90)
			(size 0.4572 0.508)
			(layers "F.Cu" "F.Mask" "F.Paste")
			(net "GND")
		)
	)
	(footprint ""
		(layer "F.Cu")
		(at 125.536452 -153.67635 90)
		(property "Reference" "R295"
			(at -111.020352 -58.8264 90)
			(unlocked yes)
			(layer "F.SilkS")
			(effects
				(font
					(size 0.7874 0.5842)
					(thickness 0.1524)
				)
				(justify left)
			)
		)
		(property "Value" ""
			(at 0 0 90)
			(layer "F.Fab")
			(effects
				(font
					(size 1.27 1.27)
				)
			)
		)
		(duplicate_pad_numbers_are_jumpers no)
		(fp_line
			(start 0.7874 -0.4064)
			(end 0.7874 0.4064)
			(stroke
				(width 0.1524)
				(type default)
			)
			(layer "F.SilkS")
		)
		(fp_line
			(start -0.7874 -0.4064)
			(end 0.7874 -0.4064)
			(stroke
				(width 0.1524)
				(type default)
			)
			(layer "F.SilkS")
		)
		(fp_line
			(start 0.7874 0.4064)
			(end -0.7874 0.4064)
			(stroke
				(width 0.1524)
				(type default)
			)
			(layer "F.SilkS")
		)
		(fp_line
			(start -0.7874 0.4064)
			(end -0.7874 -0.4064)
			(stroke
				(width 0.1524)
				(type default)
			)
			(layer "F.SilkS")
		)
		(fp_poly
			(pts
				(xy -0.508 0.2794) (xy -0.508 0.2286) (xy -0.635 0.2286) (xy -0.635 -0.254) (xy -0.5334 -0.254)
				(xy -0.5334 -0.2794) (xy 0.5334 -0.2794) (xy 0.5334 -0.254) (xy 0.635 -0.254) (xy 0.635 0.254) (xy 0.5334 0.254)
				(xy 0.5334 0.2794)
			)
			(stroke
				(width 0)
				(type default)
			)
			(fill no)
			(layer "F.CrtYd")
		)
		(pad "1" smd rect
			(at 0.40005 0 90)
			(size 0.4572 0.508)
			(layers "F.Cu" "F.Mask" "F.Paste")
			(net "GND")
		)
		(pad "2" smd rect
			(at -0.40005 0 90)
			(size 0.4572 0.508)
			(layers "F.Cu" "F.Mask" "F.Paste")
			(net "PCIE_SW_TRST")
		)
	)
	(footprint ""
		(layer "F.Cu")
		(at 118.47576 -185.205624 90)
		(property "Reference" "C748"
			(at 4.768088 0.393192 90)
			(unlocked yes)
			(layer "F.SilkS")
			(effects
				(font
					(size 0.7874 0.5842)
					(thickness 0.1524)
				)
				(justify left)
			)
		)
		(property "Value" ""
			(at 0 0 90)
			(layer "F.Fab")
			(effects
				(font
					(size 1.27 1.27)
				)
			)
		)
		(duplicate_pad_numbers_are_jumpers no)
		(fp_line
			(start 0.7874 -0.4064)
			(end 0.7874 0.4064)
			(stroke
				(width 0.1524)
				(type default)
			)
			(layer "F.SilkS")
		)
		(fp_line
			(start -0.7874 -0.4064)
			(end 0.7874 -0.4064)
			(stroke
				(width 0.1524)
				(type default)
			)
			(layer "F.SilkS")
		)
		(fp_line
			(start 0 0.381)
			(end 0 -0.381)
			(stroke
				(width 0.1524)
				(type default)
			)
			(layer "F.SilkS")
		)
		(fp_line
			(start 0.7874 0.4064)
			(end -0.7874 0.4064)
			(stroke
				(width 0.1524)
				(type default)
			)
			(layer "F.SilkS")
		)
		(fp_line
			(start -0.7874 0.4064)
			(end -0.7874 -0.4064)
			(stroke
				(width 0.1524)
				(type default)
			)
			(layer "F.SilkS")
		)
		(fp_poly
			(pts
				(xy -0.5334 0.254) (xy -0.635 0.254) (xy -0.635 0.2286) (xy -0.635 -0.254) (xy -0.5334 -0.254) (xy -0.5334 -0.2794)
				(xy 0.5334 -0.2794) (xy 0.5334 -0.254) (xy 0.635 -0.254) (xy 0.635 0.254) (xy 0.5334 0.254) (xy 0.5334 0.2794)
				(xy -0.508 0.2794) (xy -0.5334 0.2794)
			)
			(stroke
				(width 0)
				(type default)
			)
			(fill no)
			(layer "F.CrtYd")
		)
		(pad "1" smd rect
			(at 0.40005 0 90)
			(size 0.4572 0.508)
			(layers "F.Cu" "F.Mask" "F.Paste")
			(net "UART_T8_NODE2_RXD")
		)
		(pad "2" smd rect
			(at -0.40005 0 90)
			(size 0.4572 0.508)
			(layers "F.Cu" "F.Mask" "F.Paste")
			(net "GND")
		)
	)
	(footprint ""
		(layer "F.Cu")
		(at 126.415292 -58.62828)
		(property "Reference" "R1162"
			(at -5.701538 -0.84074 0)
			(unlocked yes)
			(layer "F.SilkS")
			(effects
				(font
					(size 0.7874 0.5842)
					(thickness 0.1524)
				)
				(justify left)
			)
		)
		(property "Value" ""
			(at 0 0 0)
			(layer "F.Fab")
			(effects
				(font
					(size 1.27 1.27)
				)
			)
		)
		(duplicate_pad_numbers_are_jumpers no)
		(fp_line
			(start -0.7874 -0.4064)
			(end 0.7874 -0.4064)
			(stroke
				(width 0.1524)
				(type default)
			)
			(layer "F.SilkS")
		)
		(fp_line
			(start -0.7874 0.4064)
			(end -0.7874 -0.4064)
			(stroke
				(width 0.1524)
				(type default)
			)
			(layer "F.SilkS")
		)
		(fp_line
			(start 0.7874 -0.4064)
			(end 0.7874 0.4064)
			(stroke
				(width 0.1524)
				(type default)
			)
			(layer "F.SilkS")
		)
		(fp_line
			(start 0.7874 0.4064)
			(end -0.7874 0.4064)
			(stroke
				(width 0.1524)
				(type default)
			)
			(layer "F.SilkS")
		)
		(fp_poly
			(pts
				(xy -0.508 0.2794) (xy -0.508 0.2286) (xy -0.635 0.2286) (xy -0.635 -0.254) (xy -0.5334 -0.254)
				(xy -0.5334 -0.2794) (xy 0.5334 -0.2794) (xy 0.5334 -0.254) (xy 0.635 -0.254) (xy 0.635 0.254) (xy 0.5334 0.254)
				(xy 0.5334 0.2794)
			)
			(stroke
				(width 0)
				(type default)
			)
			(fill no)
			(layer "F.CrtYd")
		)
		(pad "1" smd rect
			(at 0.40005 0)
			(size 0.4572 0.508)
			(layers "F.Cu" "F.Mask" "F.Paste")
			(net "UART_TX_P4_BUF")
		)
		(pad "2" smd rect
			(at -0.40005 0)
			(size 0.4572 0.508)
			(layers "F.Cu" "F.Mask" "F.Paste")
			(net "GND")
		)
	)
	(footprint ""
		(layer "F.Cu")
		(at 151.62276 -185.205624 90)
		(property "Reference" "C744"
			(at 4.768088 0.250952 90)
			(unlocked yes)
			(layer "F.SilkS")
			(effects
				(font
					(size 0.7874 0.5842)
					(thickness 0.1524)
				)
				(justify left)
			)
		)
		(property "Value" ""
			(at 0 0 90)
			(layer "F.Fab")
			(effects
				(font
					(size 1.27 1.27)
				)
			)
		)
		(duplicate_pad_numbers_are_jumpers no)
		(fp_line
			(start 0.7874 -0.4064)
			(end 0.7874 0.4064)
			(stroke
				(width 0.1524)
				(type default)
			)
			(layer "F.SilkS")
		)
		(fp_line
			(start -0.7874 -0.4064)
			(end 0.7874 -0.4064)
			(stroke
				(width 0.1524)
				(type default)
			)
			(layer "F.SilkS")
		)
		(fp_line
			(start 0 0.381)
			(end 0 -0.381)
			(stroke
				(width 0.1524)
				(type default)
			)
			(layer "F.SilkS")
		)
		(fp_line
			(start 0.7874 0.4064)
			(end -0.7874 0.4064)
			(stroke
				(width 0.1524)
				(type default)
			)
			(layer "F.SilkS")
		)
		(fp_line
			(start -0.7874 0.4064)
			(end -0.7874 -0.4064)
			(stroke
				(width 0.1524)
				(type default)
			)
			(layer "F.SilkS")
		)
		(fp_poly
			(pts
				(xy -0.5334 0.254) (xy -0.635 0.254) (xy -0.635 0.2286) (xy -0.635 -0.254) (xy -0.5334 -0.254) (xy -0.5334 -0.2794)
				(xy 0.5334 -0.2794) (xy 0.5334 -0.254) (xy 0.635 -0.254) (xy 0.635 0.254) (xy 0.5334 0.254) (xy 0.5334 0.2794)
				(xy -0.508 0.2794) (xy -0.5334 0.2794)
			)
			(stroke
				(width 0)
				(type default)
			)
			(fill no)
			(layer "F.CrtYd")
		)
		(pad "1" smd rect
			(at 0.40005 0 90)
			(size 0.4572 0.508)
			(layers "F.Cu" "F.Mask" "F.Paste")
			(net "UART_T12_NODE1_RXD")
		)
		(pad "2" smd rect
			(at -0.40005 0 90)
			(size 0.4572 0.508)
			(layers "F.Cu" "F.Mask" "F.Paste")
			(net "GND")
		)
	)
	(footprint ""
		(layer "F.Cu")
		(at 104.660446 -18.264124 180)
		(property "Reference" "C141"
			(at -1.324864 -1.218946 0)
			(unlocked yes)
			(layer "F.SilkS")
			(effects
				(font
					(size 0.7874 0.5842)
					(thickness 0.1524)
				)
			)
		)
		(property "Value" ""
			(at 0 0 180)
			(layer "F.Fab")
			(effects
				(font
					(size 1.27 1.27)
				)
			)
		)
		(duplicate_pad_numbers_are_jumpers no)
		(fp_line
			(start 1.2954 0.5842)
			(end -1.2954 0.5842)
			(stroke
				(width 0.1524)
				(type default)
			)
			(layer "F.SilkS")
		)
		(fp_line
			(start 1.2954 -0.5842)
			(end 1.2954 0.5842)
			(stroke
				(width 0.1524)
				(type default)
			)
			(layer "F.SilkS")
		)
		(fp_line
			(start 0 -0.5842)
			(end 0 0.5842)
			(stroke
				(width 0.1524)
				(type default)
			)
			(layer "F.SilkS")
		)
		(fp_line
			(start -1.2954 0.5842)
			(end -1.2954 -0.5842)
			(stroke
				(width 0.1524)
				(type default)
			)
			(layer "F.SilkS")
		)
		(fp_line
			(start -1.2954 -0.5842)
			(end 1.2954 -0.5842)
			(stroke
				(width 0.1524)
				(type default)
			)
			(layer "F.SilkS")
		)
		(fp_poly
			(pts
				(xy 0.8636 -0.4572) (xy 0.8636 -0.3556) (xy 1.143 -0.3556) (xy 1.143 0.3556) (xy 0.8636 0.3556)
				(xy 0.8636 0.4572) (xy -0.8636 0.4572) (xy -0.8636 0.3556) (xy -1.143 0.3556) (xy -1.143 -0.3556)
				(xy -0.8636 -0.3556) (xy -0.8636 -0.4572)
			)
			(stroke
				(width 0)
				(type default)
			)
			(fill no)
			(layer "F.CrtYd")
		)
		(fp_line
			(start 0.884936 0.504952)
			(end -0.884936 0.504952)
			(stroke
				(width 0.1)
				(type default)
			)
			(layer "F.Fab")
		)
		(fp_line
			(start 0.884936 -0.504952)
			(end 0.884936 0.504952)
			(stroke
				(width 0.1)
				(type default)
			)
			(layer "F.Fab")
		)
		(fp_line
			(start -0.884936 0.504952)
			(end -0.884936 -0.504952)
			(stroke
				(width 0.1)
				(type default)
			)
			(layer "F.Fab")
		)
		(fp_line
			(start -0.884936 -0.504952)
			(end 0.884936 -0.504952)
			(stroke
				(width 0.1)
				(type default)
			)
			(layer "F.Fab")
		)
		(pad "1" smd rect
			(at 0.7366 0 270)
			(size 0.7112 0.8128)
			(layers "F.Cu" "F.Mask" "F.Paste")
			(net "PV_VTT_DDR_NODE1")
		)
		(pad "2" smd rect
			(at -0.7366 0 270)
			(size 0.7112 0.8128)
			(layers "F.Cu" "F.Mask" "F.Paste")
			(net "GND")
		)
	)
	(footprint ""
		(layer "F.Cu")
		(at 149.57806 -30.946344)
		(property "Reference" "C530"
			(at -1.312164 2.11709 0)
			(unlocked yes)
			(layer "F.SilkS")
			(effects
				(font
					(size 0.7874 0.5842)
					(thickness 0.1524)
				)
				(justify left)
			)
		)
		(property "Value" ""
			(at 0 0 0)
			(layer "F.Fab")
			(effects
				(font
					(size 1.27 1.27)
				)
			)
		)
		(duplicate_pad_numbers_are_jumpers no)
		(fp_line
			(start -0.7874 -0.4064)
			(end 0.7874 -0.4064)
			(stroke
				(width 0.1524)
				(type default)
			)
			(layer "F.SilkS")
		)
		(fp_line
			(start -0.7874 0.4064)
			(end -0.7874 -0.4064)
			(stroke
				(width 0.1524)
				(type default)
			)
			(layer "F.SilkS")
		)
		(fp_line
			(start 0 0.381)
			(end 0 -0.381)
			(stroke
				(width 0.1524)
				(type default)
			)
			(layer "F.SilkS")
		)
		(fp_line
			(start 0.7874 -0.4064)
			(end 0.7874 0.4064)
			(stroke
				(width 0.1524)
				(type default)
			)
			(layer "F.SilkS")
		)
		(fp_line
			(start 0.7874 0.4064)
			(end -0.7874 0.4064)
			(stroke
				(width 0.1524)
				(type default)
			)
			(layer "F.SilkS")
		)
		(fp_poly
			(pts
				(xy -0.5334 0.254) (xy -0.635 0.254) (xy -0.635 0.2286) (xy -0.635 -0.254) (xy -0.5334 -0.254) (xy -0.5334 -0.2794)
				(xy 0.5334 -0.2794) (xy 0.5334 -0.254) (xy 0.635 -0.254) (xy 0.635 0.254) (xy 0.5334 0.254) (xy 0.5334 0.2794)
				(xy -0.508 0.2794) (xy -0.5334 0.2794)
			)
			(stroke
				(width 0)
				(type default)
			)
			(fill no)
			(layer "F.CrtYd")
		)
		(pad "1" smd rect
			(at 0.40005 0)
			(size 0.4572 0.508)
			(layers "F.Cu" "F.Mask" "F.Paste")
			(net "P3V3_NODE1")
		)
		(pad "2" smd rect
			(at -0.40005 0)
			(size 0.4572 0.508)
			(layers "F.Cu" "F.Mask" "F.Paste")
			(net "GND")
		)
	)
	(footprint ""
		(layer "F.Cu")
		(at 148.79447 -51.893724 90)
		(property "Reference" "C496"
			(at 17.456658 27.329892 90)
			(unlocked yes)
			(layer "F.SilkS")
			(effects
				(font
					(size 0.7874 0.5842)
					(thickness 0.1524)
				)
			)
		)
		(property "Value" ""
			(at 0 0 90)
			(layer "F.Fab")
			(effects
				(font
					(size 1.27 1.27)
				)
			)
		)
		(duplicate_pad_numbers_are_jumpers no)
		(fp_line
			(start 1.2954 -0.5842)
			(end 1.2954 0.5842)
			(stroke
				(width 0.1524)
				(type default)
			)
			(layer "F.SilkS")
		)
		(fp_line
			(start 0 -0.5842)
			(end 0 0.5842)
			(stroke
				(width 0.1524)
				(type default)
			)
			(layer "F.SilkS")
		)
		(fp_line
			(start -1.2954 -0.5842)
			(end 1.2954 -0.5842)
			(stroke
				(width 0.1524)
				(type default)
			)
			(layer "F.SilkS")
		)
		(fp_line
			(start 1.2954 0.5842)
			(end -1.2954 0.5842)
			(stroke
				(width 0.1524)
				(type default)
			)
			(layer "F.SilkS")
		)
		(fp_line
			(start -1.2954 0.5842)
			(end -1.2954 -0.5842)
			(stroke
				(width 0.1524)
				(type default)
			)
			(layer "F.SilkS")
		)
		(fp_poly
			(pts
				(xy 0.8636 -0.4572) (xy 0.8636 -0.3556) (xy 1.143 -0.3556) (xy 1.143 0.3556) (xy 0.8636 0.3556)
				(xy 0.8636 0.4572) (xy -0.8636 0.4572) (xy -0.8636 0.3556) (xy -1.143 0.3556) (xy -1.143 -0.3556)
				(xy -0.8636 -0.3556) (xy -0.8636 -0.4572)
			)
			(stroke
				(width 0)
				(type default)
			)
			(fill no)
			(layer "F.CrtYd")
		)
		(fp_line
			(start 0.884936 -0.504952)
			(end 0.884936 0.504952)
			(stroke
				(width 0.1)
				(type default)
			)
			(layer "F.Fab")
		)
		(fp_line
			(start -0.884936 -0.504952)
			(end 0.884936 -0.504952)
			(stroke
				(width 0.1)
				(type default)
			)
			(layer "F.Fab")
		)
		(fp_line
			(start 0.884936 0.504952)
			(end -0.884936 0.504952)
			(stroke
				(width 0.1)
				(type default)
			)
			(layer "F.Fab")
		)
		(fp_line
			(start -0.884936 0.504952)
			(end -0.884936 -0.504952)
			(stroke
				(width 0.1)
				(type default)
			)
			(layer "F.Fab")
		)
		(pad "1" smd rect
			(at 0.7366 0 180)
			(size 0.7112 0.8128)
			(layers "F.Cu" "F.Mask" "F.Paste")
			(net "SATA_P7")
		)
		(pad "2" smd rect
			(at -0.7366 0 180)
			(size 0.7112 0.8128)
			(layers "F.Cu" "F.Mask" "F.Paste")
			(net "GND")
		)
	)
	(footprint ""
		(layer "F.Cu")
		(at 51.748182 -173.527466 180)
		(property "Reference" "U85"
			(at 3.621278 -133.039612 90)
			(unlocked yes)
			(layer "F.SilkS")
			(effects
				(font
					(size 0.7874 0.5842)
					(thickness 0.1524)
				)
				(justify left)
			)
		)
		(property "Value" ""
			(at 0 0 180)
			(layer "F.Fab")
			(effects
				(font
					(size 1.27 1.27)
				)
			)
		)
		(duplicate_pad_numbers_are_jumpers no)
		(fp_line
			(start 1.549908 2.032)
			(end -1.549908 2.032)
			(stroke
				(width 0.1524)
				(type default)
			)
			(layer "F.SilkS")
		)
		(fp_line
			(start 1.549908 -2.032)
			(end 1.549908 2.032)
			(stroke
				(width 0.1524)
				(type default)
			)
			(layer "F.SilkS")
		)
		(fp_line
			(start -1.549908 2.032)
			(end -1.549908 -2.032)
			(stroke
				(width 0.1524)
				(type default)
			)
			(layer "F.SilkS")
		)
		(fp_line
			(start -1.549908 -2.032)
			(end 1.549908 -2.032)
			(stroke
				(width 0.1524)
				(type default)
			)
			(layer "F.SilkS")
		)
		(fp_poly
			(pts
				(xy -2.9464 1.016) (xy -2.9464 1.524) (xy -2.1844 1.27)
			)
			(stroke
				(width 0)
				(type default)
			)
			(fill yes)
			(layer "F.SilkS")
		)
		(fp_poly
			(pts
				(xy -1.549908 0.849884) (xy -1.2319 0.849884) (xy -1.2319 1.9431) (xy -1.1811 1.9431) (xy 1.1811 1.9431)
				(xy 1.2319 1.9431) (xy 1.2319 0.849884) (xy 1.549908 0.849884) (xy 1.549908 -0.849884) (xy 1.2319 -0.849884)
				(xy 1.2319 -1.9431) (xy 1.1811 -1.9431) (xy -1.1811 -1.9431) (xy -1.2319 -1.9431) (xy -1.2319 -0.849884)
				(xy -1.549908 -0.849884)
			)
			(stroke
				(width 0)
				(type default)
			)
			(fill no)
			(layer "F.CrtYd")
		)
		(fp_line
			(start 1.549908 0.849884)
			(end 1.549908 -0.849884)
			(stroke
				(width 0.1)
				(type default)
			)
			(layer "F.Fab")
		)
		(fp_line
			(start 1.549908 -0.849884)
			(end -1.549908 -0.849884)
			(stroke
				(width 0.1)
				(type default)
			)
			(layer "F.Fab")
		)
		(fp_line
			(start -1.549908 0.849884)
			(end 1.549908 0.849884)
			(stroke
				(width 0.1)
				(type default)
			)
			(layer "F.Fab")
		)
		(fp_line
			(start -1.549908 -0.849884)
			(end -1.549908 0.849884)
			(stroke
				(width 0.1)
				(type default)
			)
			(layer "F.Fab")
		)
		(fp_text user "3"
			(at 1.21793 2.684526 0)
			(unlocked yes)
			(layer "F.SilkS")
			(effects
				(font
					(size 0.635 0.4064)
					(thickness 0.1524)
				)
				(justify left)
			)
		)
		(fp_text user "4"
			(at 0.991108 -2.59334 0)
			(unlocked yes)
			(layer "F.SilkS")
			(effects
				(font
					(size 0.635 0.4064)
					(thickness 0.1524)
				)
				(justify left)
			)
		)
		(fp_text user "1"
			(at -0.14224 2.492248 0)
			(unlocked yes)
			(layer "F.SilkS")
			(effects
				(font
					(size 0.635 0.4064)
					(thickness 0.1524)
				)
				(justify left)
			)
		)
		(fp_text user "5"
			(at -1.83261 -2.563368 0)
			(unlocked yes)
			(layer "F.SilkS")
			(effects
				(font
					(size 0.635 0.4064)
					(thickness 0.1524)
				)
				(justify left)
			)
		)
		(pad "1" smd rect
			(at -0.94996 1.225042 180)
			(size 0.4572 1.3208)
			(layers "F.Cu" "F.Mask" "F.Paste")
			(net "Net_1706")
		)
		(pad "2" smd rect
			(at 0 1.225042 180)
			(size 0.4572 1.3208)
			(layers "F.Cu" "F.Mask" "F.Paste")
			(net "PSU5_DC_OK_R_BUF")
		)
		(pad "3" smd rect
			(at 0.94996 1.225042 180)
			(size 0.4572 1.3208)
			(layers "F.Cu" "F.Mask" "F.Paste")
			(net "GND")
		)
		(pad "4" smd rect
			(at 0.94996 -1.225042 180)
			(size 0.4572 1.3208)
			(layers "F.Cu" "F.Mask" "F.Paste")
			(net "PSU5_DC_OK")
		)
		(pad "5" smd rect
			(at -0.94996 -1.225042 180)
			(size 0.4572 1.3208)
			(layers "F.Cu" "F.Mask" "F.Paste")
			(net "P3V3_NODE1")
		)
	)
	(footprint ""
		(layer "F.Cu")
		(at 135.255 -51.435 90)
		(property "Reference" "R614"
			(at 16.3576 30.65907 90)
			(unlocked yes)
			(layer "F.SilkS")
			(effects
				(font
					(size 0.7874 0.5842)
					(thickness 0.1524)
				)
				(justify left)
			)
		)
		(property "Value" ""
			(at 0 0 90)
			(layer "F.Fab")
			(effects
				(font
					(size 1.27 1.27)
				)
			)
		)
		(duplicate_pad_numbers_are_jumpers no)
		(fp_line
			(start 0.7874 -0.4064)
			(end 0.7874 0.4064)
			(stroke
				(width 0.1524)
				(type default)
			)
			(layer "F.SilkS")
		)
		(fp_line
			(start -0.7874 -0.4064)
			(end 0.7874 -0.4064)
			(stroke
				(width 0.1524)
				(type default)
			)
			(layer "F.SilkS")
		)
		(fp_line
			(start 0.7874 0.4064)
			(end -0.7874 0.4064)
			(stroke
				(width 0.1524)
				(type default)
			)
			(layer "F.SilkS")
		)
		(fp_line
			(start -0.7874 0.4064)
			(end -0.7874 -0.4064)
			(stroke
				(width 0.1524)
				(type default)
			)
			(layer "F.SilkS")
		)
		(fp_poly
			(pts
				(xy -0.508 0.2794) (xy -0.508 0.2286) (xy -0.635 0.2286) (xy -0.635 -0.254) (xy -0.5334 -0.254)
				(xy -0.5334 -0.2794) (xy 0.5334 -0.2794) (xy 0.5334 -0.254) (xy 0.635 -0.254) (xy 0.635 0.254) (xy 0.5334 0.254)
				(xy 0.5334 0.2794)
			)
			(stroke
				(width 0)
				(type default)
			)
			(fill no)
			(layer "F.CrtYd")
		)
		(pad "1" smd rect
			(at 0.40005 0 90)
			(size 0.4572 0.508)
			(layers "F.Cu" "F.Mask" "F.Paste")
			(net "P5V_NODE1")
		)
		(pad "2" smd rect
			(at -0.40005 0 90)
			(size 0.4572 0.508)
			(layers "F.Cu" "F.Mask" "F.Paste")
			(net "UART_DSR_P3_N")
		)
	)
	(footprint ""
		(layer "F.Cu")
		(at 111.696246 -129.847848 90)
		(property "Reference" "PC95"
			(at -1.715008 -0.91694 90)
			(unlocked yes)
			(layer "F.SilkS")
			(effects
				(font
					(size 0.7874 0.5842)
					(thickness 0.1524)
				)
				(justify left)
			)
		)
		(property "Value" ""
			(at 0 0 90)
			(layer "F.Fab")
			(effects
				(font
					(size 1.27 1.27)
				)
			)
		)
		(duplicate_pad_numbers_are_jumpers no)
		(fp_line
			(start 0.7874 -0.4064)
			(end 0.7874 0.4064)
			(stroke
				(width 0.1524)
				(type default)
			)
			(layer "F.SilkS")
		)
		(fp_line
			(start -0.7874 -0.4064)
			(end 0.7874 -0.4064)
			(stroke
				(width 0.1524)
				(type default)
			)
			(layer "F.SilkS")
		)
		(fp_line
			(start 0 0.381)
			(end 0 -0.381)
			(stroke
				(width 0.1524)
				(type default)
			)
			(layer "F.SilkS")
		)
		(fp_line
			(start 0.7874 0.4064)
			(end -0.7874 0.4064)
			(stroke
				(width 0.1524)
				(type default)
			)
			(layer "F.SilkS")
		)
		(fp_line
			(start -0.7874 0.4064)
			(end -0.7874 -0.4064)
			(stroke
				(width 0.1524)
				(type default)
			)
			(layer "F.SilkS")
		)
		(fp_poly
			(pts
				(xy -0.5334 0.254) (xy -0.635 0.254) (xy -0.635 0.2286) (xy -0.635 -0.254) (xy -0.5334 -0.254) (xy -0.5334 -0.2794)
				(xy 0.5334 -0.2794) (xy 0.5334 -0.254) (xy 0.635 -0.254) (xy 0.635 0.254) (xy 0.5334 0.254) (xy 0.5334 0.2794)
				(xy -0.508 0.2794) (xy -0.5334 0.2794)
			)
			(stroke
				(width 0)
				(type default)
			)
			(fill no)
			(layer "F.CrtYd")
		)
		(pad "1" smd rect
			(at 0.40005 0 90)
			(size 0.4572 0.508)
			(layers "F.Cu" "F.Mask" "F.Paste")
			(net "VR_PVCCP_NODE1_TONSET_R")
		)
		(pad "2" smd rect
			(at -0.40005 0 90)
			(size 0.4572 0.508)
			(layers "F.Cu" "F.Mask" "F.Paste")
			(net "AGND_PVCCP_NODE1")
		)
	)
	(footprint ""
		(layer "F.Cu")
		(at 9.782048 -154.46375)
		(property "Reference" "C550"
			(at 8.409432 5.435854 90)
			(unlocked yes)
			(layer "F.SilkS")
			(effects
				(font
					(size 0.7874 0.5842)
					(thickness 0.1524)
				)
				(justify left)
			)
		)
		(property "Value" ""
			(at 0 0 0)
			(layer "F.Fab")
			(effects
				(font
					(size 1.27 1.27)
				)
			)
		)
		(duplicate_pad_numbers_are_jumpers no)
		(fp_line
			(start -0.7874 -0.4064)
			(end 0.7874 -0.4064)
			(stroke
				(width 0.1524)
				(type default)
			)
			(layer "F.SilkS")
		)
		(fp_line
			(start -0.7874 0.4064)
			(end -0.7874 -0.4064)
			(stroke
				(width 0.1524)
				(type default)
			)
			(layer "F.SilkS")
		)
		(fp_line
			(start 0 0.381)
			(end 0 -0.381)
			(stroke
				(width 0.1524)
				(type default)
			)
			(layer "F.SilkS")
		)
		(fp_line
			(start 0.7874 -0.4064)
			(end 0.7874 0.4064)
			(stroke
				(width 0.1524)
				(type default)
			)
			(layer "F.SilkS")
		)
		(fp_line
			(start 0.7874 0.4064)
			(end -0.7874 0.4064)
			(stroke
				(width 0.1524)
				(type default)
			)
			(layer "F.SilkS")
		)
		(fp_poly
			(pts
				(xy -0.5334 0.254) (xy -0.635 0.254) (xy -0.635 0.2286) (xy -0.635 -0.254) (xy -0.5334 -0.254) (xy -0.5334 -0.2794)
				(xy 0.5334 -0.2794) (xy 0.5334 -0.254) (xy 0.635 -0.254) (xy 0.635 0.254) (xy 0.5334 0.254) (xy 0.5334 0.2794)
				(xy -0.508 0.2794) (xy -0.5334 0.2794)
			)
			(stroke
				(width 0)
				(type default)
			)
			(fill no)
			(layer "F.CrtYd")
		)
		(pad "1" smd rect
			(at 0.40005 0)
			(size 0.4572 0.508)
			(layers "F.Cu" "F.Mask" "F.Paste")
			(net "P3V3_NODE1")
		)
		(pad "2" smd rect
			(at -0.40005 0)
			(size 0.4572 0.508)
			(layers "F.Cu" "F.Mask" "F.Paste")
			(net "GND")
		)
	)
	(footprint ""
		(layer "F.Cu")
		(at 114.621564 -135.219186 180)
		(property "Reference" "PC102"
			(at -5.453888 2.098294 90)
			(unlocked yes)
			(layer "F.SilkS")
			(effects
				(font
					(size 0.635 0.4064)
					(thickness 0.1524)
				)
				(justify left)
			)
		)
		(property "Value" ""
			(at 0 0 180)
			(layer "F.Fab")
			(effects
				(font
					(size 1.27 1.27)
				)
			)
		)
		(duplicate_pad_numbers_are_jumpers no)
		(fp_line
			(start 0.7874 0.4064)
			(end -0.7874 0.4064)
			(stroke
				(width 0.1524)
				(type default)
			)
			(layer "F.SilkS")
		)
		(fp_line
			(start 0.7874 -0.4064)
			(end 0.7874 0.4064)
			(stroke
				(width 0.1524)
				(type default)
			)
			(layer "F.SilkS")
		)
		(fp_line
			(start 0 0.381)
			(end 0 -0.381)
			(stroke
				(width 0.1524)
				(type default)
			)
			(layer "F.SilkS")
		)
		(fp_line
			(start -0.7874 0.4064)
			(end -0.7874 -0.4064)
			(stroke
				(width 0.1524)
				(type default)
			)
			(layer "F.SilkS")
		)
		(fp_line
			(start -0.7874 -0.4064)
			(end 0.7874 -0.4064)
			(stroke
				(width 0.1524)
				(type default)
			)
			(layer "F.SilkS")
		)
		(fp_poly
			(pts
				(xy -0.5334 0.254) (xy -0.635 0.254) (xy -0.635 0.2286) (xy -0.635 -0.254) (xy -0.5334 -0.254) (xy -0.5334 -0.2794)
				(xy 0.5334 -0.2794) (xy 0.5334 -0.254) (xy 0.635 -0.254) (xy 0.635 0.254) (xy 0.5334 0.254) (xy 0.5334 0.2794)
				(xy -0.508 0.2794) (xy -0.5334 0.2794)
			)
			(stroke
				(width 0)
				(type default)
			)
			(fill no)
			(layer "F.CrtYd")
		)
		(pad "1" smd rect
			(at 0.40005 0 180)
			(size 0.4572 0.508)
			(layers "F.Cu" "F.Mask" "F.Paste")
			(net "VR_PVCCP_NODE1_COMP")
		)
		(pad "2" smd rect
			(at -0.40005 0 180)
			(size 0.4572 0.508)
			(layers "F.Cu" "F.Mask" "F.Paste")
			(net "VR_PVCCP_NODE1_COMP_RC")
		)
	)
	(footprint ""
		(layer "F.Cu")
		(at 178.025044 -163.517072 90)
		(property "Reference" "U138"
			(at 6.093206 3.490976 0)
			(unlocked yes)
			(layer "F.SilkS")
			(effects
				(font
					(size 0.7874 0.5842)
					(thickness 0.1524)
				)
				(justify left)
			)
		)
		(property "Value" ""
			(at 0 0 90)
			(layer "F.Fab")
			(effects
				(font
					(size 1.27 1.27)
				)
			)
		)
		(duplicate_pad_numbers_are_jumpers no)
		(fp_line
			(start 3.564128 -7.800086)
			(end 3.564128 7.800086)
			(stroke
				(width 0.1524)
				(type default)
			)
			(layer "F.SilkS")
		)
		(fp_line
			(start 1.800098 -7.800086)
			(end 3.564128 -7.800086)
			(stroke
				(width 0.1524)
				(type default)
			)
			(layer "F.SilkS")
		)
		(fp_line
			(start -1.800098 -7.800086)
			(end 0 -5.999988)
			(stroke
				(width 0.1524)
				(type default)
			)
			(layer "F.SilkS")
		)
		(fp_line
			(start -3.564128 -7.800086)
			(end -1.800098 -7.800086)
			(stroke
				(width 0.1524)
				(type default)
			)
			(layer "F.SilkS")
		)
		(fp_line
			(start 0 -5.999988)
			(end 1.800098 -7.800086)
			(stroke
				(width 0.1524)
				(type default)
			)
			(layer "F.SilkS")
		)
		(fp_line
			(start 3.564128 7.800086)
			(end -3.564128 7.800086)
			(stroke
				(width 0.1524)
				(type default)
			)
			(layer "F.SilkS")
		)
		(fp_line
			(start -3.564128 7.800086)
			(end -3.564128 -7.800086)
			(stroke
				(width 0.1524)
				(type default)
			)
			(layer "F.SilkS")
		)
		(fp_poly
			(pts
				(xy -3.70459 -9.133586) (xy -4.72059 -9.133586) (xy -4.21259 -8.117586)
			)
			(stroke
				(width 0)
				(type default)
			)
			(fill yes)
			(layer "F.SilkS")
		)
		(fp_poly
			(pts
				(xy -4.249928 7.800086) (xy -4.249928 7.4422) (xy -5.300472 7.4422) (xy -5.300472 -7.4422) (xy -4.249928 -7.4422)
				(xy -4.249928 -7.800086) (xy 4.249928 -7.800086) (xy 4.249928 -7.4422) (xy 5.300472 -7.4422) (xy 5.300472 7.4422)
				(xy 4.249928 7.4422) (xy 4.249928 7.800086)
			)
			(stroke
				(width 0)
				(type default)
			)
			(fill no)
			(layer "F.CrtYd")
		)
		(fp_line
			(start 4.249928 -7.800086)
			(end -4.249928 -7.800086)
			(stroke
				(width 0.1)
				(type default)
			)
			(layer "F.Fab")
		)
		(fp_line
			(start -4.249928 -7.800086)
			(end -4.249928 7.800086)
			(stroke
				(width 0.1)
				(type default)
			)
			(layer "F.Fab")
		)
		(fp_line
			(start 4.249928 7.800086)
			(end 4.249928 -7.800086)
			(stroke
				(width 0.1)
				(type default)
			)
			(layer "F.Fab")
		)
		(fp_line
			(start -4.249928 7.800086)
			(end 4.249928 7.800086)
			(stroke
				(width 0.1)
				(type default)
			)
			(layer "F.Fab")
		)
		(fp_poly
			(pts
				(xy -6.477 -7.493) (xy -6.477 -6.477) (xy -5.461 -6.985)
			)
			(stroke
				(width 0)
				(type default)
			)
			(fill yes)
			(layer "F.Fab")
		)
		(pad "1" smd rect
			(at -4.474972 -6.985)
			(size 0.8128 1.5494)
			(layers "F.Cu" "F.Mask" "F.Paste")
			(net "LAN2_MDI0_DP")
		)
		(pad "2" smd rect
			(at -4.474972 -5.715)
			(size 0.8128 1.5494)
			(layers "F.Cu" "F.Mask" "F.Paste")
			(net "LAN2_MDI0_DN")
		)
		(pad "3" smd rect
			(at -4.474972 -4.445)
			(size 0.8128 1.5494)
			(layers "F.Cu" "F.Mask" "F.Paste")
			(net "P1V9_LAN2")
		)
		(pad "4" smd rect
			(at -4.474972 -3.175)
			(size 0.8128 1.5494)
			(layers "F.Cu" "F.Mask" "F.Paste")
			(net "P1V9_LAN2")
		)
		(pad "5" smd rect
			(at -4.474972 -1.905)
			(size 0.8128 1.5494)
			(layers "F.Cu" "F.Mask" "F.Paste")
			(net "LAN2_MDI1_DP")
		)
		(pad "6" smd rect
			(at -4.474972 -0.635)
			(size 0.8128 1.5494)
			(layers "F.Cu" "F.Mask" "F.Paste")
			(net "LAN2_MDI1_DN")
		)
		(pad "7" smd rect
			(at -4.474972 0.635)
			(size 0.8128 1.5494)
			(layers "F.Cu" "F.Mask" "F.Paste")
			(net "LAN2_MDI2_DP")
		)
		(pad "8" smd rect
			(at -4.474972 1.905)
			(size 0.8128 1.5494)
			(layers "F.Cu" "F.Mask" "F.Paste")
			(net "LAN2_MDI2_DN")
		)
		(pad "9" smd rect
			(at -4.474972 3.175)
			(size 0.8128 1.5494)
			(layers "F.Cu" "F.Mask" "F.Paste")
			(net "P1V9_LAN2")
		)
		(pad "10" smd rect
			(at -4.474972 4.445)
			(size 0.8128 1.5494)
			(layers "F.Cu" "F.Mask" "F.Paste")
			(net "P1V9_LAN2")
		)
		(pad "11" smd rect
			(at -4.474972 5.715)
			(size 0.8128 1.5494)
			(layers "F.Cu" "F.Mask" "F.Paste")
			(net "LAN2_MDI3_DP")
		)
		(pad "12" smd rect
			(at -4.474972 6.985)
			(size 0.8128 1.5494)
			(layers "F.Cu" "F.Mask" "F.Paste")
			(net "LAN2_MDI3_DN")
		)
		(pad "13" smd rect
			(at 4.474972 6.985)
			(size 0.8128 1.5494)
			(layers "F.Cu" "F.Mask" "F.Paste")
			(net "LAN2_P4_N")
		)
		(pad "14" smd rect
			(at 4.474972 5.715)
			(size 0.8128 1.5494)
			(layers "F.Cu" "F.Mask" "F.Paste")
			(net "LAN2_P4_P")
		)
		(pad "15" smd rect
			(at 4.474972 4.445)
			(size 0.8128 1.5494)
			(layers "F.Cu" "F.Mask" "F.Paste")
			(net "LAN2_P4_R")
		)
		(pad "16" smd rect
			(at 4.474972 3.175)
			(size 0.8128 1.5494)
			(layers "F.Cu" "F.Mask" "F.Paste")
			(net "LAN2_P3_R")
		)
		(pad "17" smd rect
			(at 4.474972 1.905)
			(size 0.8128 1.5494)
			(layers "F.Cu" "F.Mask" "F.Paste")
			(net "LAN2_P3_N")
		)
		(pad "18" smd rect
			(at 4.474972 0.635)
			(size 0.8128 1.5494)
			(layers "F.Cu" "F.Mask" "F.Paste")
			(net "LAN2_P3_P")
		)
		(pad "19" smd rect
			(at 4.474972 -0.635)
			(size 0.8128 1.5494)
			(layers "F.Cu" "F.Mask" "F.Paste")
			(net "LAN2_P2_N")
		)
		(pad "20" smd rect
			(at 4.474972 -1.905)
			(size 0.8128 1.5494)
			(layers "F.Cu" "F.Mask" "F.Paste")
			(net "LAN2_P2_P")
		)
		(pad "21" smd rect
			(at 4.474972 -3.175)
			(size 0.8128 1.5494)
			(layers "F.Cu" "F.Mask" "F.Paste")
			(net "LAN2_P2_R")
		)
		(pad "22" smd rect
			(at 4.474972 -4.445)
			(size 0.8128 1.5494)
			(layers "F.Cu" "F.Mask" "F.Paste")
			(net "LAN2_P1_R")
		)
		(pad "23" smd rect
			(at 4.474972 -5.715)
			(size 0.8128 1.5494)
			(layers "F.Cu" "F.Mask" "F.Paste")
			(net "LAN2_P1_N")
		)
		(pad "24" smd rect
			(at 4.474972 -6.985)
			(size 0.8128 1.5494)
			(layers "F.Cu" "F.Mask" "F.Paste")
			(net "LAN2_P1_P")
		)
	)
	(footprint ""
		(layer "F.Cu")
		(at 72.24776 -188.126624 90)
		(property "Reference" "C710"
			(at 4.548886 -1.035558 90)
			(unlocked yes)
			(layer "F.SilkS")
			(effects
				(font
					(size 0.7874 0.5842)
					(thickness 0.1524)
				)
				(justify left)
			)
		)
		(property "Value" ""
			(at 0 0 90)
			(layer "F.Fab")
			(effects
				(font
					(size 1.27 1.27)
				)
			)
		)
		(duplicate_pad_numbers_are_jumpers no)
		(fp_line
			(start 0.7874 -0.4064)
			(end 0.7874 0.4064)
			(stroke
				(width 0.1524)
				(type default)
			)
			(layer "F.SilkS")
		)
		(fp_line
			(start -0.7874 -0.4064)
			(end 0.7874 -0.4064)
			(stroke
				(width 0.1524)
				(type default)
			)
			(layer "F.SilkS")
		)
		(fp_line
			(start 0 0.381)
			(end 0 -0.381)
			(stroke
				(width 0.1524)
				(type default)
			)
			(layer "F.SilkS")
		)
		(fp_line
			(start 0.7874 0.4064)
			(end -0.7874 0.4064)
			(stroke
				(width 0.1524)
				(type default)
			)
			(layer "F.SilkS")
		)
		(fp_line
			(start -0.7874 0.4064)
			(end -0.7874 -0.4064)
			(stroke
				(width 0.1524)
				(type default)
			)
			(layer "F.SilkS")
		)
		(fp_poly
			(pts
				(xy -0.5334 0.254) (xy -0.635 0.254) (xy -0.635 0.2286) (xy -0.635 -0.254) (xy -0.5334 -0.254) (xy -0.5334 -0.2794)
				(xy 0.5334 -0.2794) (xy 0.5334 -0.254) (xy 0.635 -0.254) (xy 0.635 0.254) (xy 0.5334 0.254) (xy 0.5334 0.2794)
				(xy -0.508 0.2794) (xy -0.5334 0.2794)
			)
			(stroke
				(width 0)
				(type default)
			)
			(fill no)
			(layer "F.CrtYd")
		)
		(pad "1" smd rect
			(at 0.40005 0 90)
			(size 0.4572 0.508)
			(layers "F.Cu" "F.Mask" "F.Paste")
			(net "UART_T4_NODE3_TXD_R")
		)
		(pad "2" smd rect
			(at -0.40005 0 90)
			(size 0.4572 0.508)
			(layers "F.Cu" "F.Mask" "F.Paste")
			(net "GND")
		)
	)
	(footprint ""
		(layer "F.Cu")
		(at 95.004382 -9.792716 -90)
		(property "Reference" "J1"
			(at -4.160266 3.089402 0)
			(unlocked yes)
			(layer "F.SilkS")
			(effects
				(font
					(size 0.7874 0.5842)
					(thickness 0.1524)
				)
				(justify left)
			)
		)
		(property "Value" ""
			(at 0 0 270)
			(layer "F.Fab")
			(effects
				(font
					(size 1.27 1.27)
				)
			)
		)
		(duplicate_pad_numbers_are_jumpers no)
		(fp_line
			(start -3.150108 8.325104)
			(end -3.150108 6.6421)
			(stroke
				(width 0.1524)
				(type default)
			)
			(layer "F.SilkS")
		)
		(fp_line
			(start 3.150108 8.325104)
			(end -3.150108 8.325104)
			(stroke
				(width 0.1524)
				(type default)
			)
			(layer "F.SilkS")
		)
		(fp_line
			(start 3.150108 6.6421)
			(end 3.150108 8.325104)
			(stroke
				(width 0.1524)
				(type default)
			)
			(layer "F.SilkS")
		)
		(fp_line
			(start -3.150108 5.3467)
			(end -3.150108 4.6355)
			(stroke
				(width 0.1524)
				(type default)
			)
			(layer "F.SilkS")
		)
		(fp_line
			(start 3.150108 4.6482)
			(end 3.150108 5.3594)
			(stroke
				(width 0.1524)
				(type default)
			)
			(layer "F.SilkS")
		)
		(fp_line
			(start -3.150108 3.3401)
			(end -3.150108 2.6416)
			(stroke
				(width 0.1524)
				(type default)
			)
			(layer "F.SilkS")
		)
		(fp_line
			(start 3.150108 2.6416)
			(end 3.150108 3.3528)
			(stroke
				(width 0.1524)
				(type default)
			)
			(layer "F.SilkS")
		)
		(fp_line
			(start -3.150108 1.3589)
			(end -3.150108 0.635)
			(stroke
				(width 0.1524)
				(type default)
			)
			(layer "F.SilkS")
		)
		(fp_line
			(start -2.249932 1.199896)
			(end -3.1496 1.199896)
			(stroke
				(width 0.1524)
				(type default)
			)
			(layer "F.SilkS")
		)
		(fp_line
			(start 3.150108 0.647192)
			(end 3.150108 1.3589)
			(stroke
				(width 0.1524)
				(type default)
			)
			(layer "F.SilkS")
		)
		(fp_line
			(start -2.249932 0.635)
			(end -2.249932 1.199896)
			(stroke
				(width 0.1524)
				(type default)
			)
			(layer "F.SilkS")
		)
		(fp_line
			(start -3.150108 -0.647192)
			(end -3.150108 -1.3589)
			(stroke
				(width 0.1524)
				(type default)
			)
			(layer "F.SilkS")
		)
		(fp_line
			(start -3.1242 -1.199896)
			(end -2.249932 -1.199896)
			(stroke
				(width 0.1524)
				(type default)
			)
			(layer "F.SilkS")
		)
		(fp_line
			(start -2.249932 -1.199896)
			(end -2.249932 -0.635)
			(stroke
				(width 0.1524)
				(type default)
			)
			(layer "F.SilkS")
		)
		(fp_line
			(start 3.150108 -1.3589)
			(end 3.150108 -0.647192)
			(stroke
				(width 0.1524)
				(type default)
			)
			(layer "F.SilkS")
		)
		(fp_line
			(start -3.150108 -2.6416)
			(end -3.150108 -3.3528)
			(stroke
				(width 0.1524)
				(type default)
			)
			(layer "F.SilkS")
		)
		(fp_line
			(start 3.150108 -3.3528)
			(end 3.150108 -2.6416)
			(stroke
				(width 0.1524)
				(type default)
			)
			(layer "F.SilkS")
		)
		(fp_line
			(start -3.150108 -4.65201)
			(end -3.150108 -5.3594)
			(stroke
				(width 0.1524)
				(type default)
			)
			(layer "F.SilkS")
		)
		(fp_line
			(start 3.150108 -5.3594)
			(end 3.150108 -4.65201)
			(stroke
				(width 0.1524)
				(type default)
			)
			(layer "F.SilkS")
		)
		(fp_line
			(start -3.150108 -6.6548)
			(end -3.150108 -8.325104)
			(stroke
				(width 0.1524)
				(type default)
			)
			(layer "F.SilkS")
		)
		(fp_line
			(start -3.150108 -8.325104)
			(end 3.150108 -8.325104)
			(stroke
				(width 0.1524)
				(type default)
			)
			(layer "F.SilkS")
		)
		(fp_line
			(start 3.150108 -8.325104)
			(end 3.150108 -6.6548)
			(stroke
				(width 0.1524)
				(type default)
			)
			(layer "F.SilkS")
		)
		(fp_poly
			(pts
				(xy -1.616964 -10.0965) (xy -2.632964 -10.0965) (xy -2.124964 -8.9535)
			)
			(stroke
				(width 0)
				(type default)
			)
			(fill yes)
			(layer "F.SilkS")
		)
		(fp_poly
			(pts
				(xy -2.249932 0.5588) (xy -2.249932 1.199896) (xy -3.175 1.199896) (xy -3.175 0.5588)
			)
			(stroke
				(width 0)
				(type default)
			)
			(fill yes)
			(layer "F.SilkS")
		)
		(fp_poly
			(pts
				(xy -2.249932 -0.5588) (xy -2.249932 -1.199896) (xy -3.175 -1.199896) (xy -3.175 -0.5588)
			)
			(stroke
				(width 0)
				(type default)
			)
			(fill yes)
			(layer "F.SilkS")
		)
		(fp_poly
			(pts
				(arc
					(start 0.7874 4.99999)
					(mid -0.7874 4.99999)
					(end 0.7874 4.99999)
				)
			)
			(stroke
				(width 0)
				(type default)
			)
			(fill no)
			(layer "B.CrtYd")
		)
		(fp_poly
			(pts
				(arc
					(start 0.7874 -4.99999)
					(mid -0.7874 -4.99999)
					(end 0.7874 -4.99999)
				)
			)
			(stroke
				(width 0)
				(type default)
			)
			(fill no)
			(layer "B.CrtYd")
		)
		(fp_poly
			(pts
				(xy -3.1496 -6.5786) (xy -3.1496 -8.3312) (xy 3.1496 -8.3312) (xy 3.1496 -6.5786) (xy 3.5814 -6.5786)
				(xy 3.5814 6.5786) (xy 3.1496 6.5786) (xy 3.1496 8.3312) (xy -3.1496 8.3312) (xy -3.1496 6.5786)
				(xy -3.5814 6.5786) (xy -3.5814 -6.5786)
			)
			(stroke
				(width 0)
				(type default)
			)
			(fill no)
			(layer "F.CrtYd")
		)
		(fp_line
			(start -3.150108 8.325104)
			(end -3.150108 -8.325104)
			(stroke
				(width 0.1)
				(type default)
			)
			(layer "F.Fab")
		)
		(fp_line
			(start 3.150108 8.325104)
			(end -3.150108 8.325104)
			(stroke
				(width 0.1)
				(type default)
			)
			(layer "F.Fab")
		)
		(fp_line
			(start -3.150108 -8.325104)
			(end 3.150108 -8.325104)
			(stroke
				(width 0.1)
				(type default)
			)
			(layer "F.Fab")
		)
		(fp_line
			(start 3.150108 -8.325104)
			(end 3.150108 8.325104)
			(stroke
				(width 0.1)
				(type default)
			)
			(layer "F.Fab")
		)
		(fp_poly
			(pts
				(xy -1.616964 -10.0965) (xy -2.632964 -10.0965) (xy -2.124964 -8.9535)
			)
			(stroke
				(width 0)
				(type default)
			)
			(fill yes)
			(layer "F.Fab")
		)
		(fp_text user "14"
			(at 4.034028 7.27202 0)
			(unlocked yes)
			(layer "F.SilkS")
			(effects
				(font
					(size 0.635 0.4064)
					(thickness 0.1524)
				)
				(justify left)
			)
		)
		(fp_text user "13"
			(at -4.116832 6.459982 0)
			(unlocked yes)
			(layer "F.SilkS")
			(effects
				(font
					(size 0.635 0.4064)
					(thickness 0.1524)
				)
				(justify left)
			)
		)
		(fp_text user "2"
			(at 3.923284 -6.694932 0)
			(unlocked yes)
			(layer "F.SilkS")
			(effects
				(font
					(size 0.635 0.4064)
					(thickness 0.1524)
				)
				(justify left)
			)
		)
		(fp_text user "1"
			(at -3.820922 -7.16534 0)
			(unlocked yes)
			(layer "F.SilkS")
			(effects
				(font
					(size 0.635 0.4064)
					(thickness 0.1524)
				)
				(justify left)
			)
		)
		(fp_text user "13"
			(at -2.101088 8.509 180)
			(unlocked yes)
			(layer "F.Fab")
			(effects
				(font
					(size 0.7874 0.5842)
					(thickness 0.000001)
				)
				(justify left)
			)
		)
		(fp_text user "14"
			(at 2.013712 8.509 180)
			(unlocked yes)
			(layer "F.Fab")
			(effects
				(font
					(size 0.7874 0.5842)
					(thickness 0.000001)
				)
				(justify left)
			)
		)
		(fp_text user "1"
			(at -2.050288 -8.9535 180)
			(unlocked yes)
			(layer "F.Fab")
			(effects
				(font
					(size 0.7874 0.5842)
					(thickness 0.000001)
				)
				(justify left)
			)
		)
		(fp_text user "2"
			(at 2.085848 -9.0551 180)
			(unlocked yes)
			(layer "F.Fab")
			(effects
				(font
					(size 0.7874 0.5842)
					(thickness 0.000001)
				)
				(justify left)
			)
		)
		(pad "" np_thru_hole circle
			(at 0 -4.99999 180)
			(size 1.0668 1.0668)
			(drill 1.0668)
			(layers "*.Cu" "*.Mask")
			(clearance 0.381)
			(thermal_gap 0.381)
		)
		(pad "" np_thru_hole circle
			(at 0 4.99999 180)
			(size 1.0668 1.0668)
			(drill 1.0668)
			(layers "*.Cu" "*.Mask")
			(clearance 0.381)
			(thermal_gap 0.381)
		)
		(pad "1" smd rect
			(at -2.124964 -5.999988 180)
			(size 1.016 2.7686)
			(layers "F.Cu" "F.Mask" "F.Paste")
			(net "N20512395")
		)
		(pad "2" smd rect
			(at 2.124964 -5.999988 180)
			(size 1.016 2.7686)
			(layers "F.Cu" "F.Mask" "F.Paste")
			(net "TP_P3V3_NODE1_INIT_L")
		)
		(pad "3" smd rect
			(at -2.124964 -3.999992 180)
			(size 1.016 2.7686)
			(layers "F.Cu" "F.Mask" "F.Paste")
			(net "FM_CPLD_NODE1_LPCRST_L")
		)
		(pad "4" smd rect
			(at 2.124964 -3.999992 180)
			(size 1.016 2.7686)
			(layers "F.Cu" "F.Mask" "F.Paste")
			(net "P3V3_NODE1")
		)
		(pad "5" smd rect
			(at -2.124964 -1.999996 180)
			(size 1.016 2.7686)
			(layers "F.Cu" "F.Mask" "F.Paste")
			(net "LPC_CPU_TPM_LAD0")
		)
		(pad "6" smd rect
			(at 2.124964 -1.999996 180)
			(size 1.016 2.7686)
			(layers "F.Cu" "F.Mask" "F.Paste")
			(net "TP_BIOS_NODE1_PORT80_ID0")
		)
		(pad "7" smd rect
			(at -2.124964 0 180)
			(size 1.016 2.7686)
			(layers "F.Cu" "F.Mask" "F.Paste")
			(net "LPC_CPU_TPM_LAD1")
		)
		(pad "8" smd rect
			(at 2.124964 0 180)
			(size 1.016 2.7686)
			(layers "F.Cu" "F.Mask" "F.Paste")
			(net "P5V_NODE1")
		)
		(pad "9" smd rect
			(at -2.124964 1.999996 180)
			(size 1.016 2.7686)
			(layers "F.Cu" "F.Mask" "F.Paste")
			(net "LPC_CPU_TPM_LAD2")
		)
		(pad "10" smd rect
			(at 2.124964 1.999996 180)
			(size 1.016 2.7686)
			(layers "F.Cu" "F.Mask" "F.Paste")
			(net "TPM_LPC_SERIRQ_PORT80_NODE1")
		)
		(pad "11" smd rect
			(at -2.124964 3.999992 180)
			(size 1.016 2.7686)
			(layers "F.Cu" "F.Mask" "F.Paste")
			(net "LPC_CPU_TPM_LAD3")
		)
		(pad "12" smd rect
			(at 2.124964 3.999992 180)
			(size 1.016 2.7686)
			(layers "F.Cu" "F.Mask" "F.Paste")
			(net "GND")
		)
		(pad "13" smd rect
			(at -2.124964 5.999988 180)
			(size 1.016 2.7686)
			(layers "F.Cu" "F.Mask" "F.Paste")
			(net "N20512383")
		)
		(pad "14" smd rect
			(at 2.124964 5.999988 180)
			(size 1.016 2.7686)
			(layers "F.Cu" "F.Mask" "F.Paste")
			(net "GND")
		)
		(zone
			(layers "F.Cu" "B.Cu" "In1.Cu" "In2.Cu" "In3.Cu" "In4.Cu" "In5.Cu" "In6.Cu"
				"In7.Cu" "In8.Cu"
			)
			(hatch none 0.5)
			(connect_pads
				(clearance 0)
			)
			(min_thickness 0.25)
			(keepout
				(tracks not_allowed)
				(vias allowed)
				(pads allowed)
				(copperpour not_allowed)
				(footprints allowed)
			)
			(placement
				(enabled no)
				(sheetname "")
			)
			(fill
				(thermal_gap 0.5)
				(thermal_bridge_width 0.5)
				(island_removal_mode 0)
			)
			(polygon
				(pts
					(arc
						(start 90.944192 -9.792716)
						(mid 90.866697 -9.419012)
						(end 90.647012 -9.106916)
					)
					(xy 90.437716 -9.106916)
					(arc
						(start 90.437716 -8.958834)
						(mid 90.007403 -8.852971)
						(end 89.576402 -8.95604)
					)
					(xy 89.576402 -9.107678)
					(arc
						(start 89.36101 -9.107678)
						(mid 89.064596 -9.793255)
						(end 89.361772 -10.478516)
					)
					(xy 89.57691 -10.478516)
					(arc
						(start 89.57691 -10.629646)
						(mid 90.007687 -10.732494)
						(end 90.437716 -10.626598)
					)
					(xy 90.437716 -10.478516)
					(arc
						(start 90.647012 -10.478516)
						(mid 90.866725 -10.166432)
						(end 90.944192 -9.792716)
					)
				)
			)
		)
		(zone
			(layers "F.Cu" "B.Cu" "In1.Cu" "In2.Cu" "In3.Cu" "In4.Cu" "In5.Cu" "In6.Cu"
				"In7.Cu" "In8.Cu"
			)
			(hatch none 0.5)
			(connect_pads
				(clearance 0)
			)
			(min_thickness 0.25)
			(keepout
				(tracks not_allowed)
				(vias allowed)
				(pads allowed)
				(copperpour not_allowed)
				(footprints allowed)
			)
			(placement
				(enabled no)
				(sheetname "")
			)
			(fill
				(thermal_gap 0.5)
				(thermal_bridge_width 0.5)
				(island_removal_mode 0)
			)
			(polygon
				(pts
					(arc
						(start 100.944172 -9.792716)
						(mid 100.866677 -9.419012)
						(end 100.646992 -9.106916)
					)
					(xy 100.437696 -9.106916)
					(arc
						(start 100.437696 -8.958834)
						(mid 100.007383 -8.852971)
						(end 99.576382 -8.95604)
					)
					(xy 99.576382 -9.107678)
					(arc
						(start 99.36099 -9.107678)
						(mid 99.064576 -9.793255)
						(end 99.361752 -10.478516)
					)
					(xy 99.57689 -10.478516)
					(arc
						(start 99.57689 -10.629646)
						(mid 100.007667 -10.732494)
						(end 100.437696 -10.626598)
					)
					(xy 100.437696 -10.478516)
					(arc
						(start 100.646992 -10.478516)
						(mid 100.866705 -10.166432)
						(end 100.944172 -9.792716)
					)
				)
			)
		)
	)
	(footprint ""
		(layer "F.Cu")
		(at 41.240456 -185.341006 -90)
		(property "Reference" "R1019"
			(at -4.113784 0.130556 90)
			(unlocked yes)
			(layer "F.SilkS")
			(effects
				(font
					(size 0.7874 0.5842)
					(thickness 0.1524)
				)
				(justify left)
			)
		)
		(property "Value" ""
			(at 0 0 270)
			(layer "F.Fab")
			(effects
				(font
					(size 1.27 1.27)
				)
			)
		)
		(duplicate_pad_numbers_are_jumpers no)
		(fp_line
			(start -3.2258 1.3462)
			(end -3.2258 -1.3462)
			(stroke
				(width 0.1524)
				(type default)
			)
			(layer "F.SilkS")
		)
		(fp_line
			(start 3.2258 1.3462)
			(end -3.2258 1.3462)
			(stroke
				(width 0.1524)
				(type default)
			)
			(layer "F.SilkS")
		)
		(fp_line
			(start -3.2258 -1.3462)
			(end 3.2258 -1.3462)
			(stroke
				(width 0.1524)
				(type default)
			)
			(layer "F.SilkS")
		)
		(fp_line
			(start 3.2258 -1.3462)
			(end 3.2258 1.3462)
			(stroke
				(width 0.1524)
				(type default)
			)
			(layer "F.SilkS")
		)
		(fp_poly
			(pts
				(xy -2.5654 1.3462) (xy -2.5654 1.2192) (xy -3.0734 1.2192) (xy -3.0734 -1.2192) (xy -2.5654 -1.2192)
				(xy -2.5654 -1.3462) (xy 2.5654 -1.3462) (xy 2.5654 -1.2192) (xy 3.0734 -1.2192) (xy 3.0734 1.2192)
				(xy 2.5654 1.2192) (xy 2.5654 1.3462)
			)
			(stroke
				(width 0)
				(type default)
			)
			(fill no)
			(layer "F.CrtYd")
		)
		(pad "1" smd rect
			(at -2.350008 0 270)
			(size 1.4224 2.413)
			(layers "F.Cu" "F.Mask" "F.Paste")
			(net "P12V_PDB")
		)
		(pad "2" smd rect
			(at 2.350008 0 270)
			(size 1.4224 2.413)
			(layers "F.Cu" "F.Mask" "F.Paste")
			(net "VSENSE_HSC_NODE1")
		)
	)
	(footprint ""
		(layer "F.Cu")
		(at 17.229074 -36.438078 -90)
		(property "Reference" "R195"
			(at 4.171442 -0.137668 90)
			(unlocked yes)
			(layer "F.SilkS")
			(effects
				(font
					(size 0.7874 0.5842)
					(thickness 0.1524)
				)
				(justify left)
			)
		)
		(property "Value" ""
			(at 0 0 270)
			(layer "F.Fab")
			(effects
				(font
					(size 1.27 1.27)
				)
			)
		)
		(duplicate_pad_numbers_are_jumpers no)
		(fp_line
			(start -0.7874 0.4064)
			(end -0.7874 -0.4064)
			(stroke
				(width 0.1524)
				(type default)
			)
			(layer "F.SilkS")
		)
		(fp_line
			(start 0.7874 0.4064)
			(end -0.7874 0.4064)
			(stroke
				(width 0.1524)
				(type default)
			)
			(layer "F.SilkS")
		)
		(fp_line
			(start -0.7874 -0.4064)
			(end 0.7874 -0.4064)
			(stroke
				(width 0.1524)
				(type default)
			)
			(layer "F.SilkS")
		)
		(fp_line
			(start 0.7874 -0.4064)
			(end 0.7874 0.4064)
			(stroke
				(width 0.1524)
				(type default)
			)
			(layer "F.SilkS")
		)
		(fp_poly
			(pts
				(xy -0.508 0.2794) (xy -0.508 0.2286) (xy -0.635 0.2286) (xy -0.635 -0.254) (xy -0.5334 -0.254)
				(xy -0.5334 -0.2794) (xy 0.5334 -0.2794) (xy 0.5334 -0.254) (xy 0.635 -0.254) (xy 0.635 0.254) (xy 0.5334 0.254)
				(xy 0.5334 0.2794)
			)
			(stroke
				(width 0)
				(type default)
			)
			(fill no)
			(layer "F.CrtYd")
		)
		(pad "1" smd rect
			(at 0.40005 0 270)
			(size 0.4572 0.508)
			(layers "F.Cu" "F.Mask" "F.Paste")
			(net "P3V3_SUS_NODE1")
		)
		(pad "2" smd rect
			(at -0.40005 0 270)
			(size 0.4572 0.508)
			(layers "F.Cu" "F.Mask" "F.Paste")
			(net "CONSOLE_SELECT_N")
		)
	)
	(footprint ""
		(layer "F.Cu")
		(at 122.199908 -8.770112)
		(property "Reference" "H10"
			(at -0.737108 -4.665218 0)
			(unlocked yes)
			(layer "F.SilkS")
			(effects
				(font
					(size 0.7874 0.5842)
					(thickness 0.1524)
				)
				(justify left)
			)
		)
		(property "Value" ""
			(at 0 0 0)
			(layer "F.Fab")
			(effects
				(font
					(size 1.27 1.27)
				)
			)
		)
		(duplicate_pad_numbers_are_jumpers no)
		(fp_poly
			(pts
				(arc
					(start 0 3.9116)
					(mid 0 -3.9116)
					(end 0 3.9116)
				)
			)
			(stroke
				(width 0)
				(type default)
			)
			(fill no)
			(layer "F.CrtYd")
		)
		(pad "1" thru_hole circle
			(at 0 0)
			(size 7.7724 7.7724)
			(drill 5.4102)
			(layers "*.Cu" "*.Mask")
			(remove_unused_layers no)
			(net "GND")
			(clearance -0.9271)
		)
	)
	(footprint ""
		(layer "F.Cu")
		(at 142.910052 -135.18515 180)
		(property "Reference" "R305"
			(at 3.280918 -3.013964 0)
			(unlocked yes)
			(layer "F.SilkS")
			(effects
				(font
					(size 0.7874 0.5842)
					(thickness 0.1524)
				)
				(justify left)
			)
		)
		(property "Value" ""
			(at 0 0 180)
			(layer "F.Fab")
			(effects
				(font
					(size 1.27 1.27)
				)
			)
		)
		(duplicate_pad_numbers_are_jumpers no)
		(fp_line
			(start 0.7874 0.4064)
			(end -0.7874 0.4064)
			(stroke
				(width 0.1524)
				(type default)
			)
			(layer "F.SilkS")
		)
		(fp_line
			(start 0.7874 -0.4064)
			(end 0.7874 0.4064)
			(stroke
				(width 0.1524)
				(type default)
			)
			(layer "F.SilkS")
		)
		(fp_line
			(start -0.7874 0.4064)
			(end -0.7874 -0.4064)
			(stroke
				(width 0.1524)
				(type default)
			)
			(layer "F.SilkS")
		)
		(fp_line
			(start -0.7874 -0.4064)
			(end 0.7874 -0.4064)
			(stroke
				(width 0.1524)
				(type default)
			)
			(layer "F.SilkS")
		)
		(fp_poly
			(pts
				(xy -0.508 0.2794) (xy -0.508 0.2286) (xy -0.635 0.2286) (xy -0.635 -0.254) (xy -0.5334 -0.254)
				(xy -0.5334 -0.2794) (xy 0.5334 -0.2794) (xy 0.5334 -0.254) (xy 0.635 -0.254) (xy 0.635 0.254) (xy 0.5334 0.254)
				(xy 0.5334 0.2794)
			)
			(stroke
				(width 0)
				(type default)
			)
			(fill no)
			(layer "F.CrtYd")
		)
		(pad "1" smd rect
			(at 0.40005 0 180)
			(size 0.4572 0.508)
			(layers "F.Cu" "F.Mask" "F.Paste")
			(net "PCIE_SW_SLOTCLK")
		)
		(pad "2" smd rect
			(at -0.40005 0 180)
			(size 0.4572 0.508)
			(layers "F.Cu" "F.Mask" "F.Paste")
			(net "P3V3_NODE1")
		)
	)
	(footprint ""
		(layer "F.Cu")
		(at 42.636694 -108.133134 -90)
		(property "Reference" "PC20"
			(at 0.09398 3.523234 0)
			(unlocked yes)
			(layer "F.SilkS")
			(effects
				(font
					(size 0.7874 0.5842)
					(thickness 0.1524)
				)
				(justify left)
			)
		)
		(property "Value" ""
			(at 0 0 270)
			(layer "F.Fab")
			(effects
				(font
					(size 1.27 1.27)
				)
			)
		)
		(duplicate_pad_numbers_are_jumpers no)
		(fp_line
			(start -0.7874 0.4064)
			(end -0.7874 -0.4064)
			(stroke
				(width 0.1524)
				(type default)
			)
			(layer "F.SilkS")
		)
		(fp_line
			(start 0.7874 0.4064)
			(end -0.7874 0.4064)
			(stroke
				(width 0.1524)
				(type default)
			)
			(layer "F.SilkS")
		)
		(fp_line
			(start 0 0.381)
			(end 0 -0.381)
			(stroke
				(width 0.1524)
				(type default)
			)
			(layer "F.SilkS")
		)
		(fp_line
			(start -0.7874 -0.4064)
			(end 0.7874 -0.4064)
			(stroke
				(width 0.1524)
				(type default)
			)
			(layer "F.SilkS")
		)
		(fp_line
			(start 0.7874 -0.4064)
			(end 0.7874 0.4064)
			(stroke
				(width 0.1524)
				(type default)
			)
			(layer "F.SilkS")
		)
		(fp_poly
			(pts
				(xy -0.5334 0.254) (xy -0.635 0.254) (xy -0.635 0.2286) (xy -0.635 -0.254) (xy -0.5334 -0.254) (xy -0.5334 -0.2794)
				(xy 0.5334 -0.2794) (xy 0.5334 -0.254) (xy 0.635 -0.254) (xy 0.635 0.254) (xy 0.5334 0.254) (xy 0.5334 0.2794)
				(xy -0.508 0.2794) (xy -0.5334 0.2794)
			)
			(stroke
				(width 0)
				(type default)
			)
			(fill no)
			(layer "F.CrtYd")
		)
		(pad "1" smd rect
			(at 0.40005 0 270)
			(size 0.4572 0.508)
			(layers "F.Cu" "F.Mask" "F.Paste")
			(net "GND")
		)
		(pad "2" smd rect
			(at -0.40005 0 270)
			(size 0.4572 0.508)
			(layers "F.Cu" "F.Mask" "F.Paste")
			(net "P3V3_STB_NODE1_SS")
		)
	)
	(footprint ""
		(layer "F.Cu")
		(at 91.102434 -184.794398 180)
		(property "Reference" "C687"
			(at 1.458214 7.09041 0)
			(unlocked yes)
			(layer "F.SilkS")
			(effects
				(font
					(size 0.7874 0.5842)
					(thickness 0.1524)
				)
				(justify left)
			)
		)
		(property "Value" ""
			(at 0 0 180)
			(layer "F.Fab")
			(effects
				(font
					(size 1.27 1.27)
				)
			)
		)
		(duplicate_pad_numbers_are_jumpers no)
		(fp_line
			(start 0.7874 0.4064)
			(end -0.7874 0.4064)
			(stroke
				(width 0.1524)
				(type default)
			)
			(layer "F.SilkS")
		)
		(fp_line
			(start 0.7874 -0.4064)
			(end 0.7874 0.4064)
			(stroke
				(width 0.1524)
				(type default)
			)
			(layer "F.SilkS")
		)
		(fp_line
			(start 0 0.381)
			(end 0 -0.381)
			(stroke
				(width 0.1524)
				(type default)
			)
			(layer "F.SilkS")
		)
		(fp_line
			(start -0.7874 0.4064)
			(end -0.7874 -0.4064)
			(stroke
				(width 0.1524)
				(type default)
			)
			(layer "F.SilkS")
		)
		(fp_line
			(start -0.7874 -0.4064)
			(end 0.7874 -0.4064)
			(stroke
				(width 0.1524)
				(type default)
			)
			(layer "F.SilkS")
		)
		(fp_poly
			(pts
				(xy -0.5334 0.254) (xy -0.635 0.254) (xy -0.635 0.2286) (xy -0.635 -0.254) (xy -0.5334 -0.254) (xy -0.5334 -0.2794)
				(xy 0.5334 -0.2794) (xy 0.5334 -0.254) (xy 0.635 -0.254) (xy 0.635 0.254) (xy 0.5334 0.254) (xy 0.5334 0.2794)
				(xy -0.508 0.2794) (xy -0.5334 0.2794)
			)
			(stroke
				(width 0)
				(type default)
			)
			(fill no)
			(layer "F.CrtYd")
		)
		(pad "1" smd rect
			(at 0.40005 0 180)
			(size 0.4572 0.508)
			(layers "F.Cu" "F.Mask" "F.Paste")
			(net "UART_T5_NODE3_TXD_R")
		)
		(pad "2" smd rect
			(at -0.40005 0 180)
			(size 0.4572 0.508)
			(layers "F.Cu" "F.Mask" "F.Paste")
			(net "GND")
		)
	)
	(footprint ""
		(layer "F.Cu")
		(at 114.046254 -62.271148 180)
		(property "Reference" "R228"
			(at -1.25349 -1.859788 0)
			(unlocked yes)
			(layer "F.SilkS")
			(effects
				(font
					(size 0.7874 0.5842)
					(thickness 0.1524)
				)
				(justify left)
			)
		)
		(property "Value" ""
			(at 0 0 180)
			(layer "F.Fab")
			(effects
				(font
					(size 1.27 1.27)
				)
			)
		)
		(duplicate_pad_numbers_are_jumpers no)
		(fp_line
			(start 0.7874 0.4064)
			(end -0.7874 0.4064)
			(stroke
				(width 0.1524)
				(type default)
			)
			(layer "F.SilkS")
		)
		(fp_line
			(start 0.7874 -0.4064)
			(end 0.7874 0.4064)
			(stroke
				(width 0.1524)
				(type default)
			)
			(layer "F.SilkS")
		)
		(fp_line
			(start -0.7874 0.4064)
			(end -0.7874 -0.4064)
			(stroke
				(width 0.1524)
				(type default)
			)
			(layer "F.SilkS")
		)
		(fp_line
			(start -0.7874 -0.4064)
			(end 0.7874 -0.4064)
			(stroke
				(width 0.1524)
				(type default)
			)
			(layer "F.SilkS")
		)
		(fp_poly
			(pts
				(xy -0.508 0.2794) (xy -0.508 0.2286) (xy -0.635 0.2286) (xy -0.635 -0.254) (xy -0.5334 -0.254)
				(xy -0.5334 -0.2794) (xy 0.5334 -0.2794) (xy 0.5334 -0.254) (xy 0.635 -0.254) (xy 0.635 0.254) (xy 0.5334 0.254)
				(xy 0.5334 0.2794)
			)
			(stroke
				(width 0)
				(type default)
			)
			(fill no)
			(layer "F.CrtYd")
		)
		(pad "1" smd rect
			(at 0.40005 0 180)
			(size 0.4572 0.508)
			(layers "F.Cu" "F.Mask" "F.Paste")
			(net "XDP_SOC_CPU_NODE1_TDO")
		)
		(pad "2" smd rect
			(at -0.40005 0 180)
			(size 0.4572 0.508)
			(layers "F.Cu" "F.Mask" "F.Paste")
			(net "P1V05_NODE1")
		)
	)
	(footprint ""
		(layer "F.Cu")
		(at 119.538242 -39.53764 -90)
		(property "Reference" "R815"
			(at 6.720332 -0.181864 90)
			(unlocked yes)
			(layer "F.SilkS")
			(effects
				(font
					(size 0.7874 0.5842)
					(thickness 0.1524)
				)
				(justify left)
			)
		)
		(property "Value" ""
			(at 0 0 270)
			(layer "F.Fab")
			(effects
				(font
					(size 1.27 1.27)
				)
			)
		)
		(duplicate_pad_numbers_are_jumpers no)
		(fp_line
			(start -0.7874 0.4064)
			(end -0.7874 -0.4064)
			(stroke
				(width 0.1524)
				(type default)
			)
			(layer "F.SilkS")
		)
		(fp_line
			(start 0.7874 0.4064)
			(end -0.7874 0.4064)
			(stroke
				(width 0.1524)
				(type default)
			)
			(layer "F.SilkS")
		)
		(fp_line
			(start -0.7874 -0.4064)
			(end 0.7874 -0.4064)
			(stroke
				(width 0.1524)
				(type default)
			)
			(layer "F.SilkS")
		)
		(fp_line
			(start 0.7874 -0.4064)
			(end 0.7874 0.4064)
			(stroke
				(width 0.1524)
				(type default)
			)
			(layer "F.SilkS")
		)
		(fp_poly
			(pts
				(xy -0.508 0.2794) (xy -0.508 0.2286) (xy -0.635 0.2286) (xy -0.635 -0.254) (xy -0.5334 -0.254)
				(xy -0.5334 -0.2794) (xy 0.5334 -0.2794) (xy 0.5334 -0.254) (xy 0.635 -0.254) (xy 0.635 0.254) (xy 0.5334 0.254)
				(xy 0.5334 0.2794)
			)
			(stroke
				(width 0)
				(type default)
			)
			(fill no)
			(layer "F.CrtYd")
		)
		(pad "1" smd rect
			(at 0.40005 0 270)
			(size 0.4572 0.508)
			(layers "F.Cu" "F.Mask" "F.Paste")
			(net "CLK_48M_SIO")
		)
		(pad "2" smd rect
			(at -0.40005 0 270)
			(size 0.4572 0.508)
			(layers "F.Cu" "F.Mask" "F.Paste")
			(net "SIO_CLKIN")
		)
	)
	(footprint ""
		(layer "F.Cu")
		(at 53.561996 -157.982158)
		(property "Reference" "R596"
			(at -0.575564 -5.34035 0)
			(unlocked yes)
			(layer "F.SilkS")
			(effects
				(font
					(size 0.7874 0.5842)
					(thickness 0.1524)
				)
				(justify left)
			)
		)
		(property "Value" ""
			(at 0 0 0)
			(layer "F.Fab")
			(effects
				(font
					(size 1.27 1.27)
				)
			)
		)
		(duplicate_pad_numbers_are_jumpers no)
		(fp_line
			(start -0.7874 -0.4064)
			(end 0.7874 -0.4064)
			(stroke
				(width 0.1524)
				(type default)
			)
			(layer "F.SilkS")
		)
		(fp_line
			(start -0.7874 0.4064)
			(end -0.7874 -0.4064)
			(stroke
				(width 0.1524)
				(type default)
			)
			(layer "F.SilkS")
		)
		(fp_line
			(start 0.7874 -0.4064)
			(end 0.7874 0.4064)
			(stroke
				(width 0.1524)
				(type default)
			)
			(layer "F.SilkS")
		)
		(fp_line
			(start 0.7874 0.4064)
			(end -0.7874 0.4064)
			(stroke
				(width 0.1524)
				(type default)
			)
			(layer "F.SilkS")
		)
		(fp_poly
			(pts
				(xy -0.508 0.2794) (xy -0.508 0.2286) (xy -0.635 0.2286) (xy -0.635 -0.254) (xy -0.5334 -0.254)
				(xy -0.5334 -0.2794) (xy 0.5334 -0.2794) (xy 0.5334 -0.254) (xy 0.635 -0.254) (xy 0.635 0.254) (xy 0.5334 0.254)
				(xy 0.5334 0.2794)
			)
			(stroke
				(width 0)
				(type default)
			)
			(fill no)
			(layer "F.CrtYd")
		)
		(pad "1" smd rect
			(at 0.40005 0)
			(size 0.4572 0.508)
			(layers "F.Cu" "F.Mask" "F.Paste")
			(net "P3V3_NODE1")
		)
		(pad "2" smd rect
			(at -0.40005 0)
			(size 0.4572 0.508)
			(layers "F.Cu" "F.Mask" "F.Paste")
			(net "LAN1_DISABLE_N")
		)
	)
	(footprint ""
		(layer "F.Cu")
		(at 193.143886 -142.116302 180)
		(property "Reference" "C460"
			(at -2.05232 -0.462026 0)
			(unlocked yes)
			(layer "F.SilkS")
			(effects
				(font
					(size 0.7874 0.5842)
					(thickness 0.1524)
				)
				(justify left)
			)
		)
		(property "Value" ""
			(at 0 0 180)
			(layer "F.Fab")
			(effects
				(font
					(size 1.27 1.27)
				)
			)
		)
		(duplicate_pad_numbers_are_jumpers no)
		(fp_line
			(start 0.7874 0.4064)
			(end -0.7874 0.4064)
			(stroke
				(width 0.1524)
				(type default)
			)
			(layer "F.SilkS")
		)
		(fp_line
			(start 0.7874 -0.4064)
			(end 0.7874 0.4064)
			(stroke
				(width 0.1524)
				(type default)
			)
			(layer "F.SilkS")
		)
		(fp_line
			(start 0 0.381)
			(end 0 -0.381)
			(stroke
				(width 0.1524)
				(type default)
			)
			(layer "F.SilkS")
		)
		(fp_line
			(start -0.7874 0.4064)
			(end -0.7874 -0.4064)
			(stroke
				(width 0.1524)
				(type default)
			)
			(layer "F.SilkS")
		)
		(fp_line
			(start -0.7874 -0.4064)
			(end 0.7874 -0.4064)
			(stroke
				(width 0.1524)
				(type default)
			)
			(layer "F.SilkS")
		)
		(fp_poly
			(pts
				(xy -0.5334 0.254) (xy -0.635 0.254) (xy -0.635 0.2286) (xy -0.635 -0.254) (xy -0.5334 -0.254) (xy -0.5334 -0.2794)
				(xy 0.5334 -0.2794) (xy 0.5334 -0.254) (xy 0.635 -0.254) (xy 0.635 0.254) (xy 0.5334 0.254) (xy 0.5334 0.2794)
				(xy -0.508 0.2794) (xy -0.5334 0.2794)
			)
			(stroke
				(width 0)
				(type default)
			)
			(fill no)
			(layer "F.CrtYd")
		)
		(pad "1" smd rect
			(at 0.40005 0 180)
			(size 0.4572 0.508)
			(layers "F.Cu" "F.Mask" "F.Paste")
			(net "P1V9_LAN2")
		)
		(pad "2" smd rect
			(at -0.40005 0 180)
			(size 0.4572 0.508)
			(layers "F.Cu" "F.Mask" "F.Paste")
			(net "GND")
		)
	)
	(footprint ""
		(layer "F.Cu")
		(at 77.506068 -94.131892 -90)
		(property "Reference" "R153"
			(at 55.53329 -24.083264 90)
			(unlocked yes)
			(layer "F.SilkS")
			(effects
				(font
					(size 0.7874 0.5842)
					(thickness 0.1524)
				)
				(justify left)
			)
		)
		(property "Value" ""
			(at 0 0 270)
			(layer "F.Fab")
			(effects
				(font
					(size 1.27 1.27)
				)
			)
		)
		(duplicate_pad_numbers_are_jumpers no)
		(fp_line
			(start -0.7874 0.4064)
			(end -0.7874 -0.4064)
			(stroke
				(width 0.1524)
				(type default)
			)
			(layer "F.SilkS")
		)
		(fp_line
			(start 0.7874 0.4064)
			(end -0.7874 0.4064)
			(stroke
				(width 0.1524)
				(type default)
			)
			(layer "F.SilkS")
		)
		(fp_line
			(start -0.7874 -0.4064)
			(end 0.7874 -0.4064)
			(stroke
				(width 0.1524)
				(type default)
			)
			(layer "F.SilkS")
		)
		(fp_line
			(start 0.7874 -0.4064)
			(end 0.7874 0.4064)
			(stroke
				(width 0.1524)
				(type default)
			)
			(layer "F.SilkS")
		)
		(fp_poly
			(pts
				(xy -0.508 0.2794) (xy -0.508 0.2286) (xy -0.635 0.2286) (xy -0.635 -0.254) (xy -0.5334 -0.254)
				(xy -0.5334 -0.2794) (xy 0.5334 -0.2794) (xy 0.5334 -0.254) (xy 0.635 -0.254) (xy 0.635 0.254) (xy 0.5334 0.254)
				(xy 0.5334 0.2794)
			)
			(stroke
				(width 0)
				(type default)
			)
			(fill no)
			(layer "F.CrtYd")
		)
		(pad "1" smd rect
			(at 0.40005 0 270)
			(size 0.4572 0.508)
			(layers "F.Cu" "F.Mask" "F.Paste")
			(net "PU_CPU_NODE1_BRD_ID0")
		)
		(pad "2" smd rect
			(at -0.40005 0 270)
			(size 0.4572 0.508)
			(layers "F.Cu" "F.Mask" "F.Paste")
			(net "P3V3_NODE1")
		)
	)
	(footprint ""
		(layer "F.Cu")
		(at 36.707572 -72.386698)
		(property "Reference" "R46"
			(at -3.279394 0.381 0)
			(unlocked yes)
			(layer "F.SilkS")
			(effects
				(font
					(size 0.7874 0.5842)
					(thickness 0.1524)
				)
				(justify left)
			)
		)
		(property "Value" ""
			(at 0 0 0)
			(layer "F.Fab")
			(effects
				(font
					(size 1.27 1.27)
				)
			)
		)
		(duplicate_pad_numbers_are_jumpers no)
		(fp_line
			(start -0.7874 -0.4064)
			(end 0.7874 -0.4064)
			(stroke
				(width 0.1524)
				(type default)
			)
			(layer "F.SilkS")
		)
		(fp_line
			(start -0.7874 0.4064)
			(end -0.7874 -0.4064)
			(stroke
				(width 0.1524)
				(type default)
			)
			(layer "F.SilkS")
		)
		(fp_line
			(start 0.7874 -0.4064)
			(end 0.7874 0.4064)
			(stroke
				(width 0.1524)
				(type default)
			)
			(layer "F.SilkS")
		)
		(fp_line
			(start 0.7874 0.4064)
			(end -0.7874 0.4064)
			(stroke
				(width 0.1524)
				(type default)
			)
			(layer "F.SilkS")
		)
		(fp_poly
			(pts
				(xy -0.508 0.2794) (xy -0.508 0.2286) (xy -0.635 0.2286) (xy -0.635 -0.254) (xy -0.5334 -0.254)
				(xy -0.5334 -0.2794) (xy 0.5334 -0.2794) (xy 0.5334 -0.254) (xy 0.635 -0.254) (xy 0.635 0.254) (xy 0.5334 0.254)
				(xy 0.5334 0.2794)
			)
			(stroke
				(width 0)
				(type default)
			)
			(fill no)
			(layer "F.CrtYd")
		)
		(pad "1" smd rect
			(at 0.40005 0)
			(size 0.4572 0.508)
			(layers "F.Cu" "F.Mask" "F.Paste")
			(net "PD_CPU_NODE1_RP1_PERN")
		)
		(pad "2" smd rect
			(at -0.40005 0)
			(size 0.4572 0.508)
			(layers "F.Cu" "F.Mask" "F.Paste")
			(net "GND")
		)
	)
	(footprint ""
		(layer "F.Cu")
		(at 127.652018 -56.418988 -90)
		(property "Reference" "U135"
			(at -2.775966 -1.285748 0)
			(unlocked yes)
			(layer "F.SilkS")
			(effects
				(font
					(size 0.7874 0.5842)
					(thickness 0.1524)
				)
			)
		)
		(property "Value" ""
			(at 0 0 270)
			(layer "F.Fab")
			(effects
				(font
					(size 1.27 1.27)
				)
			)
		)
		(duplicate_pad_numbers_are_jumpers no)
		(fp_line
			(start 1.1176 1.7018)
			(end -1.1176 1.7018)
			(stroke
				(width 0.1524)
				(type default)
			)
			(layer "F.SilkS")
		)
		(fp_line
			(start -1.1176 0.254)
			(end -1.1176 1.7018)
			(stroke
				(width 0.1524)
				(type default)
			)
			(layer "F.SilkS")
		)
		(fp_line
			(start -0.7112 0)
			(end -1.1176 0.254)
			(stroke
				(width 0.1524)
				(type default)
			)
			(layer "F.SilkS")
		)
		(fp_line
			(start -1.1176 -0.254)
			(end -0.7112 0)
			(stroke
				(width 0.1524)
				(type default)
			)
			(layer "F.SilkS")
		)
		(fp_line
			(start -1.1176 -1.7018)
			(end -1.1176 -0.254)
			(stroke
				(width 0.1524)
				(type default)
			)
			(layer "F.SilkS")
		)
		(fp_line
			(start -1.1176 -1.7018)
			(end 1.1176 -1.7018)
			(stroke
				(width 0.1524)
				(type default)
			)
			(layer "F.SilkS")
		)
		(fp_line
			(start 1.1176 -1.7018)
			(end 1.1176 1.7018)
			(stroke
				(width 0.1524)
				(type default)
			)
			(layer "F.SilkS")
		)
		(fp_poly
			(pts
				(xy -0.675386 1.8161) (xy -0.446786 2.4003) (xy -0.878586 2.4003)
			)
			(stroke
				(width 0)
				(type default)
			)
			(fill yes)
			(layer "F.SilkS")
		)
		(fp_rect
			(start -1.1176 1.5494)
			(end 1.1176 -1.5494)
			(stroke
				(width 0)
				(type default)
			)
			(fill no)
			(layer "F.CrtYd")
		)
		(fp_line
			(start 1.1176 1.5494)
			(end -1.1176 1.5494)
			(stroke
				(width 0.1)
				(type default)
			)
			(layer "F.Fab")
		)
		(fp_line
			(start -1.1176 0.254)
			(end -1.1176 1.5494)
			(stroke
				(width 0.1)
				(type default)
			)
			(layer "F.Fab")
		)
		(fp_line
			(start -1.1176 -0.254)
			(end -1.1176 0.254)
			(stroke
				(width 0.1)
				(type default)
			)
			(layer "F.Fab")
		)
		(fp_line
			(start -1.1176 -1.5494)
			(end -1.1176 -0.254)
			(stroke
				(width 0.1)
				(type default)
			)
			(layer "F.Fab")
		)
		(fp_line
			(start -1.1176 -1.5494)
			(end 1.1176 -1.5494)
			(stroke
				(width 0.1)
				(type default)
			)
			(layer "F.Fab")
		)
		(fp_line
			(start 1.1176 -1.5494)
			(end 1.1176 1.5494)
			(stroke
				(width 0.1)
				(type default)
			)
			(layer "F.Fab")
		)
		(fp_poly
			(pts
				(xy -0.675386 1.8161) (xy -0.446786 2.4003) (xy -0.878586 2.4003)
			)
			(stroke
				(width 0)
				(type default)
			)
			(fill yes)
			(layer "F.Fab")
		)
		(pad "1" smd rect
			(at -0.649986 0.962406 270)
			(size 0.3302 1.1684)
			(layers "F.Cu" "F.Mask" "F.Paste")
			(net "COM4_EN_N")
		)
		(pad "2" smd rect
			(at 0 0.962406 270)
			(size 0.3302 1.1684)
			(layers "F.Cu" "F.Mask" "F.Paste")
			(net "UART_TX_P4_BUF")
		)
		(pad "3" smd rect
			(at 0.649986 0.962406 270)
			(size 0.3302 1.1684)
			(layers "F.Cu" "F.Mask" "F.Paste")
			(net "GND")
		)
		(pad "4" smd rect
			(at 0.649986 -0.962406 270)
			(size 0.3302 1.1684)
			(layers "F.Cu" "F.Mask" "F.Paste")
			(net "UART_TX_P4")
		)
		(pad "5" smd rect
			(at -0.649986 -0.962406 270)
			(size 0.3302 1.1684)
			(layers "F.Cu" "F.Mask" "F.Paste")
			(net "P3V3_NODE1")
		)
	)
	(footprint ""
		(layer "F.Cu")
		(at 15.247366 -60.31357 90)
		(property "Reference" "R637"
			(at -1.68656 -0.98552 90)
			(unlocked yes)
			(layer "F.SilkS")
			(effects
				(font
					(size 0.7874 0.5842)
					(thickness 0.1524)
				)
				(justify left)
			)
		)
		(property "Value" ""
			(at 0 0 90)
			(layer "F.Fab")
			(effects
				(font
					(size 1.27 1.27)
				)
			)
		)
		(duplicate_pad_numbers_are_jumpers no)
		(fp_line
			(start 0.7874 -0.4064)
			(end 0.7874 0.4064)
			(stroke
				(width 0.1524)
				(type default)
			)
			(layer "F.SilkS")
		)
		(fp_line
			(start -0.7874 -0.4064)
			(end 0.7874 -0.4064)
			(stroke
				(width 0.1524)
				(type default)
			)
			(layer "F.SilkS")
		)
		(fp_line
			(start 0.7874 0.4064)
			(end -0.7874 0.4064)
			(stroke
				(width 0.1524)
				(type default)
			)
			(layer "F.SilkS")
		)
		(fp_line
			(start -0.7874 0.4064)
			(end -0.7874 -0.4064)
			(stroke
				(width 0.1524)
				(type default)
			)
			(layer "F.SilkS")
		)
		(fp_poly
			(pts
				(xy -0.508 0.2794) (xy -0.508 0.2286) (xy -0.635 0.2286) (xy -0.635 -0.254) (xy -0.5334 -0.254)
				(xy -0.5334 -0.2794) (xy 0.5334 -0.2794) (xy 0.5334 -0.254) (xy 0.635 -0.254) (xy 0.635 0.254) (xy 0.5334 0.254)
				(xy 0.5334 0.2794)
			)
			(stroke
				(width 0)
				(type default)
			)
			(fill no)
			(layer "F.CrtYd")
		)
		(pad "1" smd rect
			(at 0.40005 0 90)
			(size 0.4572 0.508)
			(layers "F.Cu" "F.Mask" "F.Paste")
			(net "VGA_VSYNC")
		)
		(pad "2" smd rect
			(at -0.40005 0 90)
			(size 0.4572 0.508)
			(layers "F.Cu" "F.Mask" "F.Paste")
			(net "CRT_VSYNC")
		)
	)
	(footprint ""
		(layer "F.Cu")
		(at 105.000044 -95.79991)
		(property "Reference" "H5"
			(at 7.311136 -4.605782 0)
			(unlocked yes)
			(layer "F.SilkS")
			(effects
				(font
					(size 0.7874 0.5842)
					(thickness 0.1524)
				)
				(justify left)
			)
		)
		(property "Value" ""
			(at 0 0 0)
			(layer "F.Fab")
			(effects
				(font
					(size 1.27 1.27)
				)
			)
		)
		(duplicate_pad_numbers_are_jumpers no)
		(fp_circle
			(center 0 0)
			(end 7.999984 0)
			(stroke
				(width 0.1524)
				(type default)
			)
			(fill no)
			(layer "F.SilkS")
		)
		(fp_arc
			(start 11.071352 -9.680448)
			(mid 13.767871 -5.170265)
			(end 14.7066 0)
			(stroke
				(width 0.1524)
				(type default)
			)
			(layer "B.SilkS")
		)
		(fp_arc
			(start 14.7066 0)
			(mid -7.269888 12.784085)
			(end -7.519162 -12.63904)
			(stroke
				(width 0.1524)
				(type default)
			)
			(layer "B.SilkS")
		)
		(fp_circle
			(center 0 0)
			(end 7.999984 0)
			(stroke
				(width 0.1524)
				(type default)
			)
			(fill no)
			(layer "B.SilkS")
		)
		(fp_poly
			(pts
				(arc
					(start 0 5.0038)
					(mid 0 -5.0038)
					(end 0 5.0038)
				)
			)
			(stroke
				(width 0)
				(type default)
			)
			(fill no)
			(layer "F.CrtYd")
		)
		(pad "" np_thru_hole circle
			(at 0 0)
			(size 4.0132 4.0132)
			(drill 4.0132)
			(layers "*.Cu" "*.Mask")
			(clearance 0.381)
			(thermal_gap 0.381)
		)
		(pad "2" thru_hole circle
			(at 0 -3.50012)
			(size 0.762 0.762)
			(drill 0.5588)
			(layers "*.Cu" "*.Mask")
			(remove_unused_layers no)
			(net "GND")
			(clearance 0.1524)
			(thermal_gap 0.1524)
		)
		(pad "3" thru_hole circle
			(at -2.500122 -2.500122)
			(size 0.762 0.762)
			(drill 0.5588)
			(layers "*.Cu" "*.Mask")
			(remove_unused_layers no)
			(net "GND")
			(clearance 0.1524)
			(thermal_gap 0.1524)
		)
		(pad "4" thru_hole circle
			(at -3.50012 0)
			(size 0.762 0.762)
			(drill 0.5588)
			(layers "*.Cu" "*.Mask")
			(remove_unused_layers no)
			(net "GND")
			(clearance 0.1524)
			(thermal_gap 0.1524)
		)
		(pad "5" thru_hole circle
			(at -2.500122 2.500122)
			(size 0.762 0.762)
			(drill 0.5588)
			(layers "*.Cu" "*.Mask")
			(remove_unused_layers no)
			(net "GND")
			(clearance 0.1524)
			(thermal_gap 0.1524)
		)
		(pad "6" thru_hole circle
			(at 0 3.50012)
			(size 0.762 0.762)
			(drill 0.5588)
			(layers "*.Cu" "*.Mask")
			(remove_unused_layers no)
			(net "GND")
			(clearance 0.1524)
			(thermal_gap 0.1524)
		)
		(pad "7" thru_hole circle
			(at 2.500122 2.500122)
			(size 0.762 0.762)
			(drill 0.5588)
			(layers "*.Cu" "*.Mask")
			(remove_unused_layers no)
			(net "GND")
			(clearance 0.1524)
			(thermal_gap 0.1524)
		)
		(pad "8" thru_hole circle
			(at 3.50012 0)
			(size 0.762 0.762)
			(drill 0.5588)
			(layers "*.Cu" "*.Mask")
			(remove_unused_layers no)
			(net "GND")
			(clearance 0.1524)
			(thermal_gap 0.1524)
		)
		(pad "9" thru_hole circle
			(at 2.500122 -2.500122)
			(size 0.762 0.762)
			(drill 0.5588)
			(layers "*.Cu" "*.Mask")
			(remove_unused_layers no)
			(net "GND")
			(clearance 0.1524)
			(thermal_gap 0.1524)
		)
		(zone
			(layer "F.Cu")
			(hatch none 0.5)
			(connect_pads
				(clearance 0)
			)
			(min_thickness 0.25)
			(keepout
				(tracks not_allowed)
				(vias allowed)
				(pads allowed)
				(copperpour not_allowed)
				(footprints allowed)
			)
			(placement
				(enabled no)
				(sheetname "")
			)
			(fill
				(thermal_gap 0.5)
				(thermal_bridge_width 0.5)
				(island_removal_mode 0)
			)
			(polygon
				(pts
					(arc
						(start 105.000044 -90.69451)
						(mid 99.894644 -95.79991)
						(end 105.000044 -100.90531)
					)
					(arc
						(start 105.000044 -103.799894)
						(mid 97.00006 -95.79991)
						(end 105.000044 -87.799926)
					)
				)
			)
		)
		(zone
			(layer "F.Cu")
			(hatch none 0.5)
			(connect_pads
				(clearance 0)
			)
			(min_thickness 0.25)
			(keepout
				(tracks not_allowed)
				(vias allowed)
				(pads allowed)
				(copperpour not_allowed)
				(footprints allowed)
			)
			(placement
				(enabled no)
				(sheetname "")
			)
			(fill
				(thermal_gap 0.5)
				(thermal_bridge_width 0.5)
				(island_removal_mode 0)
			)
			(polygon
				(pts
					(arc
						(start 105.000044 -90.69451)
						(mid 110.105444 -95.79991)
						(end 105.000044 -100.90531)
					)
					(arc
						(start 105.000044 -103.799894)
						(mid 113.000028 -95.79991)
						(end 105.000044 -87.799926)
					)
				)
			)
		)
		(zone
			(layers "F.Cu" "B.Cu" "In1.Cu" "In2.Cu" "In3.Cu" "In4.Cu" "In5.Cu" "In6.Cu"
				"In7.Cu" "In8.Cu"
			)
			(hatch none 0.5)
			(connect_pads
				(clearance 0)
			)
			(min_thickness 0.25)
			(keepout
				(tracks not_allowed)
				(vias allowed)
				(pads allowed)
				(copperpour not_allowed)
				(footprints allowed)
			)
			(placement
				(enabled no)
				(sheetname "")
			)
			(fill
				(thermal_gap 0.5)
				(thermal_bridge_width 0.5)
				(island_removal_mode 0)
			)
			(polygon
				(pts
					(arc
						(start 105.000044 -93.28785)
						(mid 105.000044 -98.31197)
						(end 105.000044 -93.28785)
					)
				)
			)
		)
		(zone
			(layer "B.Cu")
			(hatch none 0.5)
			(connect_pads
				(clearance 0)
			)
			(min_thickness 0.25)
			(keepout
				(tracks not_allowed)
				(vias allowed)
				(pads allowed)
				(copperpour not_allowed)
				(footprints allowed)
			)
			(placement
				(enabled no)
				(sheetname "")
			)
			(fill
				(thermal_gap 0.5)
				(thermal_bridge_width 0.5)
				(island_removal_mode 0)
			)
			(polygon
				(pts
					(xy 99.974654 -90.79611) (xy 99.974654 -95.79991) (xy 99.492054 -95.79991) (xy 99.492054 -90.79611)
				)
			)
		)
		(zone
			(layer "B.Cu")
			(hatch none 0.5)
			(connect_pads
				(clearance 0)
			)
			(min_thickness 0.25)
			(keepout
				(tracks not_allowed)
				(vias allowed)
				(pads allowed)
				(copperpour not_allowed)
				(footprints allowed)
			)
			(placement
				(enabled no)
				(sheetname "")
			)
			(fill
				(thermal_gap 0.5)
				(thermal_bridge_width 0.5)
				(island_removal_mode 0)
			)
			(polygon
				(pts
					(xy 110.025434 -95.79991) (xy 110.025434 -90.79611) (xy 110.508034 -90.79611) (xy 110.508034 -95.79991)
				)
			)
		)
		(zone
			(layer "B.Cu")
			(hatch none 0.5)
			(connect_pads
				(clearance 0)
			)
			(min_thickness 0.25)
			(keepout
				(tracks not_allowed)
				(vias allowed)
				(pads allowed)
				(copperpour not_allowed)
				(footprints allowed)
			)
			(placement
				(enabled no)
				(sheetname "")
			)
			(fill
				(thermal_gap 0.5)
				(thermal_bridge_width 0.5)
				(island_removal_mode 0)
			)
			(polygon
				(pts
					(arc
						(start 110.025434 -95.79991)
						(mid 105.000044 -100.8253)
						(end 99.974654 -95.79991)
					)
					(arc
						(start 99.492054 -95.79991)
						(mid 105.000044 -101.3079)
						(end 110.508034 -95.79991)
					)
				)
			)
		)
		(zone
			(layer "B.Cu")
			(hatch none 0.5)
			(connect_pads
				(clearance 0)
			)
			(min_thickness 0.25)
			(keepout
				(tracks not_allowed)
				(vias allowed)
				(pads allowed)
				(copperpour not_allowed)
				(footprints allowed)
			)
			(placement
				(enabled no)
				(sheetname "")
			)
			(fill
				(thermal_gap 0.5)
				(thermal_bridge_width 0.5)
				(island_removal_mode 0)
			)
			(polygon
				(pts
					(arc
						(start 110.025434 -90.799666)
						(mid 105.000044 -85.774276)
						(end 99.974654 -90.799666)
					)
					(arc
						(start 99.492054 -90.799666)
						(mid 105.000044 -85.291676)
						(end 110.508034 -90.799666)
					)
				)
			)
		)
	)
	(footprint ""
		(layer "F.Cu")
		(at 157.302708 -161.19856 90)
		(property "Reference" "R572"
			(at -7.89432 19.359118 90)
			(unlocked yes)
			(layer "F.SilkS")
			(effects
				(font
					(size 0.7874 0.5842)
					(thickness 0.1524)
				)
				(justify left)
			)
		)
		(property "Value" ""
			(at 0 0 90)
			(layer "F.Fab")
			(effects
				(font
					(size 1.27 1.27)
				)
			)
		)
		(duplicate_pad_numbers_are_jumpers no)
		(fp_line
			(start 0.7874 -0.4064)
			(end 0.7874 0.4064)
			(stroke
				(width 0.1524)
				(type default)
			)
			(layer "F.SilkS")
		)
		(fp_line
			(start -0.7874 -0.4064)
			(end 0.7874 -0.4064)
			(stroke
				(width 0.1524)
				(type default)
			)
			(layer "F.SilkS")
		)
		(fp_line
			(start 0.7874 0.4064)
			(end -0.7874 0.4064)
			(stroke
				(width 0.1524)
				(type default)
			)
			(layer "F.SilkS")
		)
		(fp_line
			(start -0.7874 0.4064)
			(end -0.7874 -0.4064)
			(stroke
				(width 0.1524)
				(type default)
			)
			(layer "F.SilkS")
		)
		(fp_poly
			(pts
				(xy -0.508 0.2794) (xy -0.508 0.2286) (xy -0.635 0.2286) (xy -0.635 -0.254) (xy -0.5334 -0.254)
				(xy -0.5334 -0.2794) (xy 0.5334 -0.2794) (xy 0.5334 -0.254) (xy 0.635 -0.254) (xy 0.635 0.254) (xy 0.5334 0.254)
				(xy 0.5334 0.2794)
			)
			(stroke
				(width 0)
				(type default)
			)
			(fill no)
			(layer "F.CrtYd")
		)
		(pad "1" smd rect
			(at 0.40005 0 90)
			(size 0.4572 0.508)
			(layers "F.Cu" "F.Mask" "F.Paste")
			(net "P3V3_NODE1")
		)
		(pad "2" smd rect
			(at -0.40005 0 90)
			(size 0.4572 0.508)
			(layers "F.Cu" "F.Mask" "F.Paste")
			(net "SPI_LAN2_NVM_CS_N")
		)
	)
	(footprint ""
		(layer "F.Cu")
		(at 158.48076 -185.205624 -90)
		(property "Reference" "R821"
			(at -4.768088 -0.297942 90)
			(unlocked yes)
			(layer "F.SilkS")
			(effects
				(font
					(size 0.7874 0.5842)
					(thickness 0.1524)
				)
				(justify left)
			)
		)
		(property "Value" ""
			(at 0 0 270)
			(layer "F.Fab")
			(effects
				(font
					(size 1.27 1.27)
				)
			)
		)
		(duplicate_pad_numbers_are_jumpers no)
		(fp_line
			(start -0.7874 0.4064)
			(end -0.7874 -0.4064)
			(stroke
				(width 0.1524)
				(type default)
			)
			(layer "F.SilkS")
		)
		(fp_line
			(start 0.7874 0.4064)
			(end -0.7874 0.4064)
			(stroke
				(width 0.1524)
				(type default)
			)
			(layer "F.SilkS")
		)
		(fp_line
			(start -0.7874 -0.4064)
			(end 0.7874 -0.4064)
			(stroke
				(width 0.1524)
				(type default)
			)
			(layer "F.SilkS")
		)
		(fp_line
			(start 0.7874 -0.4064)
			(end 0.7874 0.4064)
			(stroke
				(width 0.1524)
				(type default)
			)
			(layer "F.SilkS")
		)
		(fp_poly
			(pts
				(xy -0.508 0.2794) (xy -0.508 0.2286) (xy -0.635 0.2286) (xy -0.635 -0.254) (xy -0.5334 -0.254)
				(xy -0.5334 -0.2794) (xy 0.5334 -0.2794) (xy 0.5334 -0.254) (xy 0.635 -0.254) (xy 0.635 0.254) (xy 0.5334 0.254)
				(xy 0.5334 0.2794)
			)
			(stroke
				(width 0)
				(type default)
			)
			(fill no)
			(layer "F.CrtYd")
		)
		(pad "1" smd rect
			(at 0.40005 0 270)
			(size 0.4572 0.508)
			(layers "F.Cu" "F.Mask" "F.Paste")
			(net "FAN1_TACH")
		)
		(pad "2" smd rect
			(at -0.40005 0 270)
			(size 0.4572 0.508)
			(layers "F.Cu" "F.Mask" "F.Paste")
			(net "FAN1_TACH_R")
		)
	)
	(footprint ""
		(layer "F.Cu")
		(at 135.74776 -188.126624 -90)
		(property "Reference" "R980"
			(at -4.949444 1.336548 90)
			(unlocked yes)
			(layer "F.SilkS")
			(effects
				(font
					(size 0.7874 0.5842)
					(thickness 0.1524)
				)
				(justify left)
			)
		)
		(property "Value" ""
			(at 0 0 270)
			(layer "F.Fab")
			(effects
				(font
					(size 1.27 1.27)
				)
			)
		)
		(duplicate_pad_numbers_are_jumpers no)
		(fp_line
			(start -0.7874 0.4064)
			(end -0.7874 -0.4064)
			(stroke
				(width 0.1524)
				(type default)
			)
			(layer "F.SilkS")
		)
		(fp_line
			(start 0.7874 0.4064)
			(end -0.7874 0.4064)
			(stroke
				(width 0.1524)
				(type default)
			)
			(layer "F.SilkS")
		)
		(fp_line
			(start -0.7874 -0.4064)
			(end 0.7874 -0.4064)
			(stroke
				(width 0.1524)
				(type default)
			)
			(layer "F.SilkS")
		)
		(fp_line
			(start 0.7874 -0.4064)
			(end 0.7874 0.4064)
			(stroke
				(width 0.1524)
				(type default)
			)
			(layer "F.SilkS")
		)
		(fp_poly
			(pts
				(xy -0.508 0.2794) (xy -0.508 0.2286) (xy -0.635 0.2286) (xy -0.635 -0.254) (xy -0.5334 -0.254)
				(xy -0.5334 -0.2794) (xy 0.5334 -0.2794) (xy 0.5334 -0.254) (xy 0.635 -0.254) (xy 0.635 0.254) (xy 0.5334 0.254)
				(xy 0.5334 0.2794)
			)
			(stroke
				(width 0)
				(type default)
			)
			(fill no)
			(layer "F.CrtYd")
		)
		(pad "1" smd rect
			(at 0.40005 0 270)
			(size 0.4572 0.508)
			(layers "F.Cu" "F.Mask" "F.Paste")
			(net "UART_T10_NODE1_RXD")
		)
		(pad "2" smd rect
			(at -0.40005 0 270)
			(size 0.4572 0.508)
			(layers "F.Cu" "F.Mask" "F.Paste")
			(net "UART_T10_NODE1_RXD_R")
		)
	)
	(footprint ""
		(layer "F.Cu")
		(at 148.07184 -176.29632 180)
		(property "Reference" "R806"
			(at 1.07442 2.382012 0)
			(unlocked yes)
			(layer "F.SilkS")
			(effects
				(font
					(size 0.7874 0.5842)
					(thickness 0.1524)
				)
				(justify left)
			)
		)
		(property "Value" ""
			(at 0 0 180)
			(layer "F.Fab")
			(effects
				(font
					(size 1.27 1.27)
				)
			)
		)
		(duplicate_pad_numbers_are_jumpers no)
		(fp_line
			(start 0.7874 0.4064)
			(end -0.7874 0.4064)
			(stroke
				(width 0.1524)
				(type default)
			)
			(layer "F.SilkS")
		)
		(fp_line
			(start 0.7874 -0.4064)
			(end 0.7874 0.4064)
			(stroke
				(width 0.1524)
				(type default)
			)
			(layer "F.SilkS")
		)
		(fp_line
			(start -0.7874 0.4064)
			(end -0.7874 -0.4064)
			(stroke
				(width 0.1524)
				(type default)
			)
			(layer "F.SilkS")
		)
		(fp_line
			(start -0.7874 -0.4064)
			(end 0.7874 -0.4064)
			(stroke
				(width 0.1524)
				(type default)
			)
			(layer "F.SilkS")
		)
		(fp_poly
			(pts
				(xy -0.508 0.2794) (xy -0.508 0.2286) (xy -0.635 0.2286) (xy -0.635 -0.254) (xy -0.5334 -0.254)
				(xy -0.5334 -0.2794) (xy 0.5334 -0.2794) (xy 0.5334 -0.254) (xy 0.635 -0.254) (xy 0.635 0.254) (xy 0.5334 0.254)
				(xy 0.5334 0.2794)
			)
			(stroke
				(width 0)
				(type default)
			)
			(fill no)
			(layer "F.CrtYd")
		)
		(pad "1" smd rect
			(at 0.40005 0 180)
			(size 0.4572 0.508)
			(layers "F.Cu" "F.Mask" "F.Paste")
			(net "CPLD_UART_RI_P3_N")
		)
		(pad "2" smd rect
			(at -0.40005 0 180)
			(size 0.4572 0.508)
			(layers "F.Cu" "F.Mask" "F.Paste")
			(net "GND")
		)
	)
	(footprint ""
		(layer "F.Cu")
		(at 193.143378 -143.39951 180)
		(property "Reference" "C476"
			(at -3.859784 -0.138684 0)
			(unlocked yes)
			(layer "F.SilkS")
			(effects
				(font
					(size 0.7874 0.5842)
					(thickness 0.1524)
				)
			)
		)
		(property "Value" ""
			(at 0 0 180)
			(layer "F.Fab")
			(effects
				(font
					(size 1.27 1.27)
				)
			)
		)
		(duplicate_pad_numbers_are_jumpers no)
		(fp_line
			(start 1.2954 0.5842)
			(end -1.2954 0.5842)
			(stroke
				(width 0.1524)
				(type default)
			)
			(layer "F.SilkS")
		)
		(fp_line
			(start 1.2954 -0.5842)
			(end 1.2954 0.5842)
			(stroke
				(width 0.1524)
				(type default)
			)
			(layer "F.SilkS")
		)
		(fp_line
			(start 0 -0.5842)
			(end 0 0.5842)
			(stroke
				(width 0.1524)
				(type default)
			)
			(layer "F.SilkS")
		)
		(fp_line
			(start -1.2954 0.5842)
			(end -1.2954 -0.5842)
			(stroke
				(width 0.1524)
				(type default)
			)
			(layer "F.SilkS")
		)
		(fp_line
			(start -1.2954 -0.5842)
			(end 1.2954 -0.5842)
			(stroke
				(width 0.1524)
				(type default)
			)
			(layer "F.SilkS")
		)
		(fp_poly
			(pts
				(xy 0.8636 -0.4572) (xy 0.8636 -0.3556) (xy 1.143 -0.3556) (xy 1.143 0.3556) (xy 0.8636 0.3556)
				(xy 0.8636 0.4572) (xy -0.8636 0.4572) (xy -0.8636 0.3556) (xy -1.143 0.3556) (xy -1.143 -0.3556)
				(xy -0.8636 -0.3556) (xy -0.8636 -0.4572)
			)
			(stroke
				(width 0)
				(type default)
			)
			(fill no)
			(layer "F.CrtYd")
		)
		(fp_line
			(start 0.884936 0.504952)
			(end -0.884936 0.504952)
			(stroke
				(width 0.1)
				(type default)
			)
			(layer "F.Fab")
		)
		(fp_line
			(start 0.884936 -0.504952)
			(end 0.884936 0.504952)
			(stroke
				(width 0.1)
				(type default)
			)
			(layer "F.Fab")
		)
		(fp_line
			(start -0.884936 0.504952)
			(end -0.884936 -0.504952)
			(stroke
				(width 0.1)
				(type default)
			)
			(layer "F.Fab")
		)
		(fp_line
			(start -0.884936 -0.504952)
			(end 0.884936 -0.504952)
			(stroke
				(width 0.1)
				(type default)
			)
			(layer "F.Fab")
		)
		(pad "1" smd rect
			(at 0.7366 0 270)
			(size 0.7112 0.8128)
			(layers "F.Cu" "F.Mask" "F.Paste")
			(net "P1V9_LAN2")
		)
		(pad "2" smd rect
			(at -0.7366 0 270)
			(size 0.7112 0.8128)
			(layers "F.Cu" "F.Mask" "F.Paste")
			(net "GND")
		)
	)
	(footprint ""
		(layer "F.Cu")
		(at 87.10676 -185.205624 90)
		(property "Reference" "C714"
			(at 4.198112 -2.117598 90)
			(unlocked yes)
			(layer "F.SilkS")
			(effects
				(font
					(size 0.7874 0.5842)
					(thickness 0.1524)
				)
				(justify left)
			)
		)
		(property "Value" ""
			(at 0 0 90)
			(layer "F.Fab")
			(effects
				(font
					(size 1.27 1.27)
				)
			)
		)
		(duplicate_pad_numbers_are_jumpers no)
		(fp_line
			(start 0.7874 -0.4064)
			(end 0.7874 0.4064)
			(stroke
				(width 0.1524)
				(type default)
			)
			(layer "F.SilkS")
		)
		(fp_line
			(start -0.7874 -0.4064)
			(end 0.7874 -0.4064)
			(stroke
				(width 0.1524)
				(type default)
			)
			(layer "F.SilkS")
		)
		(fp_line
			(start 0 0.381)
			(end 0 -0.381)
			(stroke
				(width 0.1524)
				(type default)
			)
			(layer "F.SilkS")
		)
		(fp_line
			(start 0.7874 0.4064)
			(end -0.7874 0.4064)
			(stroke
				(width 0.1524)
				(type default)
			)
			(layer "F.SilkS")
		)
		(fp_line
			(start -0.7874 0.4064)
			(end -0.7874 -0.4064)
			(stroke
				(width 0.1524)
				(type default)
			)
			(layer "F.SilkS")
		)
		(fp_poly
			(pts
				(xy -0.5334 0.254) (xy -0.635 0.254) (xy -0.635 0.2286) (xy -0.635 -0.254) (xy -0.5334 -0.254) (xy -0.5334 -0.2794)
				(xy 0.5334 -0.2794) (xy 0.5334 -0.254) (xy 0.635 -0.254) (xy 0.635 0.254) (xy 0.5334 0.254) (xy 0.5334 0.2794)
				(xy -0.508 0.2794) (xy -0.5334 0.2794)
			)
			(stroke
				(width 0)
				(type default)
			)
			(fill no)
			(layer "F.CrtYd")
		)
		(pad "1" smd rect
			(at 0.40005 0 90)
			(size 0.4572 0.508)
			(layers "F.Cu" "F.Mask" "F.Paste")
			(net "UART_T6_NODE4_RXD")
		)
		(pad "2" smd rect
			(at -0.40005 0 90)
			(size 0.4572 0.508)
			(layers "F.Cu" "F.Mask" "F.Paste")
			(net "GND")
		)
	)
	(footprint ""
		(layer "F.Cu")
		(at 105.191814 -108.92282 180)
		(property "Reference" "PC106"
			(at 5.833872 0.162052 0)
			(unlocked yes)
			(layer "F.SilkS")
			(effects
				(font
					(size 0.7874 0.5842)
					(thickness 0.1524)
				)
				(justify left)
			)
		)
		(property "Value" ""
			(at 0 0 180)
			(layer "F.Fab")
			(effects
				(font
					(size 1.27 1.27)
				)
			)
		)
		(duplicate_pad_numbers_are_jumpers no)
		(fp_line
			(start 1.905 0.8636)
			(end -1.905 0.8636)
			(stroke
				(width 0.1524)
				(type default)
			)
			(layer "F.SilkS")
		)
		(fp_line
			(start 1.905 -0.8636)
			(end 1.905 0.8636)
			(stroke
				(width 0.1524)
				(type default)
			)
			(layer "F.SilkS")
		)
		(fp_line
			(start 0 0.8382)
			(end 0 -0.8382)
			(stroke
				(width 0.1524)
				(type default)
			)
			(layer "F.SilkS")
		)
		(fp_line
			(start -1.905 0.8636)
			(end -1.905 -0.8636)
			(stroke
				(width 0.1524)
				(type default)
			)
			(layer "F.SilkS")
		)
		(fp_line
			(start -1.905 -0.8636)
			(end 1.905 -0.8636)
			(stroke
				(width 0.1524)
				(type default)
			)
			(layer "F.SilkS")
		)
		(fp_rect
			(start -1.524 0.7366)
			(end 1.524 -0.7366)
			(stroke
				(width 0)
				(type default)
			)
			(fill no)
			(layer "F.CrtYd")
		)
		(pad "1" smd rect
			(at 0.94996 0 180)
			(size 1.1176 1.3716)
			(layers "F.Cu" "F.Mask" "F.Paste")
			(net "GND")
		)
		(pad "2" smd rect
			(at -0.94996 0 180)
			(size 1.1176 1.3716)
			(layers "F.Cu" "F.Mask" "F.Paste")
			(net "PV_VCCP_NODE1")
		)
	)
	(footprint ""
		(layer "F.Cu")
		(at 169.643552 -57.99709)
		(property "Reference" "R268"
			(at -6.518148 0.01524 0)
			(unlocked yes)
			(layer "F.SilkS")
			(effects
				(font
					(size 0.7874 0.5842)
					(thickness 0.1524)
				)
				(justify left)
			)
		)
		(property "Value" ""
			(at 0 0 0)
			(layer "F.Fab")
			(effects
				(font
					(size 1.27 1.27)
				)
			)
		)
		(duplicate_pad_numbers_are_jumpers no)
		(fp_line
			(start -0.7874 -0.4064)
			(end 0.7874 -0.4064)
			(stroke
				(width 0.1524)
				(type default)
			)
			(layer "F.SilkS")
		)
		(fp_line
			(start -0.7874 0.4064)
			(end -0.7874 -0.4064)
			(stroke
				(width 0.1524)
				(type default)
			)
			(layer "F.SilkS")
		)
		(fp_line
			(start 0.7874 -0.4064)
			(end 0.7874 0.4064)
			(stroke
				(width 0.1524)
				(type default)
			)
			(layer "F.SilkS")
		)
		(fp_line
			(start 0.7874 0.4064)
			(end -0.7874 0.4064)
			(stroke
				(width 0.1524)
				(type default)
			)
			(layer "F.SilkS")
		)
		(fp_poly
			(pts
				(xy -0.508 0.2794) (xy -0.508 0.2286) (xy -0.635 0.2286) (xy -0.635 -0.254) (xy -0.5334 -0.254)
				(xy -0.5334 -0.2794) (xy 0.5334 -0.2794) (xy 0.5334 -0.254) (xy 0.635 -0.254) (xy 0.635 0.254) (xy 0.5334 0.254)
				(xy 0.5334 0.2794)
			)
			(stroke
				(width 0)
				(type default)
			)
			(fill no)
			(layer "F.CrtYd")
		)
		(pad "1" smd rect
			(at 0.40005 0)
			(size 0.4572 0.508)
			(layers "F.Cu" "F.Mask" "F.Paste")
			(net "USB2_L_DP")
		)
		(pad "2" smd rect
			(at -0.40005 0)
			(size 0.4572 0.508)
			(layers "F.Cu" "F.Mask" "F.Paste")
			(net "USB2_DP")
		)
	)
	(footprint ""
		(layer "F.Cu")
		(at 120.252744 -159.500316 -90)
		(property "Reference" "R645"
			(at 0.051816 1.878838 90)
			(unlocked yes)
			(layer "F.SilkS")
			(effects
				(font
					(size 0.635 0.4064)
					(thickness 0.1524)
				)
				(justify left)
			)
		)
		(property "Value" ""
			(at 0 0 270)
			(layer "F.Fab")
			(effects
				(font
					(size 1.27 1.27)
				)
			)
		)
		(duplicate_pad_numbers_are_jumpers no)
		(fp_line
			(start -0.7874 0.4064)
			(end -0.7874 -0.4064)
			(stroke
				(width 0.1524)
				(type default)
			)
			(layer "F.SilkS")
		)
		(fp_line
			(start 0.7874 0.4064)
			(end -0.7874 0.4064)
			(stroke
				(width 0.1524)
				(type default)
			)
			(layer "F.SilkS")
		)
		(fp_line
			(start -0.7874 -0.4064)
			(end 0.7874 -0.4064)
			(stroke
				(width 0.1524)
				(type default)
			)
			(layer "F.SilkS")
		)
		(fp_line
			(start 0.7874 -0.4064)
			(end 0.7874 0.4064)
			(stroke
				(width 0.1524)
				(type default)
			)
			(layer "F.SilkS")
		)
		(fp_poly
			(pts
				(xy -0.508 0.2794) (xy -0.508 0.2286) (xy -0.635 0.2286) (xy -0.635 -0.254) (xy -0.5334 -0.254)
				(xy -0.5334 -0.2794) (xy 0.5334 -0.2794) (xy 0.5334 -0.254) (xy 0.635 -0.254) (xy 0.635 0.254) (xy 0.5334 0.254)
				(xy 0.5334 0.2794)
			)
			(stroke
				(width 0)
				(type default)
			)
			(fill no)
			(layer "F.CrtYd")
		)
		(pad "1" smd rect
			(at 0.40005 0 270)
			(size 0.4572 0.508)
			(layers "F.Cu" "F.Mask" "F.Paste")
			(net "I2C_PSU2_SDA")
		)
		(pad "2" smd rect
			(at -0.40005 0 270)
			(size 0.4572 0.508)
			(layers "F.Cu" "F.Mask" "F.Paste")
			(net "I2C_PSU2_SDA_MOS")
		)
	)
	(footprint ""
		(layer "F.Cu")
		(at 85.601048 -128.998726 -90)
		(property "Reference" "R1254"
			(at 5.940044 4.649724 90)
			(unlocked yes)
			(layer "F.SilkS")
			(effects
				(font
					(size 0.7874 0.5842)
					(thickness 0.1524)
				)
				(justify left)
			)
		)
		(property "Value" ""
			(at 0 0 270)
			(layer "F.Fab")
			(effects
				(font
					(size 1.27 1.27)
				)
			)
		)
		(duplicate_pad_numbers_are_jumpers no)
		(fp_line
			(start -0.7874 0.4064)
			(end -0.7874 -0.4064)
			(stroke
				(width 0.1524)
				(type default)
			)
			(layer "F.SilkS")
		)
		(fp_line
			(start 0.7874 0.4064)
			(end -0.7874 0.4064)
			(stroke
				(width 0.1524)
				(type default)
			)
			(layer "F.SilkS")
		)
		(fp_line
			(start -0.7874 -0.4064)
			(end 0.7874 -0.4064)
			(stroke
				(width 0.1524)
				(type default)
			)
			(layer "F.SilkS")
		)
		(fp_line
			(start 0.7874 -0.4064)
			(end 0.7874 0.4064)
			(stroke
				(width 0.1524)
				(type default)
			)
			(layer "F.SilkS")
		)
		(fp_poly
			(pts
				(xy -0.508 0.2794) (xy -0.508 0.2286) (xy -0.635 0.2286) (xy -0.635 -0.254) (xy -0.5334 -0.254)
				(xy -0.5334 -0.2794) (xy 0.5334 -0.2794) (xy 0.5334 -0.254) (xy 0.635 -0.254) (xy 0.635 0.254) (xy 0.5334 0.254)
				(xy 0.5334 0.2794)
			)
			(stroke
				(width 0)
				(type default)
			)
			(fill no)
			(layer "F.CrtYd")
		)
		(pad "1" smd rect
			(at 0.40005 0 270)
			(size 0.4572 0.508)
			(layers "F.Cu" "F.Mask" "F.Paste")
			(net "PORT80_LOUT2")
		)
		(pad "2" smd rect
			(at -0.40005 0 270)
			(size 0.4572 0.508)
			(layers "F.Cu" "F.Mask" "F.Paste")
			(net "N53313479")
		)
	)
	(footprint ""
		(layer "F.Cu")
		(at 111.317532 -138.681206 90)
		(property "Reference" "PC87"
			(at 3.924554 3.960114 90)
			(unlocked yes)
			(layer "F.SilkS")
			(effects
				(font
					(size 0.635 0.4064)
					(thickness 0.1524)
				)
			)
		)
		(property "Value" ""
			(at 0 0 90)
			(layer "F.Fab")
			(effects
				(font
					(size 1.27 1.27)
				)
			)
		)
		(duplicate_pad_numbers_are_jumpers no)
		(fp_line
			(start 1.2954 -0.5842)
			(end 1.2954 0.5842)
			(stroke
				(width 0.1524)
				(type default)
			)
			(layer "F.SilkS")
		)
		(fp_line
			(start 0 -0.5842)
			(end 0 0.5842)
			(stroke
				(width 0.1524)
				(type default)
			)
			(layer "F.SilkS")
		)
		(fp_line
			(start -1.2954 -0.5842)
			(end 1.2954 -0.5842)
			(stroke
				(width 0.1524)
				(type default)
			)
			(layer "F.SilkS")
		)
		(fp_line
			(start 1.2954 0.5842)
			(end -1.2954 0.5842)
			(stroke
				(width 0.1524)
				(type default)
			)
			(layer "F.SilkS")
		)
		(fp_line
			(start -1.2954 0.5842)
			(end -1.2954 -0.5842)
			(stroke
				(width 0.1524)
				(type default)
			)
			(layer "F.SilkS")
		)
		(fp_poly
			(pts
				(xy 0.8636 -0.4572) (xy 0.8636 -0.3556) (xy 1.143 -0.3556) (xy 1.143 0.3556) (xy 0.8636 0.3556)
				(xy 0.8636 0.4572) (xy -0.8636 0.4572) (xy -0.8636 0.3556) (xy -1.143 0.3556) (xy -1.143 -0.3556)
				(xy -0.8636 -0.3556) (xy -0.8636 -0.4572)
			)
			(stroke
				(width 0)
				(type default)
			)
			(fill no)
			(layer "F.CrtYd")
		)
		(fp_line
			(start 0.884936 -0.504952)
			(end 0.884936 0.504952)
			(stroke
				(width 0.1)
				(type default)
			)
			(layer "F.Fab")
		)
		(fp_line
			(start -0.884936 -0.504952)
			(end 0.884936 -0.504952)
			(stroke
				(width 0.1)
				(type default)
			)
			(layer "F.Fab")
		)
		(fp_line
			(start 0.884936 0.504952)
			(end -0.884936 0.504952)
			(stroke
				(width 0.1)
				(type default)
			)
			(layer "F.Fab")
		)
		(fp_line
			(start -0.884936 0.504952)
			(end -0.884936 -0.504952)
			(stroke
				(width 0.1)
				(type default)
			)
			(layer "F.Fab")
		)
		(pad "1" smd rect
			(at 0.7366 0 180)
			(size 0.7112 0.8128)
			(layers "F.Cu" "F.Mask" "F.Paste")
			(net "VR_PVCCP_NODE1_VCC")
		)
		(pad "2" smd rect
			(at -0.7366 0 180)
			(size 0.7112 0.8128)
			(layers "F.Cu" "F.Mask" "F.Paste")
			(net "AGND_PVCCP_NODE1")
		)
	)
	(footprint ""
		(layer "F.Cu")
		(at 17.013174 -16.260572 -90)
		(property "Reference" "C544"
			(at 1.500124 6.13664 90)
			(unlocked yes)
			(layer "F.SilkS")
			(effects
				(font
					(size 0.7874 0.5842)
					(thickness 0.1524)
				)
				(justify left)
			)
		)
		(property "Value" ""
			(at 0 0 270)
			(layer "F.Fab")
			(effects
				(font
					(size 1.27 1.27)
				)
			)
		)
		(duplicate_pad_numbers_are_jumpers no)
		(fp_line
			(start -0.7874 0.4064)
			(end -0.7874 -0.4064)
			(stroke
				(width 0.1524)
				(type default)
			)
			(layer "F.SilkS")
		)
		(fp_line
			(start 0.7874 0.4064)
			(end -0.7874 0.4064)
			(stroke
				(width 0.1524)
				(type default)
			)
			(layer "F.SilkS")
		)
		(fp_line
			(start 0 0.381)
			(end 0 -0.381)
			(stroke
				(width 0.1524)
				(type default)
			)
			(layer "F.SilkS")
		)
		(fp_line
			(start -0.7874 -0.4064)
			(end 0.7874 -0.4064)
			(stroke
				(width 0.1524)
				(type default)
			)
			(layer "F.SilkS")
		)
		(fp_line
			(start 0.7874 -0.4064)
			(end 0.7874 0.4064)
			(stroke
				(width 0.1524)
				(type default)
			)
			(layer "F.SilkS")
		)
		(fp_poly
			(pts
				(xy -0.5334 0.254) (xy -0.635 0.254) (xy -0.635 0.2286) (xy -0.635 -0.254) (xy -0.5334 -0.254) (xy -0.5334 -0.2794)
				(xy 0.5334 -0.2794) (xy 0.5334 -0.254) (xy 0.635 -0.254) (xy 0.635 0.254) (xy 0.5334 0.254) (xy 0.5334 0.2794)
				(xy -0.508 0.2794) (xy -0.5334 0.2794)
			)
			(stroke
				(width 0)
				(type default)
			)
			(fill no)
			(layer "F.CrtYd")
		)
		(pad "1" smd rect
			(at 0.40005 0 270)
			(size 0.4572 0.508)
			(layers "F.Cu" "F.Mask" "F.Paste")
			(net "GND")
		)
		(pad "2" smd rect
			(at -0.40005 0 270)
			(size 0.4572 0.508)
			(layers "F.Cu" "F.Mask" "F.Paste")
			(net "N54251539")
		)
	)
	(footprint ""
		(layer "F.Cu")
		(at 161.200846 -33.589214)
		(property "Reference" "R656"
			(at -1.343152 -1.010412 0)
			(unlocked yes)
			(layer "F.SilkS")
			(effects
				(font
					(size 0.7874 0.5842)
					(thickness 0.1524)
				)
				(justify left)
			)
		)
		(property "Value" ""
			(at 0 0 0)
			(layer "F.Fab")
			(effects
				(font
					(size 1.27 1.27)
				)
			)
		)
		(duplicate_pad_numbers_are_jumpers no)
		(fp_line
			(start -0.7874 -0.4064)
			(end 0.7874 -0.4064)
			(stroke
				(width 0.1524)
				(type default)
			)
			(layer "F.SilkS")
		)
		(fp_line
			(start -0.7874 0.4064)
			(end -0.7874 -0.4064)
			(stroke
				(width 0.1524)
				(type default)
			)
			(layer "F.SilkS")
		)
		(fp_line
			(start 0.7874 -0.4064)
			(end 0.7874 0.4064)
			(stroke
				(width 0.1524)
				(type default)
			)
			(layer "F.SilkS")
		)
		(fp_line
			(start 0.7874 0.4064)
			(end -0.7874 0.4064)
			(stroke
				(width 0.1524)
				(type default)
			)
			(layer "F.SilkS")
		)
		(fp_poly
			(pts
				(xy -0.508 0.2794) (xy -0.508 0.2286) (xy -0.635 0.2286) (xy -0.635 -0.254) (xy -0.5334 -0.254)
				(xy -0.5334 -0.2794) (xy 0.5334 -0.2794) (xy 0.5334 -0.254) (xy 0.635 -0.254) (xy 0.635 0.254) (xy 0.5334 0.254)
				(xy 0.5334 0.2794)
			)
			(stroke
				(width 0)
				(type default)
			)
			(fill no)
			(layer "F.CrtYd")
		)
		(pad "1" smd rect
			(at 0.40005 0)
			(size 0.4572 0.508)
			(layers "F.Cu" "F.Mask" "F.Paste")
			(net "GND")
		)
		(pad "2" smd rect
			(at -0.40005 0)
			(size 0.4572 0.508)
			(layers "F.Cu" "F.Mask" "F.Paste")
			(net "N37284163")
		)
	)
	(footprint ""
		(layer "F.Cu")
		(at 55.14467 -173.527466 180)
		(property "Reference" "U89"
			(at 5.938266 -133.039612 90)
			(unlocked yes)
			(layer "F.SilkS")
			(effects
				(font
					(size 0.7874 0.5842)
					(thickness 0.1524)
				)
				(justify left)
			)
		)
		(property "Value" ""
			(at 0 0 180)
			(layer "F.Fab")
			(effects
				(font
					(size 1.27 1.27)
				)
			)
		)
		(duplicate_pad_numbers_are_jumpers no)
		(fp_line
			(start 1.549908 2.032)
			(end -1.549908 2.032)
			(stroke
				(width 0.1524)
				(type default)
			)
			(layer "F.SilkS")
		)
		(fp_line
			(start 1.549908 -2.032)
			(end 1.549908 2.032)
			(stroke
				(width 0.1524)
				(type default)
			)
			(layer "F.SilkS")
		)
		(fp_line
			(start -1.549908 2.032)
			(end -1.549908 -2.032)
			(stroke
				(width 0.1524)
				(type default)
			)
			(layer "F.SilkS")
		)
		(fp_line
			(start -1.549908 -2.032)
			(end 1.549908 -2.032)
			(stroke
				(width 0.1524)
				(type default)
			)
			(layer "F.SilkS")
		)
		(fp_poly
			(pts
				(xy -2.9464 1.016) (xy -2.9464 1.524) (xy -2.1844 1.27)
			)
			(stroke
				(width 0)
				(type default)
			)
			(fill yes)
			(layer "F.SilkS")
		)
		(fp_poly
			(pts
				(xy -1.549908 0.849884) (xy -1.2319 0.849884) (xy -1.2319 1.9431) (xy -1.1811 1.9431) (xy 1.1811 1.9431)
				(xy 1.2319 1.9431) (xy 1.2319 0.849884) (xy 1.549908 0.849884) (xy 1.549908 -0.849884) (xy 1.2319 -0.849884)
				(xy 1.2319 -1.9431) (xy 1.1811 -1.9431) (xy -1.1811 -1.9431) (xy -1.2319 -1.9431) (xy -1.2319 -0.849884)
				(xy -1.549908 -0.849884)
			)
			(stroke
				(width 0)
				(type default)
			)
			(fill no)
			(layer "F.CrtYd")
		)
		(fp_line
			(start 1.549908 0.849884)
			(end 1.549908 -0.849884)
			(stroke
				(width 0.1)
				(type default)
			)
			(layer "F.Fab")
		)
		(fp_line
			(start 1.549908 -0.849884)
			(end -1.549908 -0.849884)
			(stroke
				(width 0.1)
				(type default)
			)
			(layer "F.Fab")
		)
		(fp_line
			(start -1.549908 0.849884)
			(end 1.549908 0.849884)
			(stroke
				(width 0.1)
				(type default)
			)
			(layer "F.Fab")
		)
		(fp_line
			(start -1.549908 -0.849884)
			(end -1.549908 0.849884)
			(stroke
				(width 0.1)
				(type default)
			)
			(layer "F.Fab")
		)
		(fp_text user "3"
			(at 1.439418 2.684526 0)
			(unlocked yes)
			(layer "F.SilkS")
			(effects
				(font
					(size 0.635 0.4064)
					(thickness 0.1524)
				)
				(justify left)
			)
		)
		(fp_text user "4"
			(at 0.872998 -2.54508 0)
			(unlocked yes)
			(layer "F.SilkS")
			(effects
				(font
					(size 0.635 0.4064)
					(thickness 0.1524)
				)
				(justify left)
			)
		)
		(fp_text user "1"
			(at -0.541528 2.538222 0)
			(unlocked yes)
			(layer "F.SilkS")
			(effects
				(font
					(size 0.635 0.4064)
					(thickness 0.1524)
				)
				(justify left)
			)
		)
		(fp_text user "5"
			(at -1.881632 -2.664714 0)
			(unlocked yes)
			(layer "F.SilkS")
			(effects
				(font
					(size 0.635 0.4064)
					(thickness 0.1524)
				)
				(justify left)
			)
		)
		(pad "1" smd rect
			(at -0.94996 1.225042 180)
			(size 0.4572 1.3208)
			(layers "F.Cu" "F.Mask" "F.Paste")
			(net "Net_1710")
		)
		(pad "2" smd rect
			(at 0 1.225042 180)
			(size 0.4572 1.3208)
			(layers "F.Cu" "F.Mask" "F.Paste")
			(net "PSU4_DC_OK_R_BUF")
		)
		(pad "3" smd rect
			(at 0.94996 1.225042 180)
			(size 0.4572 1.3208)
			(layers "F.Cu" "F.Mask" "F.Paste")
			(net "GND")
		)
		(pad "4" smd rect
			(at 0.94996 -1.225042 180)
			(size 0.4572 1.3208)
			(layers "F.Cu" "F.Mask" "F.Paste")
			(net "PSU4_DC_OK")
		)
		(pad "5" smd rect
			(at -0.94996 -1.225042 180)
			(size 0.4572 1.3208)
			(layers "F.Cu" "F.Mask" "F.Paste")
			(net "P3V3_NODE1")
		)
	)
	(footprint ""
		(layer "F.Cu")
		(at 112.81029 -156.330142 180)
		(property "Reference" "U107"
			(at -1.812036 3.072638 90)
			(unlocked yes)
			(layer "F.SilkS")
			(effects
				(font
					(size 0.635 0.4064)
					(thickness 0.1524)
				)
			)
		)
		(property "Value" ""
			(at 0 0 180)
			(layer "F.Fab")
			(effects
				(font
					(size 1.27 1.27)
				)
			)
		)
		(duplicate_pad_numbers_are_jumpers no)
		(fp_line
			(start 1.651 1.905)
			(end -1.651 1.905)
			(stroke
				(width 0.1524)
				(type default)
			)
			(layer "F.SilkS")
		)
		(fp_line
			(start 1.651 -1.905)
			(end 1.651 1.905)
			(stroke
				(width 0.1524)
				(type default)
			)
			(layer "F.SilkS")
		)
		(fp_line
			(start -1.651 1.905)
			(end -1.651 -1.905)
			(stroke
				(width 0.1524)
				(type default)
			)
			(layer "F.SilkS")
		)
		(fp_line
			(start -1.651 -1.905)
			(end 1.651 -1.905)
			(stroke
				(width 0.1524)
				(type default)
			)
			(layer "F.SilkS")
		)
		(fp_poly
			(pts
				(xy -1.524 0.7112) (xy -1.524 1.7526) (xy -0.508 1.7526) (xy -0.508 0.6985) (xy 0.508 0.6985) (xy 0.508 1.7526)
				(xy 1.524 1.7526) (xy 1.524 0.6985) (xy 1.524 -0.6985) (xy 0.508 -0.6985) (xy 0.508 -1.7526) (xy -0.508 -1.7526)
				(xy -0.508 -0.6985) (xy -1.524 -0.6985) (xy -1.524 0.6985)
			)
			(stroke
				(width 0)
				(type default)
			)
			(fill no)
			(layer "F.CrtYd")
		)
		(fp_text user "D"
			(at 1.13284 -0.98171 0)
			(unlocked yes)
			(layer "F.SilkS")
			(effects
				(font
					(size 0.635 0.4064)
					(thickness 0.1524)
				)
			)
		)
		(fp_text user "S"
			(at 0.12827 1.315466 0)
			(unlocked yes)
			(layer "F.SilkS")
			(effects
				(font
					(size 0.635 0.4064)
					(thickness 0.1524)
				)
			)
		)
		(fp_text user "G"
			(at -1.140968 -0.04064 0)
			(unlocked yes)
			(layer "F.SilkS")
			(effects
				(font
					(size 0.635 0.4064)
					(thickness 0.1524)
				)
			)
		)
		(pad "D" smd rect
			(at 0 -1.1176 180)
			(size 1.016 1.27)
			(layers "F.Cu" "F.Mask" "F.Paste")
			(net "N52410978")
		)
		(pad "G" smd rect
			(at -1.016 1.1176 180)
			(size 1.016 1.27)
			(layers "F.Cu" "F.Mask" "F.Paste")
			(net "POWER_SW2_PWR_CTR_N")
		)
		(pad "S" smd rect
			(at 1.016 1.1176 180)
			(size 1.016 1.27)
			(layers "F.Cu" "F.Mask" "F.Paste")
			(net "GND")
		)
	)
	(footprint ""
		(layer "F.Cu")
		(at 90.000074 -88.799924)
		(property "Reference" "H2"
			(at 2.474468 1.009904 0)
			(unlocked yes)
			(layer "F.SilkS")
			(effects
				(font
					(size 0.7874 0.5842)
					(thickness 0.1524)
				)
				(justify left)
			)
		)
		(property "Value" ""
			(at 0 0 0)
			(layer "F.Fab")
			(effects
				(font
					(size 1.27 1.27)
				)
			)
		)
		(duplicate_pad_numbers_are_jumpers no)
		(fp_circle
			(center 0 0)
			(end 2.3114 0)
			(stroke
				(width 0.1524)
				(type default)
			)
			(fill no)
			(layer "F.SilkS")
		)
		(fp_circle
			(center 0 0)
			(end 2.3114 0)
			(stroke
				(width 0.1524)
				(type default)
			)
			(fill no)
			(layer "B.SilkS")
		)
		(fp_poly
			(pts
				(arc
					(start 0 1.4986)
					(mid 0 -1.4986)
					(end 0 1.4986)
				)
			)
			(stroke
				(width 0)
				(type default)
			)
			(fill no)
			(layer "F.CrtYd")
		)
		(pad "" np_thru_hole circle
			(at 0 0)
			(size 2.9972 2.9972)
			(drill 2.9972)
			(layers "*.Cu" "*.Mask")
			(clearance 0.381)
			(thermal_gap 0.381)
		)
		(zone
			(layers "F.Cu" "B.Cu" "In1.Cu" "In2.Cu" "In3.Cu" "In4.Cu" "In5.Cu" "In6.Cu"
				"In7.Cu" "In8.Cu"
			)
			(hatch none 0.5)
			(connect_pads
				(clearance 0)
			)
			(min_thickness 0.25)
			(keepout
				(tracks not_allowed)
				(vias allowed)
				(pads allowed)
				(copperpour not_allowed)
				(footprints allowed)
			)
			(placement
				(enabled no)
				(sheetname "")
			)
			(fill
				(thermal_gap 0.5)
				(thermal_bridge_width 0.5)
				(island_removal_mode 0)
			)
			(polygon
				(pts
					(arc
						(start 90.000074 -86.793324)
						(mid 90.000074 -90.806524)
						(end 90.000074 -86.793324)
					)
				)
			)
		)
	)
	(footprint ""
		(layer "F.Cu")
		(at 109.817154 -140.337032 90)
		(property "Reference" "PR62"
			(at 2.675128 3.839972 90)
			(unlocked yes)
			(layer "F.SilkS")
			(effects
				(font
					(size 0.635 0.4064)
					(thickness 0.1524)
				)
				(justify left)
			)
		)
		(property "Value" ""
			(at 0 0 90)
			(layer "F.Fab")
			(effects
				(font
					(size 1.27 1.27)
				)
			)
		)
		(duplicate_pad_numbers_are_jumpers no)
		(fp_line
			(start 0.7874 -0.4064)
			(end 0.7874 0.4064)
			(stroke
				(width 0.1524)
				(type default)
			)
			(layer "F.SilkS")
		)
		(fp_line
			(start -0.7874 -0.4064)
			(end 0.7874 -0.4064)
			(stroke
				(width 0.1524)
				(type default)
			)
			(layer "F.SilkS")
		)
		(fp_line
			(start 0.7874 0.4064)
			(end -0.7874 0.4064)
			(stroke
				(width 0.1524)
				(type default)
			)
			(layer "F.SilkS")
		)
		(fp_line
			(start -0.7874 0.4064)
			(end -0.7874 -0.4064)
			(stroke
				(width 0.1524)
				(type default)
			)
			(layer "F.SilkS")
		)
		(fp_poly
			(pts
				(xy -0.508 0.2794) (xy -0.508 0.2286) (xy -0.635 0.2286) (xy -0.635 -0.254) (xy -0.5334 -0.254)
				(xy -0.5334 -0.2794) (xy 0.5334 -0.2794) (xy 0.5334 -0.254) (xy 0.635 -0.254) (xy 0.635 0.254) (xy 0.5334 0.254)
				(xy 0.5334 0.2794)
			)
			(stroke
				(width 0)
				(type default)
			)
			(fill no)
			(layer "F.CrtYd")
		)
		(pad "1" smd rect
			(at 0.40005 0 90)
			(size 0.4572 0.508)
			(layers "F.Cu" "F.Mask" "F.Paste")
			(net "AGND_PVCCP_NODE1")
		)
		(pad "2" smd rect
			(at -0.40005 0 90)
			(size 0.4572 0.508)
			(layers "F.Cu" "F.Mask" "F.Paste")
			(net "VR_PVCCP_NODE1_TEMPMAX")
		)
	)
	(footprint ""
		(layer "F.Cu")
		(at 79.963518 -85.93328 180)
		(property "Reference" "C23"
			(at 1.195578 -18.994374 0)
			(unlocked yes)
			(layer "F.SilkS")
			(effects
				(font
					(size 0.7874 0.5842)
					(thickness 0.1524)
				)
				(justify left)
			)
		)
		(property "Value" ""
			(at 0 0 180)
			(layer "F.Fab")
			(effects
				(font
					(size 1.27 1.27)
				)
			)
		)
		(duplicate_pad_numbers_are_jumpers no)
		(fp_line
			(start 0.7874 0.4064)
			(end -0.7874 0.4064)
			(stroke
				(width 0.1524)
				(type default)
			)
			(layer "F.SilkS")
		)
		(fp_line
			(start 0.7874 -0.4064)
			(end 0.7874 0.4064)
			(stroke
				(width 0.1524)
				(type default)
			)
			(layer "F.SilkS")
		)
		(fp_line
			(start 0 0.381)
			(end 0 -0.381)
			(stroke
				(width 0.1524)
				(type default)
			)
			(layer "F.SilkS")
		)
		(fp_line
			(start -0.7874 0.4064)
			(end -0.7874 -0.4064)
			(stroke
				(width 0.1524)
				(type default)
			)
			(layer "F.SilkS")
		)
		(fp_line
			(start -0.7874 -0.4064)
			(end 0.7874 -0.4064)
			(stroke
				(width 0.1524)
				(type default)
			)
			(layer "F.SilkS")
		)
		(fp_poly
			(pts
				(xy -0.5334 0.254) (xy -0.635 0.254) (xy -0.635 0.2286) (xy -0.635 -0.254) (xy -0.5334 -0.254) (xy -0.5334 -0.2794)
				(xy 0.5334 -0.2794) (xy 0.5334 -0.254) (xy 0.635 -0.254) (xy 0.635 0.254) (xy 0.5334 0.254) (xy 0.5334 0.2794)
				(xy -0.508 0.2794) (xy -0.5334 0.2794)
			)
			(stroke
				(width 0)
				(type default)
			)
			(fill no)
			(layer "F.CrtYd")
		)
		(pad "1" smd rect
			(at 0.40005 0 180)
			(size 0.4572 0.508)
			(layers "F.Cu" "F.Mask" "F.Paste")
			(net "A_CPU_NODE1_RTC_EXTPAD")
		)
		(pad "2" smd rect
			(at -0.40005 0 180)
			(size 0.4572 0.508)
			(layers "F.Cu" "F.Mask" "F.Paste")
			(net "GND")
		)
	)
	(footprint ""
		(layer "F.Cu")
		(at 82.699352 -145.237962)
		(property "Reference" "C836"
			(at -1.703832 -1.368806 0)
			(unlocked yes)
			(layer "F.SilkS")
			(effects
				(font
					(size 0.7874 0.5842)
					(thickness 0.1524)
				)
				(justify left)
			)
		)
		(property "Value" ""
			(at 0 0 0)
			(layer "F.Fab")
			(effects
				(font
					(size 1.27 1.27)
				)
			)
		)
		(duplicate_pad_numbers_are_jumpers no)
		(fp_line
			(start -1.905 -0.8636)
			(end 1.905 -0.8636)
			(stroke
				(width 0.1524)
				(type default)
			)
			(layer "F.SilkS")
		)
		(fp_line
			(start -1.905 0.8636)
			(end -1.905 -0.8636)
			(stroke
				(width 0.1524)
				(type default)
			)
			(layer "F.SilkS")
		)
		(fp_line
			(start 0 0.8382)
			(end 0 -0.8382)
			(stroke
				(width 0.1524)
				(type default)
			)
			(layer "F.SilkS")
		)
		(fp_line
			(start 1.905 -0.8636)
			(end 1.905 0.8636)
			(stroke
				(width 0.1524)
				(type default)
			)
			(layer "F.SilkS")
		)
		(fp_line
			(start 1.905 0.8636)
			(end -1.905 0.8636)
			(stroke
				(width 0.1524)
				(type default)
			)
			(layer "F.SilkS")
		)
		(fp_rect
			(start -1.524 0.7366)
			(end 1.524 -0.7366)
			(stroke
				(width 0)
				(type default)
			)
			(fill no)
			(layer "F.CrtYd")
		)
		(pad "1" smd rect
			(at 0.94996 0)
			(size 1.1176 1.3716)
			(layers "F.Cu" "F.Mask" "F.Paste")
			(net "P1V8_NODE1")
		)
		(pad "2" smd rect
			(at -0.94996 0)
			(size 1.1176 1.3716)
			(layers "F.Cu" "F.Mask" "F.Paste")
			(net "GND")
		)
	)
	(footprint ""
		(layer "F.Cu")
		(at 186.131708 -127.0254)
		(property "Reference" "R1290"
			(at 4.088892 19.78787 0)
			(unlocked yes)
			(layer "F.SilkS")
			(effects
				(font
					(size 0.7874 0.5842)
					(thickness 0.1524)
				)
				(justify left)
			)
		)
		(property "Value" ""
			(at 0 0 0)
			(layer "F.Fab")
			(effects
				(font
					(size 1.27 1.27)
				)
			)
		)
		(duplicate_pad_numbers_are_jumpers no)
		(fp_line
			(start -0.7874 -0.4064)
			(end 0.7874 -0.4064)
			(stroke
				(width 0.1524)
				(type default)
			)
			(layer "F.SilkS")
		)
		(fp_line
			(start -0.7874 0.4064)
			(end -0.7874 -0.4064)
			(stroke
				(width 0.1524)
				(type default)
			)
			(layer "F.SilkS")
		)
		(fp_line
			(start 0.7874 -0.4064)
			(end 0.7874 0.4064)
			(stroke
				(width 0.1524)
				(type default)
			)
			(layer "F.SilkS")
		)
		(fp_line
			(start 0.7874 0.4064)
			(end -0.7874 0.4064)
			(stroke
				(width 0.1524)
				(type default)
			)
			(layer "F.SilkS")
		)
		(fp_poly
			(pts
				(xy -0.508 0.2794) (xy -0.508 0.2286) (xy -0.635 0.2286) (xy -0.635 -0.254) (xy -0.5334 -0.254)
				(xy -0.5334 -0.2794) (xy 0.5334 -0.2794) (xy 0.5334 -0.254) (xy 0.635 -0.254) (xy 0.635 0.254) (xy 0.5334 0.254)
				(xy 0.5334 0.2794)
			)
			(stroke
				(width 0)
				(type default)
			)
			(fill no)
			(layer "F.CrtYd")
		)
		(pad "1" smd rect
			(at 0.40005 0)
			(size 0.4572 0.508)
			(layers "F.Cu" "F.Mask" "F.Paste")
			(net "SIO_JTAG_CPLD1_TDO")
		)
		(pad "2" smd rect
			(at -0.40005 0)
			(size 0.4572 0.508)
			(layers "F.Cu" "F.Mask" "F.Paste")
			(net "P3V3_NODE1")
		)
	)
	(footprint ""
		(layer "F.Cu")
		(at 139.43838 -74.301096 180)
		(property "Reference" "R508"
			(at -0.8763 2.141474 0)
			(unlocked yes)
			(layer "F.SilkS")
			(effects
				(font
					(size 0.7874 0.5842)
					(thickness 0.1524)
				)
				(justify left)
			)
		)
		(property "Value" ""
			(at 0 0 180)
			(layer "F.Fab")
			(effects
				(font
					(size 1.27 1.27)
				)
			)
		)
		(duplicate_pad_numbers_are_jumpers no)
		(fp_line
			(start 0.7874 0.4064)
			(end -0.7874 0.4064)
			(stroke
				(width 0.1524)
				(type default)
			)
			(layer "F.SilkS")
		)
		(fp_line
			(start 0.7874 -0.4064)
			(end 0.7874 0.4064)
			(stroke
				(width 0.1524)
				(type default)
			)
			(layer "F.SilkS")
		)
		(fp_line
			(start -0.7874 0.4064)
			(end -0.7874 -0.4064)
			(stroke
				(width 0.1524)
				(type default)
			)
			(layer "F.SilkS")
		)
		(fp_line
			(start -0.7874 -0.4064)
			(end 0.7874 -0.4064)
			(stroke
				(width 0.1524)
				(type default)
			)
			(layer "F.SilkS")
		)
		(fp_poly
			(pts
				(xy -0.508 0.2794) (xy -0.508 0.2286) (xy -0.635 0.2286) (xy -0.635 -0.254) (xy -0.5334 -0.254)
				(xy -0.5334 -0.2794) (xy 0.5334 -0.2794) (xy 0.5334 -0.254) (xy 0.635 -0.254) (xy 0.635 0.254) (xy 0.5334 0.254)
				(xy 0.5334 0.2794)
			)
			(stroke
				(width 0)
				(type default)
			)
			(fill no)
			(layer "F.CrtYd")
		)
		(pad "1" smd rect
			(at 0.40005 0 180)
			(size 0.4572 0.508)
			(layers "F.Cu" "F.Mask" "F.Paste")
			(net "SATA_SPI_CLK_NODE1")
		)
		(pad "2" smd rect
			(at -0.40005 0 180)
			(size 0.4572 0.508)
			(layers "F.Cu" "F.Mask" "F.Paste")
			(net "SATA_SPI_CLK_NODE1_R")
		)
	)
	(footprint ""
		(layer "F.Cu")
		(at 68.81876 -188.126624 90)
		(property "Reference" "C634"
			(at 4.548886 -0.734568 90)
			(unlocked yes)
			(layer "F.SilkS")
			(effects
				(font
					(size 0.7874 0.5842)
					(thickness 0.1524)
				)
				(justify left)
			)
		)
		(property "Value" ""
			(at 0 0 90)
			(layer "F.Fab")
			(effects
				(font
					(size 1.27 1.27)
				)
			)
		)
		(duplicate_pad_numbers_are_jumpers no)
		(fp_line
			(start 0.7874 -0.4064)
			(end 0.7874 0.4064)
			(stroke
				(width 0.1524)
				(type default)
			)
			(layer "F.SilkS")
		)
		(fp_line
			(start -0.7874 -0.4064)
			(end 0.7874 -0.4064)
			(stroke
				(width 0.1524)
				(type default)
			)
			(layer "F.SilkS")
		)
		(fp_line
			(start 0 0.381)
			(end 0 -0.381)
			(stroke
				(width 0.1524)
				(type default)
			)
			(layer "F.SilkS")
		)
		(fp_line
			(start 0.7874 0.4064)
			(end -0.7874 0.4064)
			(stroke
				(width 0.1524)
				(type default)
			)
			(layer "F.SilkS")
		)
		(fp_line
			(start -0.7874 0.4064)
			(end -0.7874 -0.4064)
			(stroke
				(width 0.1524)
				(type default)
			)
			(layer "F.SilkS")
		)
		(fp_poly
			(pts
				(xy -0.5334 0.254) (xy -0.635 0.254) (xy -0.635 0.2286) (xy -0.635 -0.254) (xy -0.5334 -0.254) (xy -0.5334 -0.2794)
				(xy 0.5334 -0.2794) (xy 0.5334 -0.254) (xy 0.635 -0.254) (xy 0.635 0.254) (xy 0.5334 0.254) (xy 0.5334 0.2794)
				(xy -0.508 0.2794) (xy -0.5334 0.2794)
			)
			(stroke
				(width 0)
				(type default)
			)
			(fill no)
			(layer "F.CrtYd")
		)
		(pad "1" smd rect
			(at 0.40005 0 90)
			(size 0.4572 0.508)
			(layers "F.Cu" "F.Mask" "F.Paste")
			(net "T2_NODE1_EN_R")
		)
		(pad "2" smd rect
			(at -0.40005 0 90)
			(size 0.4572 0.508)
			(layers "F.Cu" "F.Mask" "F.Paste")
			(net "GND")
		)
	)
	(footprint ""
		(layer "F.Cu")
		(at 76.179426 -99.086416)
		(property "Reference" "OSC5"
			(at -1.157986 -3.207258 0)
			(unlocked yes)
			(layer "F.SilkS")
			(effects
				(font
					(size 0.7874 0.5842)
					(thickness 0.1524)
				)
				(justify left)
			)
		)
		(property "Value" ""
			(at 0 0 0)
			(layer "F.Fab")
			(effects
				(font
					(size 1.27 1.27)
				)
			)
		)
		(duplicate_pad_numbers_are_jumpers no)
		(fp_line
			(start -0.6096 -0.7366)
			(end -0.6096 2.936494)
			(stroke
				(width 0.1524)
				(type default)
			)
			(layer "F.SilkS")
		)
		(fp_line
			(start -0.6096 2.936494)
			(end 2.35966 2.936494)
			(stroke
				(width 0.1524)
				(type default)
			)
			(layer "F.SilkS")
		)
		(fp_line
			(start 2.35966 -0.7366)
			(end -0.6096 -0.7366)
			(stroke
				(width 0.1524)
				(type default)
			)
			(layer "F.SilkS")
		)
		(fp_line
			(start 2.35966 2.936494)
			(end 2.35966 -0.7366)
			(stroke
				(width 0.1524)
				(type default)
			)
			(layer "F.SilkS")
		)
		(fp_poly
			(pts
				(xy -1.843278 0.508) (xy -1.843278 -0.508) (xy -0.827278 0)
			)
			(stroke
				(width 0)
				(type default)
			)
			(fill yes)
			(layer "F.SilkS")
		)
		(fp_poly
			(pts
				(xy -0.5334 -0.6604) (xy 0.5334 -0.6604) (xy 0.5334 -0.575056) (xy 1.21666 -0.575056) (xy 1.21666 -0.6604)
				(xy 2.28346 -0.6604) (xy 2.28346 0.6604) (xy 2.199894 0.6604) (xy 2.199894 1.539494) (xy 2.28346 1.539494)
				(xy 2.28346 2.860294) (xy 1.21666 2.860294) (xy 1.21666 2.77495) (xy 0.5334 2.77495) (xy 0.5334 2.860294)
				(xy -0.5334 2.860294) (xy -0.5334 1.539494) (xy -0.450088 1.539494) (xy -0.450088 0.6604) (xy -0.5334 0.6604)
			)
			(stroke
				(width 0)
				(type default)
			)
			(fill no)
			(layer "F.CrtYd")
		)
		(fp_line
			(start -0.450088 -0.575056)
			(end -0.450088 2.77495)
			(stroke
				(width 0.1)
				(type default)
			)
			(layer "F.Fab")
		)
		(fp_line
			(start -0.450088 2.77495)
			(end 2.199894 2.77495)
			(stroke
				(width 0.1)
				(type default)
			)
			(layer "F.Fab")
		)
		(fp_line
			(start 2.199894 -0.575056)
			(end -0.450088 -0.575056)
			(stroke
				(width 0.1)
				(type default)
			)
			(layer "F.Fab")
		)
		(fp_line
			(start 2.199894 2.77495)
			(end 2.199894 -0.575056)
			(stroke
				(width 0.1)
				(type default)
			)
			(layer "F.Fab")
		)
		(fp_poly
			(pts
				(xy -1.843278 0.508) (xy -1.843278 -0.508) (xy -0.827278 0)
			)
			(stroke
				(width 0)
				(type default)
			)
			(fill yes)
			(layer "F.Fab")
		)
		(pad "1" smd rect
			(at 0 0)
			(size 0.9652 1.2192)
			(layers "F.Cu" "F.Mask" "F.Paste")
			(net "FM_OSC_NODE1_OSC_NC")
		)
		(pad "2" smd rect
			(at 0 2.199894)
			(size 0.9652 1.2192)
			(layers "F.Cu" "F.Mask" "F.Paste")
			(net "GND")
		)
		(pad "3" smd rect
			(at 1.75006 2.199894)
			(size 0.9652 1.2192)
			(layers "F.Cu" "F.Mask" "F.Paste")
			(net "CLK_33K_CPU_NODE1_SUSCLK_R")
		)
		(pad "4" smd rect
			(at 1.75006 0)
			(size 0.9652 1.2192)
			(layers "F.Cu" "F.Mask" "F.Paste")
			(net "P3V3_STB_NODE1")
		)
	)
	(footprint ""
		(layer "F.Cu")
		(at 53.95976 -185.205624 -90)
		(property "Reference" "R818"
			(at -4.006088 0.034544 90)
			(unlocked yes)
			(layer "F.SilkS")
			(effects
				(font
					(size 0.7874 0.5842)
					(thickness 0.1524)
				)
				(justify left)
			)
		)
		(property "Value" ""
			(at 0 0 270)
			(layer "F.Fab")
			(effects
				(font
					(size 1.27 1.27)
				)
			)
		)
		(duplicate_pad_numbers_are_jumpers no)
		(fp_line
			(start -0.7874 0.406146)
			(end -0.7874 -0.406146)
			(stroke
				(width 0.1524)
				(type default)
			)
			(layer "F.SilkS")
		)
		(fp_line
			(start 0.7874 0.406146)
			(end -0.7874 0.406146)
			(stroke
				(width 0.1524)
				(type default)
			)
			(layer "F.SilkS")
		)
		(fp_line
			(start -0.7874 -0.406146)
			(end 0.7874 -0.406146)
			(stroke
				(width 0.1524)
				(type default)
			)
			(layer "F.SilkS")
		)
		(fp_line
			(start 0.7874 -0.406146)
			(end 0.7874 0.406146)
			(stroke
				(width 0.1524)
				(type default)
			)
			(layer "F.SilkS")
		)
		(fp_poly
			(pts
				(xy -0.508 0.2794) (xy -0.508 0.2286) (xy -0.635 0.2286) (xy -0.635 -0.254) (xy -0.5334 -0.254)
				(xy -0.5334 -0.2794) (xy 0.5334 -0.2794) (xy 0.5334 -0.254) (xy 0.635 -0.254) (xy 0.635 0.254) (xy 0.5334 0.254)
				(xy 0.5334 0.2794)
			)
			(stroke
				(width 0)
				(type default)
			)
			(fill no)
			(layer "F.CrtYd")
		)
		(pad "1" smd rect
			(at 0.40005 0 270)
			(size 0.4572 0.508)
			(layers "F.Cu" "F.Mask" "F.Paste")
			(net "I2C_PSU1_SDA")
		)
		(pad "2" smd rect
			(at -0.40005 0 270)
			(size 0.4572 0.508)
			(layers "F.Cu" "F.Mask" "F.Paste")
			(net "I2C_PSU1_R_SDA")
		)
	)
	(footprint ""
		(layer "F.Cu")
		(at 16.04137 -56.881776)
		(property "Reference" "C501"
			(at 14.149324 0.471424 0)
			(unlocked yes)
			(layer "F.SilkS")
			(effects
				(font
					(size 0.7874 0.5842)
					(thickness 0.1524)
				)
			)
		)
		(property "Value" ""
			(at 0 0 0)
			(layer "F.Fab")
			(effects
				(font
					(size 1.27 1.27)
				)
			)
		)
		(duplicate_pad_numbers_are_jumpers no)
		(fp_line
			(start -1.2954 -0.5842)
			(end 1.2954 -0.5842)
			(stroke
				(width 0.1524)
				(type default)
			)
			(layer "F.SilkS")
		)
		(fp_line
			(start -1.2954 0.5842)
			(end -1.2954 -0.5842)
			(stroke
				(width 0.1524)
				(type default)
			)
			(layer "F.SilkS")
		)
		(fp_line
			(start 0 -0.5842)
			(end 0 0.5842)
			(stroke
				(width 0.1524)
				(type default)
			)
			(layer "F.SilkS")
		)
		(fp_line
			(start 1.2954 -0.5842)
			(end 1.2954 0.5842)
			(stroke
				(width 0.1524)
				(type default)
			)
			(layer "F.SilkS")
		)
		(fp_line
			(start 1.2954 0.5842)
			(end -1.2954 0.5842)
			(stroke
				(width 0.1524)
				(type default)
			)
			(layer "F.SilkS")
		)
		(fp_poly
			(pts
				(xy 0.8636 -0.4572) (xy 0.8636 -0.3556) (xy 1.143 -0.3556) (xy 1.143 0.3556) (xy 0.8636 0.3556)
				(xy 0.8636 0.4572) (xy -0.8636 0.4572) (xy -0.8636 0.3556) (xy -1.143 0.3556) (xy -1.143 -0.3556)
				(xy -0.8636 -0.3556) (xy -0.8636 -0.4572)
			)
			(stroke
				(width 0)
				(type default)
			)
			(fill no)
			(layer "F.CrtYd")
		)
		(fp_line
			(start -0.884936 -0.504952)
			(end 0.884936 -0.504952)
			(stroke
				(width 0.1)
				(type default)
			)
			(layer "F.Fab")
		)
		(fp_line
			(start -0.884936 0.504952)
			(end -0.884936 -0.504952)
			(stroke
				(width 0.1)
				(type default)
			)
			(layer "F.Fab")
		)
		(fp_line
			(start 0.884936 -0.504952)
			(end 0.884936 0.504952)
			(stroke
				(width 0.1)
				(type default)
			)
			(layer "F.Fab")
		)
		(fp_line
			(start 0.884936 0.504952)
			(end -0.884936 0.504952)
			(stroke
				(width 0.1)
				(type default)
			)
			(layer "F.Fab")
		)
		(pad "1" smd rect
			(at 0.7366 0 90)
			(size 0.7112 0.8128)
			(layers "F.Cu" "F.Mask" "F.Paste")
			(net "BMC_NODE1_GFX_BLUE")
		)
		(pad "2" smd rect
			(at -0.7366 0 90)
			(size 0.7112 0.8128)
			(layers "F.Cu" "F.Mask" "F.Paste")
			(net "GND")
		)
	)
	(footprint ""
		(layer "F.Cu")
		(at 140.270484 -112.534192)
		(property "Reference" "R24"
			(at 1.562862 3.197098 0)
			(unlocked yes)
			(layer "F.SilkS")
			(effects
				(font
					(size 0.7874 0.5842)
					(thickness 0.1524)
				)
				(justify left)
			)
		)
		(property "Value" ""
			(at 0 0 0)
			(layer "F.Fab")
			(effects
				(font
					(size 1.27 1.27)
				)
			)
		)
		(duplicate_pad_numbers_are_jumpers no)
		(fp_line
			(start -0.7874 -0.4064)
			(end 0.7874 -0.4064)
			(stroke
				(width 0.1524)
				(type default)
			)
			(layer "F.SilkS")
		)
		(fp_line
			(start -0.7874 0.4064)
			(end -0.7874 -0.4064)
			(stroke
				(width 0.1524)
				(type default)
			)
			(layer "F.SilkS")
		)
		(fp_line
			(start 0.7874 -0.4064)
			(end 0.7874 0.4064)
			(stroke
				(width 0.1524)
				(type default)
			)
			(layer "F.SilkS")
		)
		(fp_line
			(start 0.7874 0.4064)
			(end -0.7874 0.4064)
			(stroke
				(width 0.1524)
				(type default)
			)
			(layer "F.SilkS")
		)
		(fp_poly
			(pts
				(xy -0.508 0.2794) (xy -0.508 0.2286) (xy -0.635 0.2286) (xy -0.635 -0.254) (xy -0.5334 -0.254)
				(xy -0.5334 -0.2794) (xy 0.5334 -0.2794) (xy 0.5334 -0.254) (xy 0.635 -0.254) (xy 0.635 0.254) (xy 0.5334 0.254)
				(xy 0.5334 0.2794)
			)
			(stroke
				(width 0)
				(type default)
			)
			(fill no)
			(layer "F.CrtYd")
		)
		(pad "1" smd rect
			(at 0.40005 0)
			(size 0.4572 0.508)
			(layers "F.Cu" "F.Mask" "F.Paste")
			(net "GND")
		)
		(pad "2" smd rect
			(at -0.40005 0)
			(size 0.4572 0.508)
			(layers "F.Cu" "F.Mask" "F.Paste")
			(net "SEL_DOT_SRC5")
		)
	)
	(footprint ""
		(layer "F.Cu")
		(at 65.209166 -96.709992 90)
		(property "Reference" "R68"
			(at -54.98719 28.439364 90)
			(unlocked yes)
			(layer "F.SilkS")
			(effects
				(font
					(size 0.7874 0.5842)
					(thickness 0.1524)
				)
				(justify left)
			)
		)
		(property "Value" ""
			(at 0 0 90)
			(layer "F.Fab")
			(effects
				(font
					(size 1.27 1.27)
				)
			)
		)
		(duplicate_pad_numbers_are_jumpers no)
		(fp_line
			(start 0.7874 -0.4064)
			(end 0.7874 0.4064)
			(stroke
				(width 0.1524)
				(type default)
			)
			(layer "F.SilkS")
		)
		(fp_line
			(start -0.7874 -0.4064)
			(end 0.7874 -0.4064)
			(stroke
				(width 0.1524)
				(type default)
			)
			(layer "F.SilkS")
		)
		(fp_line
			(start 0.7874 0.4064)
			(end -0.7874 0.4064)
			(stroke
				(width 0.1524)
				(type default)
			)
			(layer "F.SilkS")
		)
		(fp_line
			(start -0.7874 0.4064)
			(end -0.7874 -0.4064)
			(stroke
				(width 0.1524)
				(type default)
			)
			(layer "F.SilkS")
		)
		(fp_poly
			(pts
				(xy -0.508 0.2794) (xy -0.508 0.2286) (xy -0.635 0.2286) (xy -0.635 -0.254) (xy -0.5334 -0.254)
				(xy -0.5334 -0.2794) (xy 0.5334 -0.2794) (xy 0.5334 -0.254) (xy 0.635 -0.254) (xy 0.635 0.254) (xy 0.5334 0.254)
				(xy 0.5334 0.2794)
			)
			(stroke
				(width 0)
				(type default)
			)
			(fill no)
			(layer "F.CrtYd")
		)
		(pad "1" smd rect
			(at 0.40005 0 90)
			(size 0.4572 0.508)
			(layers "F.Cu" "F.Mask" "F.Paste")
			(net "P3V3_NODE1")
		)
		(pad "2" smd rect
			(at -0.40005 0 90)
			(size 0.4572 0.508)
			(layers "F.Cu" "F.Mask" "F.Paste")
			(net "LPC_CPU_NODE1_CLKRUN_L")
		)
	)
	(footprint ""
		(layer "F.Cu")
		(at 105.56367 -156.619702 90)
		(property "Reference" "PC41"
			(at -2.524252 1.738884 90)
			(unlocked yes)
			(layer "F.SilkS")
			(effects
				(font
					(size 0.635 0.4064)
					(thickness 0.1524)
				)
				(justify left)
			)
		)
		(property "Value" ""
			(at 0 0 90)
			(layer "F.Fab")
			(effects
				(font
					(size 1.27 1.27)
				)
			)
		)
		(duplicate_pad_numbers_are_jumpers no)
		(fp_line
			(start 0.7874 -0.4064)
			(end 0.7874 0.4064)
			(stroke
				(width 0.1524)
				(type default)
			)
			(layer "F.SilkS")
		)
		(fp_line
			(start -0.7874 -0.4064)
			(end 0.7874 -0.4064)
			(stroke
				(width 0.1524)
				(type default)
			)
			(layer "F.SilkS")
		)
		(fp_line
			(start 0 0.381)
			(end 0 -0.381)
			(stroke
				(width 0.1524)
				(type default)
			)
			(layer "F.SilkS")
		)
		(fp_line
			(start 0.7874 0.4064)
			(end -0.7874 0.4064)
			(stroke
				(width 0.1524)
				(type default)
			)
			(layer "F.SilkS")
		)
		(fp_line
			(start -0.7874 0.4064)
			(end -0.7874 -0.4064)
			(stroke
				(width 0.1524)
				(type default)
			)
			(layer "F.SilkS")
		)
		(fp_poly
			(pts
				(xy -0.5334 0.254) (xy -0.635 0.254) (xy -0.635 0.2286) (xy -0.635 -0.254) (xy -0.5334 -0.254) (xy -0.5334 -0.2794)
				(xy 0.5334 -0.2794) (xy 0.5334 -0.254) (xy 0.635 -0.254) (xy 0.635 0.254) (xy 0.5334 0.254) (xy 0.5334 0.2794)
				(xy -0.508 0.2794) (xy -0.5334 0.2794)
			)
			(stroke
				(width 0)
				(type default)
			)
			(fill no)
			(layer "F.CrtYd")
		)
		(pad "1" smd rect
			(at 0.40005 0 90)
			(size 0.4572 0.508)
			(layers "F.Cu" "F.Mask" "F.Paste")
			(net "GND")
		)
		(pad "2" smd rect
			(at -0.40005 0 90)
			(size 0.4572 0.508)
			(layers "F.Cu" "F.Mask" "F.Paste")
			(net "P1V8_STB_NODE1_SS")
		)
	)
	(footprint ""
		(layer "F.Cu")
		(at 140.692886 -51.476656 90)
		(property "Reference" "R1024"
			(at 16.324326 30.435042 90)
			(unlocked yes)
			(layer "F.SilkS")
			(effects
				(font
					(size 0.7874 0.5842)
					(thickness 0.1524)
				)
				(justify left)
			)
		)
		(property "Value" ""
			(at 0 0 90)
			(layer "F.Fab")
			(effects
				(font
					(size 1.27 1.27)
				)
			)
		)
		(duplicate_pad_numbers_are_jumpers no)
		(fp_line
			(start 0.7874 -0.4064)
			(end 0.7874 0.4064)
			(stroke
				(width 0.1524)
				(type default)
			)
			(layer "F.SilkS")
		)
		(fp_line
			(start -0.7874 -0.4064)
			(end 0.7874 -0.4064)
			(stroke
				(width 0.1524)
				(type default)
			)
			(layer "F.SilkS")
		)
		(fp_line
			(start 0.7874 0.4064)
			(end -0.7874 0.4064)
			(stroke
				(width 0.1524)
				(type default)
			)
			(layer "F.SilkS")
		)
		(fp_line
			(start -0.7874 0.4064)
			(end -0.7874 -0.4064)
			(stroke
				(width 0.1524)
				(type default)
			)
			(layer "F.SilkS")
		)
		(fp_poly
			(pts
				(xy -0.508 0.2794) (xy -0.508 0.2286) (xy -0.635 0.2286) (xy -0.635 -0.254) (xy -0.5334 -0.254)
				(xy -0.5334 -0.2794) (xy 0.5334 -0.2794) (xy 0.5334 -0.254) (xy 0.635 -0.254) (xy 0.635 0.254) (xy 0.5334 0.254)
				(xy 0.5334 0.2794)
			)
			(stroke
				(width 0)
				(type default)
			)
			(fill no)
			(layer "F.CrtYd")
		)
		(pad "1" smd rect
			(at 0.40005 0 90)
			(size 0.4572 0.508)
			(layers "F.Cu" "F.Mask" "F.Paste")
			(net "GND")
		)
		(pad "2" smd rect
			(at -0.40005 0 90)
			(size 0.4572 0.508)
			(layers "F.Cu" "F.Mask" "F.Paste")
			(net "UART_TX_P2")
		)
	)
	(footprint ""
		(layer "F.Cu")
		(at 10.257028 -138.946636)
		(property "Reference" "C555"
			(at -4.623562 4.578858 90)
			(unlocked yes)
			(layer "F.SilkS")
			(effects
				(font
					(size 0.7874 0.5842)
					(thickness 0.1524)
				)
				(justify left)
			)
		)
		(property "Value" ""
			(at 0 0 0)
			(layer "F.Fab")
			(effects
				(font
					(size 1.27 1.27)
				)
			)
		)
		(duplicate_pad_numbers_are_jumpers no)
		(fp_line
			(start -0.7874 -0.4064)
			(end 0.7874 -0.4064)
			(stroke
				(width 0.1524)
				(type default)
			)
			(layer "F.SilkS")
		)
		(fp_line
			(start -0.7874 0.4064)
			(end -0.7874 -0.4064)
			(stroke
				(width 0.1524)
				(type default)
			)
			(layer "F.SilkS")
		)
		(fp_line
			(start 0 0.381)
			(end 0 -0.381)
			(stroke
				(width 0.1524)
				(type default)
			)
			(layer "F.SilkS")
		)
		(fp_line
			(start 0.7874 -0.4064)
			(end 0.7874 0.4064)
			(stroke
				(width 0.1524)
				(type default)
			)
			(layer "F.SilkS")
		)
		(fp_line
			(start 0.7874 0.4064)
			(end -0.7874 0.4064)
			(stroke
				(width 0.1524)
				(type default)
			)
			(layer "F.SilkS")
		)
		(fp_poly
			(pts
				(xy -0.5334 0.254) (xy -0.635 0.254) (xy -0.635 0.2286) (xy -0.635 -0.254) (xy -0.5334 -0.254) (xy -0.5334 -0.2794)
				(xy 0.5334 -0.2794) (xy 0.5334 -0.254) (xy 0.635 -0.254) (xy 0.635 0.254) (xy 0.5334 0.254) (xy 0.5334 0.2794)
				(xy -0.508 0.2794) (xy -0.5334 0.2794)
			)
			(stroke
				(width 0)
				(type default)
			)
			(fill no)
			(layer "F.CrtYd")
		)
		(pad "1" smd rect
			(at 0.40005 0)
			(size 0.4572 0.508)
			(layers "F.Cu" "F.Mask" "F.Paste")
			(net "P3V3_NODE1")
		)
		(pad "2" smd rect
			(at -0.40005 0)
			(size 0.4572 0.508)
			(layers "F.Cu" "F.Mask" "F.Paste")
			(net "GND")
		)
	)
	(footprint ""
		(layer "F.Cu")
		(at 104.548432 -130.16103 -90)
		(property "Reference" "PR79"
			(at 5.362194 7.159752 90)
			(unlocked yes)
			(layer "F.SilkS")
			(effects
				(font
					(size 0.7874 0.5842)
					(thickness 0.1524)
				)
				(justify left)
			)
		)
		(property "Value" ""
			(at 0 0 270)
			(layer "F.Fab")
			(effects
				(font
					(size 1.27 1.27)
				)
			)
		)
		(duplicate_pad_numbers_are_jumpers no)
		(fp_line
			(start -0.7874 0.4064)
			(end -0.7874 -0.4064)
			(stroke
				(width 0.1524)
				(type default)
			)
			(layer "F.SilkS")
		)
		(fp_line
			(start 0.7874 0.4064)
			(end -0.7874 0.4064)
			(stroke
				(width 0.1524)
				(type default)
			)
			(layer "F.SilkS")
		)
		(fp_line
			(start -0.7874 -0.4064)
			(end 0.7874 -0.4064)
			(stroke
				(width 0.1524)
				(type default)
			)
			(layer "F.SilkS")
		)
		(fp_line
			(start 0.7874 -0.4064)
			(end 0.7874 0.4064)
			(stroke
				(width 0.1524)
				(type default)
			)
			(layer "F.SilkS")
		)
		(fp_poly
			(pts
				(xy -0.508 0.2794) (xy -0.508 0.2286) (xy -0.635 0.2286) (xy -0.635 -0.254) (xy -0.5334 -0.254)
				(xy -0.5334 -0.2794) (xy 0.5334 -0.2794) (xy 0.5334 -0.254) (xy 0.635 -0.254) (xy 0.635 0.254) (xy 0.5334 0.254)
				(xy 0.5334 0.2794)
			)
			(stroke
				(width 0)
				(type default)
			)
			(fill no)
			(layer "F.CrtYd")
		)
		(pad "1" smd rect
			(at 0.40005 0 270)
			(size 0.4572 0.508)
			(layers "F.Cu" "F.Mask" "F.Paste")
			(net "P3V3_NODE1")
		)
		(pad "2" smd rect
			(at -0.40005 0 270)
			(size 0.4572 0.508)
			(layers "F.Cu" "F.Mask" "F.Paste")
			(net "VR_PVCCP_NODE1_EN")
		)
	)
	(footprint ""
		(layer "F.Cu")
		(at 83.67776 -188.126624 90)
		(property "Reference" "C591"
			(at 4.548886 -1.847088 90)
			(unlocked yes)
			(layer "F.SilkS")
			(effects
				(font
					(size 0.7874 0.5842)
					(thickness 0.1524)
				)
				(justify left)
			)
		)
		(property "Value" ""
			(at 0 0 90)
			(layer "F.Fab")
			(effects
				(font
					(size 1.27 1.27)
				)
			)
		)
		(duplicate_pad_numbers_are_jumpers no)
		(fp_line
			(start 0.7874 -0.4064)
			(end 0.7874 0.4064)
			(stroke
				(width 0.1524)
				(type default)
			)
			(layer "F.SilkS")
		)
		(fp_line
			(start -0.7874 -0.4064)
			(end 0.7874 -0.4064)
			(stroke
				(width 0.1524)
				(type default)
			)
			(layer "F.SilkS")
		)
		(fp_line
			(start 0 0.381)
			(end 0 -0.381)
			(stroke
				(width 0.1524)
				(type default)
			)
			(layer "F.SilkS")
		)
		(fp_line
			(start 0.7874 0.4064)
			(end -0.7874 0.4064)
			(stroke
				(width 0.1524)
				(type default)
			)
			(layer "F.SilkS")
		)
		(fp_line
			(start -0.7874 0.4064)
			(end -0.7874 -0.4064)
			(stroke
				(width 0.1524)
				(type default)
			)
			(layer "F.SilkS")
		)
		(fp_poly
			(pts
				(xy -0.5334 0.254) (xy -0.635 0.254) (xy -0.635 0.2286) (xy -0.635 -0.254) (xy -0.5334 -0.254) (xy -0.5334 -0.2794)
				(xy 0.5334 -0.2794) (xy 0.5334 -0.254) (xy 0.635 -0.254) (xy 0.635 0.254) (xy 0.5334 0.254) (xy 0.5334 0.2794)
				(xy -0.508 0.2794) (xy -0.5334 0.2794)
			)
			(stroke
				(width 0)
				(type default)
			)
			(fill no)
			(layer "F.CrtYd")
		)
		(pad "1" smd rect
			(at 0.40005 0 90)
			(size 0.4572 0.508)
			(layers "F.Cu" "F.Mask" "F.Paste")
			(net "I2C_PSU2_R_SDA")
		)
		(pad "2" smd rect
			(at -0.40005 0 90)
			(size 0.4572 0.508)
			(layers "F.Cu" "F.Mask" "F.Paste")
			(net "GND")
		)
	)
	(footprint ""
		(layer "F.Cu")
		(at 87.445596 -79.428848)
		(property "Reference" "L6"
			(at 2.724404 0.02794 0)
			(unlocked yes)
			(layer "F.SilkS")
			(effects
				(font
					(size 0.7874 0.5842)
					(thickness 0.1524)
				)
				(justify left)
			)
		)
		(property "Value" ""
			(at 0 0 0)
			(layer "F.Fab")
			(effects
				(font
					(size 1.27 1.27)
				)
			)
		)
		(duplicate_pad_numbers_are_jumpers no)
		(fp_line
			(start -0.7874 -0.4064)
			(end 0.7874 -0.4064)
			(stroke
				(width 0.1524)
				(type default)
			)
			(layer "F.SilkS")
		)
		(fp_line
			(start -0.7874 0.4064)
			(end -0.7874 -0.4064)
			(stroke
				(width 0.1524)
				(type default)
			)
			(layer "F.SilkS")
		)
		(fp_line
			(start -0.0889 0.4064)
			(end -0.0889 -0.4064)
			(stroke
				(width 0.1524)
				(type default)
			)
			(layer "F.SilkS")
		)
		(fp_line
			(start 0.0889 0.4064)
			(end 0.0889 -0.4064)
			(stroke
				(width 0.1524)
				(type default)
			)
			(layer "F.SilkS")
		)
		(fp_line
			(start 0.7874 -0.4064)
			(end 0.7874 0.4064)
			(stroke
				(width 0.1524)
				(type default)
			)
			(layer "F.SilkS")
		)
		(fp_line
			(start 0.7874 0.4064)
			(end -0.7874 0.4064)
			(stroke
				(width 0.1524)
				(type default)
			)
			(layer "F.SilkS")
		)
		(fp_poly
			(pts
				(xy -0.5334 0.254) (xy -0.635 0.254) (xy -0.635 0.2286) (xy -0.635 -0.254) (xy -0.5334 -0.254) (xy -0.5334 -0.2794)
				(xy 0.5334 -0.2794) (xy 0.5334 -0.254) (xy 0.635 -0.254) (xy 0.635 0.254) (xy 0.5334 0.254) (xy 0.5334 0.2794)
				(xy -0.508 0.2794) (xy -0.5334 0.2794)
			)
			(stroke
				(width 0)
				(type default)
			)
			(fill no)
			(layer "F.CrtYd")
		)
		(pad "1" smd rect
			(at 0.40005 0)
			(size 0.4572 0.508)
			(layers "F.Cu" "F.Mask" "F.Paste")
			(net "P1V05_NODE1")
		)
		(pad "2" smd rect
			(at -0.40005 0)
			(size 0.4572 0.508)
			(layers "F.Cu" "F.Mask" "F.Paste")
			(net "P1V05_VCCPLLCPU1SIO_NODE1")
		)
	)
	(footprint ""
		(layer "F.Cu")
		(at 106.082084 -154.823668 180)
		(property "Reference" "PC40"
			(at 2.189226 -4.749038 0)
			(unlocked yes)
			(layer "F.SilkS")
			(effects
				(font
					(size 0.635 0.4064)
					(thickness 0.1524)
				)
				(justify left)
			)
		)
		(property "Value" ""
			(at 0 0 180)
			(layer "F.Fab")
			(effects
				(font
					(size 1.27 1.27)
				)
			)
		)
		(duplicate_pad_numbers_are_jumpers no)
		(fp_line
			(start 0.7874 0.4064)
			(end -0.7874 0.4064)
			(stroke
				(width 0.1524)
				(type default)
			)
			(layer "F.SilkS")
		)
		(fp_line
			(start 0.7874 -0.4064)
			(end 0.7874 0.4064)
			(stroke
				(width 0.1524)
				(type default)
			)
			(layer "F.SilkS")
		)
		(fp_line
			(start 0 0.381)
			(end 0 -0.381)
			(stroke
				(width 0.1524)
				(type default)
			)
			(layer "F.SilkS")
		)
		(fp_line
			(start -0.7874 0.4064)
			(end -0.7874 -0.4064)
			(stroke
				(width 0.1524)
				(type default)
			)
			(layer "F.SilkS")
		)
		(fp_line
			(start -0.7874 -0.4064)
			(end 0.7874 -0.4064)
			(stroke
				(width 0.1524)
				(type default)
			)
			(layer "F.SilkS")
		)
		(fp_poly
			(pts
				(xy -0.5334 0.254) (xy -0.635 0.254) (xy -0.635 0.2286) (xy -0.635 -0.254) (xy -0.5334 -0.254) (xy -0.5334 -0.2794)
				(xy 0.5334 -0.2794) (xy 0.5334 -0.254) (xy 0.635 -0.254) (xy 0.635 0.254) (xy 0.5334 0.254) (xy 0.5334 0.2794)
				(xy -0.508 0.2794) (xy -0.5334 0.2794)
			)
			(stroke
				(width 0)
				(type default)
			)
			(fill no)
			(layer "F.CrtYd")
		)
		(pad "1" smd rect
			(at 0.40005 0 180)
			(size 0.4572 0.508)
			(layers "F.Cu" "F.Mask" "F.Paste")
			(net "P1V8_STB_NODE1_VREG5")
		)
		(pad "2" smd rect
			(at -0.40005 0 180)
			(size 0.4572 0.508)
			(layers "F.Cu" "F.Mask" "F.Paste")
			(net "GND")
		)
	)
	(footprint ""
		(layer "F.Cu")
		(at 132.207 -51.435 -90)
		(property "Reference" "R1163"
			(at -16.3322 -30.65907 90)
			(unlocked yes)
			(layer "F.SilkS")
			(effects
				(font
					(size 0.7874 0.5842)
					(thickness 0.1524)
				)
				(justify left)
			)
		)
		(property "Value" ""
			(at 0 0 270)
			(layer "F.Fab")
			(effects
				(font
					(size 1.27 1.27)
				)
			)
		)
		(duplicate_pad_numbers_are_jumpers no)
		(fp_line
			(start -0.7874 0.4064)
			(end -0.7874 -0.4064)
			(stroke
				(width 0.1524)
				(type default)
			)
			(layer "F.SilkS")
		)
		(fp_line
			(start 0.7874 0.4064)
			(end -0.7874 0.4064)
			(stroke
				(width 0.1524)
				(type default)
			)
			(layer "F.SilkS")
		)
		(fp_line
			(start -0.7874 -0.4064)
			(end 0.7874 -0.4064)
			(stroke
				(width 0.1524)
				(type default)
			)
			(layer "F.SilkS")
		)
		(fp_line
			(start 0.7874 -0.4064)
			(end 0.7874 0.4064)
			(stroke
				(width 0.1524)
				(type default)
			)
			(layer "F.SilkS")
		)
		(fp_poly
			(pts
				(xy -0.508 0.2794) (xy -0.508 0.2286) (xy -0.635 0.2286) (xy -0.635 -0.254) (xy -0.5334 -0.254)
				(xy -0.5334 -0.2794) (xy 0.5334 -0.2794) (xy 0.5334 -0.254) (xy 0.635 -0.254) (xy 0.635 0.254) (xy 0.5334 0.254)
				(xy 0.5334 0.2794)
			)
			(stroke
				(width 0)
				(type default)
			)
			(fill no)
			(layer "F.CrtYd")
		)
		(pad "1" smd rect
			(at 0.40005 0 270)
			(size 0.4572 0.508)
			(layers "F.Cu" "F.Mask" "F.Paste")
			(net "UART_DTR_P4_R_N")
		)
		(pad "2" smd rect
			(at -0.40005 0 270)
			(size 0.4572 0.508)
			(layers "F.Cu" "F.Mask" "F.Paste")
			(net "UART_DTR_P4_N")
		)
	)
	(footprint ""
		(layer "F.Cu")
		(at 87.68588 -76.013564 180)
		(property "Reference" "C61"
			(at -2.86004 -0.087376 0)
			(unlocked yes)
			(layer "F.SilkS")
			(effects
				(font
					(size 0.7874 0.5842)
					(thickness 0.1524)
				)
				(justify left)
			)
		)
		(property "Value" ""
			(at 0 0 180)
			(layer "F.Fab")
			(effects
				(font
					(size 1.27 1.27)
				)
			)
		)
		(duplicate_pad_numbers_are_jumpers no)
		(fp_line
			(start 0.7874 0.4064)
			(end -0.7874 0.4064)
			(stroke
				(width 0.1524)
				(type default)
			)
			(layer "F.SilkS")
		)
		(fp_line
			(start 0.7874 -0.4064)
			(end 0.7874 0.4064)
			(stroke
				(width 0.1524)
				(type default)
			)
			(layer "F.SilkS")
		)
		(fp_line
			(start 0 0.381)
			(end 0 -0.381)
			(stroke
				(width 0.1524)
				(type default)
			)
			(layer "F.SilkS")
		)
		(fp_line
			(start -0.7874 0.4064)
			(end -0.7874 -0.4064)
			(stroke
				(width 0.1524)
				(type default)
			)
			(layer "F.SilkS")
		)
		(fp_line
			(start -0.7874 -0.4064)
			(end 0.7874 -0.4064)
			(stroke
				(width 0.1524)
				(type default)
			)
			(layer "F.SilkS")
		)
		(fp_poly
			(pts
				(xy -0.5334 0.254) (xy -0.635 0.254) (xy -0.635 0.2286) (xy -0.635 -0.254) (xy -0.5334 -0.254) (xy -0.5334 -0.2794)
				(xy 0.5334 -0.2794) (xy 0.5334 -0.254) (xy 0.635 -0.254) (xy 0.635 0.254) (xy 0.5334 0.254) (xy 0.5334 0.2794)
				(xy -0.508 0.2794) (xy -0.5334 0.2794)
			)
			(stroke
				(width 0)
				(type default)
			)
			(fill no)
			(layer "F.CrtYd")
		)
		(pad "1" smd rect
			(at 0.40005 0 180)
			(size 0.4572 0.508)
			(layers "F.Cu" "F.Mask" "F.Paste")
			(net "P1V05_VCCPLLCPU0SIO_NODE1")
		)
		(pad "2" smd rect
			(at -0.40005 0 180)
			(size 0.4572 0.508)
			(layers "F.Cu" "F.Mask" "F.Paste")
			(net "GND")
		)
	)
	(footprint ""
		(layer "F.Cu")
		(at 155.356814 -65.482216)
		(property "Reference" "C490"
			(at -0.53086 2.179574 0)
			(unlocked yes)
			(layer "F.SilkS")
			(effects
				(font
					(size 0.7874 0.5842)
					(thickness 0.1524)
				)
				(justify left)
			)
		)
		(property "Value" ""
			(at 0 0 0)
			(layer "F.Fab")
			(effects
				(font
					(size 1.27 1.27)
				)
			)
		)
		(duplicate_pad_numbers_are_jumpers no)
		(fp_line
			(start -0.7874 -0.4064)
			(end 0.7874 -0.4064)
			(stroke
				(width 0.1524)
				(type default)
			)
			(layer "F.SilkS")
		)
		(fp_line
			(start -0.7874 0.4064)
			(end -0.7874 -0.4064)
			(stroke
				(width 0.1524)
				(type default)
			)
			(layer "F.SilkS")
		)
		(fp_line
			(start 0 0.381)
			(end 0 -0.381)
			(stroke
				(width 0.1524)
				(type default)
			)
			(layer "F.SilkS")
		)
		(fp_line
			(start 0.7874 -0.4064)
			(end 0.7874 0.4064)
			(stroke
				(width 0.1524)
				(type default)
			)
			(layer "F.SilkS")
		)
		(fp_line
			(start 0.7874 0.4064)
			(end -0.7874 0.4064)
			(stroke
				(width 0.1524)
				(type default)
			)
			(layer "F.SilkS")
		)
		(fp_poly
			(pts
				(xy -0.5334 0.254) (xy -0.635 0.254) (xy -0.635 0.2286) (xy -0.635 -0.254) (xy -0.5334 -0.254) (xy -0.5334 -0.2794)
				(xy 0.5334 -0.2794) (xy 0.5334 -0.254) (xy 0.635 -0.254) (xy 0.635 0.254) (xy 0.5334 0.254) (xy 0.5334 0.2794)
				(xy -0.508 0.2794) (xy -0.5334 0.2794)
			)
			(stroke
				(width 0)
				(type default)
			)
			(fill no)
			(layer "F.CrtYd")
		)
		(pad "1" smd rect
			(at 0.40005 0)
			(size 0.4572 0.508)
			(layers "F.Cu" "F.Mask" "F.Paste")
			(net "SATA_TX0_C_DN")
		)
		(pad "2" smd rect
			(at -0.40005 0)
			(size 0.4572 0.508)
			(layers "F.Cu" "F.Mask" "F.Paste")
			(net "SATA_A_NODE1_TX_N0")
		)
	)
	(footprint ""
		(layer "F.Cu")
		(at 116.075714 -139.122912 180)
		(property "Reference" "PJ14"
			(at -2.973832 4.671568 90)
			(unlocked yes)
			(layer "F.SilkS")
			(effects
				(font
					(size 0.7874 0.5842)
					(thickness 0.1524)
				)
				(justify left)
			)
		)
		(property "Value" ""
			(at 0 0 180)
			(layer "F.Fab")
			(effects
				(font
					(size 1.27 1.27)
				)
			)
		)
		(duplicate_pad_numbers_are_jumpers no)
		(fp_poly
			(pts
				(xy -0.360426 0.359156) (xy -0.360426 -0.381) (xy 0.3556 -0.381) (xy 0.3556 1.905) (xy -0.360426 1.905)
			)
			(stroke
				(width 0)
				(type default)
			)
			(fill no)
			(layer "F.CrtYd")
		)
		(pad "1" smd custom
			(at 0 0 180)
			(size 0.1778 0.1778)
			(layers "F.Cu" "F.Mask" "F.Paste")
			(net "VR_PVCCP_NODE1_VSEN")
			(options
				(clearance outline)
				(anchor circle)
			)
			(primitives
				(gr_poly
					(pts
						(xy -0.127 0.9398) (xy -0.127 -0.127) (xy -0.3556 -0.127) (xy -0.3556 -0.9398) (xy 0.3556 -0.9398)
						(xy 0.3556 -0.127) (xy 0.127 -0.127) (xy 0.127 0.9398)
					)
					(width 0)
					(fill yes)
				)
			)
		)
		(pad "2" smd rect
			(at 0 1.4986)
			(size 0.7112 0.8128)
			(layers "F.Cu" "F.Mask" "F.Paste")
			(net "VSENSE_VCC_CPU_NODE1")
		)
		(zone
			(layer "F.Cu")
			(hatch none 0.5)
			(connect_pads
				(clearance 0)
			)
			(min_thickness 0.25)
			(keepout
				(tracks allowed)
				(vias not_allowed)
				(pads allowed)
				(copperpour not_allowed)
				(footprints allowed)
			)
			(placement
				(enabled no)
				(sheetname "")
			)
			(fill
				(thermal_gap 0.5)
				(thermal_bridge_width 0.5)
				(island_removal_mode 0)
			)
			(polygon
				(pts
					(xy 115.669314 -141.078712) (xy 115.669314 -138.691112) (xy 116.48694 -138.691112) (xy 116.48694 -141.078712)
				)
			)
		)
	)
	(footprint ""
		(layer "F.Cu")
		(at 90.812112 -172.499782 180)
		(property "Reference" "R942"
			(at -85.974428 -74.448162 0)
			(unlocked yes)
			(layer "F.SilkS")
			(effects
				(font
					(size 0.7874 0.5842)
					(thickness 0.1524)
				)
				(justify left)
			)
		)
		(property "Value" ""
			(at 0 0 180)
			(layer "F.Fab")
			(effects
				(font
					(size 1.27 1.27)
				)
			)
		)
		(duplicate_pad_numbers_are_jumpers no)
		(fp_line
			(start 0.7874 0.4064)
			(end -0.7874 0.4064)
			(stroke
				(width 0.1524)
				(type default)
			)
			(layer "F.SilkS")
		)
		(fp_line
			(start 0.7874 -0.4064)
			(end 0.7874 0.4064)
			(stroke
				(width 0.1524)
				(type default)
			)
			(layer "F.SilkS")
		)
		(fp_line
			(start -0.7874 0.4064)
			(end -0.7874 -0.4064)
			(stroke
				(width 0.1524)
				(type default)
			)
			(layer "F.SilkS")
		)
		(fp_line
			(start -0.7874 -0.4064)
			(end 0.7874 -0.4064)
			(stroke
				(width 0.1524)
				(type default)
			)
			(layer "F.SilkS")
		)
		(fp_poly
			(pts
				(xy -0.508 0.2794) (xy -0.508 0.2286) (xy -0.635 0.2286) (xy -0.635 -0.254) (xy -0.5334 -0.254)
				(xy -0.5334 -0.2794) (xy 0.5334 -0.2794) (xy 0.5334 -0.254) (xy 0.635 -0.254) (xy 0.635 0.254) (xy 0.5334 0.254)
				(xy 0.5334 0.2794)
			)
			(stroke
				(width 0)
				(type default)
			)
			(fill no)
			(layer "F.CrtYd")
		)
		(pad "1" smd rect
			(at 0.40005 0 180)
			(size 0.4572 0.508)
			(layers "F.Cu" "F.Mask" "F.Paste")
			(net "UART_T6_NODE2_TXD")
		)
		(pad "2" smd rect
			(at -0.40005 0 180)
			(size 0.4572 0.508)
			(layers "F.Cu" "F.Mask" "F.Paste")
			(net "UART_T6_NODE2_TXD_R")
		)
	)
	(footprint ""
		(layer "F.Cu")
		(at 138.79576 -188.126624 90)
		(property "Reference" "C642"
			(at 5.519674 -0.214376 90)
			(unlocked yes)
			(layer "F.SilkS")
			(effects
				(font
					(size 0.7874 0.5842)
					(thickness 0.1524)
				)
				(justify left)
			)
		)
		(property "Value" ""
			(at 0 0 90)
			(layer "F.Fab")
			(effects
				(font
					(size 1.27 1.27)
				)
			)
		)
		(duplicate_pad_numbers_are_jumpers no)
		(fp_line
			(start 0.7874 -0.4064)
			(end 0.7874 0.4064)
			(stroke
				(width 0.1524)
				(type default)
			)
			(layer "F.SilkS")
		)
		(fp_line
			(start -0.7874 -0.4064)
			(end 0.7874 -0.4064)
			(stroke
				(width 0.1524)
				(type default)
			)
			(layer "F.SilkS")
		)
		(fp_line
			(start 0 0.381)
			(end 0 -0.381)
			(stroke
				(width 0.1524)
				(type default)
			)
			(layer "F.SilkS")
		)
		(fp_line
			(start 0.7874 0.4064)
			(end -0.7874 0.4064)
			(stroke
				(width 0.1524)
				(type default)
			)
			(layer "F.SilkS")
		)
		(fp_line
			(start -0.7874 0.4064)
			(end -0.7874 -0.4064)
			(stroke
				(width 0.1524)
				(type default)
			)
			(layer "F.SilkS")
		)
		(fp_poly
			(pts
				(xy -0.5334 0.254) (xy -0.635 0.254) (xy -0.635 0.2286) (xy -0.635 -0.254) (xy -0.5334 -0.254) (xy -0.5334 -0.2794)
				(xy 0.5334 -0.2794) (xy 0.5334 -0.254) (xy 0.635 -0.254) (xy 0.635 0.254) (xy 0.5334 0.254) (xy 0.5334 0.2794)
				(xy -0.508 0.2794) (xy -0.5334 0.2794)
			)
			(stroke
				(width 0)
				(type default)
			)
			(fill no)
			(layer "F.CrtYd")
		)
		(pad "1" smd rect
			(at 0.40005 0 90)
			(size 0.4572 0.508)
			(layers "F.Cu" "F.Mask" "F.Paste")
			(net "T10_NODE3_EN_R")
		)
		(pad "2" smd rect
			(at -0.40005 0 90)
			(size 0.4572 0.508)
			(layers "F.Cu" "F.Mask" "F.Paste")
			(net "GND")
		)
	)
	(footprint ""
		(layer "F.Cu")
		(at 102.149656 -17.68094 180)
		(property "Reference" "C140"
			(at -1.48717 -3.301746 90)
			(unlocked yes)
			(layer "F.SilkS")
			(effects
				(font
					(size 0.7874 0.5842)
					(thickness 0.1524)
				)
				(justify left)
			)
		)
		(property "Value" ""
			(at 0 0 180)
			(layer "F.Fab")
			(effects
				(font
					(size 1.27 1.27)
				)
			)
		)
		(duplicate_pad_numbers_are_jumpers no)
		(fp_line
			(start 0.7874 0.4064)
			(end -0.7874 0.4064)
			(stroke
				(width 0.1524)
				(type default)
			)
			(layer "F.SilkS")
		)
		(fp_line
			(start 0.7874 -0.4064)
			(end 0.7874 0.4064)
			(stroke
				(width 0.1524)
				(type default)
			)
			(layer "F.SilkS")
		)
		(fp_line
			(start 0 0.381)
			(end 0 -0.381)
			(stroke
				(width 0.1524)
				(type default)
			)
			(layer "F.SilkS")
		)
		(fp_line
			(start -0.7874 0.4064)
			(end -0.7874 -0.4064)
			(stroke
				(width 0.1524)
				(type default)
			)
			(layer "F.SilkS")
		)
		(fp_line
			(start -0.7874 -0.4064)
			(end 0.7874 -0.4064)
			(stroke
				(width 0.1524)
				(type default)
			)
			(layer "F.SilkS")
		)
		(fp_poly
			(pts
				(xy -0.5334 0.254) (xy -0.635 0.254) (xy -0.635 0.2286) (xy -0.635 -0.254) (xy -0.5334 -0.254) (xy -0.5334 -0.2794)
				(xy 0.5334 -0.2794) (xy 0.5334 -0.254) (xy 0.635 -0.254) (xy 0.635 0.254) (xy 0.5334 0.254) (xy 0.5334 0.2794)
				(xy -0.508 0.2794) (xy -0.5334 0.2794)
			)
			(stroke
				(width 0)
				(type default)
			)
			(fill no)
			(layer "F.CrtYd")
		)
		(pad "1" smd rect
			(at 0.40005 0 180)
			(size 0.4572 0.508)
			(layers "F.Cu" "F.Mask" "F.Paste")
			(net "P3V3_NODE1")
		)
		(pad "2" smd rect
			(at -0.40005 0 180)
			(size 0.4572 0.508)
			(layers "F.Cu" "F.Mask" "F.Paste")
			(net "GND")
		)
	)
	(footprint ""
		(layer "F.Cu")
		(at 102.009448 -136.176258)
		(property "Reference" "PR52"
			(at -4.386834 -8.420608 0)
			(unlocked yes)
			(layer "F.SilkS")
			(effects
				(font
					(size 0.7874 0.5842)
					(thickness 0.1524)
				)
				(justify left)
			)
		)
		(property "Value" ""
			(at 0 0 0)
			(layer "F.Fab")
			(effects
				(font
					(size 1.27 1.27)
				)
			)
		)
		(duplicate_pad_numbers_are_jumpers no)
		(fp_line
			(start -0.7874 -0.4064)
			(end 0.7874 -0.4064)
			(stroke
				(width 0.1524)
				(type default)
			)
			(layer "F.SilkS")
		)
		(fp_line
			(start -0.7874 0.4064)
			(end -0.7874 -0.4064)
			(stroke
				(width 0.1524)
				(type default)
			)
			(layer "F.SilkS")
		)
		(fp_line
			(start 0.7874 -0.4064)
			(end 0.7874 0.4064)
			(stroke
				(width 0.1524)
				(type default)
			)
			(layer "F.SilkS")
		)
		(fp_line
			(start 0.7874 0.4064)
			(end -0.7874 0.4064)
			(stroke
				(width 0.1524)
				(type default)
			)
			(layer "F.SilkS")
		)
		(fp_poly
			(pts
				(xy -0.508 0.2794) (xy -0.508 0.2286) (xy -0.635 0.2286) (xy -0.635 -0.254) (xy -0.5334 -0.254)
				(xy -0.5334 -0.2794) (xy 0.5334 -0.2794) (xy 0.5334 -0.254) (xy 0.635 -0.254) (xy 0.635 0.254) (xy 0.5334 0.254)
				(xy 0.5334 0.2794)
			)
			(stroke
				(width 0)
				(type default)
			)
			(fill no)
			(layer "F.CrtYd")
		)
		(pad "1" smd rect
			(at 0.40005 0)
			(size 0.4572 0.508)
			(layers "F.Cu" "F.Mask" "F.Paste")
			(net "PWRGD_NODE1_PVCCP_PG")
		)
		(pad "2" smd rect
			(at -0.40005 0)
			(size 0.4572 0.508)
			(layers "F.Cu" "F.Mask" "F.Paste")
			(net "P3V3_NODE1")
		)
	)
	(footprint ""
		(layer "F.Cu")
		(at 46.588426 -100.517706 -90)
		(property "Reference" "C139"
			(at 2.55397 0.97663 90)
			(unlocked yes)
			(layer "F.SilkS")
			(effects
				(font
					(size 0.7874 0.5842)
					(thickness 0.1524)
				)
				(justify left)
			)
		)
		(property "Value" ""
			(at 0 0 270)
			(layer "F.Fab")
			(effects
				(font
					(size 1.27 1.27)
				)
			)
		)
		(duplicate_pad_numbers_are_jumpers no)
		(fp_line
			(start -0.7874 0.4064)
			(end -0.7874 -0.4064)
			(stroke
				(width 0.1524)
				(type default)
			)
			(layer "F.SilkS")
		)
		(fp_line
			(start 0.7874 0.4064)
			(end -0.7874 0.4064)
			(stroke
				(width 0.1524)
				(type default)
			)
			(layer "F.SilkS")
		)
		(fp_line
			(start 0 0.381)
			(end 0 -0.381)
			(stroke
				(width 0.1524)
				(type default)
			)
			(layer "F.SilkS")
		)
		(fp_line
			(start -0.7874 -0.4064)
			(end 0.7874 -0.4064)
			(stroke
				(width 0.1524)
				(type default)
			)
			(layer "F.SilkS")
		)
		(fp_line
			(start 0.7874 -0.4064)
			(end 0.7874 0.4064)
			(stroke
				(width 0.1524)
				(type default)
			)
			(layer "F.SilkS")
		)
		(fp_poly
			(pts
				(xy -0.5334 0.254) (xy -0.635 0.254) (xy -0.635 0.2286) (xy -0.635 -0.254) (xy -0.5334 -0.254) (xy -0.5334 -0.2794)
				(xy 0.5334 -0.2794) (xy 0.5334 -0.254) (xy 0.635 -0.254) (xy 0.635 0.254) (xy 0.5334 0.254) (xy 0.5334 0.2794)
				(xy -0.508 0.2794) (xy -0.5334 0.2794)
			)
			(stroke
				(width 0)
				(type default)
			)
			(fill no)
			(layer "F.CrtYd")
		)
		(pad "1" smd rect
			(at 0.40005 0 270)
			(size 0.4572 0.508)
			(layers "F.Cu" "F.Mask" "F.Paste")
			(net "A_SOC_NODE1_THERMDA")
		)
		(pad "2" smd rect
			(at -0.40005 0 270)
			(size 0.4572 0.508)
			(layers "F.Cu" "F.Mask" "F.Paste")
			(net "A_SOC_NODE1_THERMDC")
		)
	)
	(footprint ""
		(layer "F.Cu")
		(at 132.5372 -54.1274 -90)
		(property "Reference" "R1326"
			(at -0.9652 -0.20447 90)
			(unlocked yes)
			(layer "F.SilkS")
			(effects
				(font
					(size 0.7874 0.5842)
					(thickness 0.1524)
				)
				(justify left)
			)
		)
		(property "Value" ""
			(at 0 0 270)
			(layer "F.Fab")
			(effects
				(font
					(size 1.27 1.27)
				)
			)
		)
		(duplicate_pad_numbers_are_jumpers no)
		(fp_line
			(start -0.7874 0.4064)
			(end -0.7874 -0.4064)
			(stroke
				(width 0.1524)
				(type default)
			)
			(layer "F.SilkS")
		)
		(fp_line
			(start 0.7874 0.4064)
			(end -0.7874 0.4064)
			(stroke
				(width 0.1524)
				(type default)
			)
			(layer "F.SilkS")
		)
		(fp_line
			(start -0.7874 -0.4064)
			(end 0.7874 -0.4064)
			(stroke
				(width 0.1524)
				(type default)
			)
			(layer "F.SilkS")
		)
		(fp_line
			(start 0.7874 -0.4064)
			(end 0.7874 0.4064)
			(stroke
				(width 0.1524)
				(type default)
			)
			(layer "F.SilkS")
		)
		(fp_poly
			(pts
				(xy -0.508 0.2794) (xy -0.508 0.2286) (xy -0.635 0.2286) (xy -0.635 -0.254) (xy -0.5334 -0.254)
				(xy -0.5334 -0.2794) (xy 0.5334 -0.2794) (xy 0.5334 -0.254) (xy 0.635 -0.254) (xy 0.635 0.254) (xy 0.5334 0.254)
				(xy 0.5334 0.2794)
			)
			(stroke
				(width 0)
				(type default)
			)
			(fill no)
			(layer "F.CrtYd")
		)
		(pad "1" smd rect
			(at 0.40005 0 270)
			(size 0.4572 0.508)
			(layers "F.Cu" "F.Mask" "F.Paste")
			(net "UART_RI_P4_R_N")
		)
		(pad "2" smd rect
			(at -0.40005 0 270)
			(size 0.4572 0.508)
			(layers "F.Cu" "F.Mask" "F.Paste")
			(net "GND")
		)
	)
	(footprint ""
		(layer "F.Cu")
		(at 60.04306 -106.237024 180)
		(property "Reference" "PC133"
			(at 1.961134 -4.863084 0)
			(unlocked yes)
			(layer "F.SilkS")
			(effects
				(font
					(size 0.7874 0.5842)
					(thickness 0.1524)
				)
				(justify left)
			)
		)
		(property "Value" ""
			(at 0 0 180)
			(layer "F.Fab")
			(effects
				(font
					(size 1.27 1.27)
				)
			)
		)
		(duplicate_pad_numbers_are_jumpers no)
		(fp_line
			(start 1.905 0.8636)
			(end -1.905 0.8636)
			(stroke
				(width 0.1524)
				(type default)
			)
			(layer "F.SilkS")
		)
		(fp_line
			(start 1.905 -0.8636)
			(end 1.905 0.8636)
			(stroke
				(width 0.1524)
				(type default)
			)
			(layer "F.SilkS")
		)
		(fp_line
			(start 0 0.8382)
			(end 0 -0.8382)
			(stroke
				(width 0.1524)
				(type default)
			)
			(layer "F.SilkS")
		)
		(fp_line
			(start -1.905 0.8636)
			(end -1.905 -0.8636)
			(stroke
				(width 0.1524)
				(type default)
			)
			(layer "F.SilkS")
		)
		(fp_line
			(start -1.905 -0.8636)
			(end 1.905 -0.8636)
			(stroke
				(width 0.1524)
				(type default)
			)
			(layer "F.SilkS")
		)
		(fp_rect
			(start -1.524 0.7366)
			(end 1.524 -0.7366)
			(stroke
				(width 0)
				(type default)
			)
			(fill no)
			(layer "F.CrtYd")
		)
		(pad "1" smd rect
			(at 0.94996 0 180)
			(size 1.1176 1.3716)
			(layers "F.Cu" "F.Mask" "F.Paste")
			(net "P3V3_STB_NODE1")
		)
		(pad "2" smd rect
			(at -0.94996 0 180)
			(size 1.1176 1.3716)
			(layers "F.Cu" "F.Mask" "F.Paste")
			(net "GND")
		)
	)
	(footprint ""
		(layer "F.Cu")
		(at 157.33776 -188.126624 90)
		(property "Reference" "R1220"
			(at 5.519674 -3.560572 90)
			(unlocked yes)
			(layer "F.SilkS")
			(effects
				(font
					(size 0.7874 0.5842)
					(thickness 0.1524)
				)
				(justify left)
			)
		)
		(property "Value" ""
			(at 0 0 90)
			(layer "F.Fab")
			(effects
				(font
					(size 1.27 1.27)
				)
			)
		)
		(duplicate_pad_numbers_are_jumpers no)
		(fp_line
			(start 0.7874 -0.4064)
			(end 0.7874 0.4064)
			(stroke
				(width 0.1524)
				(type default)
			)
			(layer "F.SilkS")
		)
		(fp_line
			(start -0.7874 -0.4064)
			(end 0.7874 -0.4064)
			(stroke
				(width 0.1524)
				(type default)
			)
			(layer "F.SilkS")
		)
		(fp_line
			(start 0.7874 0.4064)
			(end -0.7874 0.4064)
			(stroke
				(width 0.1524)
				(type default)
			)
			(layer "F.SilkS")
		)
		(fp_line
			(start -0.7874 0.4064)
			(end -0.7874 -0.4064)
			(stroke
				(width 0.1524)
				(type default)
			)
			(layer "F.SilkS")
		)
		(fp_poly
			(pts
				(xy -0.508 0.2794) (xy -0.508 0.2286) (xy -0.635 0.2286) (xy -0.635 -0.254) (xy -0.5334 -0.254)
				(xy -0.5334 -0.2794) (xy 0.5334 -0.2794) (xy 0.5334 -0.254) (xy 0.635 -0.254) (xy 0.635 0.254) (xy 0.5334 0.254)
				(xy 0.5334 0.2794)
			)
			(stroke
				(width 0)
				(type default)
			)
			(fill no)
			(layer "F.CrtYd")
		)
		(pad "1" smd rect
			(at 0.40005 0 90)
			(size 0.4572 0.508)
			(layers "F.Cu" "F.Mask" "F.Paste")
			(net "FAN2_TACH_R")
		)
		(pad "2" smd rect
			(at -0.40005 0 90)
			(size 0.4572 0.508)
			(layers "F.Cu" "F.Mask" "F.Paste")
			(net "GND")
		)
	)
	(footprint ""
		(layer "F.Cu")
		(at 12.930124 -130.120136 90)
		(property "Reference" "PR28"
			(at -2.068068 -1.078484 90)
			(unlocked yes)
			(layer "F.SilkS")
			(effects
				(font
					(size 0.7874 0.5842)
					(thickness 0.1524)
				)
				(justify left)
			)
		)
		(property "Value" ""
			(at 0 0 90)
			(layer "F.Fab")
			(effects
				(font
					(size 1.27 1.27)
				)
			)
		)
		(duplicate_pad_numbers_are_jumpers no)
		(fp_line
			(start 0.7874 -0.4064)
			(end 0.7874 0.4064)
			(stroke
				(width 0.1524)
				(type default)
			)
			(layer "F.SilkS")
		)
		(fp_line
			(start -0.7874 -0.4064)
			(end 0.7874 -0.4064)
			(stroke
				(width 0.1524)
				(type default)
			)
			(layer "F.SilkS")
		)
		(fp_line
			(start 0.7874 0.4064)
			(end -0.7874 0.4064)
			(stroke
				(width 0.1524)
				(type default)
			)
			(layer "F.SilkS")
		)
		(fp_line
			(start -0.7874 0.4064)
			(end -0.7874 -0.4064)
			(stroke
				(width 0.1524)
				(type default)
			)
			(layer "F.SilkS")
		)
		(fp_poly
			(pts
				(xy -0.508 0.2794) (xy -0.508 0.2286) (xy -0.635 0.2286) (xy -0.635 -0.254) (xy -0.5334 -0.254)
				(xy -0.5334 -0.2794) (xy 0.5334 -0.2794) (xy 0.5334 -0.254) (xy 0.635 -0.254) (xy 0.635 0.254) (xy 0.5334 0.254)
				(xy 0.5334 0.2794)
			)
			(stroke
				(width 0)
				(type default)
			)
			(fill no)
			(layer "F.CrtYd")
		)
		(pad "1" smd rect
			(at 0.40005 0 90)
			(size 0.4572 0.508)
			(layers "F.Cu" "F.Mask" "F.Paste")
			(net "P1V05_NODE1_TRIP")
		)
		(pad "2" smd rect
			(at -0.40005 0 90)
			(size 0.4572 0.508)
			(layers "F.Cu" "F.Mask" "F.Paste")
			(net "GND")
		)
	)
	(footprint ""
		(layer "F.Cu")
		(at 187.586366 -122.844814)
		(property "Reference" "R1034"
			(at 5.453634 19.112484 0)
			(unlocked yes)
			(layer "F.SilkS")
			(effects
				(font
					(size 0.7874 0.5842)
					(thickness 0.1524)
				)
				(justify left)
			)
		)
		(property "Value" ""
			(at 0 0 0)
			(layer "F.Fab")
			(effects
				(font
					(size 1.27 1.27)
				)
			)
		)
		(duplicate_pad_numbers_are_jumpers no)
		(fp_line
			(start -0.7874 -0.4064)
			(end 0.7874 -0.4064)
			(stroke
				(width 0.1524)
				(type default)
			)
			(layer "F.SilkS")
		)
		(fp_line
			(start -0.7874 0.4064)
			(end -0.7874 -0.4064)
			(stroke
				(width 0.1524)
				(type default)
			)
			(layer "F.SilkS")
		)
		(fp_line
			(start 0.7874 -0.4064)
			(end 0.7874 0.4064)
			(stroke
				(width 0.1524)
				(type default)
			)
			(layer "F.SilkS")
		)
		(fp_line
			(start 0.7874 0.4064)
			(end -0.7874 0.4064)
			(stroke
				(width 0.1524)
				(type default)
			)
			(layer "F.SilkS")
		)
		(fp_poly
			(pts
				(xy -0.508 0.2794) (xy -0.508 0.2286) (xy -0.635 0.2286) (xy -0.635 -0.254) (xy -0.5334 -0.254)
				(xy -0.5334 -0.2794) (xy 0.5334 -0.2794) (xy 0.5334 -0.254) (xy 0.635 -0.254) (xy 0.635 0.254) (xy 0.5334 0.254)
				(xy 0.5334 0.2794)
			)
			(stroke
				(width 0)
				(type default)
			)
			(fill no)
			(layer "F.CrtYd")
		)
		(pad "1" smd rect
			(at 0.40005 0)
			(size 0.4572 0.508)
			(layers "F.Cu" "F.Mask" "F.Paste")
			(net "P3V3_STB_NODE1")
		)
		(pad "2" smd rect
			(at -0.40005 0)
			(size 0.4572 0.508)
			(layers "F.Cu" "F.Mask" "F.Paste")
			(net "JTAG_CPLD1_TMS")
		)
	)
	(footprint ""
		(layer "F.Cu")
		(at 129.244344 -108.27766 180)
		(property "Reference" "Y1"
			(at 0.254 -2.310384 0)
			(unlocked yes)
			(layer "F.SilkS")
			(effects
				(font
					(size 0.7874 0.5842)
					(thickness 0.1524)
				)
				(justify left)
			)
		)
		(property "Value" ""
			(at 0 0 180)
			(layer "F.Fab")
			(effects
				(font
					(size 1.27 1.27)
				)
			)
		)
		(duplicate_pad_numbers_are_jumpers no)
		(fp_line
			(start 1.9558 1.6002)
			(end -1.9558 1.6002)
			(stroke
				(width 0.1524)
				(type default)
			)
			(layer "F.SilkS")
		)
		(fp_line
			(start 1.9558 -1.6002)
			(end 1.9558 1.6002)
			(stroke
				(width 0.1524)
				(type default)
			)
			(layer "F.SilkS")
		)
		(fp_line
			(start -1.524 0)
			(end -1.903984 0.1016)
			(stroke
				(width 0.1524)
				(type default)
			)
			(layer "F.SilkS")
		)
		(fp_line
			(start -1.903984 -0.1016)
			(end -1.524 0)
			(stroke
				(width 0.1524)
				(type default)
			)
			(layer "F.SilkS")
		)
		(fp_line
			(start -1.9558 1.6002)
			(end -1.9558 -1.6002)
			(stroke
				(width 0.1524)
				(type default)
			)
			(layer "F.SilkS")
		)
		(fp_line
			(start -1.9558 -1.6002)
			(end 1.9558 -1.6002)
			(stroke
				(width 0.1524)
				(type default)
			)
			(layer "F.SilkS")
		)
		(fp_poly
			(pts
				(xy -2.62255 0.354076) (xy -3.71475 -0.230124) (xy -3.71475 0.836676)
			)
			(stroke
				(width 0)
				(type default)
			)
			(fill yes)
			(layer "F.SilkS")
		)
		(fp_poly
			(pts
				(xy -0.3302 1.299972) (xy 0.3302 1.299972) (xy 0.3302 1.524) (xy 1.8796 1.524) (xy 1.8796 0.1778)
				(xy 1.649984 0.1778) (xy 1.649984 -0.1778) (xy 1.8796 -0.1778) (xy 1.8796 -1.524) (xy 0.3302 -1.524)
				(xy 0.3302 -1.299972) (xy -0.3302 -1.299972) (xy -0.3302 -1.524) (xy -1.8796 -1.524) (xy -1.8796 -0.1778)
				(xy -1.649984 -0.1778) (xy -1.649984 0.1778) (xy -1.8796 0.1778) (xy -1.8796 1.524) (xy -0.3302 1.524)
			)
			(stroke
				(width 0)
				(type default)
			)
			(fill no)
			(layer "F.CrtYd")
		)
		(fp_line
			(start 1.649984 1.299972)
			(end -1.649984 1.299972)
			(stroke
				(width 0.1)
				(type default)
			)
			(layer "F.Fab")
		)
		(fp_line
			(start 1.649984 -1.299972)
			(end 1.649984 1.299972)
			(stroke
				(width 0.1)
				(type default)
			)
			(layer "F.Fab")
		)
		(fp_line
			(start -1.649984 1.299972)
			(end -1.649984 -1.299972)
			(stroke
				(width 0.1)
				(type default)
			)
			(layer "F.Fab")
		)
		(fp_line
			(start -1.649984 -1.299972)
			(end 1.649984 -1.299972)
			(stroke
				(width 0.1)
				(type default)
			)
			(layer "F.Fab")
		)
		(fp_text user "3"
			(at 2.535174 -1.0033 0)
			(unlocked yes)
			(layer "F.SilkS")
			(effects
				(font
					(size 0.635 0.4064)
					(thickness 0.1524)
				)
				(justify left)
			)
		)
		(fp_text user "2"
			(at 2.4892 1.520952 0)
			(unlocked yes)
			(layer "F.SilkS")
			(effects
				(font
					(size 0.635 0.4064)
					(thickness 0.1524)
				)
				(justify left)
			)
		)
		(fp_text user "1"
			(at -2.028698 0.351028 0)
			(unlocked yes)
			(layer "F.SilkS")
			(effects
				(font
					(size 0.635 0.4064)
					(thickness 0.1524)
				)
				(justify left)
			)
		)
		(fp_text user "4"
			(at -2.227834 -1.448562 0)
			(unlocked yes)
			(layer "F.SilkS")
			(effects
				(font
					(size 0.635 0.4064)
					(thickness 0.1524)
				)
				(justify left)
			)
		)
		(pad "1" smd rect
			(at -1.100074 0.849884 270)
			(size 1.2192 1.4224)
			(layers "F.Cu" "F.Mask" "F.Paste")
			(net "XTAL_CLK_NODE1_X1")
		)
		(pad "2" smd rect
			(at 1.100074 0.849884 270)
			(size 1.2192 1.4224)
			(layers "F.Cu" "F.Mask" "F.Paste")
			(net "GND")
		)
		(pad "3" smd rect
			(at 1.100074 -0.849884 270)
			(size 1.2192 1.4224)
			(layers "F.Cu" "F.Mask" "F.Paste")
			(net "XTAL_CLK_NODE1_X2")
		)
		(pad "4" smd rect
			(at -1.100074 -0.849884 270)
			(size 1.2192 1.4224)
			(layers "F.Cu" "F.Mask" "F.Paste")
			(net "GND")
		)
	)
	(footprint ""
		(layer "F.Cu")
		(at 80.906874 -120.807226 180)
		(property "Reference" "C1120"
			(at 2.799334 -1.362964 0)
			(unlocked yes)
			(layer "F.SilkS")
			(effects
				(font
					(size 0.7874 0.5842)
					(thickness 0.1524)
				)
				(justify left)
			)
		)
		(property "Value" ""
			(at 0 0 180)
			(layer "F.Fab")
			(effects
				(font
					(size 1.27 1.27)
				)
			)
		)
		(duplicate_pad_numbers_are_jumpers no)
		(fp_line
			(start 0.7874 0.4064)
			(end -0.7874 0.4064)
			(stroke
				(width 0.1524)
				(type default)
			)
			(layer "F.SilkS")
		)
		(fp_line
			(start 0.7874 -0.4064)
			(end 0.7874 0.4064)
			(stroke
				(width 0.1524)
				(type default)
			)
			(layer "F.SilkS")
		)
		(fp_line
			(start 0 0.381)
			(end 0 -0.381)
			(stroke
				(width 0.1524)
				(type default)
			)
			(layer "F.SilkS")
		)
		(fp_line
			(start -0.7874 0.4064)
			(end -0.7874 -0.4064)
			(stroke
				(width 0.1524)
				(type default)
			)
			(layer "F.SilkS")
		)
		(fp_line
			(start -0.7874 -0.4064)
			(end 0.7874 -0.4064)
			(stroke
				(width 0.1524)
				(type default)
			)
			(layer "F.SilkS")
		)
		(fp_poly
			(pts
				(xy -0.5334 0.254) (xy -0.635 0.254) (xy -0.635 0.2286) (xy -0.635 -0.254) (xy -0.5334 -0.254) (xy -0.5334 -0.2794)
				(xy 0.5334 -0.2794) (xy 0.5334 -0.254) (xy 0.635 -0.254) (xy 0.635 0.254) (xy 0.5334 0.254) (xy 0.5334 0.2794)
				(xy -0.508 0.2794) (xy -0.5334 0.2794)
			)
			(stroke
				(width 0)
				(type default)
			)
			(fill no)
			(layer "F.CrtYd")
		)
		(pad "1" smd rect
			(at 0.40005 0 180)
			(size 0.4572 0.508)
			(layers "F.Cu" "F.Mask" "F.Paste")
			(net "GND")
		)
		(pad "2" smd rect
			(at -0.40005 0 180)
			(size 0.4572 0.508)
			(layers "F.Cu" "F.Mask" "F.Paste")
			(net "P3V3_NODE1")
		)
	)
	(footprint ""
		(layer "F.Cu")
		(at 106.170476 -166.848282 180)
		(property "Reference" "R767"
			(at -85.224366 -69.788278 0)
			(unlocked yes)
			(layer "F.SilkS")
			(effects
				(font
					(size 0.7874 0.5842)
					(thickness 0.1524)
				)
				(justify left)
			)
		)
		(property "Value" ""
			(at 0 0 180)
			(layer "F.Fab")
			(effects
				(font
					(size 1.27 1.27)
				)
			)
		)
		(duplicate_pad_numbers_are_jumpers no)
		(fp_line
			(start 0.7874 0.4064)
			(end -0.7874 0.4064)
			(stroke
				(width 0.1524)
				(type default)
			)
			(layer "F.SilkS")
		)
		(fp_line
			(start 0.7874 -0.4064)
			(end 0.7874 0.4064)
			(stroke
				(width 0.1524)
				(type default)
			)
			(layer "F.SilkS")
		)
		(fp_line
			(start -0.7874 0.4064)
			(end -0.7874 -0.4064)
			(stroke
				(width 0.1524)
				(type default)
			)
			(layer "F.SilkS")
		)
		(fp_line
			(start -0.7874 -0.4064)
			(end 0.7874 -0.4064)
			(stroke
				(width 0.1524)
				(type default)
			)
			(layer "F.SilkS")
		)
		(fp_poly
			(pts
				(xy -0.508 0.2794) (xy -0.508 0.2286) (xy -0.635 0.2286) (xy -0.635 -0.254) (xy -0.5334 -0.254)
				(xy -0.5334 -0.2794) (xy 0.5334 -0.2794) (xy 0.5334 -0.254) (xy 0.635 -0.254) (xy 0.635 0.254) (xy 0.5334 0.254)
				(xy 0.5334 0.2794)
			)
			(stroke
				(width 0)
				(type default)
			)
			(fill no)
			(layer "F.CrtYd")
		)
		(pad "1" smd rect
			(at 0.40005 0 180)
			(size 0.4572 0.508)
			(layers "F.Cu" "F.Mask" "F.Paste")
			(net "I2C_ALERT_FNACTRL2_N")
		)
		(pad "2" smd rect
			(at -0.40005 0 180)
			(size 0.4572 0.508)
			(layers "F.Cu" "F.Mask" "F.Paste")
			(net "P3V3_NODE1")
		)
	)
	(footprint ""
		(layer "F.Cu")
		(at 114.83721 -48.321976 -90)
		(property "Reference" "C484"
			(at 0.583946 1.016254 90)
			(unlocked yes)
			(layer "F.SilkS")
			(effects
				(font
					(size 0.7874 0.5842)
					(thickness 0.1524)
				)
				(justify left)
			)
		)
		(property "Value" ""
			(at 0 0 270)
			(layer "F.Fab")
			(effects
				(font
					(size 1.27 1.27)
				)
			)
		)
		(duplicate_pad_numbers_are_jumpers no)
		(fp_line
			(start -0.7874 0.4064)
			(end -0.7874 -0.4064)
			(stroke
				(width 0.1524)
				(type default)
			)
			(layer "F.SilkS")
		)
		(fp_line
			(start 0.7874 0.4064)
			(end -0.7874 0.4064)
			(stroke
				(width 0.1524)
				(type default)
			)
			(layer "F.SilkS")
		)
		(fp_line
			(start 0 0.381)
			(end 0 -0.381)
			(stroke
				(width 0.1524)
				(type default)
			)
			(layer "F.SilkS")
		)
		(fp_line
			(start -0.7874 -0.4064)
			(end 0.7874 -0.4064)
			(stroke
				(width 0.1524)
				(type default)
			)
			(layer "F.SilkS")
		)
		(fp_line
			(start 0.7874 -0.4064)
			(end 0.7874 0.4064)
			(stroke
				(width 0.1524)
				(type default)
			)
			(layer "F.SilkS")
		)
		(fp_poly
			(pts
				(xy -0.5334 0.254) (xy -0.635 0.254) (xy -0.635 0.2286) (xy -0.635 -0.254) (xy -0.5334 -0.254) (xy -0.5334 -0.2794)
				(xy 0.5334 -0.2794) (xy 0.5334 -0.254) (xy 0.635 -0.254) (xy 0.635 0.254) (xy 0.5334 0.254) (xy 0.5334 0.2794)
				(xy -0.508 0.2794) (xy -0.5334 0.2794)
			)
			(stroke
				(width 0)
				(type default)
			)
			(fill no)
			(layer "F.CrtYd")
		)
		(pad "1" smd rect
			(at 0.40005 0 270)
			(size 0.4572 0.508)
			(layers "F.Cu" "F.Mask" "F.Paste")
			(net "P3V3_NODE1")
		)
		(pad "2" smd rect
			(at -0.40005 0 270)
			(size 0.4572 0.508)
			(layers "F.Cu" "F.Mask" "F.Paste")
			(net "GND")
		)
	)
	(footprint ""
		(layer "F.Cu")
		(at 44.36618 -112.963706)
		(property "Reference" "PC14"
			(at 0.63246 -1.265936 90)
			(unlocked yes)
			(layer "F.SilkS")
			(effects
				(font
					(size 0.7874 0.5842)
					(thickness 0.1524)
				)
				(justify left)
			)
		)
		(property "Value" ""
			(at 0 0 0)
			(layer "F.Fab")
			(effects
				(font
					(size 1.27 1.27)
				)
			)
		)
		(duplicate_pad_numbers_are_jumpers no)
		(fp_line
			(start -0.7874 -0.4064)
			(end 0.7874 -0.4064)
			(stroke
				(width 0.1524)
				(type default)
			)
			(layer "F.SilkS")
		)
		(fp_line
			(start -0.7874 0.4064)
			(end -0.7874 -0.4064)
			(stroke
				(width 0.1524)
				(type default)
			)
			(layer "F.SilkS")
		)
		(fp_line
			(start 0 0.381)
			(end 0 -0.381)
			(stroke
				(width 0.1524)
				(type default)
			)
			(layer "F.SilkS")
		)
		(fp_line
			(start 0.7874 -0.4064)
			(end 0.7874 0.4064)
			(stroke
				(width 0.1524)
				(type default)
			)
			(layer "F.SilkS")
		)
		(fp_line
			(start 0.7874 0.4064)
			(end -0.7874 0.4064)
			(stroke
				(width 0.1524)
				(type default)
			)
			(layer "F.SilkS")
		)
		(fp_poly
			(pts
				(xy -0.5334 0.254) (xy -0.635 0.254) (xy -0.635 0.2286) (xy -0.635 -0.254) (xy -0.5334 -0.254) (xy -0.5334 -0.2794)
				(xy 0.5334 -0.2794) (xy 0.5334 -0.254) (xy 0.635 -0.254) (xy 0.635 0.254) (xy 0.5334 0.254) (xy 0.5334 0.2794)
				(xy -0.508 0.2794) (xy -0.5334 0.2794)
			)
			(stroke
				(width 0)
				(type default)
			)
			(fill no)
			(layer "F.CrtYd")
		)
		(pad "1" smd rect
			(at 0.40005 0)
			(size 0.4572 0.508)
			(layers "F.Cu" "F.Mask" "F.Paste")
			(net "P5V_STB_NODE1")
		)
		(pad "2" smd rect
			(at -0.40005 0)
			(size 0.4572 0.508)
			(layers "F.Cu" "F.Mask" "F.Paste")
			(net "GND")
		)
	)
	(footprint ""
		(layer "F.Cu")
		(at 190.627 -125.095 180)
		(property "Reference" "R1270"
			(at -1.27 0.10033 0)
			(unlocked yes)
			(layer "F.SilkS")
			(effects
				(font
					(size 0.7874 0.5842)
					(thickness 0.1524)
				)
				(justify left)
			)
		)
		(property "Value" ""
			(at 0 0 180)
			(layer "F.Fab")
			(effects
				(font
					(size 1.27 1.27)
				)
			)
		)
		(duplicate_pad_numbers_are_jumpers no)
		(fp_line
			(start 0.7874 0.4064)
			(end -0.7874 0.4064)
			(stroke
				(width 0.1524)
				(type default)
			)
			(layer "F.SilkS")
		)
		(fp_line
			(start 0.7874 -0.4064)
			(end 0.7874 0.4064)
			(stroke
				(width 0.1524)
				(type default)
			)
			(layer "F.SilkS")
		)
		(fp_line
			(start -0.7874 0.4064)
			(end -0.7874 -0.4064)
			(stroke
				(width 0.1524)
				(type default)
			)
			(layer "F.SilkS")
		)
		(fp_line
			(start -0.7874 -0.4064)
			(end 0.7874 -0.4064)
			(stroke
				(width 0.1524)
				(type default)
			)
			(layer "F.SilkS")
		)
		(fp_poly
			(pts
				(xy -0.508 0.2794) (xy -0.508 0.2286) (xy -0.635 0.2286) (xy -0.635 -0.254) (xy -0.5334 -0.254)
				(xy -0.5334 -0.2794) (xy 0.5334 -0.2794) (xy 0.5334 -0.254) (xy 0.635 -0.254) (xy 0.635 0.254) (xy 0.5334 0.254)
				(xy 0.5334 0.2794)
			)
			(stroke
				(width 0)
				(type default)
			)
			(fill no)
			(layer "F.CrtYd")
		)
		(pad "1" smd rect
			(at 0.40005 0 180)
			(size 0.4572 0.508)
			(layers "F.Cu" "F.Mask" "F.Paste")
			(net "SIO_JTAG_CPLD1_TCK")
		)
		(pad "2" smd rect
			(at -0.40005 0 180)
			(size 0.4572 0.508)
			(layers "F.Cu" "F.Mask" "F.Paste")
			(net "GND")
		)
	)
	(footprint ""
		(layer "F.Cu")
		(at 68.223384 -113.521744 180)
		(property "Reference" "C847"
			(at 0.308864 1.195324 0)
			(unlocked yes)
			(layer "F.SilkS")
			(effects
				(font
					(size 0.7874 0.5842)
					(thickness 0.1524)
				)
			)
		)
		(property "Value" ""
			(at 0 0 180)
			(layer "F.Fab")
			(effects
				(font
					(size 1.27 1.27)
				)
			)
		)
		(duplicate_pad_numbers_are_jumpers no)
		(fp_line
			(start 1.2954 0.5842)
			(end -1.2954 0.5842)
			(stroke
				(width 0.1524)
				(type default)
			)
			(layer "F.SilkS")
		)
		(fp_line
			(start 1.2954 -0.5842)
			(end 1.2954 0.5842)
			(stroke
				(width 0.1524)
				(type default)
			)
			(layer "F.SilkS")
		)
		(fp_line
			(start 0 -0.5842)
			(end 0 0.5842)
			(stroke
				(width 0.1524)
				(type default)
			)
			(layer "F.SilkS")
		)
		(fp_line
			(start -1.2954 0.5842)
			(end -1.2954 -0.5842)
			(stroke
				(width 0.1524)
				(type default)
			)
			(layer "F.SilkS")
		)
		(fp_line
			(start -1.2954 -0.5842)
			(end 1.2954 -0.5842)
			(stroke
				(width 0.1524)
				(type default)
			)
			(layer "F.SilkS")
		)
		(fp_poly
			(pts
				(xy 0.8636 -0.4572) (xy 0.8636 -0.3556) (xy 1.143 -0.3556) (xy 1.143 0.3556) (xy 0.8636 0.3556)
				(xy 0.8636 0.4572) (xy -0.8636 0.4572) (xy -0.8636 0.3556) (xy -1.143 0.3556) (xy -1.143 -0.3556)
				(xy -0.8636 -0.3556) (xy -0.8636 -0.4572)
			)
			(stroke
				(width 0)
				(type default)
			)
			(fill no)
			(layer "F.CrtYd")
		)
		(fp_line
			(start 0.884936 0.504952)
			(end -0.884936 0.504952)
			(stroke
				(width 0.1)
				(type default)
			)
			(layer "F.Fab")
		)
		(fp_line
			(start 0.884936 -0.504952)
			(end 0.884936 0.504952)
			(stroke
				(width 0.1)
				(type default)
			)
			(layer "F.Fab")
		)
		(fp_line
			(start -0.884936 0.504952)
			(end -0.884936 -0.504952)
			(stroke
				(width 0.1)
				(type default)
			)
			(layer "F.Fab")
		)
		(fp_line
			(start -0.884936 -0.504952)
			(end 0.884936 -0.504952)
			(stroke
				(width 0.1)
				(type default)
			)
			(layer "F.Fab")
		)
		(pad "1" smd rect
			(at 0.7366 0 270)
			(size 0.7112 0.8128)
			(layers "F.Cu" "F.Mask" "F.Paste")
			(net "FM_CPLD_NODE1_P1V8_EN_LV")
		)
		(pad "2" smd rect
			(at -0.7366 0 270)
			(size 0.7112 0.8128)
			(layers "F.Cu" "F.Mask" "F.Paste")
			(net "P1V8_NODE1")
		)
	)
	(footprint ""
		(layer "F.Cu")
		(at 93.352874 -162.206178 90)
		(property "Reference" "C886"
			(at -72.56145 87.642446 0)
			(unlocked yes)
			(layer "F.SilkS")
			(effects
				(font
					(size 0.7874 0.5842)
					(thickness 0.1524)
				)
			)
		)
		(property "Value" ""
			(at 0 0 90)
			(layer "F.Fab")
			(effects
				(font
					(size 1.27 1.27)
				)
			)
		)
		(duplicate_pad_numbers_are_jumpers no)
		(fp_line
			(start 1.2954 -0.5842)
			(end 1.2954 0.5842)
			(stroke
				(width 0.1524)
				(type default)
			)
			(layer "F.SilkS")
		)
		(fp_line
			(start 0 -0.5842)
			(end 0 0.5842)
			(stroke
				(width 0.1524)
				(type default)
			)
			(layer "F.SilkS")
		)
		(fp_line
			(start -1.2954 -0.5842)
			(end 1.2954 -0.5842)
			(stroke
				(width 0.1524)
				(type default)
			)
			(layer "F.SilkS")
		)
		(fp_line
			(start 1.2954 0.5842)
			(end -1.2954 0.5842)
			(stroke
				(width 0.1524)
				(type default)
			)
			(layer "F.SilkS")
		)
		(fp_line
			(start -1.2954 0.5842)
			(end -1.2954 -0.5842)
			(stroke
				(width 0.1524)
				(type default)
			)
			(layer "F.SilkS")
		)
		(fp_poly
			(pts
				(xy 0.8636 -0.4572) (xy 0.8636 -0.3556) (xy 1.143 -0.3556) (xy 1.143 0.3556) (xy 0.8636 0.3556)
				(xy 0.8636 0.4572) (xy -0.8636 0.4572) (xy -0.8636 0.3556) (xy -1.143 0.3556) (xy -1.143 -0.3556)
				(xy -0.8636 -0.3556) (xy -0.8636 -0.4572)
			)
			(stroke
				(width 0)
				(type default)
			)
			(fill no)
			(layer "F.CrtYd")
		)
		(fp_line
			(start 0.884936 -0.504952)
			(end 0.884936 0.504952)
			(stroke
				(width 0.1)
				(type default)
			)
			(layer "F.Fab")
		)
		(fp_line
			(start -0.884936 -0.504952)
			(end 0.884936 -0.504952)
			(stroke
				(width 0.1)
				(type default)
			)
			(layer "F.Fab")
		)
		(fp_line
			(start 0.884936 0.504952)
			(end -0.884936 0.504952)
			(stroke
				(width 0.1)
				(type default)
			)
			(layer "F.Fab")
		)
		(fp_line
			(start -0.884936 0.504952)
			(end -0.884936 -0.504952)
			(stroke
				(width 0.1)
				(type default)
			)
			(layer "F.Fab")
		)
		(pad "1" smd rect
			(at 0.7366 0 180)
			(size 0.7112 0.8128)
			(layers "F.Cu" "F.Mask" "F.Paste")
			(net "GND")
		)
		(pad "2" smd rect
			(at -0.7366 0 180)
			(size 0.7112 0.8128)
			(layers "F.Cu" "F.Mask" "F.Paste")
			(net "N52410998")
		)
	)
	(footprint ""
		(layer "F.Cu")
		(at 171.09313 -47.055786)
		(property "Reference" "C535"
			(at -3.938524 1.129538 0)
			(unlocked yes)
			(layer "F.SilkS")
			(effects
				(font
					(size 0.7874 0.5842)
					(thickness 0.1524)
				)
				(justify left)
			)
		)
		(property "Value" ""
			(at 0 0 0)
			(layer "F.Fab")
			(effects
				(font
					(size 1.27 1.27)
				)
			)
		)
		(duplicate_pad_numbers_are_jumpers no)
		(fp_line
			(start -0.7874 -0.4064)
			(end 0.7874 -0.4064)
			(stroke
				(width 0.1524)
				(type default)
			)
			(layer "F.SilkS")
		)
		(fp_line
			(start -0.7874 0.4064)
			(end -0.7874 -0.4064)
			(stroke
				(width 0.1524)
				(type default)
			)
			(layer "F.SilkS")
		)
		(fp_line
			(start 0 0.381)
			(end 0 -0.381)
			(stroke
				(width 0.1524)
				(type default)
			)
			(layer "F.SilkS")
		)
		(fp_line
			(start 0.7874 -0.4064)
			(end 0.7874 0.4064)
			(stroke
				(width 0.1524)
				(type default)
			)
			(layer "F.SilkS")
		)
		(fp_line
			(start 0.7874 0.4064)
			(end -0.7874 0.4064)
			(stroke
				(width 0.1524)
				(type default)
			)
			(layer "F.SilkS")
		)
		(fp_poly
			(pts
				(xy -0.5334 0.254) (xy -0.635 0.254) (xy -0.635 0.2286) (xy -0.635 -0.254) (xy -0.5334 -0.254) (xy -0.5334 -0.2794)
				(xy 0.5334 -0.2794) (xy 0.5334 -0.254) (xy 0.635 -0.254) (xy 0.635 0.254) (xy 0.5334 0.254) (xy 0.5334 0.2794)
				(xy -0.508 0.2794) (xy -0.5334 0.2794)
			)
			(stroke
				(width 0)
				(type default)
			)
			(fill no)
			(layer "F.CrtYd")
		)
		(pad "1" smd rect
			(at 0.40005 0)
			(size 0.4572 0.508)
			(layers "F.Cu" "F.Mask" "F.Paste")
			(net "P5V_NODE1")
		)
		(pad "2" smd rect
			(at -0.40005 0)
			(size 0.4572 0.508)
			(layers "F.Cu" "F.Mask" "F.Paste")
			(net "GND")
		)
	)
	(footprint ""
		(layer "F.Cu")
		(at 169.649394 -37.954712)
		(property "Reference" "R264"
			(at -1.495806 2.202942 0)
			(unlocked yes)
			(layer "F.SilkS")
			(effects
				(font
					(size 0.7874 0.5842)
					(thickness 0.1524)
				)
				(justify left)
			)
		)
		(property "Value" ""
			(at 0 0 0)
			(layer "F.Fab")
			(effects
				(font
					(size 1.27 1.27)
				)
			)
		)
		(duplicate_pad_numbers_are_jumpers no)
		(fp_line
			(start -0.7874 -0.4064)
			(end 0.7874 -0.4064)
			(stroke
				(width 0.1524)
				(type default)
			)
			(layer "F.SilkS")
		)
		(fp_line
			(start -0.7874 0.4064)
			(end -0.7874 -0.4064)
			(stroke
				(width 0.1524)
				(type default)
			)
			(layer "F.SilkS")
		)
		(fp_line
			(start 0.7874 -0.4064)
			(end 0.7874 0.4064)
			(stroke
				(width 0.1524)
				(type default)
			)
			(layer "F.SilkS")
		)
		(fp_line
			(start 0.7874 0.4064)
			(end -0.7874 0.4064)
			(stroke
				(width 0.1524)
				(type default)
			)
			(layer "F.SilkS")
		)
		(fp_poly
			(pts
				(xy -0.508 0.2794) (xy -0.508 0.2286) (xy -0.635 0.2286) (xy -0.635 -0.254) (xy -0.5334 -0.254)
				(xy -0.5334 -0.2794) (xy 0.5334 -0.2794) (xy 0.5334 -0.254) (xy 0.635 -0.254) (xy 0.635 0.254) (xy 0.5334 0.254)
				(xy 0.5334 0.2794)
			)
			(stroke
				(width 0)
				(type default)
			)
			(fill no)
			(layer "F.CrtYd")
		)
		(pad "1" smd rect
			(at 0.40005 0)
			(size 0.4572 0.508)
			(layers "F.Cu" "F.Mask" "F.Paste")
			(net "USB0_L_DP")
		)
		(pad "2" smd rect
			(at -0.40005 0)
			(size 0.4572 0.508)
			(layers "F.Cu" "F.Mask" "F.Paste")
			(net "USB0_DP")
		)
	)
	(footprint ""
		(layer "F.Cu")
		(at 161.83102 -188.08192 90)
		(property "Reference" "R1222"
			(at 1.118616 1.157732 90)
			(unlocked yes)
			(layer "F.SilkS")
			(effects
				(font
					(size 0.7874 0.5842)
					(thickness 0.1524)
				)
				(justify left)
			)
		)
		(property "Value" ""
			(at 0 0 90)
			(layer "F.Fab")
			(effects
				(font
					(size 1.27 1.27)
				)
			)
		)
		(duplicate_pad_numbers_are_jumpers no)
		(fp_line
			(start 0.7874 -0.4064)
			(end 0.7874 0.4064)
			(stroke
				(width 0.1524)
				(type default)
			)
			(layer "F.SilkS")
		)
		(fp_line
			(start -0.7874 -0.4064)
			(end 0.7874 -0.4064)
			(stroke
				(width 0.1524)
				(type default)
			)
			(layer "F.SilkS")
		)
		(fp_line
			(start 0.7874 0.4064)
			(end -0.7874 0.4064)
			(stroke
				(width 0.1524)
				(type default)
			)
			(layer "F.SilkS")
		)
		(fp_line
			(start -0.7874 0.4064)
			(end -0.7874 -0.4064)
			(stroke
				(width 0.1524)
				(type default)
			)
			(layer "F.SilkS")
		)
		(fp_poly
			(pts
				(xy -0.508 0.2794) (xy -0.508 0.2286) (xy -0.635 0.2286) (xy -0.635 -0.254) (xy -0.5334 -0.254)
				(xy -0.5334 -0.2794) (xy 0.5334 -0.2794) (xy 0.5334 -0.254) (xy 0.635 -0.254) (xy 0.635 0.254) (xy 0.5334 0.254)
				(xy 0.5334 0.2794)
			)
			(stroke
				(width 0)
				(type default)
			)
			(fill no)
			(layer "F.CrtYd")
		)
		(pad "1" smd rect
			(at 0.40005 0 90)
			(size 0.4572 0.508)
			(layers "F.Cu" "F.Mask" "F.Paste")
			(net "FAN4_TACH_R")
		)
		(pad "2" smd rect
			(at -0.40005 0 90)
			(size 0.4572 0.508)
			(layers "F.Cu" "F.Mask" "F.Paste")
			(net "GND")
		)
	)
	(footprint ""
		(layer "F.Cu")
		(at 48.717962 -110.52556 90)
		(property "Reference" "PC15"
			(at 2.04216 0.080518 0)
			(unlocked yes)
			(layer "F.SilkS")
			(effects
				(font
					(size 0.7874 0.5842)
					(thickness 0.1524)
				)
				(justify left)
			)
		)
		(property "Value" ""
			(at 0 0 90)
			(layer "F.Fab")
			(effects
				(font
					(size 1.27 1.27)
				)
			)
		)
		(duplicate_pad_numbers_are_jumpers no)
		(fp_line
			(start 0.7874 -0.4064)
			(end 0.7874 0.4064)
			(stroke
				(width 0.1524)
				(type default)
			)
			(layer "F.SilkS")
		)
		(fp_line
			(start -0.7874 -0.4064)
			(end 0.7874 -0.4064)
			(stroke
				(width 0.1524)
				(type default)
			)
			(layer "F.SilkS")
		)
		(fp_line
			(start 0 0.381)
			(end 0 -0.381)
			(stroke
				(width 0.1524)
				(type default)
			)
			(layer "F.SilkS")
		)
		(fp_line
			(start 0.7874 0.4064)
			(end -0.7874 0.4064)
			(stroke
				(width 0.1524)
				(type default)
			)
			(layer "F.SilkS")
		)
		(fp_line
			(start -0.7874 0.4064)
			(end -0.7874 -0.4064)
			(stroke
				(width 0.1524)
				(type default)
			)
			(layer "F.SilkS")
		)
		(fp_poly
			(pts
				(xy -0.5334 0.254) (xy -0.635 0.254) (xy -0.635 0.2286) (xy -0.635 -0.254) (xy -0.5334 -0.254) (xy -0.5334 -0.2794)
				(xy 0.5334 -0.2794) (xy 0.5334 -0.254) (xy 0.635 -0.254) (xy 0.635 0.254) (xy 0.5334 0.254) (xy 0.5334 0.2794)
				(xy -0.508 0.2794) (xy -0.5334 0.2794)
			)
			(stroke
				(width 0)
				(type default)
			)
			(fill no)
			(layer "F.CrtYd")
		)
		(pad "1" smd rect
			(at 0.40005 0 90)
			(size 0.4572 0.508)
			(layers "F.Cu" "F.Mask" "F.Paste")
			(net "SW_P3V3_STB_NODE1_BT")
		)
		(pad "2" smd rect
			(at -0.40005 0 90)
			(size 0.4572 0.508)
			(layers "F.Cu" "F.Mask" "F.Paste")
			(net "SW_P3V3_STB_NODE1_PH")
		)
	)
	(footprint ""
		(layer "F.Cu")
		(at 8.75157 -83.828128 -90)
		(property "Reference" "J19"
			(at -5.454396 -2.26695 0)
			(unlocked yes)
			(layer "F.SilkS")
			(effects
				(font
					(size 0.7874 0.5842)
					(thickness 0.1524)
				)
				(justify left)
			)
		)
		(property "Value" ""
			(at 0 0 270)
			(layer "F.Fab")
			(effects
				(font
					(size 1.27 1.27)
				)
			)
		)
		(duplicate_pad_numbers_are_jumpers no)
		(fp_line
			(start -1.700022 5.999988)
			(end 1.700022 5.999988)
			(stroke
				(width 0.1524)
				(type default)
			)
			(layer "F.SilkS")
		)
		(fp_line
			(start -1.700022 5.999988)
			(end -1.700022 4.59994)
			(stroke
				(width 0.1524)
				(type default)
			)
			(layer "F.SilkS")
		)
		(fp_line
			(start 1.700022 5.999988)
			(end 1.700022 4.59994)
			(stroke
				(width 0.1524)
				(type default)
			)
			(layer "F.SilkS")
		)
		(fp_line
			(start -4.800092 4.59994)
			(end -4.800092 -4.99999)
			(stroke
				(width 0.1524)
				(type default)
			)
			(layer "F.SilkS")
		)
		(fp_line
			(start 4.800092 4.59994)
			(end -4.800092 4.59994)
			(stroke
				(width 0.1524)
				(type default)
			)
			(layer "F.SilkS")
		)
		(fp_line
			(start -8.6614 4.1402)
			(end -4.8006 4.1402)
			(stroke
				(width 0.1524)
				(type default)
			)
			(layer "F.SilkS")
		)
		(fp_line
			(start -4.8006 4.1402)
			(end -4.8006 3.937)
			(stroke
				(width 0.1524)
				(type default)
			)
			(layer "F.SilkS")
		)
		(fp_line
			(start 4.8006 4.1402)
			(end 4.8006 4.1148)
			(stroke
				(width 0.1524)
				(type default)
			)
			(layer "F.SilkS")
		)
		(fp_line
			(start 8.6614 4.1402)
			(end 4.8006 4.1402)
			(stroke
				(width 0.1524)
				(type default)
			)
			(layer "F.SilkS")
		)
		(fp_line
			(start -8.6614 0.4318)
			(end -8.6614 4.1402)
			(stroke
				(width 0.1524)
				(type default)
			)
			(layer "F.SilkS")
		)
		(fp_line
			(start -4.8514 0.4318)
			(end -8.6614 0.4318)
			(stroke
				(width 0.1524)
				(type default)
			)
			(layer "F.SilkS")
		)
		(fp_line
			(start 4.8514 0.4318)
			(end 8.6868 0.4318)
			(stroke
				(width 0.1524)
				(type default)
			)
			(layer "F.SilkS")
		)
		(fp_line
			(start 8.6868 0.4318)
			(end 8.6614 4.1402)
			(stroke
				(width 0.1524)
				(type default)
			)
			(layer "F.SilkS")
		)
		(fp_line
			(start -4.800092 -4.99999)
			(end 4.800092 -4.99999)
			(stroke
				(width 0.1524)
				(type default)
			)
			(layer "F.SilkS")
		)
		(fp_line
			(start 4.800092 -4.99999)
			(end 4.800092 4.59994)
			(stroke
				(width 0.1524)
				(type default)
			)
			(layer "F.SilkS")
		)
		(fp_poly
			(pts
				(xy -1.7272 -5.2324) (xy -1.9558 -5.9944) (xy -1.4478 -5.9944)
			)
			(stroke
				(width 0)
				(type default)
			)
			(fill yes)
			(layer "F.SilkS")
		)
		(fp_poly
			(pts
				(xy 3.1242 1.7272) (xy -3.1242 1.7272) (xy -3.1242 3.7846) (xy 3.1242 3.7846)
			)
			(stroke
				(width 0)
				(type default)
			)
			(fill no)
			(layer "B.CrtYd")
		)
		(fp_poly
			(pts
				(xy -3.1242 -3.7846) (xy 3.1242 -3.7846) (xy 3.1242 -1.7272) (xy -3.1242 -1.7272)
			)
			(stroke
				(width 0)
				(type default)
			)
			(fill no)
			(layer "B.CrtYd")
		)
		(fp_poly
			(pts
				(arc
					(start 8.324088 2.290064)
					(mid 6.800088 0.766064)
					(end 5.276088 2.290064)
				)
				(arc
					(start 5.276088 2.315464)
					(mid 5.715018 3.375134)
					(end 6.774688 3.814064)
				)
				(arc
					(start 6.825488 3.814064)
					(mid 7.885158 3.375134)
					(end 8.324088 2.315464)
				)
			)
			(stroke
				(width 0)
				(type default)
			)
			(fill no)
			(layer "B.CrtYd")
		)
		(fp_poly
			(pts
				(arc
					(start -5.2832 2.286)
					(mid -6.8072 0.762)
					(end -8.3312 2.286)
				)
				(arc
					(start -8.3312 2.3114)
					(mid -7.89227 3.37107)
					(end -6.8326 3.81)
				)
				(arc
					(start -6.7818 3.81)
					(mid -5.72213 3.37107)
					(end -5.2832 2.3114)
				)
			)
			(stroke
				(width 0)
				(type default)
			)
			(fill no)
			(layer "B.CrtYd")
		)
		(fp_poly
			(pts
				(xy -1.7018 5.9944) (xy -1.7018 4.5974) (xy -4.8006 4.5974) (xy -4.8006 4.1402) (xy -8.255 4.1402)
				(xy -8.6614 4.1402) (xy -8.6614 0.4318) (xy -8.255 0.4318) (xy -4.826 0.4318) (xy -4.826 0.254)
				(xy -4.826 -5.0038) (xy 4.826 -5.0038) (xy 4.826 0.254) (xy 4.826 0.4318) (xy 8.255 0.4318) (xy 8.6614 0.4318)
				(xy 8.6614 4.1402) (xy 8.255 4.1402) (xy 4.8006 4.1402) (xy 4.8006 4.5974) (xy 1.7018 4.5974) (xy 1.7018 5.9944)
			)
			(stroke
				(width 0)
				(type default)
			)
			(fill no)
			(layer "F.CrtYd")
		)
		(fp_text user "3"
			(at -2.27203 5.596382 0)
			(unlocked yes)
			(layer "F.SilkS")
			(effects
				(font
					(size 0.7874 0.5842)
					(thickness 0.1524)
				)
				(justify left)
			)
		)
		(fp_text user "4"
			(at 2.614676 5.559298 0)
			(unlocked yes)
			(layer "F.SilkS")
			(effects
				(font
					(size 0.7874 0.5842)
					(thickness 0.1524)
				)
				(justify left)
			)
		)
		(fp_text user "1"
			(at -2.91211 -5.273802 0)
			(unlocked yes)
			(layer "F.SilkS")
			(effects
				(font
					(size 0.7874 0.5842)
					(thickness 0.1524)
				)
				(justify left)
			)
		)
		(fp_text user "2"
			(at 3.11912 -5.41147 0)
			(unlocked yes)
			(layer "F.SilkS")
			(effects
				(font
					(size 0.7874 0.5842)
					(thickness 0.1524)
				)
				(justify left)
			)
		)
		(fp_text user "4"
			(at 2.137156 4.300982 0)
			(unlocked yes)
			(layer "B.SilkS")
			(effects
				(font
					(size 0.7874 0.5842)
					(thickness 0.1524)
				)
				(justify left mirror)
			)
		)
		(fp_text user "3"
			(at -2.16662 4.113784 0)
			(unlocked yes)
			(layer "B.SilkS")
			(effects
				(font
					(size 0.7874 0.5842)
					(thickness 0.1524)
				)
				(justify left mirror)
			)
		)
		(fp_text user "1"
			(at -2.096516 -4.704334 0)
			(unlocked yes)
			(layer "B.SilkS")
			(effects
				(font
					(size 0.7874 0.5842)
					(thickness 0.1524)
				)
				(justify left mirror)
			)
		)
		(fp_text user "2"
			(at 2.183892 -4.844796 0)
			(unlocked yes)
			(layer "B.SilkS")
			(effects
				(font
					(size 0.7874 0.5842)
					(thickness 0.1524)
				)
				(justify left mirror)
			)
		)
		(pad "" np_thru_hole circle
			(at -6.800088 2.290064 270)
			(size 3.048 3.048)
			(drill 3.048)
			(layers "*.Cu" "*.Mask")
			(clearance 0.381)
			(thermal_gap 0.381)
		)
		(pad "" np_thru_hole circle
			(at 6.800088 2.290064 270)
			(size 3.048 3.048)
			(drill 3.048)
			(layers "*.Cu" "*.Mask")
			(clearance 0.381)
			(thermal_gap 0.381)
		)
		(pad "1" thru_hole rect
			(at -2.100072 -2.750058 270)
			(size 1.9558 1.9558)
			(drill 1.4478)
			(layers "*.Cu" "*.Mask")
			(remove_unused_layers no)
			(net "GND")
			(clearance 0)
			(padstack
				(mode front_inner_back)
				(layer "Inner"
					(shape circle)
					(size 1.9558 1.9558)
					(clearance 0)
				)
				(layer "B.Cu"
					(shape rect)
					(size 1.9558 1.9558)
					(clearance 0)
				)
			)
		)
		(pad "2" thru_hole circle
			(at 2.100072 -2.750058 270)
			(size 1.9558 1.9558)
			(drill 1.4478)
			(layers "*.Cu" "*.Mask")
			(remove_unused_layers no)
			(net "GND")
			(clearance 0)
		)
		(pad "3" thru_hole circle
			(at -2.100072 2.750058 270)
			(size 1.9558 1.9558)
			(drill 1.4478)
			(layers "*.Cu" "*.Mask")
			(remove_unused_layers no)
			(net "P12V_DBG")
			(clearance 0)
		)
		(pad "4" thru_hole circle
			(at 2.100072 2.750058 270)
			(size 1.9558 1.9558)
			(drill 1.4478)
			(layers "*.Cu" "*.Mask")
			(remove_unused_layers no)
			(net "P12V_DBG")
			(clearance 0)
		)
		(zone
			(layers "F.Cu" "B.Cu" "In1.Cu" "In2.Cu" "In3.Cu" "In4.Cu" "In5.Cu" "In6.Cu"
				"In7.Cu" "In8.Cu"
			)
			(hatch none 0.5)
			(connect_pads
				(clearance 0)
			)
			(min_thickness 0.25)
			(keepout
				(tracks not_allowed)
				(vias allowed)
				(pads allowed)
				(copperpour not_allowed)
				(footprints allowed)
			)
			(placement
				(enabled no)
				(sheetname "")
			)
			(fill
				(thermal_gap 0.5)
				(thermal_bridge_width 0.5)
				(island_removal_mode 0)
			)
			(polygon
				(pts
					(arc
						(start 4.53517 -90.635328)
						(mid 8.39597 -90.635328)
						(end 4.53517 -90.635328)
					)
				)
			)
		)
		(zone
			(layers "F.Cu" "B.Cu" "In1.Cu" "In2.Cu" "In3.Cu" "In4.Cu" "In5.Cu" "In6.Cu"
				"In7.Cu" "In8.Cu"
			)
			(hatch none 0.5)
			(connect_pads
				(clearance 0)
			)
			(min_thickness 0.25)
			(keepout
				(tracks not_allowed)
				(vias allowed)
				(pads allowed)
				(copperpour not_allowed)
				(footprints allowed)
			)
			(placement
				(enabled no)
				(sheetname "")
			)
			(fill
				(thermal_gap 0.5)
				(thermal_bridge_width 0.5)
				(island_removal_mode 0)
			)
			(polygon
				(pts
					(arc
						(start 4.53517 -77.020928)
						(mid 8.39597 -77.020928)
						(end 4.53517 -77.020928)
					)
				)
			)
		)
	)
	(footprint ""
		(layer "F.Cu")
		(at 167.243252 -100.93579)
		(property "Reference" "U32"
			(at 0.1143 -6.103366 0)
			(unlocked yes)
			(layer "F.SilkS")
			(effects
				(font
					(size 0.7874 0.5842)
					(thickness 0.1524)
				)
				(justify left)
			)
		)
		(property "Value" ""
			(at 0 0 0)
			(layer "F.Fab")
			(effects
				(font
					(size 1.27 1.27)
				)
			)
		)
		(duplicate_pad_numbers_are_jumpers no)
		(fp_line
			(start -5.5753 0.4064)
			(end -4.6863 0.4064)
			(stroke
				(width 0.1524)
				(type default)
			)
			(layer "F.SilkS")
		)
		(fp_line
			(start -5.207 -1.6002)
			(end -4.699 -1.6002)
			(stroke
				(width 0.1524)
				(type default)
			)
			(layer "F.SilkS")
		)
		(fp_line
			(start -5.207 2.413)
			(end -4.699 2.413)
			(stroke
				(width 0.1524)
				(type default)
			)
			(layer "F.SilkS")
		)
		(fp_line
			(start -3.999992 -3.999992)
			(end -3.999992 -3.415792)
			(stroke
				(width 0.1524)
				(type default)
			)
			(layer "F.SilkS")
		)
		(fp_line
			(start -3.999992 3.415792)
			(end -3.999992 3.999992)
			(stroke
				(width 0.1524)
				(type default)
			)
			(layer "F.SilkS")
		)
		(fp_line
			(start -3.999992 3.999992)
			(end -3.415792 3.999992)
			(stroke
				(width 0.1524)
				(type default)
			)
			(layer "F.SilkS")
		)
		(fp_line
			(start -3.415792 -3.999992)
			(end -3.999992 -3.999992)
			(stroke
				(width 0.1524)
				(type default)
			)
			(layer "F.SilkS")
		)
		(fp_line
			(start -2.413 5.5753)
			(end -2.413 4.6863)
			(stroke
				(width 0.1524)
				(type default)
			)
			(layer "F.SilkS")
		)
		(fp_line
			(start -2.0066 -4.699)
			(end -2.0066 -5.207)
			(stroke
				(width 0.1524)
				(type default)
			)
			(layer "F.SilkS")
		)
		(fp_line
			(start -0.4064 5.207)
			(end -0.4064 4.699)
			(stroke
				(width 0.1524)
				(type default)
			)
			(layer "F.SilkS")
		)
		(fp_line
			(start -0.0254 -4.6863)
			(end -0.0254 -5.5753)
			(stroke
				(width 0.1524)
				(type default)
			)
			(layer "F.SilkS")
		)
		(fp_line
			(start 1.6002 5.5753)
			(end 1.6002 4.6863)
			(stroke
				(width 0.1524)
				(type default)
			)
			(layer "F.SilkS")
		)
		(fp_line
			(start 1.9812 -4.6736)
			(end 1.9812 -5.1816)
			(stroke
				(width 0.1524)
				(type default)
			)
			(layer "F.SilkS")
		)
		(fp_line
			(start 3.415792 3.999992)
			(end 3.999992 3.999992)
			(stroke
				(width 0.1524)
				(type default)
			)
			(layer "F.SilkS")
		)
		(fp_line
			(start 3.999992 -3.999992)
			(end 3.415792 -3.999992)
			(stroke
				(width 0.1524)
				(type default)
			)
			(layer "F.SilkS")
		)
		(fp_line
			(start 3.999992 -3.415792)
			(end 3.999992 -3.999992)
			(stroke
				(width 0.1524)
				(type default)
			)
			(layer "F.SilkS")
		)
		(fp_line
			(start 3.999992 3.999992)
			(end 3.999992 3.415792)
			(stroke
				(width 0.1524)
				(type default)
			)
			(layer "F.SilkS")
		)
		(fp_line
			(start 4.6609 1.1938)
			(end 5.5499 1.1938)
			(stroke
				(width 0.1524)
				(type default)
			)
			(layer "F.SilkS")
		)
		(fp_line
			(start 4.6736 -0.7874)
			(end 5.1816 -0.7874)
			(stroke
				(width 0.1524)
				(type default)
			)
			(layer "F.SilkS")
		)
		(fp_line
			(start 4.6736 3.2004)
			(end 5.1816 3.2004)
			(stroke
				(width 0.1524)
				(type default)
			)
			(layer "F.SilkS")
		)
		(fp_line
			(start 4.6863 -2.794)
			(end 5.5753 -2.794)
			(stroke
				(width 0.1524)
				(type default)
			)
			(layer "F.SilkS")
		)
		(fp_poly
			(pts
				(xy -5.3848 -3.580892) (xy -5.3848 -2.818892) (xy -4.6228 -3.199892)
			)
			(stroke
				(width 0)
				(type default)
			)
			(fill yes)
			(layer "F.SilkS")
		)
		(fp_poly
			(pts
				(xy -3.339592 4.550918) (xy -3.339592 3.999992) (xy -3.999992 3.999992) (xy -3.999992 3.339592)
				(xy -4.550918 3.339592) (xy -4.550918 -3.339592) (xy -3.999992 -3.339592) (xy -3.999992 -3.999992)
				(xy -3.339592 -3.999992) (xy -3.339592 -4.550918) (xy 3.339592 -4.550918) (xy 3.339592 -3.999992)
				(xy 3.999992 -3.999992) (xy 3.999992 -3.339592) (xy 4.550918 -3.339592) (xy 4.550918 3.339592) (xy 3.999992 3.339592)
				(xy 3.999992 3.999992) (xy 3.339592 3.999992) (xy 3.339592 4.550918)
			)
			(stroke
				(width 0)
				(type default)
			)
			(fill no)
			(layer "F.CrtYd")
		)
		(fp_line
			(start -5.5753 0.4064)
			(end -4.6863 0.4064)
			(stroke
				(width 0.1)
				(type default)
			)
			(layer "F.Fab")
		)
		(fp_line
			(start -5.207 -1.6002)
			(end -4.699 -1.6002)
			(stroke
				(width 0.1)
				(type default)
			)
			(layer "F.Fab")
		)
		(fp_line
			(start -5.207 2.413)
			(end -4.699 2.413)
			(stroke
				(width 0.1)
				(type default)
			)
			(layer "F.Fab")
		)
		(fp_line
			(start -3.999992 -3.999992)
			(end -3.999992 3.999992)
			(stroke
				(width 0.1)
				(type default)
			)
			(layer "F.Fab")
		)
		(fp_line
			(start -3.999992 3.999992)
			(end 3.999992 3.999992)
			(stroke
				(width 0.1)
				(type default)
			)
			(layer "F.Fab")
		)
		(fp_line
			(start -2.413 5.5753)
			(end -2.413 4.6863)
			(stroke
				(width 0.1)
				(type default)
			)
			(layer "F.Fab")
		)
		(fp_line
			(start -2.0066 -4.699)
			(end -2.0066 -5.207)
			(stroke
				(width 0.1)
				(type default)
			)
			(layer "F.Fab")
		)
		(fp_line
			(start -0.4064 5.207)
			(end -0.4064 4.699)
			(stroke
				(width 0.1)
				(type default)
			)
			(layer "F.Fab")
		)
		(fp_line
			(start -0.0254 -4.6863)
			(end -0.0254 -5.5753)
			(stroke
				(width 0.1)
				(type default)
			)
			(layer "F.Fab")
		)
		(fp_line
			(start 1.6002 5.5753)
			(end 1.6002 4.6863)
			(stroke
				(width 0.1)
				(type default)
			)
			(layer "F.Fab")
		)
		(fp_line
			(start 1.9812 -4.6736)
			(end 1.9812 -5.1816)
			(stroke
				(width 0.1)
				(type default)
			)
			(layer "F.Fab")
		)
		(fp_line
			(start 3.999992 -3.999992)
			(end -3.999992 -3.999992)
			(stroke
				(width 0.1)
				(type default)
			)
			(layer "F.Fab")
		)
		(fp_line
			(start 3.999992 3.999992)
			(end 3.999992 -3.999992)
			(stroke
				(width 0.1)
				(type default)
			)
			(layer "F.Fab")
		)
		(fp_line
			(start 4.6609 1.1938)
			(end 5.5499 1.1938)
			(stroke
				(width 0.1)
				(type default)
			)
			(layer "F.Fab")
		)
		(fp_line
			(start 4.6736 -0.7874)
			(end 5.1816 -0.7874)
			(stroke
				(width 0.1)
				(type default)
			)
			(layer "F.Fab")
		)
		(fp_line
			(start 4.6736 3.2004)
			(end 5.1816 3.2004)
			(stroke
				(width 0.1)
				(type default)
			)
			(layer "F.Fab")
		)
		(fp_line
			(start 4.6863 -2.794)
			(end 5.5753 -2.794)
			(stroke
				(width 0.1)
				(type default)
			)
			(layer "F.Fab")
		)
		(fp_poly
			(pts
				(xy -5.3848 -3.580892) (xy -5.3848 -2.818892) (xy -4.6228 -3.199892)
			)
			(stroke
				(width 0)
				(type default)
			)
			(fill yes)
			(layer "F.Fab")
		)
		(fp_text user "17"
			(at -5.060696 3.56743 0)
			(unlocked yes)
			(layer "F.SilkS")
			(effects
				(font
					(size 0.635 0.4064)
					(thickness 0.1524)
				)
			)
		)
		(fp_text user "1"
			(at -4.7752 -3.800348 0)
			(unlocked yes)
			(layer "F.SilkS")
			(effects
				(font
					(size 0.635 0.4064)
					(thickness 0.1524)
				)
			)
		)
		(fp_text user "68"
			(at -4.512818 -4.742434 0)
			(unlocked yes)
			(layer "F.SilkS")
			(effects
				(font
					(size 0.635 0.4064)
					(thickness 0.1524)
				)
			)
		)
		(fp_text user "18"
			(at -3.964432 4.58089 0)
			(unlocked yes)
			(layer "F.SilkS")
			(effects
				(font
					(size 0.635 0.4064)
					(thickness 0.1524)
				)
			)
		)
		(fp_text user "34"
			(at 3.604006 5.477002 0)
			(unlocked yes)
			(layer "F.SilkS")
			(effects
				(font
					(size 0.635 0.4064)
					(thickness 0.1524)
				)
			)
		)
		(fp_text user "52"
			(at 3.866642 -4.472686 0)
			(unlocked yes)
			(layer "F.SilkS")
			(effects
				(font
					(size 0.635 0.4064)
					(thickness 0.1524)
				)
			)
		)
		(fp_text user "35"
			(at 4.704842 3.819144 0)
			(unlocked yes)
			(layer "F.SilkS")
			(effects
				(font
					(size 0.635 0.4064)
					(thickness 0.1524)
				)
			)
		)
		(fp_text user "51"
			(at 5.101082 -3.413252 0)
			(unlocked yes)
			(layer "F.SilkS")
			(effects
				(font
					(size 0.635 0.4064)
					(thickness 0.1524)
				)
			)
		)
		(fp_text user "17"
			(at -4.696968 3.7592 90)
			(unlocked yes)
			(layer "F.Fab")
			(effects
				(font
					(size 0.635 0.4064)
					(thickness 0.000001)
				)
			)
		)
		(fp_text user "1"
			(at -4.595368 -3.8354 90)
			(unlocked yes)
			(layer "F.Fab")
			(effects
				(font
					(size 0.635 0.4064)
					(thickness 0.000001)
				)
			)
		)
		(fp_text user "68"
			(at -4.1656 -4.595368 0)
			(unlocked yes)
			(layer "F.Fab")
			(effects
				(font
					(size 0.635 0.4064)
					(thickness 0.000001)
				)
			)
		)
		(fp_text user "18"
			(at -3.9624 4.650232 0)
			(unlocked yes)
			(layer "F.Fab")
			(effects
				(font
					(size 0.635 0.4064)
					(thickness 0.000001)
				)
			)
		)
		(fp_text user "34"
			(at 3.8354 4.675632 0)
			(unlocked yes)
			(layer "F.Fab")
			(effects
				(font
					(size 0.635 0.4064)
					(thickness 0.000001)
				)
			)
		)
		(fp_text user "52"
			(at 3.9116 -4.696968 0)
			(unlocked yes)
			(layer "F.Fab")
			(effects
				(font
					(size 0.635 0.4064)
					(thickness 0.000001)
				)
			)
		)
		(fp_text user "35"
			(at 4.701032 4.0132 90)
			(unlocked yes)
			(layer "F.Fab")
			(effects
				(font
					(size 0.635 0.4064)
					(thickness 0.000001)
				)
			)
		)
		(fp_text user "51"
			(at 4.777232 -3.9624 90)
			(unlocked yes)
			(layer "F.Fab")
			(effects
				(font
					(size 0.635 0.4064)
					(thickness 0.000001)
				)
			)
		)
		(pad "1" smd rect
			(at -3.992118 -3.199892 90)
			(size 0.1778 1.016)
			(layers "F.Cu" "F.Mask" "F.Paste")
			(net "USB_NODE1_SMI_L")
		)
		(pad "2" smd rect
			(at -3.903218 -2.800096 90)
			(size 0.1778 1.1938)
			(layers "F.Cu" "F.Mask" "F.Paste")
			(net "N34379705")
		)
		(pad "3" smd rect
			(at -3.903218 -2.400046 90)
			(size 0.1778 1.1938)
			(layers "F.Cu" "F.Mask" "F.Paste")
			(net "USB_WAKE_N")
		)
		(pad "4" smd rect
			(at -3.903218 -1.999996 90)
			(size 0.1778 1.1938)
			(layers "F.Cu" "F.Mask" "F.Paste")
			(net "CLK_100M_USB_NODE1_DP")
		)
		(pad "5" smd rect
			(at -3.903218 -1.599946 90)
			(size 0.1778 1.1938)
			(layers "F.Cu" "F.Mask" "F.Paste")
			(net "CLK_100M_USB_NODE1_DN")
		)
		(pad "6" smd rect
			(at -3.903218 -1.199896 90)
			(size 0.1778 1.1938)
			(layers "F.Cu" "F.Mask" "F.Paste")
			(net "P3V3_USB_NODE1")
		)
		(pad "7" smd rect
			(at -3.903218 -0.8001 90)
			(size 0.1778 1.1938)
			(layers "F.Cu" "F.Mask" "F.Paste")
			(net "P2E_CPU_USB_NODE1_RX_C_DP")
		)
		(pad "8" smd rect
			(at -3.903218 -0.40005 90)
			(size 0.1778 1.1938)
			(layers "F.Cu" "F.Mask" "F.Paste")
			(net "P2E_CPU_USB_NODE1_RX_C_DN")
		)
		(pad "9" smd rect
			(at -3.903218 0 90)
			(size 0.1778 1.1938)
			(layers "F.Cu" "F.Mask" "F.Paste")
			(net "P1V05_NODE1")
		)
		(pad "10" smd rect
			(at -3.903218 0.40005 90)
			(size 0.1778 1.1938)
			(layers "F.Cu" "F.Mask" "F.Paste")
			(net "P2E_CPU_USB_NODE1_TX_DP")
		)
		(pad "11" smd rect
			(at -3.903218 0.8001 90)
			(size 0.1778 1.1938)
			(layers "F.Cu" "F.Mask" "F.Paste")
			(net "P2E_CPU_USB_NODE1_TX_DN")
		)
		(pad "12" smd rect
			(at -3.903218 1.199896 90)
			(size 0.1778 1.1938)
			(layers "F.Cu" "F.Mask" "F.Paste")
			(net "P1V05_NODE1")
		)
		(pad "13" smd rect
			(at -3.903218 1.599946 90)
			(size 0.1778 1.1938)
			(layers "F.Cu" "F.Mask" "F.Paste")
			(net "USB_NODE1_PECREQ_L")
		)
		(pad "14" smd rect
			(at -3.903218 1.999996 90)
			(size 0.1778 1.1938)
			(layers "F.Cu" "F.Mask" "F.Paste")
			(net "FM_CPLD_NODE1_USB_PONRST_L")
		)
		(pad "15" smd rect
			(at -3.903218 2.400046 90)
			(size 0.1778 1.1938)
			(layers "F.Cu" "F.Mask" "F.Paste")
			(net "P3V3_NODE1")
		)
		(pad "16" smd rect
			(at -3.903218 2.800096 90)
			(size 0.1778 1.1938)
			(layers "F.Cu" "F.Mask" "F.Paste")
			(net "SPI_USB_NODE1_SI")
		)
		(pad "17" smd rect
			(at -3.992118 3.199892 90)
			(size 0.1778 1.016)
			(layers "F.Cu" "F.Mask" "F.Paste")
			(net "SPI_USB_NODE1_CSB_R_L")
		)
		(pad "18" smd rect
			(at -3.199892 3.992118)
			(size 0.1778 1.016)
			(layers "F.Cu" "F.Mask" "F.Paste")
			(net "SPI_USB_NODE1_CLK_R")
		)
		(pad "19" smd rect
			(at -2.800096 3.903218)
			(size 0.1778 1.1938)
			(layers "F.Cu" "F.Mask" "F.Paste")
			(net "SPI_USB_NODE1_R_SO")
		)
		(pad "20" smd rect
			(at -2.400046 3.903218)
			(size 0.1778 1.1938)
			(layers "F.Cu" "F.Mask" "F.Paste")
			(net "USB_OC_PU")
		)
		(pad "21" smd rect
			(at -1.999996 3.903218)
			(size 0.1778 1.1938)
			(layers "F.Cu" "F.Mask" "F.Paste")
			(net "Net_2263")
		)
		(pad "22" smd rect
			(at -1.599946 3.903218)
			(size 0.1778 1.1938)
			(layers "F.Cu" "F.Mask" "F.Paste")
			(net "USB_OC_PU")
		)
		(pad "23" smd rect
			(at -1.199896 3.903218)
			(size 0.1778 1.1938)
			(layers "F.Cu" "F.Mask" "F.Paste")
			(net "Net_2264")
		)
		(pad "24" smd rect
			(at -0.8001 3.903218)
			(size 0.1778 1.1938)
			(layers "F.Cu" "F.Mask" "F.Paste")
			(net "USB_OC_PU")
		)
		(pad "25" smd rect
			(at -0.40005 3.903218)
			(size 0.1778 1.1938)
			(layers "F.Cu" "F.Mask" "F.Paste")
			(net "Net_2265")
		)
		(pad "26" smd rect
			(at 0 3.903218)
			(size 0.1778 1.1938)
			(layers "F.Cu" "F.Mask" "F.Paste")
			(net "USB_OC_PU")
		)
		(pad "27" smd rect
			(at 0.40005 3.903218)
			(size 0.1778 1.1938)
			(layers "F.Cu" "F.Mask" "F.Paste")
			(net "Net_2266")
		)
		(pad "28" smd rect
			(at 0.8001 3.903218)
			(size 0.1778 1.1938)
			(layers "F.Cu" "F.Mask" "F.Paste")
			(net "P1V05_NODE1")
		)
		(pad "29" smd rect
			(at 1.199896 3.903218)
			(size 0.1778 1.1938)
			(layers "F.Cu" "F.Mask" "F.Paste")
			(net "P3V3_NODE1")
		)
		(pad "30" smd rect
			(at 1.599946 3.903218)
			(size 0.1778 1.1938)
			(layers "F.Cu" "F.Mask" "F.Paste")
			(net "USB_NODE1_XTA2")
		)
		(pad "31" smd rect
			(at 1.999996 3.903218)
			(size 0.1778 1.1938)
			(layers "F.Cu" "F.Mask" "F.Paste")
			(net "USB_NODE1_XTA1")
		)
		(pad "32" smd rect
			(at 2.400046 3.903218)
			(size 0.1778 1.1938)
			(layers "F.Cu" "F.Mask" "F.Paste")
			(net "P3V3_USB_NODE1")
		)
		(pad "33" smd rect
			(at 2.800096 3.903218)
			(size 0.1778 1.1938)
			(layers "F.Cu" "F.Mask" "F.Paste")
			(net "USB_NODE1_RREF")
		)
		(pad "34" smd rect
			(at 3.199892 3.992118)
			(size 0.1778 1.016)
			(layers "F.Cu" "F.Mask" "F.Paste")
			(net "GND")
		)
		(pad "35" smd rect
			(at 3.992118 3.199892 90)
			(size 0.1778 1.016)
			(layers "F.Cu" "F.Mask" "F.Paste")
			(net "TP_U3TXDP1")
		)
		(pad "36" smd rect
			(at 3.903218 2.800096 90)
			(size 0.1778 1.1938)
			(layers "F.Cu" "F.Mask" "F.Paste")
			(net "TP_U3TXDN1")
		)
		(pad "37" smd rect
			(at 3.903218 2.400046 90)
			(size 0.1778 1.1938)
			(layers "F.Cu" "F.Mask" "F.Paste")
			(net "P1V05_NODE1")
		)
		(pad "38" smd rect
			(at 3.903218 1.999996 90)
			(size 0.1778 1.1938)
			(layers "F.Cu" "F.Mask" "F.Paste")
			(net "GND")
		)
		(pad "39" smd rect
			(at 3.903218 1.599946 90)
			(size 0.1778 1.1938)
			(layers "F.Cu" "F.Mask" "F.Paste")
			(net "GND")
		)
		(pad "40" smd rect
			(at 3.903218 1.199896 90)
			(size 0.1778 1.1938)
			(layers "F.Cu" "F.Mask" "F.Paste")
			(net "P3V3_NODE1")
		)
		(pad "41" smd rect
			(at 3.903218 0.8001 90)
			(size 0.1778 1.1938)
			(layers "F.Cu" "F.Mask" "F.Paste")
			(net "USB0_DP")
		)
		(pad "42" smd rect
			(at 3.903218 0.40005 90)
			(size 0.1778 1.1938)
			(layers "F.Cu" "F.Mask" "F.Paste")
			(net "USB0_DN")
		)
		(pad "43" smd rect
			(at 3.903218 0 90)
			(size 0.1778 1.1938)
			(layers "F.Cu" "F.Mask" "F.Paste")
			(net "P1V05_NODE1")
		)
		(pad "44" smd rect
			(at 3.903218 -0.40005 90)
			(size 0.1778 1.1938)
			(layers "F.Cu" "F.Mask" "F.Paste")
			(net "TP_U3TXDP2")
		)
		(pad "45" smd rect
			(at 3.903218 -0.8001 90)
			(size 0.1778 1.1938)
			(layers "F.Cu" "F.Mask" "F.Paste")
			(net "TP_U3TXDN2")
		)
		(pad "46" smd rect
			(at 3.903218 -1.199896 90)
			(size 0.1778 1.1938)
			(layers "F.Cu" "F.Mask" "F.Paste")
			(net "P1V05_NODE1")
		)
		(pad "47" smd rect
			(at 3.903218 -1.599946 90)
			(size 0.1778 1.1938)
			(layers "F.Cu" "F.Mask" "F.Paste")
			(net "GND")
		)
		(pad "48" smd rect
			(at 3.903218 -1.999996 90)
			(size 0.1778 1.1938)
			(layers "F.Cu" "F.Mask" "F.Paste")
			(net "GND")
		)
		(pad "49" smd rect
			(at 3.903218 -2.400046 90)
			(size 0.1778 1.1938)
			(layers "F.Cu" "F.Mask" "F.Paste")
			(net "P3V3_NODE1")
		)
		(pad "50" smd rect
			(at 3.903218 -2.800096 90)
			(size 0.1778 1.1938)
			(layers "F.Cu" "F.Mask" "F.Paste")
			(net "USB1_DP")
		)
		(pad "51" smd rect
			(at 3.992118 -3.199892 90)
			(size 0.1778 1.016)
			(layers "F.Cu" "F.Mask" "F.Paste")
			(net "USB1_DN")
		)
		(pad "52" smd rect
			(at 3.199892 -3.992118)
			(size 0.1778 1.016)
			(layers "F.Cu" "F.Mask" "F.Paste")
			(net "TP_U3TXDP3")
		)
		(pad "53" smd rect
			(at 2.800096 -3.903218)
			(size 0.1778 1.1938)
			(layers "F.Cu" "F.Mask" "F.Paste")
			(net "TP_U3TXDN3")
		)
		(pad "54" smd rect
			(at 2.400046 -3.903218)
			(size 0.1778 1.1938)
			(layers "F.Cu" "F.Mask" "F.Paste")
			(net "P1V05_NODE1")
		)
		(pad "55" smd rect
			(at 1.999996 -3.903218)
			(size 0.1778 1.1938)
			(layers "F.Cu" "F.Mask" "F.Paste")
			(net "GND")
		)
		(pad "56" smd rect
			(at 1.599946 -3.903218)
			(size 0.1778 1.1938)
			(layers "F.Cu" "F.Mask" "F.Paste")
			(net "GND")
		)
		(pad "57" smd rect
			(at 1.199896 -3.903218)
			(size 0.1778 1.1938)
			(layers "F.Cu" "F.Mask" "F.Paste")
			(net "P3V3_NODE1")
		)
		(pad "58" smd rect
			(at 0.8001 -3.903218)
			(size 0.1778 1.1938)
			(layers "F.Cu" "F.Mask" "F.Paste")
			(net "USB2_DP")
		)
		(pad "59" smd rect
			(at 0.40005 -3.903218)
			(size 0.1778 1.1938)
			(layers "F.Cu" "F.Mask" "F.Paste")
			(net "USB2_DN")
		)
		(pad "60" smd rect
			(at 0 -3.903218)
			(size 0.1778 1.1938)
			(layers "F.Cu" "F.Mask" "F.Paste")
			(net "P1V05_NODE1")
		)
		(pad "61" smd rect
			(at -0.40005 -3.903218)
			(size 0.1778 1.1938)
			(layers "F.Cu" "F.Mask" "F.Paste")
			(net "TP_U3TXDP4")
		)
		(pad "62" smd rect
			(at -0.8001 -3.903218)
			(size 0.1778 1.1938)
			(layers "F.Cu" "F.Mask" "F.Paste")
			(net "TP_U3TXDN4")
		)
		(pad "63" smd rect
			(at -1.199896 -3.903218)
			(size 0.1778 1.1938)
			(layers "F.Cu" "F.Mask" "F.Paste")
			(net "P1V05_NODE1")
		)
		(pad "64" smd rect
			(at -1.599946 -3.903218)
			(size 0.1778 1.1938)
			(layers "F.Cu" "F.Mask" "F.Paste")
			(net "GND")
		)
		(pad "65" smd rect
			(at -1.999996 -3.903218)
			(size 0.1778 1.1938)
			(layers "F.Cu" "F.Mask" "F.Paste")
			(net "GND")
		)
		(pad "66" smd rect
			(at -2.400046 -3.903218)
			(size 0.1778 1.1938)
			(layers "F.Cu" "F.Mask" "F.Paste")
			(net "P3V3_NODE1")
		)
		(pad "67" smd rect
			(at -2.800096 -3.903218)
			(size 0.1778 1.1938)
			(layers "F.Cu" "F.Mask" "F.Paste")
			(net "USB3_DP")
		)
		(pad "68" smd rect
			(at -3.199892 -3.992118)
			(size 0.1778 1.016)
			(layers "F.Cu" "F.Mask" "F.Paste")
			(net "USB3_DN")
		)
		(pad "TH" smd rect
			(at 0 0)
			(size 6.1976 6.1976)
			(layers "F.Cu" "F.Mask" "F.Paste")
			(net "GND")
		)
		(zone
			(layer "F.Cu")
			(hatch none 0.5)
			(connect_pads
				(clearance 0)
			)
			(min_thickness 0.25)
			(keepout
				(tracks not_allowed)
				(vias allowed)
				(pads allowed)
				(copperpour not_allowed)
				(footprints allowed)
			)
			(placement
				(enabled no)
				(sheetname "")
			)
			(fill
				(thermal_gap 0.5)
				(thermal_bridge_width 0.5)
				(island_removal_mode 0)
			)
			(polygon
				(pts
					(xy 170.189652 -104.18699) (xy 164.296852 -104.18699) (xy 164.296852 -104.36479) (xy 163.814252 -104.36479)
					(xy 163.814252 -103.88219) (xy 163.992052 -103.88219) (xy 163.992052 -97.98939) (xy 163.814252 -97.98939)
					(xy 163.814252 -97.50679) (xy 164.296852 -97.50679) (xy 164.296852 -97.68459) (xy 170.189652 -97.68459)
					(xy 170.189652 -97.50679) (xy 170.672252 -97.50679) (xy 170.672252 -97.98939) (xy 170.494452 -97.98939)
					(xy 170.494452 -103.88219) (xy 170.672252 -103.88219) (xy 170.672252 -104.05999) (xy 170.494452 -104.05999)
					(xy 170.392852 -104.05999) (xy 170.392852 -97.78619) (xy 164.093652 -97.78619) (xy 164.093652 -104.08539)
					(xy 170.494452 -104.08539) (xy 170.672252 -104.08539) (xy 170.672252 -104.36479) (xy 170.189652 -104.36479)
				)
			)
		)
		(zone
			(layer "F.Cu")
			(hatch none 0.5)
			(connect_pads
				(clearance 0)
			)
			(min_thickness 0.25)
			(keepout
				(tracks allowed)
				(vias not_allowed)
				(pads allowed)
				(copperpour not_allowed)
				(footprints allowed)
			)
			(placement
				(enabled no)
				(sheetname "")
			)
			(fill
				(thermal_gap 0.5)
				(thermal_bridge_width 0.5)
				(island_removal_mode 0)
			)
			(polygon
				(pts
					(xy 170.189652 -104.18699) (xy 164.296852 -104.18699) (xy 164.296852 -104.36479) (xy 163.814252 -104.36479)
					(xy 163.814252 -103.88219) (xy 163.992052 -103.88219) (xy 163.992052 -97.98939) (xy 163.814252 -97.98939)
					(xy 163.814252 -97.50679) (xy 164.296852 -97.50679) (xy 164.296852 -97.68459) (xy 170.189652 -97.68459)
					(xy 170.189652 -97.50679) (xy 170.672252 -97.50679) (xy 170.672252 -97.98939) (xy 170.494452 -97.98939)
					(xy 170.494452 -103.88219) (xy 170.672252 -103.88219) (xy 170.672252 -104.05999) (xy 170.494452 -104.05999)
					(xy 170.392852 -104.05999) (xy 170.392852 -97.78619) (xy 164.093652 -97.78619) (xy 164.093652 -104.08539)
					(xy 170.494452 -104.08539) (xy 170.672252 -104.08539) (xy 170.672252 -104.36479) (xy 170.189652 -104.36479)
				)
			)
		)
	)
	(footprint ""
		(layer "F.Cu")
		(at 126.644146 -164.228526 180)
		(property "Reference" "R684"
			(at 0.939546 4.341622 0)
			(unlocked yes)
			(layer "F.SilkS")
			(effects
				(font
					(size 0.7874 0.5842)
					(thickness 0.1524)
				)
				(justify left)
			)
		)
		(property "Value" ""
			(at 0 0 180)
			(layer "F.Fab")
			(effects
				(font
					(size 1.27 1.27)
				)
			)
		)
		(duplicate_pad_numbers_are_jumpers no)
		(fp_line
			(start 0.7874 0.4064)
			(end -0.7874 0.4064)
			(stroke
				(width 0.1524)
				(type default)
			)
			(layer "F.SilkS")
		)
		(fp_line
			(start 0.7874 -0.4064)
			(end 0.7874 0.4064)
			(stroke
				(width 0.1524)
				(type default)
			)
			(layer "F.SilkS")
		)
		(fp_line
			(start -0.7874 0.4064)
			(end -0.7874 -0.4064)
			(stroke
				(width 0.1524)
				(type default)
			)
			(layer "F.SilkS")
		)
		(fp_line
			(start -0.7874 -0.4064)
			(end 0.7874 -0.4064)
			(stroke
				(width 0.1524)
				(type default)
			)
			(layer "F.SilkS")
		)
		(fp_poly
			(pts
				(xy -0.508 0.2794) (xy -0.508 0.2286) (xy -0.635 0.2286) (xy -0.635 -0.254) (xy -0.5334 -0.254)
				(xy -0.5334 -0.2794) (xy 0.5334 -0.2794) (xy 0.5334 -0.254) (xy 0.635 -0.254) (xy 0.635 0.254) (xy 0.5334 0.254)
				(xy 0.5334 0.2794)
			)
			(stroke
				(width 0)
				(type default)
			)
			(fill no)
			(layer "F.CrtYd")
		)
		(pad "1" smd rect
			(at 0.40005 0 180)
			(size 0.4572 0.508)
			(layers "F.Cu" "F.Mask" "F.Paste")
			(net "CPLD123_RSV2")
		)
		(pad "2" smd rect
			(at -0.40005 0 180)
			(size 0.4572 0.508)
			(layers "F.Cu" "F.Mask" "F.Paste")
			(net "CPLD3_RSV2")
		)
	)
	(footprint ""
		(layer "F.Cu")
		(at 80.93456 -80.683608 -90)
		(property "Reference" "C82"
			(at 17.592294 -1.189482 90)
			(unlocked yes)
			(layer "F.SilkS")
			(effects
				(font
					(size 0.7874 0.5842)
					(thickness 0.1524)
				)
				(justify left)
			)
		)
		(property "Value" ""
			(at 0 0 270)
			(layer "F.Fab")
			(effects
				(font
					(size 1.27 1.27)
				)
			)
		)
		(duplicate_pad_numbers_are_jumpers no)
		(fp_line
			(start -0.7874 0.4064)
			(end -0.7874 -0.4064)
			(stroke
				(width 0.1524)
				(type default)
			)
			(layer "F.SilkS")
		)
		(fp_line
			(start 0.7874 0.4064)
			(end -0.7874 0.4064)
			(stroke
				(width 0.1524)
				(type default)
			)
			(layer "F.SilkS")
		)
		(fp_line
			(start 0 0.381)
			(end 0 -0.381)
			(stroke
				(width 0.1524)
				(type default)
			)
			(layer "F.SilkS")
		)
		(fp_line
			(start -0.7874 -0.4064)
			(end 0.7874 -0.4064)
			(stroke
				(width 0.1524)
				(type default)
			)
			(layer "F.SilkS")
		)
		(fp_line
			(start 0.7874 -0.4064)
			(end 0.7874 0.4064)
			(stroke
				(width 0.1524)
				(type default)
			)
			(layer "F.SilkS")
		)
		(fp_poly
			(pts
				(xy -0.5334 0.254) (xy -0.635 0.254) (xy -0.635 0.2286) (xy -0.635 -0.254) (xy -0.5334 -0.254) (xy -0.5334 -0.2794)
				(xy 0.5334 -0.2794) (xy 0.5334 -0.254) (xy 0.635 -0.254) (xy 0.635 0.254) (xy 0.5334 0.254) (xy 0.5334 0.2794)
				(xy -0.508 0.2794) (xy -0.5334 0.2794)
			)
			(stroke
				(width 0)
				(type default)
			)
			(fill no)
			(layer "F.CrtYd")
		)
		(pad "1" smd rect
			(at 0.40005 0 270)
			(size 0.4572 0.508)
			(layers "F.Cu" "F.Mask" "F.Paste")
			(net "PV_VCCP_NODE1")
		)
		(pad "2" smd rect
			(at -0.40005 0 270)
			(size 0.4572 0.508)
			(layers "F.Cu" "F.Mask" "F.Paste")
			(net "GND")
		)
	)
	(footprint ""
		(layer "F.Cu")
		(at 142.02156 -114.383058 90)
		(property "Reference" "R135"
			(at -1.995678 3.151632 90)
			(unlocked yes)
			(layer "F.SilkS")
			(effects
				(font
					(size 0.7874 0.5842)
					(thickness 0.1524)
				)
				(justify left)
			)
		)
		(property "Value" ""
			(at 0 0 90)
			(layer "F.Fab")
			(effects
				(font
					(size 1.27 1.27)
				)
			)
		)
		(duplicate_pad_numbers_are_jumpers no)
		(fp_line
			(start 0.7874 -0.4064)
			(end 0.7874 0.4064)
			(stroke
				(width 0.1524)
				(type default)
			)
			(layer "F.SilkS")
		)
		(fp_line
			(start -0.7874 -0.4064)
			(end 0.7874 -0.4064)
			(stroke
				(width 0.1524)
				(type default)
			)
			(layer "F.SilkS")
		)
		(fp_line
			(start 0.7874 0.4064)
			(end -0.7874 0.4064)
			(stroke
				(width 0.1524)
				(type default)
			)
			(layer "F.SilkS")
		)
		(fp_line
			(start -0.7874 0.4064)
			(end -0.7874 -0.4064)
			(stroke
				(width 0.1524)
				(type default)
			)
			(layer "F.SilkS")
		)
		(fp_poly
			(pts
				(xy -0.508 0.2794) (xy -0.508 0.2286) (xy -0.635 0.2286) (xy -0.635 -0.254) (xy -0.5334 -0.254)
				(xy -0.5334 -0.2794) (xy 0.5334 -0.2794) (xy 0.5334 -0.254) (xy 0.635 -0.254) (xy 0.635 0.254) (xy 0.5334 0.254)
				(xy 0.5334 0.2794)
			)
			(stroke
				(width 0)
				(type default)
			)
			(fill no)
			(layer "F.CrtYd")
		)
		(pad "1" smd rect
			(at 0.40005 0 90)
			(size 0.4572 0.508)
			(layers "F.Cu" "F.Mask" "F.Paste")
			(net "CLKREQC_NODE1_N")
		)
		(pad "2" smd rect
			(at -0.40005 0 90)
			(size 0.4572 0.508)
			(layers "F.Cu" "F.Mask" "F.Paste")
			(net "CLK_48M_SIO")
		)
	)
	(footprint ""
		(layer "F.Cu")
		(at 58.53176 -185.205624 -90)
		(property "Reference" "R946"
			(at -4.006088 0.281178 90)
			(unlocked yes)
			(layer "F.SilkS")
			(effects
				(font
					(size 0.7874 0.5842)
					(thickness 0.1524)
				)
				(justify left)
			)
		)
		(property "Value" ""
			(at 0 0 270)
			(layer "F.Fab")
			(effects
				(font
					(size 1.27 1.27)
				)
			)
		)
		(duplicate_pad_numbers_are_jumpers no)
		(fp_line
			(start -0.7874 0.4064)
			(end -0.7874 -0.4064)
			(stroke
				(width 0.1524)
				(type default)
			)
			(layer "F.SilkS")
		)
		(fp_line
			(start 0.7874 0.4064)
			(end -0.7874 0.4064)
			(stroke
				(width 0.1524)
				(type default)
			)
			(layer "F.SilkS")
		)
		(fp_line
			(start -0.7874 -0.4064)
			(end 0.7874 -0.4064)
			(stroke
				(width 0.1524)
				(type default)
			)
			(layer "F.SilkS")
		)
		(fp_line
			(start 0.7874 -0.4064)
			(end 0.7874 0.4064)
			(stroke
				(width 0.1524)
				(type default)
			)
			(layer "F.SilkS")
		)
		(fp_poly
			(pts
				(xy -0.508 0.2794) (xy -0.508 0.2286) (xy -0.635 0.2286) (xy -0.635 -0.254) (xy -0.5334 -0.254)
				(xy -0.5334 -0.2794) (xy 0.5334 -0.2794) (xy 0.5334 -0.254) (xy 0.635 -0.254) (xy 0.635 0.254) (xy 0.5334 0.254)
				(xy 0.5334 0.2794)
			)
			(stroke
				(width 0)
				(type default)
			)
			(fill no)
			(layer "F.CrtYd")
		)
		(pad "1" smd rect
			(at 0.40005 0 270)
			(size 0.4572 0.508)
			(layers "F.Cu" "F.Mask" "F.Paste")
			(net "UART_T2_NODE3_TXD")
		)
		(pad "2" smd rect
			(at -0.40005 0 270)
			(size 0.4572 0.508)
			(layers "F.Cu" "F.Mask" "F.Paste")
			(net "UART_T2_NODE3_TXD_R")
		)
	)
	(footprint ""
		(layer "F.Cu")
		(at 153.501852 -87.16899 -90)
		(property "Reference" "R528"
			(at 0.05461 3.688588 0)
			(unlocked yes)
			(layer "F.SilkS")
			(effects
				(font
					(size 0.7874 0.5842)
					(thickness 0.1524)
				)
				(justify left)
			)
		)
		(property "Value" ""
			(at 0 0 270)
			(layer "F.Fab")
			(effects
				(font
					(size 1.27 1.27)
				)
			)
		)
		(duplicate_pad_numbers_are_jumpers no)
		(fp_line
			(start -0.7874 0.4064)
			(end -0.7874 -0.4064)
			(stroke
				(width 0.1524)
				(type default)
			)
			(layer "F.SilkS")
		)
		(fp_line
			(start 0.7874 0.4064)
			(end -0.7874 0.4064)
			(stroke
				(width 0.1524)
				(type default)
			)
			(layer "F.SilkS")
		)
		(fp_line
			(start -0.7874 -0.4064)
			(end 0.7874 -0.4064)
			(stroke
				(width 0.1524)
				(type default)
			)
			(layer "F.SilkS")
		)
		(fp_line
			(start 0.7874 -0.4064)
			(end 0.7874 0.4064)
			(stroke
				(width 0.1524)
				(type default)
			)
			(layer "F.SilkS")
		)
		(fp_poly
			(pts
				(xy -0.508 0.2794) (xy -0.508 0.2286) (xy -0.635 0.2286) (xy -0.635 -0.254) (xy -0.5334 -0.254)
				(xy -0.5334 -0.2794) (xy 0.5334 -0.2794) (xy 0.5334 -0.254) (xy 0.635 -0.254) (xy 0.635 0.254) (xy 0.5334 0.254)
				(xy 0.5334 0.2794)
			)
			(stroke
				(width 0)
				(type default)
			)
			(fill no)
			(layer "F.CrtYd")
		)
		(pad "1" smd rect
			(at 0.40005 0 270)
			(size 0.4572 0.508)
			(layers "F.Cu" "F.Mask" "F.Paste")
			(net "P3V3_NODE1")
		)
		(pad "2" smd rect
			(at -0.40005 0 270)
			(size 0.4572 0.508)
			(layers "F.Cu" "F.Mask" "F.Paste")
			(net "SPI_USB_NODE1_WP_L")
		)
	)
	(footprint ""
		(layer "F.Cu")
		(at 140.31976 -115.863624)
		(property "Reference" "R15"
			(at -0.882396 -2.02438 0)
			(unlocked yes)
			(layer "F.SilkS")
			(effects
				(font
					(size 0.7874 0.5842)
					(thickness 0.1524)
				)
				(justify left)
			)
		)
		(property "Value" ""
			(at 0 0 0)
			(layer "F.Fab")
			(effects
				(font
					(size 1.27 1.27)
				)
			)
		)
		(duplicate_pad_numbers_are_jumpers no)
		(fp_line
			(start -0.7874 -0.4064)
			(end 0.7874 -0.4064)
			(stroke
				(width 0.1524)
				(type default)
			)
			(layer "F.SilkS")
		)
		(fp_line
			(start -0.7874 0.4064)
			(end -0.7874 -0.4064)
			(stroke
				(width 0.1524)
				(type default)
			)
			(layer "F.SilkS")
		)
		(fp_line
			(start 0.7874 -0.4064)
			(end 0.7874 0.4064)
			(stroke
				(width 0.1524)
				(type default)
			)
			(layer "F.SilkS")
		)
		(fp_line
			(start 0.7874 0.4064)
			(end -0.7874 0.4064)
			(stroke
				(width 0.1524)
				(type default)
			)
			(layer "F.SilkS")
		)
		(fp_poly
			(pts
				(xy -0.508 0.2794) (xy -0.508 0.2286) (xy -0.635 0.2286) (xy -0.635 -0.254) (xy -0.5334 -0.254)
				(xy -0.5334 -0.2794) (xy 0.5334 -0.2794) (xy 0.5334 -0.254) (xy 0.635 -0.254) (xy 0.635 0.254) (xy 0.5334 0.254)
				(xy 0.5334 0.2794)
			)
			(stroke
				(width 0)
				(type default)
			)
			(fill no)
			(layer "F.CrtYd")
		)
		(pad "1" smd rect
			(at 0.40005 0)
			(size 0.4572 0.508)
			(layers "F.Cu" "F.Mask" "F.Paste")
			(net "GND")
		)
		(pad "2" smd rect
			(at -0.40005 0)
			(size 0.4572 0.508)
			(layers "F.Cu" "F.Mask" "F.Paste")
			(net "CLKREQB_NODE1_N")
		)
	)
	(footprint ""
		(layer "F.Cu")
		(at 104.761792 -120.961404)
		(property "Reference" "PR75"
			(at -3.70205 -0.385572 0)
			(unlocked yes)
			(layer "F.SilkS")
			(effects
				(font
					(size 0.7874 0.5842)
					(thickness 0.1524)
				)
				(justify left)
			)
		)
		(property "Value" ""
			(at 0 0 0)
			(layer "F.Fab")
			(effects
				(font
					(size 1.27 1.27)
				)
			)
		)
		(duplicate_pad_numbers_are_jumpers no)
		(fp_line
			(start -0.4572 -0.44069)
			(end 0.4572 -0.44069)
			(stroke
				(width 0.1524)
				(type default)
			)
			(layer "F.SilkS")
		)
		(fp_line
			(start -0.4572 1.51511)
			(end -0.4572 -0.44069)
			(stroke
				(width 0.1524)
				(type default)
			)
			(layer "F.SilkS")
		)
		(fp_line
			(start -0.4572 1.54051)
			(end -0.4572 1.51511)
			(stroke
				(width 0.1524)
				(type default)
			)
			(layer "F.SilkS")
		)
		(fp_line
			(start 0.4572 -0.44069)
			(end 0.4572 1.54051)
			(stroke
				(width 0.1524)
				(type default)
			)
			(layer "F.SilkS")
		)
		(fp_line
			(start 0.4572 1.54051)
			(end -0.4572 1.54051)
			(stroke
				(width 0.1524)
				(type default)
			)
			(layer "F.SilkS")
		)
		(fp_poly
			(pts
				(xy 0.3556 0.37211) (xy 0.3556 -0.36449) (xy -0.3556 -0.36449) (xy -0.3556 1.46431) (xy 0.3556 1.46431)
				(xy 0.3556 0.72771)
			)
			(stroke
				(width 0)
				(type default)
			)
			(fill no)
			(layer "F.CrtYd")
		)
		(fp_line
			(start -0.299974 -0.025146)
			(end 0.299974 -0.025146)
			(stroke
				(width 0.1)
				(type default)
			)
			(layer "F.Fab")
		)
		(fp_line
			(start -0.299974 1.124966)
			(end -0.299974 -0.025146)
			(stroke
				(width 0.1)
				(type default)
			)
			(layer "F.Fab")
		)
		(fp_line
			(start 0.299974 -0.025146)
			(end 0.299974 1.124966)
			(stroke
				(width 0.1)
				(type default)
			)
			(layer "F.Fab")
		)
		(fp_line
			(start 0.299974 1.124966)
			(end -0.299974 1.124966)
			(stroke
				(width 0.1)
				(type default)
			)
			(layer "F.Fab")
		)
		(pad "1" smd rect
			(at 0 0 90)
			(size 0.6096 0.6096)
			(layers "F.Cu" "F.Mask" "F.Paste")
			(net "VR_PVCCP_NODE1_VCC")
		)
		(pad "2" smd rect
			(at 0 1.09982 90)
			(size 0.6096 0.6096)
			(layers "F.Cu" "F.Mask" "F.Paste")
			(net "VR_PVCCP_NODE1_TSEN_R")
		)
	)
	(footprint ""
		(layer "F.Cu")
		(at 62.663324 -99.685856 90)
		(property "Reference" "Q29"
			(at 4.319778 0.737616 0)
			(unlocked yes)
			(layer "F.SilkS")
			(effects
				(font
					(size 0.7874 0.5842)
					(thickness 0.1524)
				)
			)
		)
		(property "Value" ""
			(at 0 0 90)
			(layer "F.Fab")
			(effects
				(font
					(size 1.27 1.27)
				)
			)
		)
		(duplicate_pad_numbers_are_jumpers no)
		(fp_line
			(start 2.899918 -0.525018)
			(end 2.899918 -0.345694)
			(stroke
				(width 0.1524)
				(type default)
			)
			(layer "F.SilkS")
		)
		(fp_line
			(start 1.755648 -0.525018)
			(end 2.899918 -0.525018)
			(stroke
				(width 0.1524)
				(type default)
			)
			(layer "F.SilkS")
		)
		(fp_line
			(start -0.100076 -0.525018)
			(end 1.044448 -0.525018)
			(stroke
				(width 0.1524)
				(type default)
			)
			(layer "F.SilkS")
		)
		(fp_line
			(start -0.100076 -0.320294)
			(end -0.100076 -0.525018)
			(stroke
				(width 0.1524)
				(type default)
			)
			(layer "F.SilkS")
		)
		(fp_line
			(start 2.899918 2.295906)
			(end 2.899918 2.474976)
			(stroke
				(width 0.1524)
				(type default)
			)
			(layer "F.SilkS")
		)
		(fp_line
			(start 2.899918 2.474976)
			(end 1.755648 2.474976)
			(stroke
				(width 0.1524)
				(type default)
			)
			(layer "F.SilkS")
		)
		(fp_line
			(start 1.044448 2.474976)
			(end -0.100076 2.474976)
			(stroke
				(width 0.1524)
				(type default)
			)
			(layer "F.SilkS")
		)
		(fp_line
			(start -0.100076 2.474976)
			(end -0.100076 2.295906)
			(stroke
				(width 0.1524)
				(type default)
			)
			(layer "F.SilkS")
		)
		(fp_poly
			(pts
				(xy -0.99695 0.26924) (xy -0.99695 -0.249682) (xy -0.419608 0.01397)
			)
			(stroke
				(width 0)
				(type default)
			)
			(fill yes)
			(layer "F.SilkS")
		)
		(fp_poly
			(pts
				(xy -0.100076 -0.525018) (xy -0.100076 -0.244094) (xy -0.301752 -0.244094) (xy -0.301752 2.194306)
				(xy -0.100076 2.194306) (xy -0.100076 2.474976) (xy 1.120648 2.474976) (xy 1.120648 2.651506) (xy 1.679448 2.651506)
				(xy 1.679448 2.474976) (xy 2.899918 2.474976) (xy 2.899918 2.219706) (xy 3.101848 2.219706) (xy 3.101848 -0.269494)
				(xy 2.899918 -0.269494) (xy 2.899918 -0.525018) (xy 1.679448 -0.525018) (xy 1.679448 -0.701294)
				(xy 1.120648 -0.701294) (xy 1.120648 -0.525018)
			)
			(stroke
				(width 0)
				(type default)
			)
			(fill no)
			(layer "F.CrtYd")
		)
		(fp_line
			(start 2.899918 -0.525018)
			(end 2.899918 2.474976)
			(stroke
				(width 0.1)
				(type default)
			)
			(layer "F.Fab")
		)
		(fp_line
			(start -0.100076 -0.525018)
			(end 2.899918 -0.525018)
			(stroke
				(width 0.1)
				(type default)
			)
			(layer "F.Fab")
		)
		(fp_line
			(start 2.899918 2.474976)
			(end -0.100076 2.474976)
			(stroke
				(width 0.1)
				(type default)
			)
			(layer "F.Fab")
		)
		(fp_line
			(start -0.100076 2.474976)
			(end -0.100076 -0.525018)
			(stroke
				(width 0.1)
				(type default)
			)
			(layer "F.Fab")
		)
		(pad "1" smd rect
			(at 0 0)
			(size 0.3556 0.508)
			(layers "F.Cu" "F.Mask" "F.Paste")
			(net "P1V8_SUS_NODE1")
		)
		(pad "2" smd rect
			(at 0 0.649986)
			(size 0.3556 0.508)
			(layers "F.Cu" "F.Mask" "F.Paste")
			(net "P1V8_SUS_NODE1")
		)
		(pad "3" smd rect
			(at 0 1.299972)
			(size 0.3556 0.508)
			(layers "F.Cu" "F.Mask" "F.Paste")
			(net "P1V8_SUS_NODE1")
		)
		(pad "4" smd rect
			(at 0 1.949958)
			(size 0.3556 0.508)
			(layers "F.Cu" "F.Mask" "F.Paste")
			(net "FM_CPLD_NODE1_P1V8_SUS_EN_LV")
		)
		(pad "5" smd custom
			(at 1.400048 0.975106)
			(size 0.569976 0.569976)
			(layers "F.Cu" "F.Mask" "F.Paste")
			(net "P1V8_STB_NODE1")
			(options
				(clearance outline)
				(anchor circle)
			)
			(primitives
				(gr_poly
					(pts
						(xy -1.225042 1.139952) (xy -1.225042 0.724916) (xy -1.605026 0.724916) (xy -1.605026 0.295148)
						(xy -1.225042 0.295148) (xy -1.225042 -0.839978) (xy -1.175004 -0.839978) (xy -1.175004 -1.139952)
						(xy -0.774954 -1.139952) (xy -0.774954 -0.839978) (xy -0.525018 -0.839978) (xy -0.525018 -1.139952)
						(xy -0.124968 -1.139952) (xy -0.124968 -0.839978) (xy 0.124968 -0.839978) (xy 0.124968 -1.139952)
						(xy 0.525018 -1.139952) (xy 0.525018 -0.839978) (xy 0.774954 -0.839978) (xy 0.774954 -1.139952)
						(xy 1.175004 -1.139952) (xy 1.175004 -0.839978) (xy 1.225042 -0.839978) (xy 1.225042 0.295148)
						(xy 1.605026 0.295148) (xy 1.605026 0.724916) (xy 1.225042 0.724916) (xy 1.225042 1.139952)
					)
					(width 0)
					(fill yes)
				)
			)
		)
		(zone
			(layer "F.Cu")
			(hatch none 0.5)
			(connect_pads
				(clearance 0)
			)
			(min_thickness 0.25)
			(keepout
				(tracks allowed)
				(vias not_allowed)
				(pads allowed)
				(copperpour not_allowed)
				(footprints allowed)
			)
			(placement
				(enabled no)
				(sheetname "")
			)
			(fill
				(thermal_gap 0.5)
				(thermal_bridge_width 0.5)
				(island_removal_mode 0)
			)
			(polygon
				(pts
					(xy 62.13983 -100.400104) (xy 65.13703 -100.400104) (xy 65.13703 -100.019104) (xy 62.13983 -100.019104)
				)
			)
		)
		(zone
			(layer "F.Cu")
			(hatch none 0.5)
			(connect_pads
				(clearance 0)
			)
			(min_thickness 0.25)
			(keepout
				(tracks not_allowed)
				(vias allowed)
				(pads allowed)
				(copperpour not_allowed)
				(footprints allowed)
			)
			(placement
				(enabled no)
				(sheetname "")
			)
			(fill
				(thermal_gap 0.5)
				(thermal_bridge_width 0.5)
				(island_removal_mode 0)
			)
			(polygon
				(pts
					(xy 62.13983 -100.019104) (xy 65.13703 -100.019104) (xy 65.13703 -100.400104) (xy 62.13983 -100.400104)
				)
			)
		)
	)
	(footprint ""
		(layer "F.Cu")
		(at 144.916652 -140.21435)
		(property "Reference" "R286"
			(at -0.990346 17.852644 0)
			(unlocked yes)
			(layer "F.SilkS")
			(effects
				(font
					(size 0.7874 0.5842)
					(thickness 0.1524)
				)
				(justify left)
			)
		)
		(property "Value" ""
			(at 0 0 0)
			(layer "F.Fab")
			(effects
				(font
					(size 1.27 1.27)
				)
			)
		)
		(duplicate_pad_numbers_are_jumpers no)
		(fp_line
			(start -0.7874 -0.4064)
			(end 0.7874 -0.4064)
			(stroke
				(width 0.1524)
				(type default)
			)
			(layer "F.SilkS")
		)
		(fp_line
			(start -0.7874 0.4064)
			(end -0.7874 -0.4064)
			(stroke
				(width 0.1524)
				(type default)
			)
			(layer "F.SilkS")
		)
		(fp_line
			(start 0.7874 -0.4064)
			(end 0.7874 0.4064)
			(stroke
				(width 0.1524)
				(type default)
			)
			(layer "F.SilkS")
		)
		(fp_line
			(start 0.7874 0.4064)
			(end -0.7874 0.4064)
			(stroke
				(width 0.1524)
				(type default)
			)
			(layer "F.SilkS")
		)
		(fp_poly
			(pts
				(xy -0.508 0.2794) (xy -0.508 0.2286) (xy -0.635 0.2286) (xy -0.635 -0.254) (xy -0.5334 -0.254)
				(xy -0.5334 -0.2794) (xy 0.5334 -0.2794) (xy 0.5334 -0.254) (xy 0.635 -0.254) (xy 0.635 0.254) (xy 0.5334 0.254)
				(xy 0.5334 0.2794)
			)
			(stroke
				(width 0)
				(type default)
			)
			(fill no)
			(layer "F.CrtYd")
		)
		(pad "1" smd rect
			(at 0.40005 0)
			(size 0.4572 0.508)
			(layers "F.Cu" "F.Mask" "F.Paste")
			(net "GND")
		)
		(pad "2" smd rect
			(at -0.40005 0)
			(size 0.4572 0.508)
			(layers "F.Cu" "F.Mask" "F.Paste")
			(net "PCIE_SW_TEST3")
		)
	)
	(footprint ""
		(layer "F.Cu")
		(at 60.129166 -96.709992 -90)
		(property "Reference" "R56"
			(at 54.98719 -28.490164 90)
			(unlocked yes)
			(layer "F.SilkS")
			(effects
				(font
					(size 0.7874 0.5842)
					(thickness 0.1524)
				)
				(justify left)
			)
		)
		(property "Value" ""
			(at 0 0 270)
			(layer "F.Fab")
			(effects
				(font
					(size 1.27 1.27)
				)
			)
		)
		(duplicate_pad_numbers_are_jumpers no)
		(fp_line
			(start -0.7874 0.4064)
			(end -0.7874 -0.4064)
			(stroke
				(width 0.1524)
				(type default)
			)
			(layer "F.SilkS")
		)
		(fp_line
			(start 0.7874 0.4064)
			(end -0.7874 0.4064)
			(stroke
				(width 0.1524)
				(type default)
			)
			(layer "F.SilkS")
		)
		(fp_line
			(start -0.7874 -0.4064)
			(end 0.7874 -0.4064)
			(stroke
				(width 0.1524)
				(type default)
			)
			(layer "F.SilkS")
		)
		(fp_line
			(start 0.7874 -0.4064)
			(end 0.7874 0.4064)
			(stroke
				(width 0.1524)
				(type default)
			)
			(layer "F.SilkS")
		)
		(fp_poly
			(pts
				(xy -0.508 0.2794) (xy -0.508 0.2286) (xy -0.635 0.2286) (xy -0.635 -0.254) (xy -0.5334 -0.254)
				(xy -0.5334 -0.2794) (xy 0.5334 -0.2794) (xy 0.5334 -0.254) (xy 0.635 -0.254) (xy 0.635 0.254) (xy 0.5334 0.254)
				(xy 0.5334 0.2794)
			)
			(stroke
				(width 0)
				(type default)
			)
			(fill no)
			(layer "F.CrtYd")
		)
		(pad "1" smd rect
			(at 0.40005 0 270)
			(size 0.4572 0.508)
			(layers "F.Cu" "F.Mask" "F.Paste")
			(net "PD_CPU_NODE1_DFX_GPIO_GRP1_0")
		)
		(pad "2" smd rect
			(at -0.40005 0 270)
			(size 0.4572 0.508)
			(layers "F.Cu" "F.Mask" "F.Paste")
			(net "GND")
		)
	)
	(footprint ""
		(layer "F.Cu")
		(at 76.901548 -101.200966)
		(property "Reference" "R1051"
			(at -1.890268 -2.053082 0)
			(unlocked yes)
			(layer "F.SilkS")
			(effects
				(font
					(size 0.7874 0.5842)
					(thickness 0.1524)
				)
				(justify left)
			)
		)
		(property "Value" ""
			(at 0 0 0)
			(layer "F.Fab")
			(effects
				(font
					(size 1.27 1.27)
				)
			)
		)
		(duplicate_pad_numbers_are_jumpers no)
		(fp_line
			(start -0.7874 -0.4064)
			(end 0.7874 -0.4064)
			(stroke
				(width 0.1524)
				(type default)
			)
			(layer "F.SilkS")
		)
		(fp_line
			(start -0.7874 0.4064)
			(end -0.7874 -0.4064)
			(stroke
				(width 0.1524)
				(type default)
			)
			(layer "F.SilkS")
		)
		(fp_line
			(start 0.7874 -0.4064)
			(end 0.7874 0.4064)
			(stroke
				(width 0.1524)
				(type default)
			)
			(layer "F.SilkS")
		)
		(fp_line
			(start 0.7874 0.4064)
			(end -0.7874 0.4064)
			(stroke
				(width 0.1524)
				(type default)
			)
			(layer "F.SilkS")
		)
		(fp_poly
			(pts
				(xy -0.508 0.2794) (xy -0.508 0.2286) (xy -0.635 0.2286) (xy -0.635 -0.254) (xy -0.5334 -0.254)
				(xy -0.5334 -0.2794) (xy 0.5334 -0.2794) (xy 0.5334 -0.254) (xy 0.635 -0.254) (xy 0.635 0.254) (xy 0.5334 0.254)
				(xy 0.5334 0.2794)
			)
			(stroke
				(width 0)
				(type default)
			)
			(fill no)
			(layer "F.CrtYd")
		)
		(pad "1" smd rect
			(at 0.40005 0)
			(size 0.4572 0.508)
			(layers "F.Cu" "F.Mask" "F.Paste")
			(net "P3V3_STB_NODE1")
		)
		(pad "2" smd rect
			(at -0.40005 0)
			(size 0.4572 0.508)
			(layers "F.Cu" "F.Mask" "F.Paste")
			(net "FM_OSC_NODE1_OSC_NC")
		)
	)
	(footprint ""
		(layer "F.Cu")
		(at 143.748252 -25.812242 90)
		(property "Reference" "L36"
			(at 1.223772 0.17907 90)
			(unlocked yes)
			(layer "F.SilkS")
			(effects
				(font
					(size 0.7874 0.5842)
					(thickness 0.1524)
				)
				(justify left)
			)
		)
		(property "Value" ""
			(at 0 0 90)
			(layer "F.Fab")
			(effects
				(font
					(size 1.27 1.27)
				)
			)
		)
		(duplicate_pad_numbers_are_jumpers no)
		(fp_line
			(start 0.7874 -0.4064)
			(end 0.7874 0.4064)
			(stroke
				(width 0.1524)
				(type default)
			)
			(layer "F.SilkS")
		)
		(fp_line
			(start -0.7874 -0.4064)
			(end 0.7874 -0.4064)
			(stroke
				(width 0.1524)
				(type default)
			)
			(layer "F.SilkS")
		)
		(fp_line
			(start 0.7874 0.4064)
			(end -0.7874 0.4064)
			(stroke
				(width 0.1524)
				(type default)
			)
			(layer "F.SilkS")
		)
		(fp_line
			(start 0.0889 0.4064)
			(end 0.0889 -0.4064)
			(stroke
				(width 0.1524)
				(type default)
			)
			(layer "F.SilkS")
		)
		(fp_line
			(start -0.0889 0.4064)
			(end -0.0889 -0.4064)
			(stroke
				(width 0.1524)
				(type default)
			)
			(layer "F.SilkS")
		)
		(fp_line
			(start -0.7874 0.4064)
			(end -0.7874 -0.4064)
			(stroke
				(width 0.1524)
				(type default)
			)
			(layer "F.SilkS")
		)
		(fp_poly
			(pts
				(xy -0.5334 0.254) (xy -0.635 0.254) (xy -0.635 0.2286) (xy -0.635 -0.254) (xy -0.5334 -0.254) (xy -0.5334 -0.2794)
				(xy 0.5334 -0.2794) (xy 0.5334 -0.254) (xy 0.635 -0.254) (xy 0.635 0.254) (xy 0.5334 0.254) (xy 0.5334 0.2794)
				(xy -0.508 0.2794) (xy -0.5334 0.2794)
			)
			(stroke
				(width 0)
				(type default)
			)
			(fill no)
			(layer "F.CrtYd")
		)
		(pad "1" smd rect
			(at 0.40005 0 90)
			(size 0.4572 0.508)
			(layers "F.Cu" "F.Mask" "F.Paste")
			(net "SIO_AVCC")
		)
		(pad "2" smd rect
			(at -0.40005 0 90)
			(size 0.4572 0.508)
			(layers "F.Cu" "F.Mask" "F.Paste")
			(net "P5V_NODE1")
		)
	)
	(footprint ""
		(layer "F.Cu")
		(at 123.70816 -163.475416)
		(property "Reference" "C567"
			(at 29.783278 46.44517 0)
			(unlocked yes)
			(layer "F.SilkS")
			(effects
				(font
					(size 0.7874 0.5842)
					(thickness 0.1524)
				)
				(justify left)
			)
		)
		(property "Value" ""
			(at 0 0 0)
			(layer "F.Fab")
			(effects
				(font
					(size 1.27 1.27)
				)
			)
		)
		(duplicate_pad_numbers_are_jumpers no)
		(fp_line
			(start -0.7874 -0.4064)
			(end 0.7874 -0.4064)
			(stroke
				(width 0.1524)
				(type default)
			)
			(layer "F.SilkS")
		)
		(fp_line
			(start -0.7874 0.4064)
			(end -0.7874 -0.4064)
			(stroke
				(width 0.1524)
				(type default)
			)
			(layer "F.SilkS")
		)
		(fp_line
			(start 0 0.381)
			(end 0 -0.381)
			(stroke
				(width 0.1524)
				(type default)
			)
			(layer "F.SilkS")
		)
		(fp_line
			(start 0.7874 -0.4064)
			(end 0.7874 0.4064)
			(stroke
				(width 0.1524)
				(type default)
			)
			(layer "F.SilkS")
		)
		(fp_line
			(start 0.7874 0.4064)
			(end -0.7874 0.4064)
			(stroke
				(width 0.1524)
				(type default)
			)
			(layer "F.SilkS")
		)
		(fp_poly
			(pts
				(xy -0.5334 0.254) (xy -0.635 0.254) (xy -0.635 0.2286) (xy -0.635 -0.254) (xy -0.5334 -0.254) (xy -0.5334 -0.2794)
				(xy 0.5334 -0.2794) (xy 0.5334 -0.254) (xy 0.635 -0.254) (xy 0.635 0.254) (xy 0.5334 0.254) (xy 0.5334 0.2794)
				(xy -0.508 0.2794) (xy -0.5334 0.2794)
			)
			(stroke
				(width 0)
				(type default)
			)
			(fill no)
			(layer "F.CrtYd")
		)
		(pad "1" smd rect
			(at 0.40005 0)
			(size 0.4572 0.508)
			(layers "F.Cu" "F.Mask" "F.Paste")
			(net "GND")
		)
		(pad "2" smd rect
			(at -0.40005 0)
			(size 0.4572 0.508)
			(layers "F.Cu" "F.Mask" "F.Paste")
			(net "P3V3_NODE1")
		)
	)
	(footprint ""
		(layer "F.Cu")
		(at 102.596188 -158.497524)
		(property "Reference" "PJ4"
			(at 2.828798 0.984504 90)
			(unlocked yes)
			(layer "F.SilkS")
			(effects
				(font
					(size 0.635 0.4064)
					(thickness 0.1524)
				)
				(justify left)
			)
		)
		(property "Value" ""
			(at 0 0 0)
			(layer "F.Fab")
			(effects
				(font
					(size 1.27 1.27)
				)
			)
		)
		(duplicate_pad_numbers_are_jumpers no)
		(fp_poly
			(pts
				(xy 0.2794 0.907796) (xy 0.254 0.907796) (xy 0.254 1.0414) (xy -0.254 1.0414) (xy -0.254 1.034796)
				(xy -0.254 0.933196) (xy -0.2794 0.933196) (xy -0.2794 -0.133604) (xy -0.254 -0.133604) (xy -0.254 -0.235204)
				(xy 0.254 -0.235204) (xy 0.254 -0.133604) (xy 0.2794 -0.133604)
			)
			(stroke
				(width 0)
				(type default)
			)
			(fill no)
			(layer "F.CrtYd")
		)
		(pad "1" smd custom
			(at 0 -0.000254)
			(size 0.127 0.127)
			(layers "F.Cu" "F.Mask" "F.Paste")
			(net "FM_CPLD_NODE1_P1V8_STB_EN")
			(options
				(clearance outline)
				(anchor circle)
			)
			(primitives
				(gr_poly
					(pts
						(xy -0.127 0.508) (xy -0.127 -0.0508) (xy -0.254 -0.0508) (xy -0.254 -0.508) (xy 0.254 -0.508)
						(xy 0.254 -0.0508) (xy 0.127 -0.0508) (xy 0.127 0.508)
					)
					(width 0)
					(fill yes)
				)
			)
		)
		(pad "2" smd rect
			(at 0 0.799846 90)
			(size 0.4572 0.508)
			(layers "F.Cu" "F.Mask" "F.Paste")
			(net "FM_CPLD_NODE1_P1V8_STB_S_EN")
		)
		(zone
			(layer "F.Cu")
			(hatch none 0.5)
			(connect_pads
				(clearance 0)
			)
			(min_thickness 0.25)
			(keepout
				(tracks allowed)
				(vias not_allowed)
				(pads allowed)
				(copperpour not_allowed)
				(footprints allowed)
			)
			(placement
				(enabled no)
				(sheetname "")
			)
			(fill
				(thermal_gap 0.5)
				(thermal_bridge_width 0.5)
				(island_removal_mode 0)
			)
			(polygon
				(pts
					(xy 102.291388 -157.411928) (xy 102.900988 -157.411928) (xy 102.900988 -158.783528) (xy 102.291388 -158.783528)
				)
			)
		)
	)
	(footprint ""
		(layer "F.Cu")
		(at 139.98956 -114.383058 -90)
		(property "Reference" "R25"
			(at 1.995678 -3.115818 90)
			(unlocked yes)
			(layer "F.SilkS")
			(effects
				(font
					(size 0.7874 0.5842)
					(thickness 0.1524)
				)
				(justify left)
			)
		)
		(property "Value" ""
			(at 0 0 270)
			(layer "F.Fab")
			(effects
				(font
					(size 1.27 1.27)
				)
			)
		)
		(duplicate_pad_numbers_are_jumpers no)
		(fp_line
			(start -0.7874 0.4064)
			(end -0.7874 -0.4064)
			(stroke
				(width 0.1524)
				(type default)
			)
			(layer "F.SilkS")
		)
		(fp_line
			(start 0.7874 0.4064)
			(end -0.7874 0.4064)
			(stroke
				(width 0.1524)
				(type default)
			)
			(layer "F.SilkS")
		)
		(fp_line
			(start -0.7874 -0.4064)
			(end 0.7874 -0.4064)
			(stroke
				(width 0.1524)
				(type default)
			)
			(layer "F.SilkS")
		)
		(fp_line
			(start 0.7874 -0.4064)
			(end 0.7874 0.4064)
			(stroke
				(width 0.1524)
				(type default)
			)
			(layer "F.SilkS")
		)
		(fp_poly
			(pts
				(xy -0.508 0.2794) (xy -0.508 0.2286) (xy -0.635 0.2286) (xy -0.635 -0.254) (xy -0.5334 -0.254)
				(xy -0.5334 -0.2794) (xy 0.5334 -0.2794) (xy 0.5334 -0.254) (xy 0.635 -0.254) (xy 0.635 0.254) (xy 0.5334 0.254)
				(xy 0.5334 0.2794)
			)
			(stroke
				(width 0)
				(type default)
			)
			(fill no)
			(layer "F.CrtYd")
		)
		(pad "1" smd rect
			(at 0.40005 0 270)
			(size 0.4572 0.508)
			(layers "F.Cu" "F.Mask" "F.Paste")
			(net "GND")
		)
		(pad "2" smd rect
			(at -0.40005 0 270)
			(size 0.4572 0.508)
			(layers "F.Cu" "F.Mask" "F.Paste")
			(net "CLKREQC_NODE1_N")
		)
	)
	(footprint ""
		(layer "F.Cu")
		(at 152.510998 -142.88643 -90)
		(property "Reference" "R591"
			(at -1.457706 1.209802 90)
			(unlocked yes)
			(layer "F.SilkS")
			(effects
				(font
					(size 0.635 0.4064)
					(thickness 0.1524)
				)
				(justify left)
			)
		)
		(property "Value" ""
			(at 0 0 270)
			(layer "F.Fab")
			(effects
				(font
					(size 1.27 1.27)
				)
			)
		)
		(duplicate_pad_numbers_are_jumpers no)
		(fp_line
			(start -0.7874 0.4064)
			(end -0.7874 -0.4064)
			(stroke
				(width 0.1524)
				(type default)
			)
			(layer "F.SilkS")
		)
		(fp_line
			(start 0.7874 0.4064)
			(end -0.7874 0.4064)
			(stroke
				(width 0.1524)
				(type default)
			)
			(layer "F.SilkS")
		)
		(fp_line
			(start -0.7874 -0.4064)
			(end 0.7874 -0.4064)
			(stroke
				(width 0.1524)
				(type default)
			)
			(layer "F.SilkS")
		)
		(fp_line
			(start 0.7874 -0.4064)
			(end 0.7874 0.4064)
			(stroke
				(width 0.1524)
				(type default)
			)
			(layer "F.SilkS")
		)
		(fp_poly
			(pts
				(xy -0.508 0.2794) (xy -0.508 0.2286) (xy -0.635 0.2286) (xy -0.635 -0.254) (xy -0.5334 -0.254)
				(xy -0.5334 -0.2794) (xy 0.5334 -0.2794) (xy 0.5334 -0.254) (xy 0.635 -0.254) (xy 0.635 0.254) (xy 0.5334 0.254)
				(xy 0.5334 0.2794)
			)
			(stroke
				(width 0)
				(type default)
			)
			(fill no)
			(layer "F.CrtYd")
		)
		(pad "1" smd rect
			(at 0.40005 0 270)
			(size 0.4572 0.508)
			(layers "F.Cu" "F.Mask" "F.Paste")
			(net "PCH_I2C_ALERT_N")
		)
		(pad "2" smd rect
			(at -0.40005 0 270)
			(size 0.4572 0.508)
			(layers "F.Cu" "F.Mask" "F.Paste")
			(net "SMB_LAN2_ALT_N")
		)
	)
	(footprint ""
		(layer "F.Cu")
		(at 72.321166 -96.709992 -90)
		(property "Reference" "R111"
			(at 54.98719 -28.313888 90)
			(unlocked yes)
			(layer "F.SilkS")
			(effects
				(font
					(size 0.7874 0.5842)
					(thickness 0.1524)
				)
				(justify left)
			)
		)
		(property "Value" ""
			(at 0 0 270)
			(layer "F.Fab")
			(effects
				(font
					(size 1.27 1.27)
				)
			)
		)
		(duplicate_pad_numbers_are_jumpers no)
		(fp_line
			(start -0.7874 0.4064)
			(end -0.7874 -0.4064)
			(stroke
				(width 0.1524)
				(type default)
			)
			(layer "F.SilkS")
		)
		(fp_line
			(start 0.7874 0.4064)
			(end -0.7874 0.4064)
			(stroke
				(width 0.1524)
				(type default)
			)
			(layer "F.SilkS")
		)
		(fp_line
			(start -0.7874 -0.4064)
			(end 0.7874 -0.4064)
			(stroke
				(width 0.1524)
				(type default)
			)
			(layer "F.SilkS")
		)
		(fp_line
			(start 0.7874 -0.4064)
			(end 0.7874 0.4064)
			(stroke
				(width 0.1524)
				(type default)
			)
			(layer "F.SilkS")
		)
		(fp_poly
			(pts
				(xy -0.508 0.2794) (xy -0.508 0.2286) (xy -0.635 0.2286) (xy -0.635 -0.254) (xy -0.5334 -0.254)
				(xy -0.5334 -0.2794) (xy 0.5334 -0.2794) (xy 0.5334 -0.254) (xy 0.635 -0.254) (xy 0.635 0.254) (xy 0.5334 0.254)
				(xy 0.5334 0.2794)
			)
			(stroke
				(width 0)
				(type default)
			)
			(fill no)
			(layer "F.CrtYd")
		)
		(pad "1" smd rect
			(at 0.40005 0 270)
			(size 0.4572 0.508)
			(layers "F.Cu" "F.Mask" "F.Paste")
			(net "H_CPU_NODE1_ERR0_R")
		)
		(pad "2" smd rect
			(at -0.40005 0 270)
			(size 0.4572 0.508)
			(layers "F.Cu" "F.Mask" "F.Paste")
			(net "P3V3_NODE1")
		)
	)
	(footprint ""
		(layer "F.Cu")
		(at 5.48513 -167.373554 180)
		(property "Reference" "R1297"
			(at 1.65862 1.044194 0)
			(unlocked yes)
			(layer "F.SilkS")
			(effects
				(font
					(size 0.7874 0.5842)
					(thickness 0.1524)
				)
				(justify left)
			)
		)
		(property "Value" ""
			(at 0 0 180)
			(layer "F.Fab")
			(effects
				(font
					(size 1.27 1.27)
				)
			)
		)
		(duplicate_pad_numbers_are_jumpers no)
		(fp_line
			(start 0.7874 0.4064)
			(end -0.7874 0.4064)
			(stroke
				(width 0.1524)
				(type default)
			)
			(layer "F.SilkS")
		)
		(fp_line
			(start 0.7874 -0.4064)
			(end 0.7874 0.4064)
			(stroke
				(width 0.1524)
				(type default)
			)
			(layer "F.SilkS")
		)
		(fp_line
			(start -0.7874 0.4064)
			(end -0.7874 -0.4064)
			(stroke
				(width 0.1524)
				(type default)
			)
			(layer "F.SilkS")
		)
		(fp_line
			(start -0.7874 -0.4064)
			(end 0.7874 -0.4064)
			(stroke
				(width 0.1524)
				(type default)
			)
			(layer "F.SilkS")
		)
		(fp_poly
			(pts
				(xy -0.508 0.2794) (xy -0.508 0.2286) (xy -0.635 0.2286) (xy -0.635 -0.254) (xy -0.5334 -0.254)
				(xy -0.5334 -0.2794) (xy 0.5334 -0.2794) (xy 0.5334 -0.254) (xy 0.635 -0.254) (xy 0.635 0.254) (xy 0.5334 0.254)
				(xy 0.5334 0.2794)
			)
			(stroke
				(width 0)
				(type default)
			)
			(fill no)
			(layer "F.CrtYd")
		)
		(pad "1" smd rect
			(at 0.40005 0 180)
			(size 0.4572 0.508)
			(layers "F.Cu" "F.Mask" "F.Paste")
			(net "GND")
		)
		(pad "2" smd rect
			(at -0.40005 0 180)
			(size 0.4572 0.508)
			(layers "F.Cu" "F.Mask" "F.Paste")
			(net "N54258454")
		)
	)
	(footprint ""
		(layer "F.Cu")
		(at 148.193252 -138.48715)
		(property "Reference" "R284"
			(at 0.971804 0.110744 0)
			(unlocked yes)
			(layer "F.SilkS")
			(effects
				(font
					(size 0.635 0.4064)
					(thickness 0.1524)
				)
				(justify left)
			)
		)
		(property "Value" ""
			(at 0 0 0)
			(layer "F.Fab")
			(effects
				(font
					(size 1.27 1.27)
				)
			)
		)
		(duplicate_pad_numbers_are_jumpers no)
		(fp_line
			(start -0.7874 -0.4064)
			(end 0.7874 -0.4064)
			(stroke
				(width 0.1524)
				(type default)
			)
			(layer "F.SilkS")
		)
		(fp_line
			(start -0.7874 0.4064)
			(end -0.7874 -0.4064)
			(stroke
				(width 0.1524)
				(type default)
			)
			(layer "F.SilkS")
		)
		(fp_line
			(start 0.7874 -0.4064)
			(end 0.7874 0.4064)
			(stroke
				(width 0.1524)
				(type default)
			)
			(layer "F.SilkS")
		)
		(fp_line
			(start 0.7874 0.4064)
			(end -0.7874 0.4064)
			(stroke
				(width 0.1524)
				(type default)
			)
			(layer "F.SilkS")
		)
		(fp_poly
			(pts
				(xy -0.508 0.2794) (xy -0.508 0.2286) (xy -0.635 0.2286) (xy -0.635 -0.254) (xy -0.5334 -0.254)
				(xy -0.5334 -0.2794) (xy 0.5334 -0.2794) (xy 0.5334 -0.254) (xy 0.635 -0.254) (xy 0.635 0.254) (xy 0.5334 0.254)
				(xy 0.5334 0.2794)
			)
			(stroke
				(width 0)
				(type default)
			)
			(fill no)
			(layer "F.CrtYd")
		)
		(pad "1" smd rect
			(at 0.40005 0)
			(size 0.4572 0.508)
			(layers "F.Cu" "F.Mask" "F.Paste")
			(net "GND")
		)
		(pad "2" smd rect
			(at -0.40005 0)
			(size 0.4572 0.508)
			(layers "F.Cu" "F.Mask" "F.Paste")
			(net "PCIE_SW_TEST4")
		)
	)
	(footprint ""
		(layer "F.Cu")
		(at 177.653442 -142.838424)
		(property "Reference" "C439"
			(at -5.183632 0.136652 0)
			(unlocked yes)
			(layer "F.SilkS")
			(effects
				(font
					(size 0.7874 0.5842)
					(thickness 0.1524)
				)
				(justify left)
			)
		)
		(property "Value" ""
			(at 0 0 0)
			(layer "F.Fab")
			(effects
				(font
					(size 1.27 1.27)
				)
			)
		)
		(duplicate_pad_numbers_are_jumpers no)
		(fp_line
			(start -1.905 -0.8636)
			(end 1.905 -0.8636)
			(stroke
				(width 0.1524)
				(type default)
			)
			(layer "F.SilkS")
		)
		(fp_line
			(start -1.905 0.8636)
			(end -1.905 -0.8636)
			(stroke
				(width 0.1524)
				(type default)
			)
			(layer "F.SilkS")
		)
		(fp_line
			(start 0 0.8382)
			(end 0 -0.8382)
			(stroke
				(width 0.1524)
				(type default)
			)
			(layer "F.SilkS")
		)
		(fp_line
			(start 1.905 -0.8636)
			(end 1.905 0.8636)
			(stroke
				(width 0.1524)
				(type default)
			)
			(layer "F.SilkS")
		)
		(fp_line
			(start 1.905 0.8636)
			(end -1.905 0.8636)
			(stroke
				(width 0.1524)
				(type default)
			)
			(layer "F.SilkS")
		)
		(fp_rect
			(start -1.524 0.7366)
			(end 1.524 -0.7366)
			(stroke
				(width 0)
				(type default)
			)
			(fill no)
			(layer "F.CrtYd")
		)
		(pad "1" smd rect
			(at 0.94996 0)
			(size 1.1176 1.3716)
			(layers "F.Cu" "F.Mask" "F.Paste")
			(net "P3V3_NODE1")
		)
		(pad "2" smd rect
			(at -0.94996 0)
			(size 1.1176 1.3716)
			(layers "F.Cu" "F.Mask" "F.Paste")
			(net "GND")
		)
	)
	(footprint ""
		(layer "F.Cu")
		(at 106.170476 -165.793928)
		(property "Reference" "R771"
			(at 85.286342 69.748146 0)
			(unlocked yes)
			(layer "F.SilkS")
			(effects
				(font
					(size 0.7874 0.5842)
					(thickness 0.1524)
				)
				(justify left)
			)
		)
		(property "Value" ""
			(at 0 0 0)
			(layer "F.Fab")
			(effects
				(font
					(size 1.27 1.27)
				)
			)
		)
		(duplicate_pad_numbers_are_jumpers no)
		(fp_line
			(start -0.7874 -0.4064)
			(end 0.7874 -0.4064)
			(stroke
				(width 0.1524)
				(type default)
			)
			(layer "F.SilkS")
		)
		(fp_line
			(start -0.7874 0.4064)
			(end -0.7874 -0.4064)
			(stroke
				(width 0.1524)
				(type default)
			)
			(layer "F.SilkS")
		)
		(fp_line
			(start 0.7874 -0.4064)
			(end 0.7874 0.4064)
			(stroke
				(width 0.1524)
				(type default)
			)
			(layer "F.SilkS")
		)
		(fp_line
			(start 0.7874 0.4064)
			(end -0.7874 0.4064)
			(stroke
				(width 0.1524)
				(type default)
			)
			(layer "F.SilkS")
		)
		(fp_poly
			(pts
				(xy -0.508 0.2794) (xy -0.508 0.2286) (xy -0.635 0.2286) (xy -0.635 -0.254) (xy -0.5334 -0.254)
				(xy -0.5334 -0.2794) (xy 0.5334 -0.2794) (xy 0.5334 -0.254) (xy 0.635 -0.254) (xy 0.635 0.254) (xy 0.5334 0.254)
				(xy 0.5334 0.2794)
			)
			(stroke
				(width 0)
				(type default)
			)
			(fill no)
			(layer "F.CrtYd")
		)
		(pad "1" smd rect
			(at 0.40005 0)
			(size 0.4572 0.508)
			(layers "F.Cu" "F.Mask" "F.Paste")
			(net "P3V3_NODE1")
		)
		(pad "2" smd rect
			(at -0.40005 0)
			(size 0.4572 0.508)
			(layers "F.Cu" "F.Mask" "F.Paste")
			(net "FNACTRL2_ADD")
		)
	)
	(footprint ""
		(layer "F.Cu")
		(at 123.70816 -165.507416)
		(property "Reference" "R792"
			(at 30.075378 46.17339 0)
			(unlocked yes)
			(layer "F.SilkS")
			(effects
				(font
					(size 0.7874 0.5842)
					(thickness 0.1524)
				)
				(justify left)
			)
		)
		(property "Value" ""
			(at 0 0 0)
			(layer "F.Fab")
			(effects
				(font
					(size 1.27 1.27)
				)
			)
		)
		(duplicate_pad_numbers_are_jumpers no)
		(fp_line
			(start -0.7874 -0.4064)
			(end 0.7874 -0.4064)
			(stroke
				(width 0.1524)
				(type default)
			)
			(layer "F.SilkS")
		)
		(fp_line
			(start -0.7874 0.4064)
			(end -0.7874 -0.4064)
			(stroke
				(width 0.1524)
				(type default)
			)
			(layer "F.SilkS")
		)
		(fp_line
			(start 0.7874 -0.4064)
			(end 0.7874 0.4064)
			(stroke
				(width 0.1524)
				(type default)
			)
			(layer "F.SilkS")
		)
		(fp_line
			(start 0.7874 0.4064)
			(end -0.7874 0.4064)
			(stroke
				(width 0.1524)
				(type default)
			)
			(layer "F.SilkS")
		)
		(fp_poly
			(pts
				(xy -0.508 0.2794) (xy -0.508 0.2286) (xy -0.635 0.2286) (xy -0.635 -0.254) (xy -0.5334 -0.254)
				(xy -0.5334 -0.2794) (xy 0.5334 -0.2794) (xy 0.5334 -0.254) (xy 0.635 -0.254) (xy 0.635 0.254) (xy 0.5334 0.254)
				(xy 0.5334 0.2794)
			)
			(stroke
				(width 0)
				(type default)
			)
			(fill no)
			(layer "F.CrtYd")
		)
		(pad "1" smd rect
			(at 0.40005 0)
			(size 0.4572 0.508)
			(layers "F.Cu" "F.Mask" "F.Paste")
			(net "GND")
		)
		(pad "2" smd rect
			(at -0.40005 0)
			(size 0.4572 0.508)
			(layers "F.Cu" "F.Mask" "F.Paste")
			(net "COM3_WAKEUP")
		)
	)
	(footprint ""
		(layer "F.Cu")
		(at 61.145166 -96.709992 -90)
		(property "Reference" "R52"
			(at 54.98719 -28.524962 90)
			(unlocked yes)
			(layer "F.SilkS")
			(effects
				(font
					(size 0.7874 0.5842)
					(thickness 0.1524)
				)
				(justify left)
			)
		)
		(property "Value" ""
			(at 0 0 270)
			(layer "F.Fab")
			(effects
				(font
					(size 1.27 1.27)
				)
			)
		)
		(duplicate_pad_numbers_are_jumpers no)
		(fp_line
			(start -0.7874 0.4064)
			(end -0.7874 -0.4064)
			(stroke
				(width 0.1524)
				(type default)
			)
			(layer "F.SilkS")
		)
		(fp_line
			(start 0.7874 0.4064)
			(end -0.7874 0.4064)
			(stroke
				(width 0.1524)
				(type default)
			)
			(layer "F.SilkS")
		)
		(fp_line
			(start -0.7874 -0.4064)
			(end 0.7874 -0.4064)
			(stroke
				(width 0.1524)
				(type default)
			)
			(layer "F.SilkS")
		)
		(fp_line
			(start 0.7874 -0.4064)
			(end 0.7874 0.4064)
			(stroke
				(width 0.1524)
				(type default)
			)
			(layer "F.SilkS")
		)
		(fp_poly
			(pts
				(xy -0.508 0.2794) (xy -0.508 0.2286) (xy -0.635 0.2286) (xy -0.635 -0.254) (xy -0.5334 -0.254)
				(xy -0.5334 -0.2794) (xy 0.5334 -0.2794) (xy 0.5334 -0.254) (xy 0.635 -0.254) (xy 0.635 0.254) (xy 0.5334 0.254)
				(xy 0.5334 0.2794)
			)
			(stroke
				(width 0)
				(type default)
			)
			(fill no)
			(layer "F.CrtYd")
		)
		(pad "1" smd rect
			(at 0.40005 0 270)
			(size 0.4572 0.508)
			(layers "F.Cu" "F.Mask" "F.Paste")
			(net "PD_CPU_NODE1_DFX_GPIO_GRP1_4")
		)
		(pad "2" smd rect
			(at -0.40005 0 270)
			(size 0.4572 0.508)
			(layers "F.Cu" "F.Mask" "F.Paste")
			(net "GND")
		)
	)
	(footprint ""
		(layer "F.Cu")
		(at 193.719958 -146.726656 180)
		(property "Reference" "C474"
			(at -2.372868 0.683514 0)
			(unlocked yes)
			(layer "F.SilkS")
			(effects
				(font
					(size 0.7874 0.5842)
					(thickness 0.1524)
				)
				(justify left)
			)
		)
		(property "Value" ""
			(at 0 0 180)
			(layer "F.Fab")
			(effects
				(font
					(size 1.27 1.27)
				)
			)
		)
		(duplicate_pad_numbers_are_jumpers no)
		(fp_line
			(start 1.905 0.8636)
			(end -1.905 0.8636)
			(stroke
				(width 0.1524)
				(type default)
			)
			(layer "F.SilkS")
		)
		(fp_line
			(start 1.905 -0.8636)
			(end 1.905 0.8636)
			(stroke
				(width 0.1524)
				(type default)
			)
			(layer "F.SilkS")
		)
		(fp_line
			(start 0 0.8382)
			(end 0 -0.8382)
			(stroke
				(width 0.1524)
				(type default)
			)
			(layer "F.SilkS")
		)
		(fp_line
			(start -1.905 0.8636)
			(end -1.905 -0.8636)
			(stroke
				(width 0.1524)
				(type default)
			)
			(layer "F.SilkS")
		)
		(fp_line
			(start -1.905 -0.8636)
			(end 1.905 -0.8636)
			(stroke
				(width 0.1524)
				(type default)
			)
			(layer "F.SilkS")
		)
		(fp_rect
			(start -1.524 0.7366)
			(end 1.524 -0.7366)
			(stroke
				(width 0)
				(type default)
			)
			(fill no)
			(layer "F.CrtYd")
		)
		(pad "1" smd rect
			(at 0.94996 0 180)
			(size 1.1176 1.3716)
			(layers "F.Cu" "F.Mask" "F.Paste")
			(net "P1V9_LAN2")
		)
		(pad "2" smd rect
			(at -0.94996 0 180)
			(size 1.1176 1.3716)
			(layers "F.Cu" "F.Mask" "F.Paste")
			(net "GND")
		)
	)
	(footprint ""
		(layer "F.Cu")
		(at 170.036744 -93.866208 180)
		(property "Reference" "C365"
			(at -4.314952 -0.54991 90)
			(unlocked yes)
			(layer "F.SilkS")
			(effects
				(font
					(size 0.7874 0.5842)
					(thickness 0.1524)
				)
				(justify left)
			)
		)
		(property "Value" ""
			(at 0 0 180)
			(layer "F.Fab")
			(effects
				(font
					(size 1.27 1.27)
				)
			)
		)
		(duplicate_pad_numbers_are_jumpers no)
		(fp_line
			(start 0.7874 0.4064)
			(end -0.7874 0.4064)
			(stroke
				(width 0.1524)
				(type default)
			)
			(layer "F.SilkS")
		)
		(fp_line
			(start 0.7874 -0.4064)
			(end 0.7874 0.4064)
			(stroke
				(width 0.1524)
				(type default)
			)
			(layer "F.SilkS")
		)
		(fp_line
			(start 0 0.381)
			(end 0 -0.381)
			(stroke
				(width 0.1524)
				(type default)
			)
			(layer "F.SilkS")
		)
		(fp_line
			(start -0.7874 0.4064)
			(end -0.7874 -0.4064)
			(stroke
				(width 0.1524)
				(type default)
			)
			(layer "F.SilkS")
		)
		(fp_line
			(start -0.7874 -0.4064)
			(end 0.7874 -0.4064)
			(stroke
				(width 0.1524)
				(type default)
			)
			(layer "F.SilkS")
		)
		(fp_poly
			(pts
				(xy -0.5334 0.254) (xy -0.635 0.254) (xy -0.635 0.2286) (xy -0.635 -0.254) (xy -0.5334 -0.254) (xy -0.5334 -0.2794)
				(xy 0.5334 -0.2794) (xy 0.5334 -0.254) (xy 0.635 -0.254) (xy 0.635 0.254) (xy 0.5334 0.254) (xy 0.5334 0.2794)
				(xy -0.508 0.2794) (xy -0.5334 0.2794)
			)
			(stroke
				(width 0)
				(type default)
			)
			(fill no)
			(layer "F.CrtYd")
		)
		(pad "1" smd rect
			(at 0.40005 0 180)
			(size 0.4572 0.508)
			(layers "F.Cu" "F.Mask" "F.Paste")
			(net "USB_NODE1_XTA1")
		)
		(pad "2" smd rect
			(at -0.40005 0 180)
			(size 0.4572 0.508)
			(layers "F.Cu" "F.Mask" "F.Paste")
			(net "GND")
		)
	)
	(footprint ""
		(layer "F.Cu")
		(at 53.7718 -100.866956 -90)
		(property "Reference" "C138"
			(at -0.702564 -1.347724 90)
			(unlocked yes)
			(layer "F.SilkS")
			(effects
				(font
					(size 0.7874 0.5842)
					(thickness 0.1524)
				)
				(justify left)
			)
		)
		(property "Value" ""
			(at 0 0 270)
			(layer "F.Fab")
			(effects
				(font
					(size 1.27 1.27)
				)
			)
		)
		(duplicate_pad_numbers_are_jumpers no)
		(fp_line
			(start -0.7874 0.4064)
			(end -0.7874 -0.4064)
			(stroke
				(width 0.1524)
				(type default)
			)
			(layer "F.SilkS")
		)
		(fp_line
			(start 0.7874 0.4064)
			(end -0.7874 0.4064)
			(stroke
				(width 0.1524)
				(type default)
			)
			(layer "F.SilkS")
		)
		(fp_line
			(start 0 0.381)
			(end 0 -0.381)
			(stroke
				(width 0.1524)
				(type default)
			)
			(layer "F.SilkS")
		)
		(fp_line
			(start -0.7874 -0.4064)
			(end 0.7874 -0.4064)
			(stroke
				(width 0.1524)
				(type default)
			)
			(layer "F.SilkS")
		)
		(fp_line
			(start 0.7874 -0.4064)
			(end 0.7874 0.4064)
			(stroke
				(width 0.1524)
				(type default)
			)
			(layer "F.SilkS")
		)
		(fp_poly
			(pts
				(xy -0.5334 0.254) (xy -0.635 0.254) (xy -0.635 0.2286) (xy -0.635 -0.254) (xy -0.5334 -0.254) (xy -0.5334 -0.2794)
				(xy 0.5334 -0.2794) (xy 0.5334 -0.254) (xy 0.635 -0.254) (xy 0.635 0.254) (xy 0.5334 0.254) (xy 0.5334 0.2794)
				(xy -0.508 0.2794) (xy -0.5334 0.2794)
			)
			(stroke
				(width 0)
				(type default)
			)
			(fill no)
			(layer "F.CrtYd")
		)
		(pad "1" smd rect
			(at 0.40005 0 270)
			(size 0.4572 0.508)
			(layers "F.Cu" "F.Mask" "F.Paste")
			(net "A_CPU1_NODE1_THERMDA")
		)
		(pad "2" smd rect
			(at -0.40005 0 270)
			(size 0.4572 0.508)
			(layers "F.Cu" "F.Mask" "F.Paste")
			(net "A_CPU1_NODE1_THERMDC")
		)
	)
	(footprint ""
		(layer "F.Cu")
		(at 98.389948 -138.41349 -90)
		(property "Reference" "C812"
			(at 0.82296 -1.559052 90)
			(unlocked yes)
			(layer "F.SilkS")
			(effects
				(font
					(size 0.7874 0.5842)
					(thickness 0.1524)
				)
				(justify left)
			)
		)
		(property "Value" ""
			(at 0 0 270)
			(layer "F.Fab")
			(effects
				(font
					(size 1.27 1.27)
				)
			)
		)
		(duplicate_pad_numbers_are_jumpers no)
		(fp_line
			(start -1.905 0.8636)
			(end -1.905 -0.8636)
			(stroke
				(width 0.1524)
				(type default)
			)
			(layer "F.SilkS")
		)
		(fp_line
			(start 1.905 0.8636)
			(end -1.905 0.8636)
			(stroke
				(width 0.1524)
				(type default)
			)
			(layer "F.SilkS")
		)
		(fp_line
			(start 0 0.8382)
			(end 0 -0.8382)
			(stroke
				(width 0.1524)
				(type default)
			)
			(layer "F.SilkS")
		)
		(fp_line
			(start -1.905 -0.8636)
			(end 1.905 -0.8636)
			(stroke
				(width 0.1524)
				(type default)
			)
			(layer "F.SilkS")
		)
		(fp_line
			(start 1.905 -0.8636)
			(end 1.905 0.8636)
			(stroke
				(width 0.1524)
				(type default)
			)
			(layer "F.SilkS")
		)
		(fp_rect
			(start -1.524 0.7366)
			(end 1.524 -0.7366)
			(stroke
				(width 0)
				(type default)
			)
			(fill no)
			(layer "F.CrtYd")
		)
		(pad "1" smd rect
			(at 0.94996 0 270)
			(size 1.1176 1.3716)
			(layers "F.Cu" "F.Mask" "F.Paste")
			(net "P1V05_SUS_NODE1")
		)
		(pad "2" smd rect
			(at -0.94996 0 270)
			(size 1.1176 1.3716)
			(layers "F.Cu" "F.Mask" "F.Paste")
			(net "GND")
		)
	)
	(footprint ""
		(layer "F.Cu")
		(at 114.537998 -123.911106 90)
		(property "Reference" "PC89"
			(at -1.144016 5.335524 90)
			(unlocked yes)
			(layer "F.SilkS")
			(effects
				(font
					(size 0.7874 0.5842)
					(thickness 0.1524)
				)
				(justify left)
			)
		)
		(property "Value" ""
			(at 0 0 90)
			(layer "F.Fab")
			(effects
				(font
					(size 1.27 1.27)
				)
			)
		)
		(duplicate_pad_numbers_are_jumpers no)
		(fp_line
			(start 0.7874 -0.4064)
			(end 0.7874 0.4064)
			(stroke
				(width 0.1524)
				(type default)
			)
			(layer "F.SilkS")
		)
		(fp_line
			(start -0.7874 -0.4064)
			(end 0.7874 -0.4064)
			(stroke
				(width 0.1524)
				(type default)
			)
			(layer "F.SilkS")
		)
		(fp_line
			(start 0 0.381)
			(end 0 -0.381)
			(stroke
				(width 0.1524)
				(type default)
			)
			(layer "F.SilkS")
		)
		(fp_line
			(start 0.7874 0.4064)
			(end -0.7874 0.4064)
			(stroke
				(width 0.1524)
				(type default)
			)
			(layer "F.SilkS")
		)
		(fp_line
			(start -0.7874 0.4064)
			(end -0.7874 -0.4064)
			(stroke
				(width 0.1524)
				(type default)
			)
			(layer "F.SilkS")
		)
		(fp_poly
			(pts
				(xy -0.5334 0.254) (xy -0.635 0.254) (xy -0.635 0.2286) (xy -0.635 -0.254) (xy -0.5334 -0.254) (xy -0.5334 -0.2794)
				(xy 0.5334 -0.2794) (xy 0.5334 -0.254) (xy 0.635 -0.254) (xy 0.635 0.254) (xy 0.5334 0.254) (xy 0.5334 0.2794)
				(xy -0.508 0.2794) (xy -0.5334 0.2794)
			)
			(stroke
				(width 0)
				(type default)
			)
			(fill no)
			(layer "F.CrtYd")
		)
		(pad "1" smd rect
			(at 0.40005 0 90)
			(size 0.4572 0.508)
			(layers "F.Cu" "F.Mask" "F.Paste")
			(net "SW_VR_PVCCP_NODE1_VIN_FLT")
		)
		(pad "2" smd rect
			(at -0.40005 0 90)
			(size 0.4572 0.508)
			(layers "F.Cu" "F.Mask" "F.Paste")
			(net "GND")
		)
	)
	(footprint ""
		(layer "F.Cu")
		(at 65.253108 -112.672368 180)
		(property "Reference" "R1111"
			(at 4.968748 0.0254 0)
			(unlocked yes)
			(layer "F.SilkS")
			(effects
				(font
					(size 0.7874 0.5842)
					(thickness 0.1524)
				)
				(justify left)
			)
		)
		(property "Value" ""
			(at 0 0 180)
			(layer "F.Fab")
			(effects
				(font
					(size 1.27 1.27)
				)
			)
		)
		(duplicate_pad_numbers_are_jumpers no)
		(fp_line
			(start 0.7874 0.4064)
			(end -0.7874 0.4064)
			(stroke
				(width 0.1524)
				(type default)
			)
			(layer "F.SilkS")
		)
		(fp_line
			(start 0.7874 -0.4064)
			(end 0.7874 0.4064)
			(stroke
				(width 0.1524)
				(type default)
			)
			(layer "F.SilkS")
		)
		(fp_line
			(start -0.7874 0.4064)
			(end -0.7874 -0.4064)
			(stroke
				(width 0.1524)
				(type default)
			)
			(layer "F.SilkS")
		)
		(fp_line
			(start -0.7874 -0.4064)
			(end 0.7874 -0.4064)
			(stroke
				(width 0.1524)
				(type default)
			)
			(layer "F.SilkS")
		)
		(fp_poly
			(pts
				(xy -0.508 0.2794) (xy -0.508 0.2286) (xy -0.635 0.2286) (xy -0.635 -0.254) (xy -0.5334 -0.254)
				(xy -0.5334 -0.2794) (xy 0.5334 -0.2794) (xy 0.5334 -0.254) (xy 0.635 -0.254) (xy 0.635 0.254) (xy 0.5334 0.254)
				(xy 0.5334 0.2794)
			)
			(stroke
				(width 0)
				(type default)
			)
			(fill no)
			(layer "F.CrtYd")
		)
		(pad "1" smd rect
			(at 0.40005 0 180)
			(size 0.4572 0.508)
			(layers "F.Cu" "F.Mask" "F.Paste")
			(net "P5V_STB_NODE1")
		)
		(pad "2" smd rect
			(at -0.40005 0 180)
			(size 0.4572 0.508)
			(layers "F.Cu" "F.Mask" "F.Paste")
			(net "FM_CPLD_NODE1_P1V8_EN_LV")
		)
	)
	(footprint ""
		(layer "F.Cu")
		(at 106.426508 -178.984656)
		(property "Reference" "C573"
			(at -0.442468 -4.012692 0)
			(unlocked yes)
			(layer "F.SilkS")
			(effects
				(font
					(size 0.7874 0.5842)
					(thickness 0.1524)
				)
				(justify left)
			)
		)
		(property "Value" ""
			(at 0 0 0)
			(layer "F.Fab")
			(effects
				(font
					(size 1.27 1.27)
				)
			)
		)
		(duplicate_pad_numbers_are_jumpers no)
		(fp_line
			(start -0.7874 -0.4064)
			(end 0.7874 -0.4064)
			(stroke
				(width 0.1524)
				(type default)
			)
			(layer "F.SilkS")
		)
		(fp_line
			(start -0.7874 0.4064)
			(end -0.7874 -0.4064)
			(stroke
				(width 0.1524)
				(type default)
			)
			(layer "F.SilkS")
		)
		(fp_line
			(start 0 0.381)
			(end 0 -0.381)
			(stroke
				(width 0.1524)
				(type default)
			)
			(layer "F.SilkS")
		)
		(fp_line
			(start 0.7874 -0.4064)
			(end 0.7874 0.4064)
			(stroke
				(width 0.1524)
				(type default)
			)
			(layer "F.SilkS")
		)
		(fp_line
			(start 0.7874 0.4064)
			(end -0.7874 0.4064)
			(stroke
				(width 0.1524)
				(type default)
			)
			(layer "F.SilkS")
		)
		(fp_poly
			(pts
				(xy -0.5334 0.254) (xy -0.635 0.254) (xy -0.635 0.2286) (xy -0.635 -0.254) (xy -0.5334 -0.254) (xy -0.5334 -0.2794)
				(xy 0.5334 -0.2794) (xy 0.5334 -0.254) (xy 0.635 -0.254) (xy 0.635 0.254) (xy 0.5334 0.254) (xy 0.5334 0.2794)
				(xy -0.508 0.2794) (xy -0.5334 0.2794)
			)
			(stroke
				(width 0)
				(type default)
			)
			(fill no)
			(layer "F.CrtYd")
		)
		(pad "1" smd rect
			(at 0.40005 0)
			(size 0.4572 0.508)
			(layers "F.Cu" "F.Mask" "F.Paste")
			(net "GND")
		)
		(pad "2" smd rect
			(at -0.40005 0)
			(size 0.4572 0.508)
			(layers "F.Cu" "F.Mask" "F.Paste")
			(net "P3V3_NODE1")
		)
	)
	(footprint ""
		(layer "F.Cu")
		(at 78.522068 -94.131892 90)
		(property "Reference" "R156"
			(at -55.53329 24.090122 90)
			(unlocked yes)
			(layer "F.SilkS")
			(effects
				(font
					(size 0.7874 0.5842)
					(thickness 0.1524)
				)
				(justify left)
			)
		)
		(property "Value" ""
			(at 0 0 90)
			(layer "F.Fab")
			(effects
				(font
					(size 1.27 1.27)
				)
			)
		)
		(duplicate_pad_numbers_are_jumpers no)
		(fp_line
			(start 0.7874 -0.4064)
			(end 0.7874 0.4064)
			(stroke
				(width 0.1524)
				(type default)
			)
			(layer "F.SilkS")
		)
		(fp_line
			(start -0.7874 -0.4064)
			(end 0.7874 -0.4064)
			(stroke
				(width 0.1524)
				(type default)
			)
			(layer "F.SilkS")
		)
		(fp_line
			(start 0.7874 0.4064)
			(end -0.7874 0.4064)
			(stroke
				(width 0.1524)
				(type default)
			)
			(layer "F.SilkS")
		)
		(fp_line
			(start -0.7874 0.4064)
			(end -0.7874 -0.4064)
			(stroke
				(width 0.1524)
				(type default)
			)
			(layer "F.SilkS")
		)
		(fp_poly
			(pts
				(xy -0.508 0.2794) (xy -0.508 0.2286) (xy -0.635 0.2286) (xy -0.635 -0.254) (xy -0.5334 -0.254)
				(xy -0.5334 -0.2794) (xy 0.5334 -0.2794) (xy 0.5334 -0.254) (xy 0.635 -0.254) (xy 0.635 0.254) (xy 0.5334 0.254)
				(xy 0.5334 0.2794)
			)
			(stroke
				(width 0)
				(type default)
			)
			(fill no)
			(layer "F.CrtYd")
		)
		(pad "1" smd rect
			(at 0.40005 0 90)
			(size 0.4572 0.508)
			(layers "F.Cu" "F.Mask" "F.Paste")
			(net "GND")
		)
		(pad "2" smd rect
			(at -0.40005 0 90)
			(size 0.4572 0.508)
			(layers "F.Cu" "F.Mask" "F.Paste")
			(net "PU_CPU_NODE1_BRD_ID0")
		)
	)
	(footprint ""
		(layer "F.Cu")
		(at 116.007388 -135.617204 -90)
		(property "Reference" "PR66"
			(at -2.629916 -5.241798 90)
			(unlocked yes)
			(layer "F.SilkS")
			(effects
				(font
					(size 0.635 0.4064)
					(thickness 0.1524)
				)
				(justify left)
			)
		)
		(property "Value" ""
			(at 0 0 270)
			(layer "F.Fab")
			(effects
				(font
					(size 1.27 1.27)
				)
			)
		)
		(duplicate_pad_numbers_are_jumpers no)
		(fp_line
			(start -0.7874 0.4064)
			(end -0.7874 -0.4064)
			(stroke
				(width 0.1524)
				(type default)
			)
			(layer "F.SilkS")
		)
		(fp_line
			(start 0.7874 0.4064)
			(end -0.7874 0.4064)
			(stroke
				(width 0.1524)
				(type default)
			)
			(layer "F.SilkS")
		)
		(fp_line
			(start -0.7874 -0.4064)
			(end 0.7874 -0.4064)
			(stroke
				(width 0.1524)
				(type default)
			)
			(layer "F.SilkS")
		)
		(fp_line
			(start 0.7874 -0.4064)
			(end 0.7874 0.4064)
			(stroke
				(width 0.1524)
				(type default)
			)
			(layer "F.SilkS")
		)
		(fp_poly
			(pts
				(xy -0.508 0.2794) (xy -0.508 0.2286) (xy -0.635 0.2286) (xy -0.635 -0.254) (xy -0.5334 -0.254)
				(xy -0.5334 -0.2794) (xy 0.5334 -0.2794) (xy 0.5334 -0.254) (xy 0.635 -0.254) (xy 0.635 0.254) (xy 0.5334 0.254)
				(xy 0.5334 0.2794)
			)
			(stroke
				(width 0)
				(type default)
			)
			(fill no)
			(layer "F.CrtYd")
		)
		(pad "1" smd rect
			(at 0.40005 0 270)
			(size 0.4572 0.508)
			(layers "F.Cu" "F.Mask" "F.Paste")
			(net "VR_PVCCP_NODE1_COMP_RC")
		)
		(pad "2" smd rect
			(at -0.40005 0 270)
			(size 0.4572 0.508)
			(layers "F.Cu" "F.Mask" "F.Paste")
			(net "VR_PVCCP_NODE1_FB")
		)
	)
	(footprint ""
		(layer "F.Cu")
		(at 41.303448 -12.945872)
		(property "Reference" "PC76"
			(at 1.017524 -2.261108 90)
			(unlocked yes)
			(layer "F.SilkS")
			(effects
				(font
					(size 0.7874 0.5842)
					(thickness 0.1524)
				)
			)
		)
		(property "Value" ""
			(at 0 0 0)
			(layer "F.Fab")
			(effects
				(font
					(size 1.27 1.27)
				)
			)
		)
		(duplicate_pad_numbers_are_jumpers no)
		(fp_line
			(start -1.2954 -0.5842)
			(end 1.2954 -0.5842)
			(stroke
				(width 0.1524)
				(type default)
			)
			(layer "F.SilkS")
		)
		(fp_line
			(start -1.2954 0.5842)
			(end -1.2954 -0.5842)
			(stroke
				(width 0.1524)
				(type default)
			)
			(layer "F.SilkS")
		)
		(fp_line
			(start 0 -0.5842)
			(end 0 0.5842)
			(stroke
				(width 0.1524)
				(type default)
			)
			(layer "F.SilkS")
		)
		(fp_line
			(start 1.2954 -0.5842)
			(end 1.2954 0.5842)
			(stroke
				(width 0.1524)
				(type default)
			)
			(layer "F.SilkS")
		)
		(fp_line
			(start 1.2954 0.5842)
			(end -1.2954 0.5842)
			(stroke
				(width 0.1524)
				(type default)
			)
			(layer "F.SilkS")
		)
		(fp_poly
			(pts
				(xy 0.8636 -0.4572) (xy 0.8636 -0.3556) (xy 1.143 -0.3556) (xy 1.143 0.3556) (xy 0.8636 0.3556)
				(xy 0.8636 0.4572) (xy -0.8636 0.4572) (xy -0.8636 0.3556) (xy -1.143 0.3556) (xy -1.143 -0.3556)
				(xy -0.8636 -0.3556) (xy -0.8636 -0.4572)
			)
			(stroke
				(width 0)
				(type default)
			)
			(fill no)
			(layer "F.CrtYd")
		)
		(fp_line
			(start -0.884936 -0.504952)
			(end 0.884936 -0.504952)
			(stroke
				(width 0.1)
				(type default)
			)
			(layer "F.Fab")
		)
		(fp_line
			(start -0.884936 0.504952)
			(end -0.884936 -0.504952)
			(stroke
				(width 0.1)
				(type default)
			)
			(layer "F.Fab")
		)
		(fp_line
			(start 0.884936 -0.504952)
			(end 0.884936 0.504952)
			(stroke
				(width 0.1)
				(type default)
			)
			(layer "F.Fab")
		)
		(fp_line
			(start 0.884936 0.504952)
			(end -0.884936 0.504952)
			(stroke
				(width 0.1)
				(type default)
			)
			(layer "F.Fab")
		)
		(pad "1" smd rect
			(at 0.7366 0 90)
			(size 0.7112 0.8128)
			(layers "F.Cu" "F.Mask" "F.Paste")
			(net "GND")
		)
		(pad "2" smd rect
			(at -0.7366 0 90)
			(size 0.7112 0.8128)
			(layers "F.Cu" "F.Mask" "F.Paste")
			(net "P5V_STB_NODE1")
		)
	)
	(footprint ""
		(layer "F.Cu")
		(at 143.36776 -185.205624 90)
		(property "Reference" "C762"
			(at 4.768088 -0.544068 90)
			(unlocked yes)
			(layer "F.SilkS")
			(effects
				(font
					(size 0.7874 0.5842)
					(thickness 0.1524)
				)
				(justify left)
			)
		)
		(property "Value" ""
			(at 0 0 90)
			(layer "F.Fab")
			(effects
				(font
					(size 1.27 1.27)
				)
			)
		)
		(duplicate_pad_numbers_are_jumpers no)
		(fp_line
			(start 0.7874 -0.4064)
			(end 0.7874 0.4064)
			(stroke
				(width 0.1524)
				(type default)
			)
			(layer "F.SilkS")
		)
		(fp_line
			(start -0.7874 -0.4064)
			(end 0.7874 -0.4064)
			(stroke
				(width 0.1524)
				(type default)
			)
			(layer "F.SilkS")
		)
		(fp_line
			(start 0 0.381)
			(end 0 -0.381)
			(stroke
				(width 0.1524)
				(type default)
			)
			(layer "F.SilkS")
		)
		(fp_line
			(start 0.7874 0.4064)
			(end -0.7874 0.4064)
			(stroke
				(width 0.1524)
				(type default)
			)
			(layer "F.SilkS")
		)
		(fp_line
			(start -0.7874 0.4064)
			(end -0.7874 -0.4064)
			(stroke
				(width 0.1524)
				(type default)
			)
			(layer "F.SilkS")
		)
		(fp_poly
			(pts
				(xy -0.5334 0.254) (xy -0.635 0.254) (xy -0.635 0.2286) (xy -0.635 -0.254) (xy -0.5334 -0.254) (xy -0.5334 -0.2794)
				(xy 0.5334 -0.2794) (xy 0.5334 -0.254) (xy 0.635 -0.254) (xy 0.635 0.254) (xy 0.5334 0.254) (xy 0.5334 0.2794)
				(xy -0.508 0.2794) (xy -0.5334 0.2794)
			)
			(stroke
				(width 0)
				(type default)
			)
			(fill no)
			(layer "F.CrtYd")
		)
		(pad "1" smd rect
			(at 0.40005 0 90)
			(size 0.4572 0.508)
			(layers "F.Cu" "F.Mask" "F.Paste")
			(net "UART_T12_NODE4_RXD")
		)
		(pad "2" smd rect
			(at -0.40005 0 90)
			(size 0.4572 0.508)
			(layers "F.Cu" "F.Mask" "F.Paste")
			(net "GND")
		)
	)
	(footprint ""
		(layer "F.Cu")
		(at 109.45876 -185.205624 -90)
		(property "Reference" "R890"
			(at -4.768088 -0.724408 90)
			(unlocked yes)
			(layer "F.SilkS")
			(effects
				(font
					(size 0.7874 0.5842)
					(thickness 0.1524)
				)
				(justify left)
			)
		)
		(property "Value" ""
			(at 0 0 270)
			(layer "F.Fab")
			(effects
				(font
					(size 1.27 1.27)
				)
			)
		)
		(duplicate_pad_numbers_are_jumpers no)
		(fp_line
			(start -0.7874 0.4064)
			(end -0.7874 -0.4064)
			(stroke
				(width 0.1524)
				(type default)
			)
			(layer "F.SilkS")
		)
		(fp_line
			(start 0.7874 0.4064)
			(end -0.7874 0.4064)
			(stroke
				(width 0.1524)
				(type default)
			)
			(layer "F.SilkS")
		)
		(fp_line
			(start -0.7874 -0.4064)
			(end 0.7874 -0.4064)
			(stroke
				(width 0.1524)
				(type default)
			)
			(layer "F.SilkS")
		)
		(fp_line
			(start 0.7874 -0.4064)
			(end 0.7874 0.4064)
			(stroke
				(width 0.1524)
				(type default)
			)
			(layer "F.SilkS")
		)
		(fp_poly
			(pts
				(xy -0.508 0.2794) (xy -0.508 0.2286) (xy -0.635 0.2286) (xy -0.635 -0.254) (xy -0.5334 -0.254)
				(xy -0.5334 -0.2794) (xy 0.5334 -0.2794) (xy 0.5334 -0.254) (xy 0.635 -0.254) (xy 0.635 0.254) (xy 0.5334 0.254)
				(xy 0.5334 0.2794)
			)
			(stroke
				(width 0)
				(type default)
			)
			(fill no)
			(layer "F.CrtYd")
		)
		(pad "1" smd rect
			(at 0.40005 0 270)
			(size 0.4572 0.508)
			(layers "F.Cu" "F.Mask" "F.Paste")
			(net "T6_NODE3_EN")
		)
		(pad "2" smd rect
			(at -0.40005 0 270)
			(size 0.4572 0.508)
			(layers "F.Cu" "F.Mask" "F.Paste")
			(net "T6_NODE3_EN_R")
		)
	)
	(footprint ""
		(layer "F.Cu")
		(at 161.762694 -131.24942)
		(property "Reference" "R1032"
			(at -1.957578 -1.021334 0)
			(unlocked yes)
			(layer "F.SilkS")
			(effects
				(font
					(size 0.7874 0.5842)
					(thickness 0.1524)
				)
				(justify left)
			)
		)
		(property "Value" ""
			(at 0 0 0)
			(layer "F.Fab")
			(effects
				(font
					(size 1.27 1.27)
				)
			)
		)
		(duplicate_pad_numbers_are_jumpers no)
		(fp_line
			(start -0.7874 -0.4064)
			(end 0.7874 -0.4064)
			(stroke
				(width 0.1524)
				(type default)
			)
			(layer "F.SilkS")
		)
		(fp_line
			(start -0.7874 0.4064)
			(end -0.7874 -0.4064)
			(stroke
				(width 0.1524)
				(type default)
			)
			(layer "F.SilkS")
		)
		(fp_line
			(start 0.7874 -0.4064)
			(end 0.7874 0.4064)
			(stroke
				(width 0.1524)
				(type default)
			)
			(layer "F.SilkS")
		)
		(fp_line
			(start 0.7874 0.4064)
			(end -0.7874 0.4064)
			(stroke
				(width 0.1524)
				(type default)
			)
			(layer "F.SilkS")
		)
		(fp_poly
			(pts
				(xy -0.508 0.2794) (xy -0.508 0.2286) (xy -0.635 0.2286) (xy -0.635 -0.254) (xy -0.5334 -0.254)
				(xy -0.5334 -0.2794) (xy 0.5334 -0.2794) (xy 0.5334 -0.254) (xy 0.635 -0.254) (xy 0.635 0.254) (xy 0.5334 0.254)
				(xy 0.5334 0.2794)
			)
			(stroke
				(width 0)
				(type default)
			)
			(fill no)
			(layer "F.CrtYd")
		)
		(pad "1" smd rect
			(at 0.40005 0)
			(size 0.4572 0.508)
			(layers "F.Cu" "F.Mask" "F.Paste")
			(net "P3V3_STB_NODE1")
		)
		(pad "2" smd rect
			(at -0.40005 0)
			(size 0.4572 0.508)
			(layers "F.Cu" "F.Mask" "F.Paste")
			(net "LED_CPU_NODE1_CPLD_D")
		)
	)
	(footprint ""
		(layer "F.Cu")
		(at 65.741804 -134.859522 -90)
		(property "Reference" "U14"
			(at 12.258294 13.71092 90)
			(unlocked yes)
			(layer "F.SilkS")
			(effects
				(font
					(size 1.6002 1.1938)
					(thickness 0.1524)
				)
				(justify left)
			)
		)
		(property "Value" ""
			(at 0 0 270)
			(layer "F.Fab")
			(effects
				(font
					(size 1.27 1.27)
				)
			)
		)
		(duplicate_pad_numbers_are_jumpers no)
		(fp_line
			(start -12.549886 12.549886)
			(end -12.549886 -12.549886)
			(stroke
				(width 0.1524)
				(type default)
			)
			(layer "F.SilkS")
		)
		(fp_line
			(start -8.42772 12.549886)
			(end -12.549886 12.549886)
			(stroke
				(width 0.1524)
				(type default)
			)
			(layer "F.SilkS")
		)
		(fp_line
			(start -3.22072 12.549886)
			(end -7.15772 12.549886)
			(stroke
				(width 0.1524)
				(type default)
			)
			(layer "F.SilkS")
		)
		(fp_line
			(start 12.549886 12.549886)
			(end -2.58572 12.549886)
			(stroke
				(width 0.1524)
				(type default)
			)
			(layer "F.SilkS")
		)
		(fp_line
			(start -9.549892 9.549892)
			(end -9.549892 -9.549892)
			(stroke
				(width 0.1524)
				(type default)
			)
			(layer "F.SilkS")
		)
		(fp_line
			(start 9.549892 9.549892)
			(end -9.549892 9.549892)
			(stroke
				(width 0.1524)
				(type default)
			)
			(layer "F.SilkS")
		)
		(fp_line
			(start 12.549886 5.559552)
			(end 12.549886 12.549886)
			(stroke
				(width 0.1524)
				(type default)
			)
			(layer "F.SilkS")
		)
		(fp_line
			(start -9.549892 -9.549892)
			(end 9.549892 -9.549892)
			(stroke
				(width 0.1524)
				(type default)
			)
			(layer "F.SilkS")
		)
		(fp_line
			(start 9.549892 -9.549892)
			(end 9.549892 9.549892)
			(stroke
				(width 0.1524)
				(type default)
			)
			(layer "F.SilkS")
		)
		(fp_line
			(start -12.549886 -12.549886)
			(end 12.549886 -12.549886)
			(stroke
				(width 0.1524)
				(type default)
			)
			(layer "F.SilkS")
		)
		(fp_line
			(start 12.549886 -12.549886)
			(end 12.549886 4.416552)
			(stroke
				(width 0.1524)
				(type default)
			)
			(layer "F.SilkS")
		)
		(fp_poly
			(pts
				(xy -12.513818 -12.577318) (xy -8.773668 -12.577318) (xy -8.773668 -12.482068) (xy -9.973818 -11.281918)
				(xy -8.31215 -9.62025) (xy -8.352282 -9.580118) (xy -9.542018 -9.580118) (xy -9.542018 -8.415782)
				(xy -9.5504 -8.4074) (xy -9.59485 -8.36295) (xy -11.243818 -10.011918) (xy -12.469368 -8.786368)
				(xy -12.513818 -8.786368)
			)
			(stroke
				(width 0)
				(type default)
			)
			(fill yes)
			(layer "F.SilkS")
		)
		(fp_poly
			(pts
				(xy -9.549892 9.549892) (xy 9.549892 9.549892) (xy 9.549892 -9.549892) (xy -9.549892 -9.549892)
			)
			(stroke
				(width 0)
				(type default)
			)
			(fill no)
			(layer "F.CrtYd")
		)
		(fp_line
			(start -9.549892 9.549892)
			(end -9.549892 -9.549892)
			(stroke
				(width 0.1)
				(type default)
			)
			(layer "F.Fab")
		)
		(fp_line
			(start 9.549892 9.549892)
			(end -9.549892 9.549892)
			(stroke
				(width 0.1)
				(type default)
			)
			(layer "F.Fab")
		)
		(fp_line
			(start -9.549892 -9.549892)
			(end 9.549892 -9.549892)
			(stroke
				(width 0.1)
				(type default)
			)
			(layer "F.Fab")
		)
		(fp_line
			(start 9.549892 -9.549892)
			(end 9.549892 9.549892)
			(stroke
				(width 0.1)
				(type default)
			)
			(layer "F.Fab")
		)
		(fp_poly
			(pts
				(xy -12.513818 -12.577318) (xy -8.773668 -12.577318) (xy -8.773668 -12.482068) (xy -9.973818 -11.281918)
				(xy -8.31215 -9.62025) (xy -8.352282 -9.580118) (xy -9.542018 -9.580118) (xy -9.542018 -8.415782)
				(xy -9.59485 -8.36295) (xy -11.243818 -10.011918) (xy -12.469368 -8.786368) (xy -12.513818 -8.786368)
			)
			(stroke
				(width 0)
				(type default)
			)
			(fill yes)
			(layer "F.Fab")
		)
		(fp_text user "AB"
			(at -9.95172 8.961882 90)
			(unlocked yes)
			(layer "F.SilkS")
			(effects
				(font
					(size 0.7874 0.5842)
					(thickness 0.1524)
				)
				(justify left)
			)
		)
		(fp_text user "AA"
			(at -10.84072 6.802882 90)
			(unlocked yes)
			(layer "F.SilkS")
			(effects
				(font
					(size 0.7874 0.5842)
					(thickness 0.1524)
				)
				(justify left)
			)
		)
		(fp_text user "Y"
			(at -10.05713 6.5278 90)
			(unlocked yes)
			(layer "F.SilkS")
			(effects
				(font
					(size 0.7874 0.5842)
					(thickness 0.1524)
				)
				(justify left)
			)
		)
		(fp_text user "W"
			(at -11.657076 5.7277 90)
			(unlocked yes)
			(layer "F.SilkS")
			(effects
				(font
					(size 0.7874 0.5842)
					(thickness 0.1524)
				)
				(justify left)
			)
		)
		(fp_text user "V"
			(at -10.05713 4.927854 90)
			(unlocked yes)
			(layer "F.SilkS")
			(effects
				(font
					(size 0.7874 0.5842)
					(thickness 0.1524)
				)
				(justify left)
			)
		)
		(fp_text user "U"
			(at -11.657076 4.127754 90)
			(unlocked yes)
			(layer "F.SilkS")
			(effects
				(font
					(size 0.7874 0.5842)
					(thickness 0.1524)
				)
				(justify left)
			)
		)
		(fp_text user "T"
			(at -10.05713 3.327908 90)
			(unlocked yes)
			(layer "F.SilkS")
			(effects
				(font
					(size 0.7874 0.5842)
					(thickness 0.1524)
				)
				(justify left)
			)
		)
		(fp_text user "R"
			(at -11.657076 2.527808 90)
			(unlocked yes)
			(layer "F.SilkS")
			(effects
				(font
					(size 0.7874 0.5842)
					(thickness 0.1524)
				)
				(justify left)
			)
		)
		(fp_text user "P"
			(at -10.05713 1.727708 90)
			(unlocked yes)
			(layer "F.SilkS")
			(effects
				(font
					(size 0.7874 0.5842)
					(thickness 0.1524)
				)
				(justify left)
			)
		)
		(fp_text user "N"
			(at -11.60272 1.468882 90)
			(unlocked yes)
			(layer "F.SilkS")
			(effects
				(font
					(size 0.7874 0.5842)
					(thickness 0.1524)
				)
				(justify left)
			)
		)
		(fp_text user "M"
			(at -10.05713 0.127762 90)
			(unlocked yes)
			(layer "F.SilkS")
			(effects
				(font
					(size 0.7874 0.5842)
					(thickness 0.1524)
				)
				(justify left)
			)
		)
		(fp_text user "L"
			(at -11.657076 -0.672084 90)
			(unlocked yes)
			(layer "F.SilkS")
			(effects
				(font
					(size 0.7874 0.5842)
					(thickness 0.1524)
				)
				(justify left)
			)
		)
		(fp_text user "K"
			(at -10.05713 -1.472184 90)
			(unlocked yes)
			(layer "F.SilkS")
			(effects
				(font
					(size 0.7874 0.5842)
					(thickness 0.1524)
				)
				(justify left)
			)
		)
		(fp_text user "J"
			(at -11.72972 -1.833118 90)
			(unlocked yes)
			(layer "F.SilkS")
			(effects
				(font
					(size 0.7874 0.5842)
					(thickness 0.1524)
				)
				(justify left)
			)
		)
		(fp_text user "H"
			(at -10.05713 -3.07213 90)
			(unlocked yes)
			(layer "F.SilkS")
			(effects
				(font
					(size 0.7874 0.5842)
					(thickness 0.1524)
				)
				(justify left)
			)
		)
		(fp_text user "G"
			(at -11.657076 -3.87223 90)
			(unlocked yes)
			(layer "F.SilkS")
			(effects
				(font
					(size 0.7874 0.5842)
					(thickness 0.1524)
				)
				(justify left)
			)
		)
		(fp_text user "F"
			(at -10.05713 -4.672076 90)
			(unlocked yes)
			(layer "F.SilkS")
			(effects
				(font
					(size 0.7874 0.5842)
					(thickness 0.1524)
				)
				(justify left)
			)
		)
		(fp_text user "E"
			(at -11.72972 -6.024118 90)
			(unlocked yes)
			(layer "F.SilkS")
			(effects
				(font
					(size 0.7874 0.5842)
					(thickness 0.1524)
				)
				(justify left)
			)
		)
		(fp_text user "D"
			(at -10.05713 -6.272276 90)
			(unlocked yes)
			(layer "F.SilkS")
			(effects
				(font
					(size 0.7874 0.5842)
					(thickness 0.1524)
				)
				(justify left)
			)
		)
		(fp_text user "C"
			(at -11.657076 -7.072122 90)
			(unlocked yes)
			(layer "F.SilkS")
			(effects
				(font
					(size 0.7874 0.5842)
					(thickness 0.1524)
				)
				(justify left)
			)
		)
		(fp_text user "B"
			(at -10.05713 -7.872222 90)
			(unlocked yes)
			(layer "F.SilkS")
			(effects
				(font
					(size 0.7874 0.5842)
					(thickness 0.1524)
				)
				(justify left)
			)
		)
		(fp_text user "A"
			(at -11.657076 -8.672068 90)
			(unlocked yes)
			(layer "F.SilkS")
			(effects
				(font
					(size 0.7874 0.5842)
					(thickness 0.1524)
				)
				(justify left)
			)
		)
		(fp_text user "22"
			(at 10.49528 -10.469118 90)
			(unlocked yes)
			(layer "F.SilkS")
			(effects
				(font
					(size 0.7874 0.5842)
					(thickness 0.1524)
				)
				(justify left)
			)
		)
		(fp_text user "2"
			(at -6.495034 -10.545064 90)
			(unlocked yes)
			(layer "F.SilkS")
			(effects
				(font
					(size 0.7874 0.5842)
					(thickness 0.1524)
				)
				(justify left)
			)
		)
		(fp_text user "4"
			(at -4.895088 -10.545064 90)
			(unlocked yes)
			(layer "F.SilkS")
			(effects
				(font
					(size 0.7874 0.5842)
					(thickness 0.1524)
				)
				(justify left)
			)
		)
		(fp_text user "6"
			(at -3.295142 -10.545064 90)
			(unlocked yes)
			(layer "F.SilkS")
			(effects
				(font
					(size 0.7874 0.5842)
					(thickness 0.1524)
				)
				(justify left)
			)
		)
		(fp_text user "8"
			(at -1.695196 -10.545064 90)
			(unlocked yes)
			(layer "F.SilkS")
			(effects
				(font
					(size 0.7874 0.5842)
					(thickness 0.1524)
				)
				(justify left)
			)
		)
		(fp_text user "10"
			(at -0.996696 -10.545064 90)
			(unlocked yes)
			(layer "F.SilkS")
			(effects
				(font
					(size 0.7874 0.5842)
					(thickness 0.1524)
				)
				(justify left)
			)
		)
		(fp_text user "12"
			(at 0.60325 -10.545064 90)
			(unlocked yes)
			(layer "F.SilkS")
			(effects
				(font
					(size 0.7874 0.5842)
					(thickness 0.1524)
				)
				(justify left)
			)
		)
		(fp_text user "14"
			(at 2.203196 -10.545064 90)
			(unlocked yes)
			(layer "F.SilkS")
			(effects
				(font
					(size 0.7874 0.5842)
					(thickness 0.1524)
				)
				(justify left)
			)
		)
		(fp_text user "16"
			(at 3.803142 -10.545064 90)
			(unlocked yes)
			(layer "F.SilkS")
			(effects
				(font
					(size 0.7874 0.5842)
					(thickness 0.1524)
				)
				(justify left)
			)
		)
		(fp_text user "18"
			(at 5.911088 -10.545064 90)
			(unlocked yes)
			(layer "F.SilkS")
			(effects
				(font
					(size 0.7874 0.5842)
					(thickness 0.1524)
				)
				(justify left)
			)
		)
		(fp_text user "20"
			(at 7.911084 -10.545064 90)
			(unlocked yes)
			(layer "F.SilkS")
			(effects
				(font
					(size 0.7874 0.5842)
					(thickness 0.1524)
				)
				(justify left)
			)
		)
		(fp_text user "1"
			(at -7.295134 -11.745214 90)
			(unlocked yes)
			(layer "F.SilkS")
			(effects
				(font
					(size 0.7874 0.5842)
					(thickness 0.1524)
				)
				(justify left)
			)
		)
		(fp_text user "3"
			(at -5.695188 -11.745214 90)
			(unlocked yes)
			(layer "F.SilkS")
			(effects
				(font
					(size 0.7874 0.5842)
					(thickness 0.1524)
				)
				(justify left)
			)
		)
		(fp_text user "5"
			(at -4.094988 -11.745214 90)
			(unlocked yes)
			(layer "F.SilkS")
			(effects
				(font
					(size 0.7874 0.5842)
					(thickness 0.1524)
				)
				(justify left)
			)
		)
		(fp_text user "7"
			(at -2.495042 -11.745214 90)
			(unlocked yes)
			(layer "F.SilkS")
			(effects
				(font
					(size 0.7874 0.5842)
					(thickness 0.1524)
				)
				(justify left)
			)
		)
		(fp_text user "9"
			(at -0.895096 -11.745214 90)
			(unlocked yes)
			(layer "F.SilkS")
			(effects
				(font
					(size 0.7874 0.5842)
					(thickness 0.1524)
				)
				(justify left)
			)
		)
		(fp_text user "11"
			(at 0.31115 -11.745214 90)
			(unlocked yes)
			(layer "F.SilkS")
			(effects
				(font
					(size 0.7874 0.5842)
					(thickness 0.1524)
				)
				(justify left)
			)
		)
		(fp_text user "13"
			(at 1.911096 -11.745214 90)
			(unlocked yes)
			(layer "F.SilkS")
			(effects
				(font
					(size 0.7874 0.5842)
					(thickness 0.1524)
				)
				(justify left)
			)
		)
		(fp_text user "15"
			(at 3.511296 -11.745214 90)
			(unlocked yes)
			(layer "F.SilkS")
			(effects
				(font
					(size 0.7874 0.5842)
					(thickness 0.1524)
				)
				(justify left)
			)
		)
		(fp_text user "17"
			(at 5.111242 -11.745214 90)
			(unlocked yes)
			(layer "F.SilkS")
			(effects
				(font
					(size 0.7874 0.5842)
					(thickness 0.1524)
				)
				(justify left)
			)
		)
		(fp_text user "19"
			(at 6.711188 -11.745214 90)
			(unlocked yes)
			(layer "F.SilkS")
			(effects
				(font
					(size 0.7874 0.5842)
					(thickness 0.1524)
				)
				(justify left)
			)
		)
		(fp_text user "21"
			(at 8.711184 -11.745214 90)
			(unlocked yes)
			(layer "F.SilkS")
			(effects
				(font
					(size 0.7874 0.5842)
					(thickness 0.1524)
				)
				(justify left)
			)
		)
		(fp_text user "AB"
			(at -11.08583 8.308086 270)
			(unlocked yes)
			(layer "F.Fab")
			(effects
				(font
					(size 0.7874 0.5842)
					(thickness 0.000001)
				)
				(justify left)
			)
		)
		(fp_text user "A"
			(at -12.292076 -8.491728 270)
			(unlocked yes)
			(layer "F.Fab")
			(effects
				(font
					(size 0.7874 0.5842)
					(thickness 0.000001)
				)
				(justify left)
			)
		)
		(fp_text user "22"
			(at 8.114284 -10.491724 270)
			(unlocked yes)
			(layer "F.Fab")
			(effects
				(font
					(size 0.7874 0.5842)
					(thickness 0.000001)
				)
				(justify left)
			)
		)
		(fp_text user "1"
			(at -8.692134 -11.691874 270)
			(unlocked yes)
			(layer "F.Fab")
			(effects
				(font
					(size 0.7874 0.5842)
					(thickness 0.000001)
				)
				(justify left)
			)
		)
		(pad "A1" smd circle
			(at -8.400034 -8.400034 270)
			(size 0.3683 0.3683)
			(layers "F.Cu" "F.Mask" "F.Paste")
			(net "GND")
		)
		(pad "A2" smd circle
			(at -7.599934 -8.400034 270)
			(size 0.3683 0.3683)
			(layers "F.Cu" "F.Mask" "F.Paste")
			(net "GND")
		)
		(pad "A3" smd circle
			(at -6.800088 -8.400034 270)
			(size 0.3683 0.3683)
			(layers "F.Cu" "F.Mask" "F.Paste")
			(net "GND")
		)
		(pad "A4" smd circle
			(at -5.999988 -8.400034 270)
			(size 0.3683 0.3683)
			(layers "F.Cu" "F.Mask" "F.Paste")
			(net "N3975090766")
		)
		(pad "A5" smd circle
			(at -5.199888 -8.400034 270)
			(size 0.3683 0.3683)
			(layers "F.Cu" "F.Mask" "F.Paste")
			(net "Net_1753")
		)
		(pad "A6" smd circle
			(at -4.400042 -8.400034 270)
			(size 0.3683 0.3683)
			(layers "F.Cu" "F.Mask" "F.Paste")
			(net "Net_1740")
		)
		(pad "A7" smd circle
			(at -3.599942 -8.400034 270)
			(size 0.3683 0.3683)
			(layers "F.Cu" "F.Mask" "F.Paste")
			(net "Net_1737")
		)
		(pad "A8" smd circle
			(at -2.800096 -8.400034 270)
			(size 0.3683 0.3683)
			(layers "F.Cu" "F.Mask" "F.Paste")
			(net "Net_1735")
		)
		(pad "A9" smd circle
			(at -1.999996 -8.400034 270)
			(size 0.3683 0.3683)
			(layers "F.Cu" "F.Mask" "F.Paste")
			(net "GND")
		)
		(pad "A10" smd circle
			(at -1.199896 -8.400034 270)
			(size 0.3683 0.3683)
			(layers "F.Cu" "F.Mask" "F.Paste")
			(net "Net_1762")
		)
		(pad "A11" smd circle
			(at -0.40005 -8.400034 270)
			(size 0.3683 0.3683)
			(layers "F.Cu" "F.Mask" "F.Paste")
			(net "GND")
		)
		(pad "A12" smd circle
			(at 0.40005 -8.400034 270)
			(size 0.3683 0.3683)
			(layers "F.Cu" "F.Mask" "F.Paste")
			(net "Net_1754")
		)
		(pad "A13" smd circle
			(at 1.199896 -8.400034 270)
			(size 0.3683 0.3683)
			(layers "F.Cu" "F.Mask" "F.Paste")
			(net "Net_1759")
		)
		(pad "A14" smd circle
			(at 1.999996 -8.400034 270)
			(size 0.3683 0.3683)
			(layers "F.Cu" "F.Mask" "F.Paste")
			(net "Net_510")
		)
		(pad "A15" smd circle
			(at 2.800096 -8.400034 270)
			(size 0.3683 0.3683)
			(layers "F.Cu" "F.Mask" "F.Paste")
			(net "Net_1723")
		)
		(pad "A16" smd circle
			(at 3.599942 -8.400034 270)
			(size 0.3683 0.3683)
			(layers "F.Cu" "F.Mask" "F.Paste")
			(net "Net_1719")
		)
		(pad "A17" smd circle
			(at 4.400042 -8.400034 270)
			(size 0.3683 0.3683)
			(layers "F.Cu" "F.Mask" "F.Paste")
			(net "Net_1716")
		)
		(pad "A18" smd circle
			(at 5.199888 -8.400034 270)
			(size 0.3683 0.3683)
			(layers "F.Cu" "F.Mask" "F.Paste")
			(net "Net_564")
		)
		(pad "A19" smd circle
			(at 5.999988 -8.400034 270)
			(size 0.3683 0.3683)
			(layers "F.Cu" "F.Mask" "F.Paste")
			(net "Net_1732")
		)
		(pad "A20" smd circle
			(at 6.800088 -8.400034 270)
			(size 0.3683 0.3683)
			(layers "F.Cu" "F.Mask" "F.Paste")
			(net "Net_1730")
		)
		(pad "A21" smd circle
			(at 7.599934 -8.400034 270)
			(size 0.3683 0.3683)
			(layers "F.Cu" "F.Mask" "F.Paste")
			(net "PD_BMC_LPC")
		)
		(pad "A22" smd circle
			(at 8.400034 -8.400034 270)
			(size 0.3683 0.3683)
			(layers "F.Cu" "F.Mask" "F.Paste")
			(net "PD_BMC_LPC")
		)
		(pad "AA1" smd circle
			(at -8.400034 7.599934 270)
			(size 0.3683 0.3683)
			(layers "F.Cu" "F.Mask" "F.Paste")
			(net "Net_476")
		)
		(pad "AA2" smd circle
			(at -7.599934 7.599934 270)
			(size 0.3683 0.3683)
			(layers "F.Cu" "F.Mask" "F.Paste")
			(net "Net_542")
		)
		(pad "AA3" smd circle
			(at -6.800088 7.599934 270)
			(size 0.3683 0.3683)
			(layers "F.Cu" "F.Mask" "F.Paste")
			(net "Net_1776")
		)
		(pad "AA4" smd circle
			(at -5.999988 7.599934 270)
			(size 0.3683 0.3683)
			(layers "F.Cu" "F.Mask" "F.Paste")
			(net "Net_1779")
		)
		(pad "AA5" smd circle
			(at -5.199888 7.599934 270)
			(size 0.3683 0.3683)
			(layers "F.Cu" "F.Mask" "F.Paste")
			(net "Net_1780")
		)
		(pad "AA6" smd circle
			(at -4.400042 7.599934 270)
			(size 0.3683 0.3683)
			(layers "F.Cu" "F.Mask" "F.Paste")
			(net "Net_544")
		)
		(pad "AA7" smd circle
			(at -3.599942 7.599934 270)
			(size 0.3683 0.3683)
			(layers "F.Cu" "F.Mask" "F.Paste")
			(net "Net_505")
		)
		(pad "AA8" smd circle
			(at -2.800096 7.599934 270)
			(size 0.3683 0.3683)
			(layers "F.Cu" "F.Mask" "F.Paste")
			(net "BMC_NODE1_DDR_DQS1_DP")
		)
		(pad "AA9" smd circle
			(at -1.999996 7.599934 270)
			(size 0.3683 0.3683)
			(layers "F.Cu" "F.Mask" "F.Paste")
			(net "BMC_NODE1_DDR_D10")
		)
		(pad "AA10" smd circle
			(at -1.199896 7.599934 270)
			(size 0.3683 0.3683)
			(layers "F.Cu" "F.Mask" "F.Paste")
			(net "BMC_NODE1_DDR_DQS0_DN")
		)
		(pad "AA11" smd circle
			(at -0.40005 7.599934 270)
			(size 0.3683 0.3683)
			(layers "F.Cu" "F.Mask" "F.Paste")
			(net "BMC_NODE1_DDR_D3")
		)
		(pad "AA12" smd circle
			(at 0.40005 7.599934 270)
			(size 0.3683 0.3683)
			(layers "F.Cu" "F.Mask" "F.Paste")
			(net "BMC_NODE1_DDR_CLK_DN")
		)
		(pad "AA13" smd circle
			(at 1.199896 7.599934 270)
			(size 0.3683 0.3683)
			(layers "F.Cu" "F.Mask" "F.Paste")
			(net "BMC_NODE1_DDR_CS_L")
		)
		(pad "AA14" smd circle
			(at 1.999996 7.599934 270)
			(size 0.3683 0.3683)
			(layers "F.Cu" "F.Mask" "F.Paste")
			(net "BMC_NODE1_DDR_BA1")
		)
		(pad "AA15" smd circle
			(at 2.800096 7.599934 270)
			(size 0.3683 0.3683)
			(layers "F.Cu" "F.Mask" "F.Paste")
			(net "BMC_NODE1_DDR_MA6")
		)
		(pad "AA16" smd circle
			(at 3.599942 7.599934 270)
			(size 0.3683 0.3683)
			(layers "F.Cu" "F.Mask" "F.Paste")
			(net "BMC_NODE1_DDR_MA11")
		)
		(pad "AA17" smd circle
			(at 4.400042 7.599934 270)
			(size 0.3683 0.3683)
			(layers "F.Cu" "F.Mask" "F.Paste")
			(net "BMC_NODE1_DDR_MA9")
		)
		(pad "AA18" smd circle
			(at 5.199888 7.599934 270)
			(size 0.3683 0.3683)
			(layers "F.Cu" "F.Mask" "F.Paste")
			(net "GND")
		)
		(pad "AA19" smd circle
			(at 5.999988 7.599934 270)
			(size 0.3683 0.3683)
			(layers "F.Cu" "F.Mask" "F.Paste")
			(net "GND")
		)
		(pad "AA20" smd circle
			(at 6.800088 7.599934 270)
			(size 0.3683 0.3683)
			(layers "F.Cu" "F.Mask" "F.Paste")
			(net "BMC_NODE1_USBVREF")
		)
		(pad "AA21" smd circle
			(at 7.599934 7.599934 270)
			(size 0.3683 0.3683)
			(layers "F.Cu" "F.Mask" "F.Paste")
			(net "Net_531")
		)
		(pad "AA22" smd circle
			(at 8.400034 7.599934 270)
			(size 0.3683 0.3683)
			(layers "F.Cu" "F.Mask" "F.Paste")
			(net "Net_1770")
		)
		(pad "AB1" smd circle
			(at -8.400034 8.400034 270)
			(size 0.3683 0.3683)
			(layers "F.Cu" "F.Mask" "F.Paste")
			(net "Net_541")
		)
		(pad "AB2" smd circle
			(at -7.599934 8.400034 270)
			(size 0.3683 0.3683)
			(layers "F.Cu" "F.Mask" "F.Paste")
			(net "Net_1777")
		)
		(pad "AB3" smd circle
			(at -6.800088 8.400034 270)
			(size 0.3683 0.3683)
			(layers "F.Cu" "F.Mask" "F.Paste")
			(net "Net_540")
		)
		(pad "AB4" smd circle
			(at -5.999988 8.400034 270)
			(size 0.3683 0.3683)
			(layers "F.Cu" "F.Mask" "F.Paste")
			(net "Net_543")
		)
		(pad "AB5" smd circle
			(at -5.199888 8.400034 270)
			(size 0.3683 0.3683)
			(layers "F.Cu" "F.Mask" "F.Paste")
			(net "Net_1783")
		)
		(pad "AB6" smd circle
			(at -4.400042 8.400034 270)
			(size 0.3683 0.3683)
			(layers "F.Cu" "F.Mask" "F.Paste")
			(net "Net_507")
		)
		(pad "AB7" smd circle
			(at -3.599942 8.400034 270)
			(size 0.3683 0.3683)
			(layers "F.Cu" "F.Mask" "F.Paste")
			(net "Net_545")
		)
		(pad "AB8" smd circle
			(at -2.800096 8.400034 270)
			(size 0.3683 0.3683)
			(layers "F.Cu" "F.Mask" "F.Paste")
			(net "BMC_NODE1_DDR_DQS1_DN")
		)
		(pad "AB9" smd circle
			(at -1.999996 8.400034 270)
			(size 0.3683 0.3683)
			(layers "F.Cu" "F.Mask" "F.Paste")
			(net "BMC_NODE1_DDR_D9")
		)
		(pad "AB10" smd circle
			(at -1.199896 8.400034 270)
			(size 0.3683 0.3683)
			(layers "F.Cu" "F.Mask" "F.Paste")
			(net "BMC_NODE1_DDR_DQS0_DP")
		)
		(pad "AB11" smd circle
			(at -0.40005 8.400034 270)
			(size 0.3683 0.3683)
			(layers "F.Cu" "F.Mask" "F.Paste")
			(net "BMC_NODE1_DDR_D2")
		)
		(pad "AB12" smd circle
			(at 0.40005 8.400034 270)
			(size 0.3683 0.3683)
			(layers "F.Cu" "F.Mask" "F.Paste")
			(net "BMC_NODE1_DDR_CLK_DP")
		)
		(pad "AB13" smd circle
			(at 1.199896 8.400034 270)
			(size 0.3683 0.3683)
			(layers "F.Cu" "F.Mask" "F.Paste")
			(net "BMC_NODE1_DDR_CAS_L")
		)
		(pad "AB14" smd circle
			(at 1.999996 8.400034 270)
			(size 0.3683 0.3683)
			(layers "F.Cu" "F.Mask" "F.Paste")
			(net "BMC_NODE1_DDR_MA0")
		)
		(pad "AB15" smd circle
			(at 2.800096 8.400034 270)
			(size 0.3683 0.3683)
			(layers "F.Cu" "F.Mask" "F.Paste")
			(net "BMC_NODE1_DDR_MA4")
		)
		(pad "AB16" smd circle
			(at 3.599942 8.400034 270)
			(size 0.3683 0.3683)
			(layers "F.Cu" "F.Mask" "F.Paste")
			(net "BMC_NODE1_DDR_MA8")
		)
		(pad "AB17" smd circle
			(at 4.400042 8.400034 270)
			(size 0.3683 0.3683)
			(layers "F.Cu" "F.Mask" "F.Paste")
			(net "BMC_NODE1_DDR_MA14")
		)
		(pad "AB18" smd circle
			(at 5.199888 8.400034 270)
			(size 0.3683 0.3683)
			(layers "F.Cu" "F.Mask" "F.Paste")
			(net "BMC_NODE1_DDR_MA7")
		)
		(pad "AB19" smd circle
			(at 5.999988 8.400034 270)
			(size 0.3683 0.3683)
			(layers "F.Cu" "F.Mask" "F.Paste")
			(net "BMC_NODE1_MPLLAV33")
		)
		(pad "AB20" smd circle
			(at 6.800088 8.400034 270)
			(size 0.3683 0.3683)
			(layers "F.Cu" "F.Mask" "F.Paste")
			(net "Net_520")
		)
		(pad "AB21" smd circle
			(at 7.599934 8.400034 270)
			(size 0.3683 0.3683)
			(layers "F.Cu" "F.Mask" "F.Paste")
			(net "Net_521")
		)
		(pad "AB22" smd circle
			(at 8.400034 8.400034 270)
			(size 0.3683 0.3683)
			(layers "F.Cu" "F.Mask" "F.Paste")
			(net "BMC_NODE1_CLK_24M")
		)
		(pad "B1" smd circle
			(at -8.400034 -7.599934 270)
			(size 0.3683 0.3683)
			(layers "F.Cu" "F.Mask" "F.Paste")
			(net "GND")
		)
		(pad "B2" smd circle
			(at -7.599934 -7.599934 270)
			(size 0.3683 0.3683)
			(layers "F.Cu" "F.Mask" "F.Paste")
			(net "GND")
		)
		(pad "B3" smd circle
			(at -6.800088 -7.599934 270)
			(size 0.3683 0.3683)
			(layers "F.Cu" "F.Mask" "F.Paste")
			(net "GND")
		)
		(pad "B4" smd circle
			(at -5.999988 -7.599934 270)
			(size 0.3683 0.3683)
			(layers "F.Cu" "F.Mask" "F.Paste")
			(net "GND")
		)
		(pad "B5" smd circle
			(at -5.199888 -7.599934 270)
			(size 0.3683 0.3683)
			(layers "F.Cu" "F.Mask" "F.Paste")
			(net "N3975090765")
		)
		(pad "B6" smd circle
			(at -4.400042 -7.599934 270)
			(size 0.3683 0.3683)
			(layers "F.Cu" "F.Mask" "F.Paste")
			(net "Net_1739")
		)
		(pad "B7" smd circle
			(at -3.599942 -7.599934 270)
			(size 0.3683 0.3683)
			(layers "F.Cu" "F.Mask" "F.Paste")
			(net "Net_1736")
		)
		(pad "B8" smd circle
			(at -2.800096 -7.599934 270)
			(size 0.3683 0.3683)
			(layers "F.Cu" "F.Mask" "F.Paste")
			(net "GND")
		)
		(pad "B9" smd circle
			(at -1.999996 -7.599934 270)
			(size 0.3683 0.3683)
			(layers "F.Cu" "F.Mask" "F.Paste")
			(net "GND")
		)
		(pad "B10" smd circle
			(at -1.199896 -7.599934 270)
			(size 0.3683 0.3683)
			(layers "F.Cu" "F.Mask" "F.Paste")
			(net "Net_1763")
		)
		(pad "B11" smd circle
			(at -0.40005 -7.599934 270)
			(size 0.3683 0.3683)
			(layers "F.Cu" "F.Mask" "F.Paste")
			(net "GND")
		)
		(pad "B12" smd circle
			(at 0.40005 -7.599934 270)
			(size 0.3683 0.3683)
			(layers "F.Cu" "F.Mask" "F.Paste")
			(net "Net_1755")
		)
		(pad "B13" smd circle
			(at 1.199896 -7.599934 270)
			(size 0.3683 0.3683)
			(layers "F.Cu" "F.Mask" "F.Paste")
			(net "Net_1768")
		)
		(pad "B14" smd circle
			(at 1.999996 -7.599934 270)
			(size 0.3683 0.3683)
			(layers "F.Cu" "F.Mask" "F.Paste")
			(net "Net_1727")
		)
		(pad "B15" smd circle
			(at 2.800096 -7.599934 270)
			(size 0.3683 0.3683)
			(layers "F.Cu" "F.Mask" "F.Paste")
			(net "Net_1722")
		)
		(pad "B16" smd circle
			(at 3.599942 -7.599934 270)
			(size 0.3683 0.3683)
			(layers "F.Cu" "F.Mask" "F.Paste")
			(net "Net_1718")
		)
		(pad "B17" smd circle
			(at 4.400042 -7.599934 270)
			(size 0.3683 0.3683)
			(layers "F.Cu" "F.Mask" "F.Paste")
			(net "Net_1715")
		)
		(pad "B18" smd circle
			(at 5.199888 -7.599934 270)
			(size 0.3683 0.3683)
			(layers "F.Cu" "F.Mask" "F.Paste")
			(net "Net_1731")
		)
		(pad "B19" smd circle
			(at 5.999988 -7.599934 270)
			(size 0.3683 0.3683)
			(layers "F.Cu" "F.Mask" "F.Paste")
			(net "Net_1729")
		)
		(pad "B20" smd circle
			(at 6.800088 -7.599934 270)
			(size 0.3683 0.3683)
			(layers "F.Cu" "F.Mask" "F.Paste")
			(net "LPC_CLK_AST")
		)
		(pad "B21" smd circle
			(at 7.599934 -7.599934 270)
			(size 0.3683 0.3683)
			(layers "F.Cu" "F.Mask" "F.Paste")
			(net "PD_BMC_LPC")
		)
		(pad "B22" smd circle
			(at 8.400034 -7.599934 270)
			(size 0.3683 0.3683)
			(layers "F.Cu" "F.Mask" "F.Paste")
			(net "Net_1744")
		)
		(pad "C1" smd circle
			(at -8.400034 -6.800088 270)
			(size 0.3683 0.3683)
			(layers "F.Cu" "F.Mask" "F.Paste")
			(net "GND")
		)
		(pad "C2" smd circle
			(at -7.599934 -6.800088 270)
			(size 0.3683 0.3683)
			(layers "F.Cu" "F.Mask" "F.Paste")
			(net "GND")
		)
		(pad "C3" smd circle
			(at -6.800088 -6.800088 270)
			(size 0.3683 0.3683)
			(layers "F.Cu" "F.Mask" "F.Paste")
			(net "GND")
		)
		(pad "C4" smd circle
			(at -5.999988 -6.800088 270)
			(size 0.3683 0.3683)
			(layers "F.Cu" "F.Mask" "F.Paste")
			(net "GND")
		)
		(pad "C5" smd circle
			(at -5.199888 -6.800088 270)
			(size 0.3683 0.3683)
			(layers "F.Cu" "F.Mask" "F.Paste")
			(net "GND")
		)
		(pad "C6" smd circle
			(at -4.400042 -6.800088 270)
			(size 0.3683 0.3683)
			(layers "F.Cu" "F.Mask" "F.Paste")
			(net "Net_1752")
		)
		(pad "C7" smd circle
			(at -3.599942 -6.800088 270)
			(size 0.3683 0.3683)
			(layers "F.Cu" "F.Mask" "F.Paste")
			(net "Net_538")
		)
		(pad "C8" smd circle
			(at -2.800096 -6.800088 270)
			(size 0.3683 0.3683)
			(layers "F.Cu" "F.Mask" "F.Paste")
			(net "GND")
		)
		(pad "C9" smd circle
			(at -1.999996 -6.800088 270)
			(size 0.3683 0.3683)
			(layers "F.Cu" "F.Mask" "F.Paste")
			(net "GND")
		)
		(pad "C10" smd circle
			(at -1.199896 -6.800088 270)
			(size 0.3683 0.3683)
			(layers "F.Cu" "F.Mask" "F.Paste")
			(net "Net_1764")
		)
		(pad "C11" smd circle
			(at -0.40005 -6.800088 270)
			(size 0.3683 0.3683)
			(layers "F.Cu" "F.Mask" "F.Paste")
			(net "GND")
		)
		(pad "C12" smd circle
			(at 0.40005 -6.800088 270)
			(size 0.3683 0.3683)
			(layers "F.Cu" "F.Mask" "F.Paste")
			(net "Net_1756")
		)
		(pad "C13" smd circle
			(at 1.199896 -6.800088 270)
			(size 0.3683 0.3683)
			(layers "F.Cu" "F.Mask" "F.Paste")
			(net "Net_1767")
		)
		(pad "C14" smd circle
			(at 1.999996 -6.800088 270)
			(size 0.3683 0.3683)
			(layers "F.Cu" "F.Mask" "F.Paste")
			(net "Net_1726")
		)
		(pad "C15" smd circle
			(at 2.800096 -6.800088 270)
			(size 0.3683 0.3683)
			(layers "F.Cu" "F.Mask" "F.Paste")
			(net "Net_469")
		)
		(pad "C16" smd circle
			(at 3.599942 -6.800088 270)
			(size 0.3683 0.3683)
			(layers "F.Cu" "F.Mask" "F.Paste")
			(net "Net_1717")
		)
		(pad "C17" smd circle
			(at 4.400042 -6.800088 270)
			(size 0.3683 0.3683)
			(layers "F.Cu" "F.Mask" "F.Paste")
			(net "Net_1734")
		)
		(pad "C18" smd circle
			(at 5.199888 -6.800088 270)
			(size 0.3683 0.3683)
			(layers "F.Cu" "F.Mask" "F.Paste")
			(net "Net_1746")
		)
		(pad "C19" smd circle
			(at 5.999988 -6.800088 270)
			(size 0.3683 0.3683)
			(layers "F.Cu" "F.Mask" "F.Paste")
			(net "PD_BMC_LPC")
		)
		(pad "C20" smd circle
			(at 6.800088 -6.800088 270)
			(size 0.3683 0.3683)
			(layers "F.Cu" "F.Mask" "F.Paste")
			(net "Net_539")
		)
		(pad "C21" smd circle
			(at 7.599934 -6.800088 270)
			(size 0.3683 0.3683)
			(layers "F.Cu" "F.Mask" "F.Paste")
			(net "BMC_NODE1_VCC_1V8_PCIEA")
		)
		(pad "C22" smd circle
			(at 8.400034 -6.800088 270)
			(size 0.3683 0.3683)
			(layers "F.Cu" "F.Mask" "F.Paste")
			(net "Net_537")
		)
		(pad "D1" smd circle
			(at -8.400034 -5.999988 270)
			(size 0.3683 0.3683)
			(layers "F.Cu" "F.Mask" "F.Paste")
			(net "GND")
		)
		(pad "D2" smd circle
			(at -7.599934 -5.999988 270)
			(size 0.3683 0.3683)
			(layers "F.Cu" "F.Mask" "F.Paste")
			(net "GND")
		)
		(pad "D3" smd circle
			(at -6.800088 -5.999988 270)
			(size 0.3683 0.3683)
			(layers "F.Cu" "F.Mask" "F.Paste")
			(net "GND")
		)
		(pad "D4" smd circle
			(at -5.999988 -5.999988 270)
			(size 0.3683 0.3683)
			(layers "F.Cu" "F.Mask" "F.Paste")
			(net "GND")
		)
		(pad "D5" smd circle
			(at -5.199888 -5.999988 270)
			(size 0.3683 0.3683)
			(layers "F.Cu" "F.Mask" "F.Paste")
			(net "GND")
		)
		(pad "D6" smd circle
			(at -4.400042 -5.999988 270)
			(size 0.3683 0.3683)
			(layers "F.Cu" "F.Mask" "F.Paste")
			(net "Net_1766")
		)
		(pad "D7" smd circle
			(at -3.599942 -5.999988 270)
			(size 0.3683 0.3683)
			(layers "F.Cu" "F.Mask" "F.Paste")
			(net "Net_1738")
		)
		(pad "D8" smd circle
			(at -2.800096 -5.999988 270)
			(size 0.3683 0.3683)
			(layers "F.Cu" "F.Mask" "F.Paste")
			(net "GND")
		)
		(pad "D9" smd circle
			(at -1.999996 -5.999988 270)
			(size 0.3683 0.3683)
			(layers "F.Cu" "F.Mask" "F.Paste")
			(net "Net_1760")
		)
		(pad "D10" smd circle
			(at -1.199896 -5.999988 270)
			(size 0.3683 0.3683)
			(layers "F.Cu" "F.Mask" "F.Paste")
			(net "Net_1765")
		)
		(pad "D11" smd circle
			(at -0.40005 -5.999988 270)
			(size 0.3683 0.3683)
			(layers "F.Cu" "F.Mask" "F.Paste")
			(net "GND")
		)
		(pad "D12" smd circle
			(at 0.40005 -5.999988 270)
			(size 0.3683 0.3683)
			(layers "F.Cu" "F.Mask" "F.Paste")
			(net "Net_1757")
		)
		(pad "D13" smd circle
			(at 1.199896 -5.999988 270)
			(size 0.3683 0.3683)
			(layers "F.Cu" "F.Mask" "F.Paste")
			(net "Net_536")
		)
		(pad "D14" smd circle
			(at 1.999996 -5.999988 270)
			(size 0.3683 0.3683)
			(layers "F.Cu" "F.Mask" "F.Paste")
			(net "Net_1725")
		)
		(pad "D15" smd circle
			(at 2.800096 -5.999988 270)
			(size 0.3683 0.3683)
			(layers "F.Cu" "F.Mask" "F.Paste")
			(net "Net_1721")
		)
		(pad "D16" smd circle
			(at 3.599942 -5.999988 270)
			(size 0.3683 0.3683)
			(layers "F.Cu" "F.Mask" "F.Paste")
			(net "Net_1714")
		)
		(pad "D17" smd circle
			(at 4.400042 -5.999988 270)
			(size 0.3683 0.3683)
			(layers "F.Cu" "F.Mask" "F.Paste")
			(net "Net_514")
		)
		(pad "D18" smd circle
			(at 5.199888 -5.999988 270)
			(size 0.3683 0.3683)
			(layers "F.Cu" "F.Mask" "F.Paste")
			(net "Net_1728")
		)
		(pad "D19" smd circle
			(at 5.999988 -5.999988 270)
			(size 0.3683 0.3683)
			(layers "F.Cu" "F.Mask" "F.Paste")
			(net "Net_1743")
		)
		(pad "D20" smd circle
			(at 6.800088 -5.999988 270)
			(size 0.3683 0.3683)
			(layers "F.Cu" "F.Mask" "F.Paste")
			(net "PD_BMC_NODE1_PEREXT")
		)
		(pad "D21" smd circle
			(at 7.599934 -5.999988 270)
			(size 0.3683 0.3683)
			(layers "F.Cu" "F.Mask" "F.Paste")
			(net "GND")
		)
		(pad "D22" smd circle
			(at 8.400034 -5.999988 270)
			(size 0.3683 0.3683)
			(layers "F.Cu" "F.Mask" "F.Paste")
			(net "GND")
		)
		(pad "E1" smd circle
			(at -8.400034 -5.199888 270)
			(size 0.3683 0.3683)
			(layers "F.Cu" "F.Mask" "F.Paste")
			(net "BMC_NODE1_JTAG_TRST")
		)
		(pad "E2" smd circle
			(at -7.599934 -5.199888 270)
			(size 0.3683 0.3683)
			(layers "F.Cu" "F.Mask" "F.Paste")
			(net "GND")
		)
		(pad "E3" smd circle
			(at -6.800088 -5.199888 270)
			(size 0.3683 0.3683)
			(layers "F.Cu" "F.Mask" "F.Paste")
			(net "GND")
		)
		(pad "E4" smd circle
			(at -5.999988 -5.199888 270)
			(size 0.3683 0.3683)
			(layers "F.Cu" "F.Mask" "F.Paste")
			(net "N20822523")
		)
		(pad "E5" smd circle
			(at -5.199888 -5.199888 270)
			(size 0.3683 0.3683)
			(layers "F.Cu" "F.Mask" "F.Paste")
			(net "GND")
		)
		(pad "E6" smd circle
			(at -4.400042 -5.199888 270)
			(size 0.3683 0.3683)
			(layers "F.Cu" "F.Mask" "F.Paste")
			(net "N3975090767")
		)
		(pad "E7" smd circle
			(at -3.599942 -5.199888 270)
			(size 0.3683 0.3683)
			(layers "F.Cu" "F.Mask" "F.Paste")
			(net "Net_1741")
		)
		(pad "E8" smd circle
			(at -2.800096 -5.199888 270)
			(size 0.3683 0.3683)
			(layers "F.Cu" "F.Mask" "F.Paste")
			(net "GND")
		)
		(pad "E9" smd circle
			(at -1.999996 -5.199888 270)
			(size 0.3683 0.3683)
			(layers "F.Cu" "F.Mask" "F.Paste")
			(net "Net_1761")
		)
		(pad "E10" smd circle
			(at -1.199896 -5.199888 270)
			(size 0.3683 0.3683)
			(layers "F.Cu" "F.Mask" "F.Paste")
			(net "GND")
		)
		(pad "E11" smd circle
			(at -0.40005 -5.199888 270)
			(size 0.3683 0.3683)
			(layers "F.Cu" "F.Mask" "F.Paste")
			(net "GND")
		)
		(pad "E12" smd circle
			(at 0.40005 -5.199888 270)
			(size 0.3683 0.3683)
			(layers "F.Cu" "F.Mask" "F.Paste")
			(net "Net_1758")
		)
		(pad "E13" smd circle
			(at 1.199896 -5.199888 270)
			(size 0.3683 0.3683)
			(layers "F.Cu" "F.Mask" "F.Paste")
			(net "Net_535")
		)
		(pad "E14" smd circle
			(at 1.999996 -5.199888 270)
			(size 0.3683 0.3683)
			(layers "F.Cu" "F.Mask" "F.Paste")
			(net "Net_1724")
		)
		(pad "E15" smd circle
			(at 2.800096 -5.199888 270)
			(size 0.3683 0.3683)
			(layers "F.Cu" "F.Mask" "F.Paste")
			(net "Net_1720")
		)
		(pad "E16" smd circle
			(at 3.599942 -5.199888 270)
			(size 0.3683 0.3683)
			(layers "F.Cu" "F.Mask" "F.Paste")
			(net "Net_1733")
		)
		(pad "E17" smd circle
			(at 4.400042 -5.199888 270)
			(size 0.3683 0.3683)
			(layers "F.Cu" "F.Mask" "F.Paste")
			(net "PD_BMC_LPC")
		)
		(pad "E18" smd circle
			(at 5.199888 -5.199888 270)
			(size 0.3683 0.3683)
			(layers "F.Cu" "F.Mask" "F.Paste")
			(net "Net_529")
		)
		(pad "E19" smd circle
			(at 5.999988 -5.199888 270)
			(size 0.3683 0.3683)
			(layers "F.Cu" "F.Mask" "F.Paste")
			(net "Net_511")
		)
		(pad "E20" smd circle
			(at 6.800088 -5.199888 270)
			(size 0.3683 0.3683)
			(layers "F.Cu" "F.Mask" "F.Paste")
			(net "Net_1747")
		)
		(pad "E21" smd circle
			(at 7.599934 -5.199888 270)
			(size 0.3683 0.3683)
			(layers "F.Cu" "F.Mask" "F.Paste")
			(net "P2E_CPU_BMC_NODE1_RX_C_DN")
		)
		(pad "E22" smd circle
			(at 8.400034 -5.199888 270)
			(size 0.3683 0.3683)
			(layers "F.Cu" "F.Mask" "F.Paste")
			(net "P2E_CPU_BMC_NODE1_RX_C_DP")
		)
		(pad "F1" smd circle
			(at -8.400034 -4.400042 270)
			(size 0.3683 0.3683)
			(layers "F.Cu" "F.Mask" "F.Paste")
			(net "BMC_NODE1_JTAG_TDI")
		)
		(pad "F2" smd circle
			(at -7.599934 -4.400042 270)
			(size 0.3683 0.3683)
			(layers "F.Cu" "F.Mask" "F.Paste")
			(net "BMC_NODE1_JTAG_TCK")
		)
		(pad "F3" smd circle
			(at -6.800088 -4.400042 270)
			(size 0.3683 0.3683)
			(layers "F.Cu" "F.Mask" "F.Paste")
			(net "GND")
		)
		(pad "F4" smd circle
			(at -5.999988 -4.400042 270)
			(size 0.3683 0.3683)
			(layers "F.Cu" "F.Mask" "F.Paste")
			(net "GND")
		)
		(pad "F5" smd circle
			(at -5.199888 -4.400042 270)
			(size 0.3683 0.3683)
			(layers "F.Cu" "F.Mask" "F.Paste")
			(net "GND")
		)
		(pad "F8" smd circle
			(at -2.800096 -4.400042 270)
			(size 0.3683 0.3683)
			(layers "F.Cu" "F.Mask" "F.Paste")
			(net "P3V3_NODE1")
		)
		(pad "F9" smd circle
			(at -1.999996 -4.400042 270)
			(size 0.3683 0.3683)
			(layers "F.Cu" "F.Mask" "F.Paste")
			(net "P3V3_NODE1")
		)
		(pad "F10" smd circle
			(at -1.199896 -4.400042 270)
			(size 0.3683 0.3683)
			(layers "F.Cu" "F.Mask" "F.Paste")
			(net "P3V3_NODE1")
		)
		(pad "F11" smd circle
			(at -0.40005 -4.400042 270)
			(size 0.3683 0.3683)
			(layers "F.Cu" "F.Mask" "F.Paste")
			(net "P3V3_NODE1")
		)
		(pad "F12" smd circle
			(at 0.40005 -4.400042 270)
			(size 0.3683 0.3683)
			(layers "F.Cu" "F.Mask" "F.Paste")
			(net "P3V3_NODE1")
		)
		(pad "F13" smd circle
			(at 1.199896 -4.400042 270)
			(size 0.3683 0.3683)
			(layers "F.Cu" "F.Mask" "F.Paste")
			(net "P3V3_NODE1")
		)
		(pad "F14" smd circle
			(at 1.999996 -4.400042 270)
			(size 0.3683 0.3683)
			(layers "F.Cu" "F.Mask" "F.Paste")
			(net "P1V26_BMC_NODE1")
		)
		(pad "F15" smd circle
			(at 2.800096 -4.400042 270)
			(size 0.3683 0.3683)
			(layers "F.Cu" "F.Mask" "F.Paste")
			(net "P1V26_BMC_NODE1")
		)
		(pad "F18" smd circle
			(at 5.199888 -4.400042 270)
			(size 0.3683 0.3683)
			(layers "F.Cu" "F.Mask" "F.Paste")
			(net "Net_1713")
		)
		(pad "F19" smd circle
			(at 5.999988 -4.400042 270)
			(size 0.3683 0.3683)
			(layers "F.Cu" "F.Mask" "F.Paste")
			(net "PD_BMC_LPC")
		)
		(pad "F20" smd circle
			(at 6.800088 -4.400042 270)
			(size 0.3683 0.3683)
			(layers "F.Cu" "F.Mask" "F.Paste")
			(net "BMC_NODE1_VCC_1V8_PCIEA")
		)
		(pad "F21" smd circle
			(at 7.599934 -4.400042 270)
			(size 0.3683 0.3683)
			(layers "F.Cu" "F.Mask" "F.Paste")
			(net "P2E_CPU_BMC_NODE1_TX_DP")
		)
		(pad "F22" smd circle
			(at 8.400034 -4.400042 270)
			(size 0.3683 0.3683)
			(layers "F.Cu" "F.Mask" "F.Paste")
			(net "P2E_CPU_BMC_NODE1_TX_DN")
		)
		(pad "G1" smd circle
			(at -8.400034 -3.599942 270)
			(size 0.3683 0.3683)
			(layers "F.Cu" "F.Mask" "F.Paste")
			(net "BMC_DEBUG_RXD")
		)
		(pad "G2" smd circle
			(at -7.599934 -3.599942 270)
			(size 0.3683 0.3683)
			(layers "F.Cu" "F.Mask" "F.Paste")
			(net "BMC_NODE1_JTAG_TMS")
		)
		(pad "G3" smd circle
			(at -6.800088 -3.599942 270)
			(size 0.3683 0.3683)
			(layers "F.Cu" "F.Mask" "F.Paste")
			(net "N3975090755")
		)
		(pad "G4" smd circle
			(at -5.999988 -3.599942 270)
			(size 0.3683 0.3683)
			(layers "F.Cu" "F.Mask" "F.Paste")
			(net "Net_532")
		)
		(pad "G5" smd circle
			(at -5.199888 -3.599942 270)
			(size 0.3683 0.3683)
			(layers "F.Cu" "F.Mask" "F.Paste")
			(net "GND")
		)
		(pad "G18" smd circle
			(at 5.199888 -3.599942 270)
			(size 0.3683 0.3683)
			(layers "F.Cu" "F.Mask" "F.Paste")
			(net "Net_1742")
		)
		(pad "G19" smd circle
			(at 5.999988 -3.599942 270)
			(size 0.3683 0.3683)
			(layers "F.Cu" "F.Mask" "F.Paste")
			(net "Net_1745")
		)
		(pad "G20" smd circle
			(at 6.800088 -3.599942 270)
			(size 0.3683 0.3683)
			(layers "F.Cu" "F.Mask" "F.Paste")
			(net "BMC_NODE1_VCC_1V8_PCIE")
		)
		(pad "G21" smd circle
			(at 7.599934 -3.599942 270)
			(size 0.3683 0.3683)
			(layers "F.Cu" "F.Mask" "F.Paste")
			(net "CLK_100M_BMC_NODE1_DN")
		)
		(pad "G22" smd circle
			(at 8.400034 -3.599942 270)
			(size 0.3683 0.3683)
			(layers "F.Cu" "F.Mask" "F.Paste")
			(net "CLK_100M_BMC_NODE1_DP")
		)
		(pad "H1" smd circle
			(at -8.400034 -2.800096 270)
			(size 0.3683 0.3683)
			(layers "F.Cu" "F.Mask" "F.Paste")
			(net "GND")
		)
		(pad "H2" smd circle
			(at -7.599934 -2.800096 270)
			(size 0.3683 0.3683)
			(layers "F.Cu" "F.Mask" "F.Paste")
			(net "GND")
		)
		(pad "H3" smd circle
			(at -6.800088 -2.800096 270)
			(size 0.3683 0.3683)
			(layers "F.Cu" "F.Mask" "F.Paste")
			(net "GND")
		)
		(pad "H4" smd circle
			(at -5.999988 -2.800096 270)
			(size 0.3683 0.3683)
			(layers "F.Cu" "F.Mask" "F.Paste")
			(net "GND")
		)
		(pad "H5" smd circle
			(at -5.199888 -2.800096 270)
			(size 0.3683 0.3683)
			(layers "F.Cu" "F.Mask" "F.Paste")
			(net "BMC_DEBUG_TXD")
		)
		(pad "H6" smd circle
			(at -4.400042 -2.800096 270)
			(size 0.3683 0.3683)
			(layers "F.Cu" "F.Mask" "F.Paste")
			(net "P3V3_NODE1")
		)
		(pad "H17" smd circle
			(at 4.400042 -2.800096 270)
			(size 0.3683 0.3683)
			(layers "F.Cu" "F.Mask" "F.Paste")
			(net "P3V3_NODE1")
		)
		(pad "H18" smd circle
			(at 5.199888 -2.800096 270)
			(size 0.3683 0.3683)
			(layers "F.Cu" "F.Mask" "F.Paste")
			(net "Net_1712")
		)
		(pad "H19" smd circle
			(at 5.999988 -2.800096 270)
			(size 0.3683 0.3683)
			(layers "F.Cu" "F.Mask" "F.Paste")
			(net "Net_548")
		)
		(pad "H20" smd circle
			(at 6.800088 -2.800096 270)
			(size 0.3683 0.3683)
			(layers "F.Cu" "F.Mask" "F.Paste")
			(net "Net_547")
		)
		(pad "H21" smd circle
			(at 7.599934 -2.800096 270)
			(size 0.3683 0.3683)
			(layers "F.Cu" "F.Mask" "F.Paste")
			(net "BMC_NODE1_VCC_1V8_PCIE")
		)
		(pad "H22" smd circle
			(at 8.400034 -2.800096 270)
			(size 0.3683 0.3683)
			(layers "F.Cu" "F.Mask" "F.Paste")
			(net "BMC_NODE1_VCC_1V8_PCIE")
		)
		(pad "J1" smd circle
			(at -8.400034 -1.999996 270)
			(size 0.3683 0.3683)
			(layers "F.Cu" "F.Mask" "F.Paste")
			(net "Net_533")
		)
		(pad "J2" smd circle
			(at -7.599934 -1.999996 270)
			(size 0.3683 0.3683)
			(layers "F.Cu" "F.Mask" "F.Paste")
			(net "Net_528")
		)
		(pad "J3" smd circle
			(at -6.800088 -1.999996 270)
			(size 0.3683 0.3683)
			(layers "F.Cu" "F.Mask" "F.Paste")
			(net "GND")
		)
		(pad "J4" smd circle
			(at -5.999988 -1.999996 270)
			(size 0.3683 0.3683)
			(layers "F.Cu" "F.Mask" "F.Paste")
			(net "Net_1749")
		)
		(pad "J5" smd circle
			(at -5.199888 -1.999996 270)
			(size 0.3683 0.3683)
			(layers "F.Cu" "F.Mask" "F.Paste")
			(net "Net_1748")
		)
		(pad "J6" smd circle
			(at -4.400042 -1.999996 270)
			(size 0.3683 0.3683)
			(layers "F.Cu" "F.Mask" "F.Paste")
			(net "P3V3_NODE1")
		)
		(pad "J9" smd circle
			(at -1.999996 -1.999996 270)
			(size 0.3683 0.3683)
			(layers "F.Cu" "F.Mask" "F.Paste")
			(net "GND")
		)
		(pad "J10" smd circle
			(at -1.199896 -1.999996 270)
			(size 0.3683 0.3683)
			(layers "F.Cu" "F.Mask" "F.Paste")
			(net "GND")
		)
		(pad "J11" smd circle
			(at -0.40005 -1.999996 270)
			(size 0.3683 0.3683)
			(layers "F.Cu" "F.Mask" "F.Paste")
			(net "GND")
		)
		(pad "J12" smd circle
			(at 0.40005 -1.999996 270)
			(size 0.3683 0.3683)
			(layers "F.Cu" "F.Mask" "F.Paste")
			(net "GND")
		)
		(pad "J13" smd circle
			(at 1.199896 -1.999996 270)
			(size 0.3683 0.3683)
			(layers "F.Cu" "F.Mask" "F.Paste")
			(net "GND")
		)
		(pad "J14" smd circle
			(at 1.999996 -1.999996 270)
			(size 0.3683 0.3683)
			(layers "F.Cu" "F.Mask" "F.Paste")
			(net "GND")
		)
		(pad "J17" smd circle
			(at 4.400042 -1.999996 270)
			(size 0.3683 0.3683)
			(layers "F.Cu" "F.Mask" "F.Paste")
			(net "P3V3_NODE1")
		)
		(pad "J18" smd circle
			(at 5.199888 -1.999996 270)
			(size 0.3683 0.3683)
			(layers "F.Cu" "F.Mask" "F.Paste")
			(net "GND")
		)
		(pad "J19" smd circle
			(at 5.999988 -1.999996 270)
			(size 0.3683 0.3683)
			(layers "F.Cu" "F.Mask" "F.Paste")
			(net "GND")
		)
		(pad "J20" smd circle
			(at 6.800088 -1.999996 270)
			(size 0.3683 0.3683)
			(layers "F.Cu" "F.Mask" "F.Paste")
			(net "Net_1711")
		)
		(pad "J21" smd circle
			(at 7.599934 -1.999996 270)
			(size 0.3683 0.3683)
			(layers "F.Cu" "F.Mask" "F.Paste")
			(net "Net_546")
		)
		(pad "J22" smd circle
			(at 8.400034 -1.999996 270)
			(size 0.3683 0.3683)
			(layers "F.Cu" "F.Mask" "F.Paste")
			(net "IRQ_LVC3_CPU_NODE1_WAKE_R_L")
		)
		(pad "K1" smd circle
			(at -8.400034 -1.199896 270)
			(size 0.3683 0.3683)
			(layers "F.Cu" "F.Mask" "F.Paste")
			(net "TP_BMC_NODE1_ADCVREFP")
		)
		(pad "K2" smd circle
			(at -7.599934 -1.199896 270)
			(size 0.3683 0.3683)
			(layers "F.Cu" "F.Mask" "F.Paste")
			(net "TP_BMC_NODE1_ADCVREFN")
		)
		(pad "K3" smd circle
			(at -6.800088 -1.199896 270)
			(size 0.3683 0.3683)
			(layers "F.Cu" "F.Mask" "F.Paste")
			(net "Net_534")
		)
		(pad "K4" smd circle
			(at -5.999988 -1.199896 270)
			(size 0.3683 0.3683)
			(layers "F.Cu" "F.Mask" "F.Paste")
			(net "Net_530")
		)
		(pad "K5" smd circle
			(at -5.199888 -1.199896 270)
			(size 0.3683 0.3683)
			(layers "F.Cu" "F.Mask" "F.Paste")
			(net "GND")
		)
		(pad "K6" smd circle
			(at -4.400042 -1.199896 270)
			(size 0.3683 0.3683)
			(layers "F.Cu" "F.Mask" "F.Paste")
			(net "P1V26_BMC_NODE1")
		)
		(pad "K9" smd circle
			(at -1.999996 -1.199896 270)
			(size 0.3683 0.3683)
			(layers "F.Cu" "F.Mask" "F.Paste")
			(net "GND")
		)
		(pad "K10" smd circle
			(at -1.199896 -1.199896 270)
			(size 0.3683 0.3683)
			(layers "F.Cu" "F.Mask" "F.Paste")
			(net "GND")
		)
		(pad "K11" smd circle
			(at -0.40005 -1.199896 270)
			(size 0.3683 0.3683)
			(layers "F.Cu" "F.Mask" "F.Paste")
			(net "GND")
		)
		(pad "K12" smd circle
			(at 0.40005 -1.199896 270)
			(size 0.3683 0.3683)
			(layers "F.Cu" "F.Mask" "F.Paste")
			(net "GND")
		)
		(pad "K13" smd circle
			(at 1.199896 -1.199896 270)
			(size 0.3683 0.3683)
			(layers "F.Cu" "F.Mask" "F.Paste")
			(net "GND")
		)
		(pad "K14" smd circle
			(at 1.999996 -1.199896 270)
			(size 0.3683 0.3683)
			(layers "F.Cu" "F.Mask" "F.Paste")
			(net "GND")
		)
		(pad "K17" smd circle
			(at 4.400042 -1.199896 270)
			(size 0.3683 0.3683)
			(layers "F.Cu" "F.Mask" "F.Paste")
			(net "P1V26_BMC_NODE1")
		)
		(pad "K18" smd circle
			(at 5.199888 -1.199896 270)
			(size 0.3683 0.3683)
			(layers "F.Cu" "F.Mask" "F.Paste")
			(net "BMC_ROMA23")
		)
		(pad "K19" smd circle
			(at 5.999988 -1.199896 270)
			(size 0.3683 0.3683)
			(layers "F.Cu" "F.Mask" "F.Paste")
			(net "RST_BMC_NODE1_PERST_L")
		)
		(pad "K20" smd circle
			(at 6.800088 -1.199896 270)
			(size 0.3683 0.3683)
			(layers "F.Cu" "F.Mask" "F.Paste")
			(net "GND")
		)
		(pad "K21" smd circle
			(at 7.599934 -1.199896 270)
			(size 0.3683 0.3683)
			(layers "F.Cu" "F.Mask" "F.Paste")
			(net "PU_I2C_BMC_SCL")
		)
		(pad "K22" smd circle
			(at 8.400034 -1.199896 270)
			(size 0.3683 0.3683)
			(layers "F.Cu" "F.Mask" "F.Paste")
			(net "PU_I2C_BMC_SDA")
		)
		(pad "L1" smd circle
			(at -8.400034 -0.40005 270)
			(size 0.3683 0.3683)
			(layers "F.Cu" "F.Mask" "F.Paste")
			(net "GND")
		)
		(pad "L2" smd circle
			(at -7.599934 -0.40005 270)
			(size 0.3683 0.3683)
			(layers "F.Cu" "F.Mask" "F.Paste")
			(net "GND")
		)
		(pad "L3" smd circle
			(at -6.800088 -0.40005 270)
			(size 0.3683 0.3683)
			(layers "F.Cu" "F.Mask" "F.Paste")
			(net "GND")
		)
		(pad "L4" smd circle
			(at -5.999988 -0.40005 270)
			(size 0.3683 0.3683)
			(layers "F.Cu" "F.Mask" "F.Paste")
			(net "GND")
		)
		(pad "L5" smd circle
			(at -5.199888 -0.40005 270)
			(size 0.3683 0.3683)
			(layers "F.Cu" "F.Mask" "F.Paste")
			(net "GND")
		)
		(pad "L6" smd circle
			(at -4.400042 -0.40005 270)
			(size 0.3683 0.3683)
			(layers "F.Cu" "F.Mask" "F.Paste")
			(net "P1V26_BMC_NODE1")
		)
		(pad "L9" smd circle
			(at -1.999996 -0.40005 270)
			(size 0.3683 0.3683)
			(layers "F.Cu" "F.Mask" "F.Paste")
			(net "GND")
		)
		(pad "L10" smd circle
			(at -1.199896 -0.40005 270)
			(size 0.3683 0.3683)
			(layers "F.Cu" "F.Mask" "F.Paste")
			(net "GND")
		)
		(pad "L11" smd circle
			(at -0.40005 -0.40005 270)
			(size 0.3683 0.3683)
			(layers "F.Cu" "F.Mask" "F.Paste")
			(net "GND")
		)
		(pad "L12" smd circle
			(at 0.40005 -0.40005 270)
			(size 0.3683 0.3683)
			(layers "F.Cu" "F.Mask" "F.Paste")
			(net "GND")
		)
		(pad "L13" smd circle
			(at 1.199896 -0.40005 270)
			(size 0.3683 0.3683)
			(layers "F.Cu" "F.Mask" "F.Paste")
			(net "GND")
		)
		(pad "L14" smd circle
			(at 1.999996 -0.40005 270)
			(size 0.3683 0.3683)
			(layers "F.Cu" "F.Mask" "F.Paste")
			(net "GND")
		)
		(pad "L17" smd circle
			(at 4.400042 -0.40005 270)
			(size 0.3683 0.3683)
			(layers "F.Cu" "F.Mask" "F.Paste")
			(net "P1V26_BMC_NODE1")
		)
		(pad "L18" smd circle
			(at 5.199888 -0.40005 270)
			(size 0.3683 0.3683)
			(layers "F.Cu" "F.Mask" "F.Paste")
			(net "BMC_ROMA12")
		)
		(pad "L19" smd circle
			(at 5.999988 -0.40005 270)
			(size 0.3683 0.3683)
			(layers "F.Cu" "F.Mask" "F.Paste")
			(net "BMC_ROMA13")
		)
		(pad "L20" smd circle
			(at 6.800088 -0.40005 270)
			(size 0.3683 0.3683)
			(layers "F.Cu" "F.Mask" "F.Paste")
			(net "BMC_ROMA14")
		)
		(pad "L21" smd circle
			(at 7.599934 -0.40005 270)
			(size 0.3683 0.3683)
			(layers "F.Cu" "F.Mask" "F.Paste")
			(net "BMC_ROMA15")
		)
		(pad "L22" smd circle
			(at 8.400034 -0.40005 270)
			(size 0.3683 0.3683)
			(layers "F.Cu" "F.Mask" "F.Paste")
			(net "BMC_ROMA22")
		)
		(pad "M1" smd circle
			(at -8.400034 0.40005 270)
			(size 0.3683 0.3683)
			(layers "F.Cu" "F.Mask" "F.Paste")
			(net "GND")
		)
		(pad "M2" smd circle
			(at -7.599934 0.40005 270)
			(size 0.3683 0.3683)
			(layers "F.Cu" "F.Mask" "F.Paste")
			(net "GND")
		)
		(pad "M3" smd circle
			(at -6.800088 0.40005 270)
			(size 0.3683 0.3683)
			(layers "F.Cu" "F.Mask" "F.Paste")
			(net "GND")
		)
		(pad "M4" smd circle
			(at -5.999988 0.40005 270)
			(size 0.3683 0.3683)
			(layers "F.Cu" "F.Mask" "F.Paste")
			(net "GND")
		)
		(pad "M5" smd circle
			(at -5.199888 0.40005 270)
			(size 0.3683 0.3683)
			(layers "F.Cu" "F.Mask" "F.Paste")
			(net "GND")
		)
		(pad "M6" smd circle
			(at -4.400042 0.40005 270)
			(size 0.3683 0.3683)
			(layers "F.Cu" "F.Mask" "F.Paste")
			(net "P3V3_NODE1")
		)
		(pad "M9" smd circle
			(at -1.999996 0.40005 270)
			(size 0.3683 0.3683)
			(layers "F.Cu" "F.Mask" "F.Paste")
			(net "GND")
		)
		(pad "M10" smd circle
			(at -1.199896 0.40005 270)
			(size 0.3683 0.3683)
			(layers "F.Cu" "F.Mask" "F.Paste")
			(net "GND")
		)
		(pad "M11" smd circle
			(at -0.40005 0.40005 270)
			(size 0.3683 0.3683)
			(layers "F.Cu" "F.Mask" "F.Paste")
			(net "GND")
		)
		(pad "M12" smd circle
			(at 0.40005 0.40005 270)
			(size 0.3683 0.3683)
			(layers "F.Cu" "F.Mask" "F.Paste")
			(net "GND")
		)
		(pad "M13" smd circle
			(at 1.199896 0.40005 270)
			(size 0.3683 0.3683)
			(layers "F.Cu" "F.Mask" "F.Paste")
			(net "GND")
		)
		(pad "M14" smd circle
			(at 1.999996 0.40005 270)
			(size 0.3683 0.3683)
			(layers "F.Cu" "F.Mask" "F.Paste")
			(net "GND")
		)
		(pad "M17" smd circle
			(at 4.400042 0.40005 270)
			(size 0.3683 0.3683)
			(layers "F.Cu" "F.Mask" "F.Paste")
			(net "P3V3_NODE1")
		)
		(pad "M18" smd circle
			(at 5.199888 0.40005 270)
			(size 0.3683 0.3683)
			(layers "F.Cu" "F.Mask" "F.Paste")
			(net "BMC_ROMA19")
		)
		(pad "M19" smd circle
			(at 5.999988 0.40005 270)
			(size 0.3683 0.3683)
			(layers "F.Cu" "F.Mask" "F.Paste")
			(net "BMC_ROMA8")
		)
		(pad "M20" smd circle
			(at 6.800088 0.40005 270)
			(size 0.3683 0.3683)
			(layers "F.Cu" "F.Mask" "F.Paste")
			(net "BMC_ROMA9")
		)
		(pad "M21" smd circle
			(at 7.599934 0.40005 270)
			(size 0.3683 0.3683)
			(layers "F.Cu" "F.Mask" "F.Paste")
			(net "BMC_ROMA10")
		)
		(pad "M22" smd circle
			(at 8.400034 0.40005 270)
			(size 0.3683 0.3683)
			(layers "F.Cu" "F.Mask" "F.Paste")
			(net "BMC_ROMA11")
		)
		(pad "N1" smd circle
			(at -8.400034 1.199896 270)
			(size 0.3683 0.3683)
			(layers "F.Cu" "F.Mask" "F.Paste")
			(net "GND")
		)
		(pad "N2" smd circle
			(at -7.599934 1.199896 270)
			(size 0.3683 0.3683)
			(layers "F.Cu" "F.Mask" "F.Paste")
			(net "GND")
		)
		(pad "N3" smd circle
			(at -6.800088 1.199896 270)
			(size 0.3683 0.3683)
			(layers "F.Cu" "F.Mask" "F.Paste")
			(net "GND")
		)
		(pad "N4" smd circle
			(at -5.999988 1.199896 270)
			(size 0.3683 0.3683)
			(layers "F.Cu" "F.Mask" "F.Paste")
			(net "GND")
		)
		(pad "N5" smd circle
			(at -5.199888 1.199896 270)
			(size 0.3683 0.3683)
			(layers "F.Cu" "F.Mask" "F.Paste")
			(net "GND")
		)
		(pad "N6" smd circle
			(at -4.400042 1.199896 270)
			(size 0.3683 0.3683)
			(layers "F.Cu" "F.Mask" "F.Paste")
			(net "P3V3_NODE1")
		)
		(pad "N9" smd circle
			(at -1.999996 1.199896 270)
			(size 0.3683 0.3683)
			(layers "F.Cu" "F.Mask" "F.Paste")
			(net "GND")
		)
		(pad "N10" smd circle
			(at -1.199896 1.199896 270)
			(size 0.3683 0.3683)
			(layers "F.Cu" "F.Mask" "F.Paste")
			(net "GND")
		)
		(pad "N11" smd circle
			(at -0.40005 1.199896 270)
			(size 0.3683 0.3683)
			(layers "F.Cu" "F.Mask" "F.Paste")
			(net "GND")
		)
		(pad "N12" smd circle
			(at 0.40005 1.199896 270)
			(size 0.3683 0.3683)
			(layers "F.Cu" "F.Mask" "F.Paste")
			(net "GND")
		)
		(pad "N13" smd circle
			(at 1.199896 1.199896 270)
			(size 0.3683 0.3683)
			(layers "F.Cu" "F.Mask" "F.Paste")
			(net "GND")
		)
		(pad "N14" smd circle
			(at 1.999996 1.199896 270)
			(size 0.3683 0.3683)
			(layers "F.Cu" "F.Mask" "F.Paste")
			(net "GND")
		)
		(pad "N17" smd circle
			(at 4.400042 1.199896 270)
			(size 0.3683 0.3683)
			(layers "F.Cu" "F.Mask" "F.Paste")
			(net "P3V3_NODE1")
		)
		(pad "N18" smd circle
			(at 5.199888 1.199896 270)
			(size 0.3683 0.3683)
			(layers "F.Cu" "F.Mask" "F.Paste")
			(net "BMC_ROMA17")
		)
		(pad "N19" smd circle
			(at 5.999988 1.199896 270)
			(size 0.3683 0.3683)
			(layers "F.Cu" "F.Mask" "F.Paste")
			(net "BMC_ROMA18")
		)
		(pad "N20" smd circle
			(at 6.800088 1.199896 270)
			(size 0.3683 0.3683)
			(layers "F.Cu" "F.Mask" "F.Paste")
			(net "BMC_ROMA21")
		)
		(pad "N21" smd circle
			(at 7.599934 1.199896 270)
			(size 0.3683 0.3683)
			(layers "F.Cu" "F.Mask" "F.Paste")
			(net "Net_515")
		)
		(pad "N22" smd circle
			(at 8.400034 1.199896 270)
			(size 0.3683 0.3683)
			(layers "F.Cu" "F.Mask" "F.Paste")
			(net "BMC_ROMA20")
		)
		(pad "P1" smd circle
			(at -8.400034 1.999996 270)
			(size 0.3683 0.3683)
			(layers "F.Cu" "F.Mask" "F.Paste")
			(net "BMC_NODE1_DACAV33")
		)
		(pad "P2" smd circle
			(at -7.599934 1.999996 270)
			(size 0.3683 0.3683)
			(layers "F.Cu" "F.Mask" "F.Paste")
			(net "BMC_NODE1_ADCREXT")
		)
		(pad "P3" smd circle
			(at -6.800088 1.999996 270)
			(size 0.3683 0.3683)
			(layers "F.Cu" "F.Mask" "F.Paste")
			(net "BMC_NODE1_ADCAV33")
		)
		(pad "P4" smd circle
			(at -5.999988 1.999996 270)
			(size 0.3683 0.3683)
			(layers "F.Cu" "F.Mask" "F.Paste")
			(net "GND")
		)
		(pad "P5" smd circle
			(at -5.199888 1.999996 270)
			(size 0.3683 0.3683)
			(layers "F.Cu" "F.Mask" "F.Paste")
			(net "GND")
		)
		(pad "P6" smd circle
			(at -4.400042 1.999996 270)
			(size 0.3683 0.3683)
			(layers "F.Cu" "F.Mask" "F.Paste")
			(net "P1V26_BMC_NODE1")
		)
		(pad "P9" smd circle
			(at -1.999996 1.999996 270)
			(size 0.3683 0.3683)
			(layers "F.Cu" "F.Mask" "F.Paste")
			(net "GND")
		)
		(pad "P10" smd circle
			(at -1.199896 1.999996 270)
			(size 0.3683 0.3683)
			(layers "F.Cu" "F.Mask" "F.Paste")
			(net "GND")
		)
		(pad "P11" smd circle
			(at -0.40005 1.999996 270)
			(size 0.3683 0.3683)
			(layers "F.Cu" "F.Mask" "F.Paste")
			(net "GND")
		)
		(pad "P12" smd circle
			(at 0.40005 1.999996 270)
			(size 0.3683 0.3683)
			(layers "F.Cu" "F.Mask" "F.Paste")
			(net "GND")
		)
		(pad "P13" smd circle
			(at 1.199896 1.999996 270)
			(size 0.3683 0.3683)
			(layers "F.Cu" "F.Mask" "F.Paste")
			(net "GND")
		)
		(pad "P14" smd circle
			(at 1.999996 1.999996 270)
			(size 0.3683 0.3683)
			(layers "F.Cu" "F.Mask" "F.Paste")
			(net "GND")
		)
		(pad "P17" smd circle
			(at 4.400042 1.999996 270)
			(size 0.3683 0.3683)
			(layers "F.Cu" "F.Mask" "F.Paste")
			(net "P1V26_BMC_NODE1")
		)
		(pad "P18" smd circle
			(at 5.199888 1.999996 270)
			(size 0.3683 0.3683)
			(layers "F.Cu" "F.Mask" "F.Paste")
			(net "BMC_ROMA3")
		)
		(pad "P19" smd circle
			(at 5.999988 1.999996 270)
			(size 0.3683 0.3683)
			(layers "F.Cu" "F.Mask" "F.Paste")
			(net "BMC_ROMA4")
		)
		(pad "P20" smd circle
			(at 6.800088 1.999996 270)
			(size 0.3683 0.3683)
			(layers "F.Cu" "F.Mask" "F.Paste")
			(net "BMC_ROMA5")
		)
		(pad "P21" smd circle
			(at 7.599934 1.999996 270)
			(size 0.3683 0.3683)
			(layers "F.Cu" "F.Mask" "F.Paste")
			(net "BMC_ROMA6")
		)
		(pad "P22" smd circle
			(at 8.400034 1.999996 270)
			(size 0.3683 0.3683)
			(layers "F.Cu" "F.Mask" "F.Paste")
			(net "BMC_ROMA7")
		)
		(pad "R1" smd circle
			(at -8.400034 2.800096 270)
			(size 0.3683 0.3683)
			(layers "F.Cu" "F.Mask" "F.Paste")
			(net "BMC_NODE1_DACRSET")
		)
		(pad "R2" smd circle
			(at -7.599934 2.800096 270)
			(size 0.3683 0.3683)
			(layers "F.Cu" "F.Mask" "F.Paste")
			(net "BMC_NODE1_GFX_RED")
		)
		(pad "R3" smd circle
			(at -6.800088 2.800096 270)
			(size 0.3683 0.3683)
			(layers "F.Cu" "F.Mask" "F.Paste")
			(net "BMC_NODE1_GFX_GREEN")
		)
		(pad "R4" smd circle
			(at -5.999988 2.800096 270)
			(size 0.3683 0.3683)
			(layers "F.Cu" "F.Mask" "F.Paste")
			(net "BMC_NODE1_GFX_BLUE")
		)
		(pad "R5" smd circle
			(at -5.199888 2.800096 270)
			(size 0.3683 0.3683)
			(layers "F.Cu" "F.Mask" "F.Paste")
			(net "GND")
		)
		(pad "R6" smd circle
			(at -4.400042 2.800096 270)
			(size 0.3683 0.3683)
			(layers "F.Cu" "F.Mask" "F.Paste")
			(net "P1V26_BMC_NODE1")
		)
		(pad "R17" smd circle
			(at 4.400042 2.800096 270)
			(size 0.3683 0.3683)
			(layers "F.Cu" "F.Mask" "F.Paste")
			(net "P1V26_BMC_NODE1")
		)
		(pad "R18" smd circle
			(at 5.199888 2.800096 270)
			(size 0.3683 0.3683)
			(layers "F.Cu" "F.Mask" "F.Paste")
			(net "Net_516")
		)
		(pad "R19" smd circle
			(at 5.999988 2.800096 270)
			(size 0.3683 0.3683)
			(layers "F.Cu" "F.Mask" "F.Paste")
			(net "Net_472")
		)
		(pad "R20" smd circle
			(at 6.800088 2.800096 270)
			(size 0.3683 0.3683)
			(layers "F.Cu" "F.Mask" "F.Paste")
			(net "BMC_ROMA0")
		)
		(pad "R21" smd circle
			(at 7.599934 2.800096 270)
			(size 0.3683 0.3683)
			(layers "F.Cu" "F.Mask" "F.Paste")
			(net "BMC_ROMA1")
		)
		(pad "R22" smd circle
			(at 8.400034 2.800096 270)
			(size 0.3683 0.3683)
			(layers "F.Cu" "F.Mask" "F.Paste")
			(net "BMC_ROMA2")
		)
		(pad "T1" smd circle
			(at -8.400034 3.599942 270)
			(size 0.3683 0.3683)
			(layers "F.Cu" "F.Mask" "F.Paste")
			(net "SMB_BMC_NODE1_DDC_DAT")
		)
		(pad "T2" smd circle
			(at -7.599934 3.599942 270)
			(size 0.3683 0.3683)
			(layers "F.Cu" "F.Mask" "F.Paste")
			(net "SMB_BMC_NODE1_DDC_CLK")
		)
		(pad "T3" smd circle
			(at -6.800088 3.599942 270)
			(size 0.3683 0.3683)
			(layers "F.Cu" "F.Mask" "F.Paste")
			(net "BMC_NODE1_DACAV33")
		)
		(pad "T4" smd circle
			(at -5.999988 3.599942 270)
			(size 0.3683 0.3683)
			(layers "F.Cu" "F.Mask" "F.Paste")
			(net "BMC_NODE1_GFX_HSYNC_R")
		)
		(pad "T5" smd circle
			(at -5.199888 3.599942 270)
			(size 0.3683 0.3683)
			(layers "F.Cu" "F.Mask" "F.Paste")
			(net "Net_473")
		)
		(pad "T18" smd circle
			(at 5.199888 3.599942 270)
			(size 0.3683 0.3683)
			(layers "F.Cu" "F.Mask" "F.Paste")
			(net "BMC_ROMA16")
		)
		(pad "T19" smd circle
			(at 5.999988 3.599942 270)
			(size 0.3683 0.3683)
			(layers "F.Cu" "F.Mask" "F.Paste")
			(net "Net_519")
		)
		(pad "T20" smd circle
			(at 6.800088 3.599942 270)
			(size 0.3683 0.3683)
			(layers "F.Cu" "F.Mask" "F.Paste")
			(net "BMC_ROMD2")
		)
		(pad "T21" smd circle
			(at 7.599934 3.599942 270)
			(size 0.3683 0.3683)
			(layers "F.Cu" "F.Mask" "F.Paste")
			(net "BMC_ROMD1")
		)
		(pad "T22" smd circle
			(at 8.400034 3.599942 270)
			(size 0.3683 0.3683)
			(layers "F.Cu" "F.Mask" "F.Paste")
			(net "BMC_ROMD0")
		)
		(pad "U1" smd circle
			(at -8.400034 4.400042 270)
			(size 0.3683 0.3683)
			(layers "F.Cu" "F.Mask" "F.Paste")
			(net "Net_475")
		)
		(pad "U2" smd circle
			(at -7.599934 4.400042 270)
			(size 0.3683 0.3683)
			(layers "F.Cu" "F.Mask" "F.Paste")
			(net "BMC_NODE1_GFX_VSYNC_R")
		)
		(pad "U3" smd circle
			(at -6.800088 4.400042 270)
			(size 0.3683 0.3683)
			(layers "F.Cu" "F.Mask" "F.Paste")
			(net "Net_479")
		)
		(pad "U4" smd circle
			(at -5.999988 4.400042 270)
			(size 0.3683 0.3683)
			(layers "F.Cu" "F.Mask" "F.Paste")
			(net "Net_477")
		)
		(pad "U5" smd circle
			(at -5.199888 4.400042 270)
			(size 0.3683 0.3683)
			(layers "F.Cu" "F.Mask" "F.Paste")
			(net "Net_471")
		)
		(pad "U8" smd circle
			(at -2.800096 4.400042 270)
			(size 0.3683 0.3683)
			(layers "F.Cu" "F.Mask" "F.Paste")
			(net "P3V3_NODE1")
		)
		(pad "U9" smd circle
			(at -1.999996 4.400042 270)
			(size 0.3683 0.3683)
			(layers "F.Cu" "F.Mask" "F.Paste")
			(net "P3V3_NODE1")
		)
		(pad "U10" smd circle
			(at -1.199896 4.400042 270)
			(size 0.3683 0.3683)
			(layers "F.Cu" "F.Mask" "F.Paste")
			(net "P1V538_BMC_NODE1")
		)
		(pad "U11" smd circle
			(at -0.40005 4.400042 270)
			(size 0.3683 0.3683)
			(layers "F.Cu" "F.Mask" "F.Paste")
			(net "P1V538_BMC_NODE1")
		)
		(pad "U12" smd circle
			(at 0.40005 4.400042 270)
			(size 0.3683 0.3683)
			(layers "F.Cu" "F.Mask" "F.Paste")
			(net "P1V26_BMC_NODE1")
		)
		(pad "U13" smd circle
			(at 1.199896 4.400042 270)
			(size 0.3683 0.3683)
			(layers "F.Cu" "F.Mask" "F.Paste")
			(net "P1V26_BMC_NODE1")
		)
		(pad "U14" smd circle
			(at 1.999996 4.400042 270)
			(size 0.3683 0.3683)
			(layers "F.Cu" "F.Mask" "F.Paste")
			(net "P1V538_BMC_NODE1")
		)
		(pad "U15" smd circle
			(at 2.800096 4.400042 270)
			(size 0.3683 0.3683)
			(layers "F.Cu" "F.Mask" "F.Paste")
			(net "P1V538_BMC_NODE1")
		)
		(pad "U18" smd circle
			(at 5.199888 4.400042 270)
			(size 0.3683 0.3683)
			(layers "F.Cu" "F.Mask" "F.Paste")
			(net "Net_1771")
		)
		(pad "U19" smd circle
			(at 5.999988 4.400042 270)
			(size 0.3683 0.3683)
			(layers "F.Cu" "F.Mask" "F.Paste")
			(net "Net_524")
		)
		(pad "U20" smd circle
			(at 6.800088 4.400042 270)
			(size 0.3683 0.3683)
			(layers "F.Cu" "F.Mask" "F.Paste")
			(net "Net_517")
		)
		(pad "U21" smd circle
			(at 7.599934 4.400042 270)
			(size 0.3683 0.3683)
			(layers "F.Cu" "F.Mask" "F.Paste")
			(net "BMC_ROMD4")
		)
		(pad "U22" smd circle
			(at 8.400034 4.400042 270)
			(size 0.3683 0.3683)
			(layers "F.Cu" "F.Mask" "F.Paste")
			(net "BMC_ROMD3")
		)
		(pad "V1" smd circle
			(at -8.400034 5.199888 270)
			(size 0.3683 0.3683)
			(layers "F.Cu" "F.Mask" "F.Paste")
			(net "Net_478")
		)
		(pad "V2" smd circle
			(at -7.599934 5.199888 270)
			(size 0.3683 0.3683)
			(layers "F.Cu" "F.Mask" "F.Paste")
			(net "Net_480")
		)
		(pad "V3" smd circle
			(at -6.800088 5.199888 270)
			(size 0.3683 0.3683)
			(layers "F.Cu" "F.Mask" "F.Paste")
			(net "Net_468")
		)
		(pad "V4" smd circle
			(at -5.999988 5.199888 270)
			(size 0.3683 0.3683)
			(layers "F.Cu" "F.Mask" "F.Paste")
			(net "Net_483")
		)
		(pad "V5" smd circle
			(at -5.199888 5.199888 270)
			(size 0.3683 0.3683)
			(layers "F.Cu" "F.Mask" "F.Paste")
			(net "Net_1751")
		)
		(pad "V6" smd circle
			(at -4.400042 5.199888 270)
			(size 0.3683 0.3683)
			(layers "F.Cu" "F.Mask" "F.Paste")
			(net "Net_509")
		)
		(pad "V7" smd circle
			(at -3.599942 5.199888 270)
			(size 0.3683 0.3683)
			(layers "F.Cu" "F.Mask" "F.Paste")
			(net "Net_1781")
		)
		(pad "V8" smd circle
			(at -2.800096 5.199888 270)
			(size 0.3683 0.3683)
			(layers "F.Cu" "F.Mask" "F.Paste")
			(net "BMC_NODE1_DDR_DM1")
		)
		(pad "V9" smd circle
			(at -1.999996 5.199888 270)
			(size 0.3683 0.3683)
			(layers "F.Cu" "F.Mask" "F.Paste")
			(net "BMC_NODE1_DDR_D13")
		)
		(pad "V10" smd circle
			(at -1.199896 5.199888 270)
			(size 0.3683 0.3683)
			(layers "F.Cu" "F.Mask" "F.Paste")
			(net "BMC_NODE1_DDR_D8")
		)
		(pad "V11" smd circle
			(at -0.40005 5.199888 270)
			(size 0.3683 0.3683)
			(layers "F.Cu" "F.Mask" "F.Paste")
			(net "BMC_NODE1_DDR_D6")
		)
		(pad "V12" smd circle
			(at 0.40005 5.199888 270)
			(size 0.3683 0.3683)
			(layers "F.Cu" "F.Mask" "F.Paste")
			(net "BMC_NODE1_DDR_D1")
		)
		(pad "V13" smd circle
			(at 1.199896 5.199888 270)
			(size 0.3683 0.3683)
			(layers "F.Cu" "F.Mask" "F.Paste")
			(net "P0V75_BMC_VTTREF_NODE1")
		)
		(pad "V14" smd circle
			(at 1.999996 5.199888 270)
			(size 0.3683 0.3683)
			(layers "F.Cu" "F.Mask" "F.Paste")
			(net "BMC_NODE1_DDR_ODT")
		)
		(pad "V15" smd circle
			(at 2.800096 5.199888 270)
			(size 0.3683 0.3683)
			(layers "F.Cu" "F.Mask" "F.Paste")
			(net "BMC_NODE1_DDR_MA2")
		)
		(pad "V16" smd circle
			(at 3.599942 5.199888 270)
			(size 0.3683 0.3683)
			(layers "F.Cu" "F.Mask" "F.Paste")
			(net "BMC_NODE1_DDR_IOZ")
		)
		(pad "V17" smd circle
			(at 4.400042 5.199888 270)
			(size 0.3683 0.3683)
			(layers "F.Cu" "F.Mask" "F.Paste")
			(net "BMC_NODE1_HPLLAV33")
		)
		(pad "V18" smd circle
			(at 5.199888 5.199888 270)
			(size 0.3683 0.3683)
			(layers "F.Cu" "F.Mask" "F.Paste")
			(net "GND")
		)
		(pad "V19" smd circle
			(at 5.999988 5.199888 270)
			(size 0.3683 0.3683)
			(layers "F.Cu" "F.Mask" "F.Paste")
			(net "PECIVDD")
		)
		(pad "V20" smd circle
			(at 6.800088 5.199888 270)
			(size 0.3683 0.3683)
			(layers "F.Cu" "F.Mask" "F.Paste")
			(net "Net_527")
		)
		(pad "V21" smd circle
			(at 7.599934 5.199888 270)
			(size 0.3683 0.3683)
			(layers "F.Cu" "F.Mask" "F.Paste")
			(net "Net_523")
		)
		(pad "V22" smd circle
			(at 8.400034 5.199888 270)
			(size 0.3683 0.3683)
			(layers "F.Cu" "F.Mask" "F.Paste")
			(net "Net_518")
		)
		(pad "W1" smd circle
			(at -8.400034 5.999988 270)
			(size 0.3683 0.3683)
			(layers "F.Cu" "F.Mask" "F.Paste")
			(net "Net_470")
		)
		(pad "W2" smd circle
			(at -7.599934 5.999988 270)
			(size 0.3683 0.3683)
			(layers "F.Cu" "F.Mask" "F.Paste")
			(net "Net_481")
		)
		(pad "W3" smd circle
			(at -6.800088 5.999988 270)
			(size 0.3683 0.3683)
			(layers "F.Cu" "F.Mask" "F.Paste")
			(net "Net_1750")
		)
		(pad "W4" smd circle
			(at -5.999988 5.999988 270)
			(size 0.3683 0.3683)
			(layers "F.Cu" "F.Mask" "F.Paste")
			(net "Net_1772")
		)
		(pad "W5" smd circle
			(at -5.199888 5.999988 270)
			(size 0.3683 0.3683)
			(layers "F.Cu" "F.Mask" "F.Paste")
			(net "Net_1774")
		)
		(pad "W6" smd circle
			(at -4.400042 5.999988 270)
			(size 0.3683 0.3683)
			(layers "F.Cu" "F.Mask" "F.Paste")
			(net "Net_508")
		)
		(pad "W7" smd circle
			(at -3.599942 5.999988 270)
			(size 0.3683 0.3683)
			(layers "F.Cu" "F.Mask" "F.Paste")
			(net "Net_1784")
		)
		(pad "W8" smd circle
			(at -2.800096 5.999988 270)
			(size 0.3683 0.3683)
			(layers "F.Cu" "F.Mask" "F.Paste")
			(net "BMC_NODE1_DDR_D15")
		)
		(pad "W9" smd circle
			(at -1.999996 5.999988 270)
			(size 0.3683 0.3683)
			(layers "F.Cu" "F.Mask" "F.Paste")
			(net "BMC_NODE1_DDR_D12")
		)
		(pad "W10" smd circle
			(at -1.199896 5.999988 270)
			(size 0.3683 0.3683)
			(layers "F.Cu" "F.Mask" "F.Paste")
			(net "BMC_NODE1_DDR_DM0")
		)
		(pad "W11" smd circle
			(at -0.40005 5.999988 270)
			(size 0.3683 0.3683)
			(layers "F.Cu" "F.Mask" "F.Paste")
			(net "BMC_NODE1_DDR_D5")
		)
		(pad "W12" smd circle
			(at 0.40005 5.999988 270)
			(size 0.3683 0.3683)
			(layers "F.Cu" "F.Mask" "F.Paste")
			(net "BMC_NODE1_DDR_D0")
		)
		(pad "W13" smd circle
			(at 1.199896 5.999988 270)
			(size 0.3683 0.3683)
			(layers "F.Cu" "F.Mask" "F.Paste")
			(net "BMC_NODE1_DDR_RAS_L")
		)
		(pad "W14" smd circle
			(at 1.999996 5.999988 270)
			(size 0.3683 0.3683)
			(layers "F.Cu" "F.Mask" "F.Paste")
			(net "BMC_NODE1_DDR_BA0")
		)
		(pad "W15" smd circle
			(at 2.800096 5.999988 270)
			(size 0.3683 0.3683)
			(layers "F.Cu" "F.Mask" "F.Paste")
			(net "BMC_NODE1_DDR_MA1")
		)
		(pad "W16" smd circle
			(at 3.599942 5.999988 270)
			(size 0.3683 0.3683)
			(layers "F.Cu" "F.Mask" "F.Paste")
			(net "BMC_NODE1_DDR_MA5")
		)
		(pad "W17" smd circle
			(at 4.400042 5.999988 270)
			(size 0.3683 0.3683)
			(layers "F.Cu" "F.Mask" "F.Paste")
			(net "BMC_NODE1_DDR_MA12")
		)
		(pad "W18" smd circle
			(at 5.199888 5.999988 270)
			(size 0.3683 0.3683)
			(layers "F.Cu" "F.Mask" "F.Paste")
			(net "P3V3_NODE1")
		)
		(pad "W19" smd circle
			(at 5.999988 5.999988 270)
			(size 0.3683 0.3683)
			(layers "F.Cu" "F.Mask" "F.Paste")
			(net "BMC_NODE1_V1PLLAV12")
		)
		(pad "W20" smd circle
			(at 6.800088 5.999988 270)
			(size 0.3683 0.3683)
			(layers "F.Cu" "F.Mask" "F.Paste")
			(net "FM_BMC_NODE1_RESET_L")
		)
		(pad "W21" smd circle
			(at 7.599934 5.999988 270)
			(size 0.3683 0.3683)
			(layers "F.Cu" "F.Mask" "F.Paste")
			(net "Net_526")
		)
		(pad "W22" smd circle
			(at 8.400034 5.999988 270)
			(size 0.3683 0.3683)
			(layers "F.Cu" "F.Mask" "F.Paste")
			(net "Net_522")
		)
		(pad "Y1" smd circle
			(at -8.400034 6.800088 270)
			(size 0.3683 0.3683)
			(layers "F.Cu" "F.Mask" "F.Paste")
			(net "Net_482")
		)
		(pad "Y2" smd circle
			(at -7.599934 6.800088 270)
			(size 0.3683 0.3683)
			(layers "F.Cu" "F.Mask" "F.Paste")
			(net "Net_474")
		)
		(pad "Y3" smd circle
			(at -6.800088 6.800088 270)
			(size 0.3683 0.3683)
			(layers "F.Cu" "F.Mask" "F.Paste")
			(net "Net_1773")
		)
		(pad "Y4" smd circle
			(at -5.999988 6.800088 270)
			(size 0.3683 0.3683)
			(layers "F.Cu" "F.Mask" "F.Paste")
			(net "Net_1775")
		)
		(pad "Y5" smd circle
			(at -5.199888 6.800088 270)
			(size 0.3683 0.3683)
			(layers "F.Cu" "F.Mask" "F.Paste")
			(net "Net_1778")
		)
		(pad "Y6" smd circle
			(at -4.400042 6.800088 270)
			(size 0.3683 0.3683)
			(layers "F.Cu" "F.Mask" "F.Paste")
			(net "Net_1782")
		)
		(pad "Y7" smd circle
			(at -3.599942 6.800088 270)
			(size 0.3683 0.3683)
			(layers "F.Cu" "F.Mask" "F.Paste")
			(net "Net_506")
		)
		(pad "Y8" smd circle
			(at -2.800096 6.800088 270)
			(size 0.3683 0.3683)
			(layers "F.Cu" "F.Mask" "F.Paste")
			(net "BMC_NODE1_DDR_D14")
		)
		(pad "Y9" smd circle
			(at -1.999996 6.800088 270)
			(size 0.3683 0.3683)
			(layers "F.Cu" "F.Mask" "F.Paste")
			(net "BMC_NODE1_DDR_D11")
		)
		(pad "Y10" smd circle
			(at -1.199896 6.800088 270)
			(size 0.3683 0.3683)
			(layers "F.Cu" "F.Mask" "F.Paste")
			(net "BMC_NODE1_DDR_D7")
		)
		(pad "Y11" smd circle
			(at -0.40005 6.800088 270)
			(size 0.3683 0.3683)
			(layers "F.Cu" "F.Mask" "F.Paste")
			(net "BMC_NODE1_DDR_D4")
		)
		(pad "Y12" smd circle
			(at 0.40005 6.800088 270)
			(size 0.3683 0.3683)
			(layers "F.Cu" "F.Mask" "F.Paste")
			(net "BMC_NODE1_DDR_CKE")
		)
		(pad "Y13" smd circle
			(at 1.199896 6.800088 270)
			(size 0.3683 0.3683)
			(layers "F.Cu" "F.Mask" "F.Paste")
			(net "BMC_NODE1_DDR_WE_L")
		)
		(pad "Y14" smd circle
			(at 1.999996 6.800088 270)
			(size 0.3683 0.3683)
			(layers "F.Cu" "F.Mask" "F.Paste")
			(net "BMC_NODE1_DDR_BA2")
		)
		(pad "Y15" smd circle
			(at 2.800096 6.800088 270)
			(size 0.3683 0.3683)
			(layers "F.Cu" "F.Mask" "F.Paste")
			(net "BMC_NODE1_DDR_MA10")
		)
		(pad "Y16" smd circle
			(at 3.599942 6.800088 270)
			(size 0.3683 0.3683)
			(layers "F.Cu" "F.Mask" "F.Paste")
			(net "BMC_NODE1_DDR_MA3")
		)
		(pad "Y17" smd circle
			(at 4.400042 6.800088 270)
			(size 0.3683 0.3683)
			(layers "F.Cu" "F.Mask" "F.Paste")
			(net "BMC_NODE1_DDR_MA13")
		)
		(pad "Y18" smd circle
			(at 5.199888 6.800088 270)
			(size 0.3683 0.3683)
			(layers "F.Cu" "F.Mask" "F.Paste")
			(net "P1V26_BMC_NODE1")
		)
		(pad "Y19" smd circle
			(at 5.999988 6.800088 270)
			(size 0.3683 0.3683)
			(layers "F.Cu" "F.Mask" "F.Paste")
			(net "GND")
		)
		(pad "Y20" smd circle
			(at 6.800088 6.800088 270)
			(size 0.3683 0.3683)
			(layers "F.Cu" "F.Mask" "F.Paste")
			(net "BMC_NODE1_V1PLLAV12")
		)
		(pad "Y21" smd circle
			(at 7.599934 6.800088 270)
			(size 0.3683 0.3683)
			(layers "F.Cu" "F.Mask" "F.Paste")
			(net "Net_1769")
		)
		(pad "Y22" smd circle
			(at 8.400034 6.800088 270)
			(size 0.3683 0.3683)
			(layers "F.Cu" "F.Mask" "F.Paste")
			(net "Net_525")
		)
		(zone
			(layer "F.Cu")
			(hatch none 0.5)
			(connect_pads
				(clearance 0)
			)
			(min_thickness 0.25)
			(keepout
				(tracks allowed)
				(vias not_allowed)
				(pads allowed)
				(copperpour not_allowed)
				(footprints allowed)
			)
			(placement
				(enabled no)
				(sheetname "")
			)
			(fill
				(thermal_gap 0.5)
				(thermal_bridge_width 0.5)
				(island_removal_mode 0)
			)
			(polygon
				(pts
					(xy 56.343804 -135.011922) (xy 75.139804 -135.011922) (xy 75.139804 -134.707122) (xy 56.343804 -134.707122)
				)
			)
		)
		(zone
			(layer "F.Cu")
			(hatch none 0.5)
			(connect_pads
				(clearance 0)
			)
			(min_thickness 0.25)
			(keepout
				(tracks allowed)
				(vias not_allowed)
				(pads allowed)
				(copperpour not_allowed)
				(footprints allowed)
			)
			(placement
				(enabled no)
				(sheetname "")
			)
			(fill
				(thermal_gap 0.5)
				(thermal_bridge_width 0.5)
				(island_removal_mode 0)
			)
			(polygon
				(pts
					(xy 65.589404 -125.461522) (xy 65.589404 -144.257522) (xy 65.894204 -144.257522) (xy 65.894204 -125.461522)
				)
			)
		)
	)
	(footprint ""
		(layer "F.Cu")
		(at 134.85876 -108.370624 90)
		(property "Reference" "R188"
			(at -6.585204 0.586486 90)
			(unlocked yes)
			(layer "F.SilkS")
			(effects
				(font
					(size 0.7874 0.5842)
					(thickness 0.1524)
				)
				(justify left)
			)
		)
		(property "Value" ""
			(at 0 0 90)
			(layer "F.Fab")
			(effects
				(font
					(size 1.27 1.27)
				)
			)
		)
		(duplicate_pad_numbers_are_jumpers no)
		(fp_line
			(start 0.7874 -0.4064)
			(end 0.7874 0.4064)
			(stroke
				(width 0.1524)
				(type default)
			)
			(layer "F.SilkS")
		)
		(fp_line
			(start -0.7874 -0.4064)
			(end 0.7874 -0.4064)
			(stroke
				(width 0.1524)
				(type default)
			)
			(layer "F.SilkS")
		)
		(fp_line
			(start 0.7874 0.4064)
			(end -0.7874 0.4064)
			(stroke
				(width 0.1524)
				(type default)
			)
			(layer "F.SilkS")
		)
		(fp_line
			(start -0.7874 0.4064)
			(end -0.7874 -0.4064)
			(stroke
				(width 0.1524)
				(type default)
			)
			(layer "F.SilkS")
		)
		(fp_poly
			(pts
				(xy -0.508 0.2794) (xy -0.508 0.2286) (xy -0.635 0.2286) (xy -0.635 -0.254) (xy -0.5334 -0.254)
				(xy -0.5334 -0.2794) (xy 0.5334 -0.2794) (xy 0.5334 -0.254) (xy 0.635 -0.254) (xy 0.635 0.254) (xy 0.5334 0.254)
				(xy 0.5334 0.2794)
			)
			(stroke
				(width 0)
				(type default)
			)
			(fill no)
			(layer "F.CrtYd")
		)
		(pad "1" smd rect
			(at 0.40005 0 90)
			(size 0.4572 0.508)
			(layers "F.Cu" "F.Mask" "F.Paste")
			(net "CLP_ITP_EN_NODE1")
		)
		(pad "2" smd rect
			(at -0.40005 0 90)
			(size 0.4572 0.508)
			(layers "F.Cu" "F.Mask" "F.Paste")
			(net "CLK_33M_PORT80")
		)
	)
	(footprint ""
		(layer "F.Cu")
		(at 27.772868 -104.628696 -90)
		(property "Reference" "C819"
			(at 0.684276 1.029462 90)
			(unlocked yes)
			(layer "F.SilkS")
			(effects
				(font
					(size 0.7874 0.5842)
					(thickness 0.1524)
				)
				(justify left)
			)
		)
		(property "Value" ""
			(at 0 0 270)
			(layer "F.Fab")
			(effects
				(font
					(size 1.27 1.27)
				)
			)
		)
		(duplicate_pad_numbers_are_jumpers no)
		(fp_line
			(start -0.7874 0.4064)
			(end -0.7874 -0.4064)
			(stroke
				(width 0.1524)
				(type default)
			)
			(layer "F.SilkS")
		)
		(fp_line
			(start 0.7874 0.4064)
			(end -0.7874 0.4064)
			(stroke
				(width 0.1524)
				(type default)
			)
			(layer "F.SilkS")
		)
		(fp_line
			(start 0 0.381)
			(end 0 -0.381)
			(stroke
				(width 0.1524)
				(type default)
			)
			(layer "F.SilkS")
		)
		(fp_line
			(start -0.7874 -0.4064)
			(end 0.7874 -0.4064)
			(stroke
				(width 0.1524)
				(type default)
			)
			(layer "F.SilkS")
		)
		(fp_line
			(start 0.7874 -0.4064)
			(end 0.7874 0.4064)
			(stroke
				(width 0.1524)
				(type default)
			)
			(layer "F.SilkS")
		)
		(fp_poly
			(pts
				(xy -0.5334 0.254) (xy -0.635 0.254) (xy -0.635 0.2286) (xy -0.635 -0.254) (xy -0.5334 -0.254) (xy -0.5334 -0.2794)
				(xy 0.5334 -0.2794) (xy 0.5334 -0.254) (xy 0.635 -0.254) (xy 0.635 0.254) (xy 0.5334 0.254) (xy 0.5334 0.2794)
				(xy -0.508 0.2794) (xy -0.5334 0.2794)
			)
			(stroke
				(width 0)
				(type default)
			)
			(fill no)
			(layer "F.CrtYd")
		)
		(pad "1" smd rect
			(at 0.40005 0 270)
			(size 0.4572 0.508)
			(layers "F.Cu" "F.Mask" "F.Paste")
			(net "FM_CPLD_NODE1_P1V5_SUS_EN")
		)
		(pad "2" smd rect
			(at -0.40005 0 270)
			(size 0.4572 0.508)
			(layers "F.Cu" "F.Mask" "F.Paste")
			(net "GND")
		)
	)
	(footprint ""
		(layer "F.Cu")
		(at 136.12876 -108.370624 90)
		(property "Reference" "R14"
			(at -6.585204 0.466852 90)
			(unlocked yes)
			(layer "F.SilkS")
			(effects
				(font
					(size 0.7874 0.5842)
					(thickness 0.1524)
				)
				(justify left)
			)
		)
		(property "Value" ""
			(at 0 0 90)
			(layer "F.Fab")
			(effects
				(font
					(size 1.27 1.27)
				)
			)
		)
		(duplicate_pad_numbers_are_jumpers no)
		(fp_line
			(start 0.7874 -0.4064)
			(end 0.7874 0.4064)
			(stroke
				(width 0.1524)
				(type default)
			)
			(layer "F.SilkS")
		)
		(fp_line
			(start -0.7874 -0.4064)
			(end 0.7874 -0.4064)
			(stroke
				(width 0.1524)
				(type default)
			)
			(layer "F.SilkS")
		)
		(fp_line
			(start 0.7874 0.4064)
			(end -0.7874 0.4064)
			(stroke
				(width 0.1524)
				(type default)
			)
			(layer "F.SilkS")
		)
		(fp_line
			(start -0.7874 0.4064)
			(end -0.7874 -0.4064)
			(stroke
				(width 0.1524)
				(type default)
			)
			(layer "F.SilkS")
		)
		(fp_poly
			(pts
				(xy -0.508 0.2794) (xy -0.508 0.2286) (xy -0.635 0.2286) (xy -0.635 -0.254) (xy -0.5334 -0.254)
				(xy -0.5334 -0.2794) (xy 0.5334 -0.2794) (xy 0.5334 -0.254) (xy 0.635 -0.254) (xy 0.635 0.254) (xy 0.5334 0.254)
				(xy 0.5334 0.2794)
			)
			(stroke
				(width 0)
				(type default)
			)
			(fill no)
			(layer "F.CrtYd")
		)
		(pad "1" smd rect
			(at 0.40005 0 90)
			(size 0.4572 0.508)
			(layers "F.Cu" "F.Mask" "F.Paste")
			(net "CLK_FSLB_NODE1")
		)
		(pad "2" smd rect
			(at -0.40005 0 90)
			(size 0.4572 0.508)
			(layers "F.Cu" "F.Mask" "F.Paste")
			(net "P3V3_CLK_NODE1")
		)
	)
	(footprint ""
		(layer "F.Cu")
		(at 79.963518 -87.979504)
		(property "Reference" "R48"
			(at -1.195578 18.989294 0)
			(unlocked yes)
			(layer "F.SilkS")
			(effects
				(font
					(size 0.7874 0.5842)
					(thickness 0.1524)
				)
				(justify left)
			)
		)
		(property "Value" ""
			(at 0 0 0)
			(layer "F.Fab")
			(effects
				(font
					(size 1.27 1.27)
				)
			)
		)
		(duplicate_pad_numbers_are_jumpers no)
		(fp_line
			(start -0.7874 -0.4064)
			(end 0.7874 -0.4064)
			(stroke
				(width 0.1524)
				(type default)
			)
			(layer "F.SilkS")
		)
		(fp_line
			(start -0.7874 0.4064)
			(end -0.7874 -0.4064)
			(stroke
				(width 0.1524)
				(type default)
			)
			(layer "F.SilkS")
		)
		(fp_line
			(start 0.7874 -0.4064)
			(end 0.7874 0.4064)
			(stroke
				(width 0.1524)
				(type default)
			)
			(layer "F.SilkS")
		)
		(fp_line
			(start 0.7874 0.4064)
			(end -0.7874 0.4064)
			(stroke
				(width 0.1524)
				(type default)
			)
			(layer "F.SilkS")
		)
		(fp_poly
			(pts
				(xy -0.508 0.2794) (xy -0.508 0.2286) (xy -0.635 0.2286) (xy -0.635 -0.254) (xy -0.5334 -0.254)
				(xy -0.5334 -0.2794) (xy 0.5334 -0.2794) (xy 0.5334 -0.254) (xy 0.635 -0.254) (xy 0.635 0.254) (xy 0.5334 0.254)
				(xy 0.5334 0.2794)
			)
			(stroke
				(width 0)
				(type default)
			)
			(fill no)
			(layer "F.CrtYd")
		)
		(pad "1" smd rect
			(at 0.40005 0)
			(size 0.4572 0.508)
			(layers "F.Cu" "F.Mask" "F.Paste")
			(net "P3V3_NODE1")
		)
		(pad "2" smd rect
			(at -0.40005 0)
			(size 0.4572 0.508)
			(layers "F.Cu" "F.Mask" "F.Paste")
			(net "SPI_CPU_NODE1_WP_R_L")
		)
	)
	(footprint ""
		(layer "F.Cu")
		(at 86.458552 -145.07083 90)
		(property "Reference" "R1234"
			(at -1.63068 2.29235 90)
			(unlocked yes)
			(layer "F.SilkS")
			(effects
				(font
					(size 0.7874 0.5842)
					(thickness 0.1524)
				)
				(justify left)
			)
		)
		(property "Value" ""
			(at 0 0 90)
			(layer "F.Fab")
			(effects
				(font
					(size 1.27 1.27)
				)
			)
		)
		(duplicate_pad_numbers_are_jumpers no)
		(fp_line
			(start 0.7874 -0.4064)
			(end 0.7874 0.4064)
			(stroke
				(width 0.1524)
				(type default)
			)
			(layer "F.SilkS")
		)
		(fp_line
			(start -0.7874 -0.4064)
			(end 0.7874 -0.4064)
			(stroke
				(width 0.1524)
				(type default)
			)
			(layer "F.SilkS")
		)
		(fp_line
			(start 0.7874 0.4064)
			(end -0.7874 0.4064)
			(stroke
				(width 0.1524)
				(type default)
			)
			(layer "F.SilkS")
		)
		(fp_line
			(start -0.7874 0.4064)
			(end -0.7874 -0.4064)
			(stroke
				(width 0.1524)
				(type default)
			)
			(layer "F.SilkS")
		)
		(fp_poly
			(pts
				(xy -0.508 0.2794) (xy -0.508 0.2286) (xy -0.635 0.2286) (xy -0.635 -0.254) (xy -0.5334 -0.254)
				(xy -0.5334 -0.2794) (xy 0.5334 -0.2794) (xy 0.5334 -0.254) (xy 0.635 -0.254) (xy 0.635 0.254) (xy 0.5334 0.254)
				(xy 0.5334 0.2794)
			)
			(stroke
				(width 0)
				(type default)
			)
			(fill no)
			(layer "F.CrtYd")
		)
		(pad "1" smd rect
			(at 0.40005 0 90)
			(size 0.4572 0.508)
			(layers "F.Cu" "F.Mask" "F.Paste")
			(net "GND")
		)
		(pad "2" smd rect
			(at -0.40005 0 90)
			(size 0.4572 0.508)
			(layers "F.Cu" "F.Mask" "F.Paste")
			(net "FM_CPLD_NODE1_P1V26_BMC_EN")
		)
	)
	(footprint ""
		(layer "F.Cu")
		(at 12.98702 -121.979182)
		(property "Reference" "PC55"
			(at -5.525008 -0.243332 0)
			(unlocked yes)
			(layer "F.SilkS")
			(effects
				(font
					(size 0.7874 0.5842)
					(thickness 0.1524)
				)
				(justify left)
			)
		)
		(property "Value" ""
			(at 0 0 0)
			(layer "F.Fab")
			(effects
				(font
					(size 1.27 1.27)
				)
			)
		)
		(duplicate_pad_numbers_are_jumpers no)
		(fp_line
			(start -2.2098 -0.9398)
			(end 2.2098 -0.9398)
			(stroke
				(width 0.1524)
				(type default)
			)
			(layer "F.SilkS")
		)
		(fp_line
			(start -2.2098 0.9398)
			(end -2.2098 -0.9398)
			(stroke
				(width 0.1524)
				(type default)
			)
			(layer "F.SilkS")
		)
		(fp_line
			(start 0 -0.9398)
			(end 0 0.9398)
			(stroke
				(width 0.1524)
				(type default)
			)
			(layer "F.SilkS")
		)
		(fp_line
			(start 2.2098 -0.9398)
			(end 2.2098 0.9398)
			(stroke
				(width 0.1524)
				(type default)
			)
			(layer "F.SilkS")
		)
		(fp_line
			(start 2.2098 0.9398)
			(end -2.2098 0.9398)
			(stroke
				(width 0.1524)
				(type default)
			)
			(layer "F.SilkS")
		)
		(fp_poly
			(pts
				(xy -1.6764 0.889) (xy -1.6764 0.7874) (xy -2.0574 0.7874) (xy -2.0574 -0.7874) (xy -1.6764 -0.7874)
				(xy -1.6764 -0.9398) (xy 1.6764 -0.9398) (xy 1.6764 -0.7874) (xy 2.0574 -0.7874) (xy 2.0574 0.7874)
				(xy 1.6764 0.7874) (xy 1.6764 0.9398) (xy -1.6764 0.9398)
			)
			(stroke
				(width 0)
				(type default)
			)
			(fill no)
			(layer "F.CrtYd")
		)
		(fp_line
			(start -1.700022 -0.899922)
			(end 1.700022 -0.899922)
			(stroke
				(width 0.1)
				(type default)
			)
			(layer "F.Fab")
		)
		(fp_line
			(start -1.700022 0.899922)
			(end -1.700022 -0.899922)
			(stroke
				(width 0.1)
				(type default)
			)
			(layer "F.Fab")
		)
		(fp_line
			(start 1.700022 -0.899922)
			(end 1.700022 0.899922)
			(stroke
				(width 0.1)
				(type default)
			)
			(layer "F.Fab")
		)
		(fp_line
			(start 1.700022 0.899922)
			(end -1.700022 0.899922)
			(stroke
				(width 0.1)
				(type default)
			)
			(layer "F.Fab")
		)
		(pad "1" smd rect
			(at 1.4732 0)
			(size 1.1684 1.5748)
			(layers "F.Cu" "F.Mask" "F.Paste")
			(net "SW_P1V05_NODE1_VIN_FLT")
		)
		(pad "2" smd rect
			(at -1.4732 0)
			(size 1.1684 1.5748)
			(layers "F.Cu" "F.Mask" "F.Paste")
			(net "GND")
		)
	)
	(footprint ""
		(layer "F.Cu")
		(at 77.03185 -151.842724)
		(property "Reference" "PC2"
			(at -3.893312 -0.161036 0)
			(unlocked yes)
			(layer "F.SilkS")
			(effects
				(font
					(size 0.7874 0.5842)
					(thickness 0.1524)
				)
				(justify left)
			)
		)
		(property "Value" ""
			(at 0 0 0)
			(layer "F.Fab")
			(effects
				(font
					(size 1.27 1.27)
				)
			)
		)
		(duplicate_pad_numbers_are_jumpers no)
		(fp_line
			(start -0.7874 -0.4064)
			(end 0.7874 -0.4064)
			(stroke
				(width 0.1524)
				(type default)
			)
			(layer "F.SilkS")
		)
		(fp_line
			(start -0.7874 0.4064)
			(end -0.7874 -0.4064)
			(stroke
				(width 0.1524)
				(type default)
			)
			(layer "F.SilkS")
		)
		(fp_line
			(start 0 0.381)
			(end 0 -0.381)
			(stroke
				(width 0.1524)
				(type default)
			)
			(layer "F.SilkS")
		)
		(fp_line
			(start 0.7874 -0.4064)
			(end 0.7874 0.4064)
			(stroke
				(width 0.1524)
				(type default)
			)
			(layer "F.SilkS")
		)
		(fp_line
			(start 0.7874 0.4064)
			(end -0.7874 0.4064)
			(stroke
				(width 0.1524)
				(type default)
			)
			(layer "F.SilkS")
		)
		(fp_poly
			(pts
				(xy -0.5334 0.254) (xy -0.635 0.254) (xy -0.635 0.2286) (xy -0.635 -0.254) (xy -0.5334 -0.254) (xy -0.5334 -0.2794)
				(xy 0.5334 -0.2794) (xy 0.5334 -0.254) (xy 0.635 -0.254) (xy 0.635 0.254) (xy 0.5334 0.254) (xy 0.5334 0.2794)
				(xy -0.508 0.2794) (xy -0.5334 0.2794)
			)
			(stroke
				(width 0)
				(type default)
			)
			(fill no)
			(layer "F.CrtYd")
		)
		(pad "1" smd rect
			(at 0.40005 0)
			(size 0.4572 0.508)
			(layers "F.Cu" "F.Mask" "F.Paste")
			(net "P12V_AUX")
		)
		(pad "2" smd rect
			(at -0.40005 0)
			(size 0.4572 0.508)
			(layers "F.Cu" "F.Mask" "F.Paste")
			(net "GND")
		)
	)
	(footprint ""
		(layer "F.Cu")
		(at 13.041884 -124.093224)
		(property "Reference" "PC56"
			(at -5.58419 0.842772 0)
			(unlocked yes)
			(layer "F.SilkS")
			(effects
				(font
					(size 0.7874 0.5842)
					(thickness 0.1524)
				)
				(justify left)
			)
		)
		(property "Value" ""
			(at 0 0 0)
			(layer "F.Fab")
			(effects
				(font
					(size 1.27 1.27)
				)
			)
		)
		(duplicate_pad_numbers_are_jumpers no)
		(fp_line
			(start -2.2098 -0.9398)
			(end 2.2098 -0.9398)
			(stroke
				(width 0.1524)
				(type default)
			)
			(layer "F.SilkS")
		)
		(fp_line
			(start -2.2098 0.9398)
			(end -2.2098 -0.9398)
			(stroke
				(width 0.1524)
				(type default)
			)
			(layer "F.SilkS")
		)
		(fp_line
			(start 0 -0.9398)
			(end 0 0.9398)
			(stroke
				(width 0.1524)
				(type default)
			)
			(layer "F.SilkS")
		)
		(fp_line
			(start 2.2098 -0.9398)
			(end 2.2098 0.9398)
			(stroke
				(width 0.1524)
				(type default)
			)
			(layer "F.SilkS")
		)
		(fp_line
			(start 2.2098 0.9398)
			(end -2.2098 0.9398)
			(stroke
				(width 0.1524)
				(type default)
			)
			(layer "F.SilkS")
		)
		(fp_poly
			(pts
				(xy -1.6764 0.889) (xy -1.6764 0.7874) (xy -2.0574 0.7874) (xy -2.0574 -0.7874) (xy -1.6764 -0.7874)
				(xy -1.6764 -0.9398) (xy 1.6764 -0.9398) (xy 1.6764 -0.7874) (xy 2.0574 -0.7874) (xy 2.0574 0.7874)
				(xy 1.6764 0.7874) (xy 1.6764 0.9398) (xy -1.6764 0.9398)
			)
			(stroke
				(width 0)
				(type default)
			)
			(fill no)
			(layer "F.CrtYd")
		)
		(fp_line
			(start -1.700022 -0.899922)
			(end 1.700022 -0.899922)
			(stroke
				(width 0.1)
				(type default)
			)
			(layer "F.Fab")
		)
		(fp_line
			(start -1.700022 0.899922)
			(end -1.700022 -0.899922)
			(stroke
				(width 0.1)
				(type default)
			)
			(layer "F.Fab")
		)
		(fp_line
			(start 1.700022 -0.899922)
			(end 1.700022 0.899922)
			(stroke
				(width 0.1)
				(type default)
			)
			(layer "F.Fab")
		)
		(fp_line
			(start 1.700022 0.899922)
			(end -1.700022 0.899922)
			(stroke
				(width 0.1)
				(type default)
			)
			(layer "F.Fab")
		)
		(pad "1" smd rect
			(at 1.4732 0)
			(size 1.1684 1.5748)
			(layers "F.Cu" "F.Mask" "F.Paste")
			(net "SW_P1V05_NODE1_VIN_FLT")
		)
		(pad "2" smd rect
			(at -1.4732 0)
			(size 1.1684 1.5748)
			(layers "F.Cu" "F.Mask" "F.Paste")
			(net "GND")
		)
	)
	(footprint ""
		(layer "F.Cu")
		(at 122.79376 -185.205624 -90)
		(property "Reference" "R863"
			(at -4.768088 -0.152908 90)
			(unlocked yes)
			(layer "F.SilkS")
			(effects
				(font
					(size 0.7874 0.5842)
					(thickness 0.1524)
				)
				(justify left)
			)
		)
		(property "Value" ""
			(at 0 0 270)
			(layer "F.Fab")
			(effects
				(font
					(size 1.27 1.27)
				)
			)
		)
		(duplicate_pad_numbers_are_jumpers no)
		(fp_line
			(start -0.7874 0.4064)
			(end -0.7874 -0.4064)
			(stroke
				(width 0.1524)
				(type default)
			)
			(layer "F.SilkS")
		)
		(fp_line
			(start 0.7874 0.4064)
			(end -0.7874 0.4064)
			(stroke
				(width 0.1524)
				(type default)
			)
			(layer "F.SilkS")
		)
		(fp_line
			(start -0.7874 -0.4064)
			(end 0.7874 -0.4064)
			(stroke
				(width 0.1524)
				(type default)
			)
			(layer "F.SilkS")
		)
		(fp_line
			(start 0.7874 -0.4064)
			(end 0.7874 0.4064)
			(stroke
				(width 0.1524)
				(type default)
			)
			(layer "F.SilkS")
		)
		(fp_poly
			(pts
				(xy -0.508 0.2794) (xy -0.508 0.2286) (xy -0.635 0.2286) (xy -0.635 -0.254) (xy -0.5334 -0.254)
				(xy -0.5334 -0.2794) (xy 0.5334 -0.2794) (xy 0.5334 -0.254) (xy 0.635 -0.254) (xy 0.635 0.254) (xy 0.5334 0.254)
				(xy 0.5334 0.2794)
			)
			(stroke
				(width 0)
				(type default)
			)
			(fill no)
			(layer "F.CrtYd")
		)
		(pad "1" smd rect
			(at 0.40005 0 270)
			(size 0.4572 0.508)
			(layers "F.Cu" "F.Mask" "F.Paste")
			(net "T8_NODE2_EN")
		)
		(pad "2" smd rect
			(at -0.40005 0 270)
			(size 0.4572 0.508)
			(layers "F.Cu" "F.Mask" "F.Paste")
			(net "T8_NODE2_EN_R")
		)
	)
	(footprint ""
		(layer "F.Cu")
		(at 35.013138 -170.551856 -90)
		(property "Reference" "U109"
			(at 6.111748 1.307338 0)
			(unlocked yes)
			(layer "F.SilkS")
			(effects
				(font
					(size 0.7874 0.5842)
					(thickness 0.1524)
				)
			)
		)
		(property "Value" ""
			(at 0 0 270)
			(layer "F.Fab")
			(effects
				(font
					(size 1.27 1.27)
				)
			)
		)
		(duplicate_pad_numbers_are_jumpers no)
		(fp_line
			(start -1.651 1.905)
			(end -1.651 -1.905)
			(stroke
				(width 0.1524)
				(type default)
			)
			(layer "F.SilkS")
		)
		(fp_line
			(start 1.651 1.905)
			(end -1.651 1.905)
			(stroke
				(width 0.1524)
				(type default)
			)
			(layer "F.SilkS")
		)
		(fp_line
			(start -1.651 -1.905)
			(end 1.651 -1.905)
			(stroke
				(width 0.1524)
				(type default)
			)
			(layer "F.SilkS")
		)
		(fp_line
			(start 1.651 -1.905)
			(end 1.651 1.905)
			(stroke
				(width 0.1524)
				(type default)
			)
			(layer "F.SilkS")
		)
		(fp_poly
			(pts
				(xy -1.524 0.7112) (xy -1.524 1.7526) (xy -0.508 1.7526) (xy -0.508 0.6985) (xy 0.508 0.6985) (xy 0.508 1.7526)
				(xy 1.524 1.7526) (xy 1.524 0.6985) (xy 1.524 -0.6985) (xy 0.508 -0.6985) (xy 0.508 -1.7526) (xy -0.508 -1.7526)
				(xy -0.508 -0.6985) (xy -1.524 -0.6985) (xy -1.524 0.6985)
			)
			(stroke
				(width 0)
				(type default)
			)
			(fill no)
			(layer "F.CrtYd")
		)
		(fp_text user "G"
			(at -2.298192 1.322578 0)
			(unlocked yes)
			(layer "F.SilkS")
			(effects
				(font
					(size 0.7874 0.5842)
					(thickness 0.1524)
				)
			)
		)
		(fp_text user "S"
			(at 2.322068 0.692658 0)
			(unlocked yes)
			(layer "F.SilkS")
			(effects
				(font
					(size 0.7874 0.5842)
					(thickness 0.1524)
				)
			)
		)
		(fp_text user "D"
			(at -0.318262 -2.54127 0)
			(unlocked yes)
			(layer "F.SilkS")
			(effects
				(font
					(size 0.7874 0.5842)
					(thickness 0.1524)
				)
			)
		)
		(pad "D" smd rect
			(at 0 -1.1176 270)
			(size 1.016 1.27)
			(layers "F.Cu" "F.Mask" "F.Paste")
			(net "P12V_AUX_EN")
		)
		(pad "G" smd rect
			(at -1.016 1.1176 270)
			(size 1.016 1.27)
			(layers "F.Cu" "F.Mask" "F.Paste")
			(net "CM_PWR_CTL_IN_R")
		)
		(pad "S" smd rect
			(at 1.016 1.1176 270)
			(size 1.016 1.27)
			(layers "F.Cu" "F.Mask" "F.Paste")
			(net "GND")
		)
	)
	(footprint ""
		(layer "F.Cu")
		(at 154.638502 -129.314448)
		(property "Reference" "S3"
			(at -3.178302 4.244848 0)
			(unlocked yes)
			(layer "F.SilkS")
			(effects
				(font
					(size 0.7874 0.5842)
					(thickness 0.1524)
				)
				(justify left)
			)
		)
		(property "Value" ""
			(at 0 0 0)
			(layer "F.Fab")
			(effects
				(font
					(size 1.27 1.27)
				)
			)
		)
		(duplicate_pad_numbers_are_jumpers no)
		(fp_line
			(start -3.0988 -3.0988)
			(end 3.0988 -3.0988)
			(stroke
				(width 0.1524)
				(type default)
			)
			(layer "F.SilkS")
		)
		(fp_line
			(start -3.0988 -2.667)
			(end -3.0988 -3.0988)
			(stroke
				(width 0.1524)
				(type default)
			)
			(layer "F.SilkS")
		)
		(fp_line
			(start -3.0988 -1.3462)
			(end -3.0988 1.3208)
			(stroke
				(width 0.1524)
				(type default)
			)
			(layer "F.SilkS")
		)
		(fp_line
			(start -3.0988 2.6416)
			(end -3.0988 3.0988)
			(stroke
				(width 0.1524)
				(type default)
			)
			(layer "F.SilkS")
		)
		(fp_line
			(start -3.0988 3.0988)
			(end 3.0988 3.0988)
			(stroke
				(width 0.1524)
				(type default)
			)
			(layer "F.SilkS")
		)
		(fp_line
			(start 3.0988 -3.0988)
			(end 3.0988 -2.667)
			(stroke
				(width 0.1524)
				(type default)
			)
			(layer "F.SilkS")
		)
		(fp_line
			(start 3.0988 1.3208)
			(end 3.0988 -1.3208)
			(stroke
				(width 0.1524)
				(type default)
			)
			(layer "F.SilkS")
		)
		(fp_line
			(start 3.0988 3.0988)
			(end 3.0988 2.667)
			(stroke
				(width 0.1524)
				(type default)
			)
			(layer "F.SilkS")
		)
		(fp_poly
			(pts
				(xy -4.797298 -2.696972) (xy -6.829298 -2.112772) (xy -6.829298 -3.408172)
			)
			(stroke
				(width 0)
				(type default)
			)
			(fill yes)
			(layer "F.SilkS")
		)
		(fp_poly
			(pts
				(xy -3.0988 3.0988) (xy -3.0988 2.5146) (xy -5.0038 2.5146) (xy -5.0038 1.4732) (xy -3.0988 1.4732)
				(xy -3.0988 -1.4986) (xy -5.0038 -1.4986) (xy -5.0038 -2.5146) (xy -3.0988 -2.5146) (xy -3.0988 -3.0988)
				(xy 3.0988 -3.0988) (xy 3.0988 -2.5146) (xy 5.0038 -2.5146) (xy 5.0038 -1.4732) (xy 3.0988 -1.4732)
				(xy 3.0988 1.4732) (xy 5.0038 1.4732) (xy 5.0038 2.5146) (xy 3.0988 2.5146) (xy 3.0988 3.0988)
			)
			(stroke
				(width 0)
				(type default)
			)
			(fill no)
			(layer "F.CrtYd")
		)
		(fp_text user "1"
			(at -4.618482 -0.670052 0)
			(unlocked yes)
			(layer "F.SilkS")
			(effects
				(font
					(size 0.635 0.4064)
					(thickness 0.1524)
				)
				(justify left)
			)
		)
		(fp_text user "3"
			(at -4.225036 3.265424 0)
			(unlocked yes)
			(layer "F.SilkS")
			(effects
				(font
					(size 0.635 0.4064)
					(thickness 0.1524)
				)
				(justify left)
			)
		)
		(fp_text user "4"
			(at 4.946904 0.843788 0)
			(unlocked yes)
			(layer "F.SilkS")
			(effects
				(font
					(size 0.635 0.4064)
					(thickness 0.1524)
				)
				(justify left)
			)
		)
		(fp_text user "2"
			(at 5.249672 -1.6383 0)
			(unlocked yes)
			(layer "F.SilkS")
			(effects
				(font
					(size 0.635 0.4064)
					(thickness 0.1524)
				)
				(justify left)
			)
		)
		(pad "1" smd rect
			(at -3.400044 -1.999996 90)
			(size 1.016 3.2004)
			(layers "F.Cu" "F.Mask" "F.Paste")
			(net "RST_BTN_L")
		)
		(pad "2" smd rect
			(at 3.400044 -1.999996 90)
			(size 1.016 3.2004)
			(layers "F.Cu" "F.Mask" "F.Paste")
			(net "RST_BTN_L")
		)
		(pad "3" smd rect
			(at -3.400044 1.999996 90)
			(size 1.016 3.2004)
			(layers "F.Cu" "F.Mask" "F.Paste")
			(net "GND")
		)
		(pad "4" smd rect
			(at 3.400044 1.999996 90)
			(size 1.016 3.2004)
			(layers "F.Cu" "F.Mask" "F.Paste")
			(net "GND")
		)
	)
	(footprint ""
		(layer "F.Cu")
		(at 134.22376 -185.205624 -90)
		(property "Reference" "R983"
			(at -4.510786 0.392938 90)
			(unlocked yes)
			(layer "F.SilkS")
			(effects
				(font
					(size 0.7874 0.5842)
					(thickness 0.1524)
				)
				(justify left)
			)
		)
		(property "Value" ""
			(at 0 0 270)
			(layer "F.Fab")
			(effects
				(font
					(size 1.27 1.27)
				)
			)
		)
		(duplicate_pad_numbers_are_jumpers no)
		(fp_line
			(start -0.7874 0.4064)
			(end -0.7874 -0.4064)
			(stroke
				(width 0.1524)
				(type default)
			)
			(layer "F.SilkS")
		)
		(fp_line
			(start 0.7874 0.4064)
			(end -0.7874 0.4064)
			(stroke
				(width 0.1524)
				(type default)
			)
			(layer "F.SilkS")
		)
		(fp_line
			(start -0.7874 -0.4064)
			(end 0.7874 -0.4064)
			(stroke
				(width 0.1524)
				(type default)
			)
			(layer "F.SilkS")
		)
		(fp_line
			(start 0.7874 -0.4064)
			(end 0.7874 0.4064)
			(stroke
				(width 0.1524)
				(type default)
			)
			(layer "F.SilkS")
		)
		(fp_poly
			(pts
				(xy -0.508 0.2794) (xy -0.508 0.2286) (xy -0.635 0.2286) (xy -0.635 -0.254) (xy -0.5334 -0.254)
				(xy -0.5334 -0.2794) (xy 0.5334 -0.2794) (xy 0.5334 -0.254) (xy 0.635 -0.254) (xy 0.635 0.254) (xy 0.5334 0.254)
				(xy 0.5334 0.2794)
			)
			(stroke
				(width 0)
				(type default)
			)
			(fill no)
			(layer "F.CrtYd")
		)
		(pad "1" smd rect
			(at 0.40005 0 270)
			(size 0.4572 0.508)
			(layers "F.Cu" "F.Mask" "F.Paste")
			(net "UART_T10_NODE1_TXD")
		)
		(pad "2" smd rect
			(at -0.40005 0 270)
			(size 0.4572 0.508)
			(layers "F.Cu" "F.Mask" "F.Paste")
			(net "UART_T10_NODE1_TXD_R")
		)
	)
	(footprint ""
		(layer "F.Cu")
		(at 113.90376 -185.205624 90)
		(property "Reference" "C760"
			(at 4.731512 -0.124968 90)
			(unlocked yes)
			(layer "F.SilkS")
			(effects
				(font
					(size 0.7874 0.5842)
					(thickness 0.1524)
				)
				(justify left)
			)
		)
		(property "Value" ""
			(at 0 0 90)
			(layer "F.Fab")
			(effects
				(font
					(size 1.27 1.27)
				)
			)
		)
		(duplicate_pad_numbers_are_jumpers no)
		(fp_line
			(start 0.7874 -0.4064)
			(end 0.7874 0.4064)
			(stroke
				(width 0.1524)
				(type default)
			)
			(layer "F.SilkS")
		)
		(fp_line
			(start -0.7874 -0.4064)
			(end 0.7874 -0.4064)
			(stroke
				(width 0.1524)
				(type default)
			)
			(layer "F.SilkS")
		)
		(fp_line
			(start 0 0.381)
			(end 0 -0.381)
			(stroke
				(width 0.1524)
				(type default)
			)
			(layer "F.SilkS")
		)
		(fp_line
			(start 0.7874 0.4064)
			(end -0.7874 0.4064)
			(stroke
				(width 0.1524)
				(type default)
			)
			(layer "F.SilkS")
		)
		(fp_line
			(start -0.7874 0.4064)
			(end -0.7874 -0.4064)
			(stroke
				(width 0.1524)
				(type default)
			)
			(layer "F.SilkS")
		)
		(fp_poly
			(pts
				(xy -0.5334 0.254) (xy -0.635 0.254) (xy -0.635 0.2286) (xy -0.635 -0.254) (xy -0.5334 -0.254) (xy -0.5334 -0.2794)
				(xy 0.5334 -0.2794) (xy 0.5334 -0.254) (xy 0.635 -0.254) (xy 0.635 0.254) (xy 0.5334 0.254) (xy 0.5334 0.2794)
				(xy -0.508 0.2794) (xy -0.5334 0.2794)
			)
			(stroke
				(width 0)
				(type default)
			)
			(fill no)
			(layer "F.CrtYd")
		)
		(pad "1" smd rect
			(at 0.40005 0 90)
			(size 0.4572 0.508)
			(layers "F.Cu" "F.Mask" "F.Paste")
			(net "UART_T8_NODE4_RXD")
		)
		(pad "2" smd rect
			(at -0.40005 0 90)
			(size 0.4572 0.508)
			(layers "F.Cu" "F.Mask" "F.Paste")
			(net "GND")
		)
	)
	(footprint ""
		(layer "F.Cu")
		(at 152.67051 -146.025362)
		(property "Reference" "C529"
			(at 1.873758 -1.693926 90)
			(unlocked yes)
			(layer "F.SilkS")
			(effects
				(font
					(size 0.635 0.4064)
					(thickness 0.1524)
				)
				(justify left)
			)
		)
		(property "Value" ""
			(at 0 0 0)
			(layer "F.Fab")
			(effects
				(font
					(size 1.27 1.27)
				)
			)
		)
		(duplicate_pad_numbers_are_jumpers no)
		(fp_line
			(start -0.7874 -0.4064)
			(end 0.7874 -0.4064)
			(stroke
				(width 0.1524)
				(type default)
			)
			(layer "F.SilkS")
		)
		(fp_line
			(start -0.7874 0.4064)
			(end -0.7874 -0.4064)
			(stroke
				(width 0.1524)
				(type default)
			)
			(layer "F.SilkS")
		)
		(fp_line
			(start 0 0.381)
			(end 0 -0.381)
			(stroke
				(width 0.1524)
				(type default)
			)
			(layer "F.SilkS")
		)
		(fp_line
			(start 0.7874 -0.4064)
			(end 0.7874 0.4064)
			(stroke
				(width 0.1524)
				(type default)
			)
			(layer "F.SilkS")
		)
		(fp_line
			(start 0.7874 0.4064)
			(end -0.7874 0.4064)
			(stroke
				(width 0.1524)
				(type default)
			)
			(layer "F.SilkS")
		)
		(fp_poly
			(pts
				(xy -0.5334 0.254) (xy -0.635 0.254) (xy -0.635 0.2286) (xy -0.635 -0.254) (xy -0.5334 -0.254) (xy -0.5334 -0.2794)
				(xy 0.5334 -0.2794) (xy 0.5334 -0.254) (xy 0.635 -0.254) (xy 0.635 0.254) (xy 0.5334 0.254) (xy 0.5334 0.2794)
				(xy -0.508 0.2794) (xy -0.5334 0.2794)
			)
			(stroke
				(width 0)
				(type default)
			)
			(fill no)
			(layer "F.CrtYd")
		)
		(pad "1" smd rect
			(at 0.40005 0)
			(size 0.4572 0.508)
			(layers "F.Cu" "F.Mask" "F.Paste")
			(net "LAN2_LED_LINK_1000_N")
		)
		(pad "2" smd rect
			(at -0.40005 0)
			(size 0.4572 0.508)
			(layers "F.Cu" "F.Mask" "F.Paste")
			(net "GND")
		)
	)
	(footprint ""
		(layer "F.Cu")
		(at 112.700816 -28.99791 -90)
		(property "Reference" "C858"
			(at -2.253996 -0.724408 90)
			(unlocked yes)
			(layer "F.SilkS")
			(effects
				(font
					(size 0.7874 0.5842)
					(thickness 0.1524)
				)
				(justify left)
			)
		)
		(property "Value" ""
			(at 0 0 270)
			(layer "F.Fab")
			(effects
				(font
					(size 1.27 1.27)
				)
			)
		)
		(duplicate_pad_numbers_are_jumpers no)
		(fp_line
			(start -1.905 0.8636)
			(end -1.905 -0.8636)
			(stroke
				(width 0.1524)
				(type default)
			)
			(layer "F.SilkS")
		)
		(fp_line
			(start 1.905 0.8636)
			(end -1.905 0.8636)
			(stroke
				(width 0.1524)
				(type default)
			)
			(layer "F.SilkS")
		)
		(fp_line
			(start 0 0.8382)
			(end 0 -0.8382)
			(stroke
				(width 0.1524)
				(type default)
			)
			(layer "F.SilkS")
		)
		(fp_line
			(start -1.905 -0.8636)
			(end 1.905 -0.8636)
			(stroke
				(width 0.1524)
				(type default)
			)
			(layer "F.SilkS")
		)
		(fp_line
			(start 1.905 -0.8636)
			(end 1.905 0.8636)
			(stroke
				(width 0.1524)
				(type default)
			)
			(layer "F.SilkS")
		)
		(fp_rect
			(start -1.524 0.7366)
			(end 1.524 -0.7366)
			(stroke
				(width 0)
				(type default)
			)
			(fill no)
			(layer "F.CrtYd")
		)
		(pad "1" smd rect
			(at 0.94996 0 270)
			(size 1.1176 1.3716)
			(layers "F.Cu" "F.Mask" "F.Paste")
			(net "PV_VTT_DDR_NODE1")
		)
		(pad "2" smd rect
			(at -0.94996 0 270)
			(size 1.1176 1.3716)
			(layers "F.Cu" "F.Mask" "F.Paste")
			(net "GND")
		)
	)
	(footprint ""
		(layer "F.Cu")
		(at 79.971392 -162.050222 90)
		(property "Reference" "C578"
			(at -2.815082 1.079754 90)
			(unlocked yes)
			(layer "F.SilkS")
			(effects
				(font
					(size 0.7874 0.5842)
					(thickness 0.1524)
				)
				(justify left)
			)
		)
		(property "Value" ""
			(at 0 0 90)
			(layer "F.Fab")
			(effects
				(font
					(size 1.27 1.27)
				)
			)
		)
		(duplicate_pad_numbers_are_jumpers no)
		(fp_line
			(start 0.7874 -0.4064)
			(end 0.7874 0.4064)
			(stroke
				(width 0.1524)
				(type default)
			)
			(layer "F.SilkS")
		)
		(fp_line
			(start -0.7874 -0.4064)
			(end 0.7874 -0.4064)
			(stroke
				(width 0.1524)
				(type default)
			)
			(layer "F.SilkS")
		)
		(fp_line
			(start 0 0.381)
			(end 0 -0.381)
			(stroke
				(width 0.1524)
				(type default)
			)
			(layer "F.SilkS")
		)
		(fp_line
			(start 0.7874 0.4064)
			(end -0.7874 0.4064)
			(stroke
				(width 0.1524)
				(type default)
			)
			(layer "F.SilkS")
		)
		(fp_line
			(start -0.7874 0.4064)
			(end -0.7874 -0.4064)
			(stroke
				(width 0.1524)
				(type default)
			)
			(layer "F.SilkS")
		)
		(fp_poly
			(pts
				(xy -0.5334 0.254) (xy -0.635 0.254) (xy -0.635 0.2286) (xy -0.635 -0.254) (xy -0.5334 -0.254) (xy -0.5334 -0.2794)
				(xy 0.5334 -0.2794) (xy 0.5334 -0.254) (xy 0.635 -0.254) (xy 0.635 0.254) (xy 0.5334 0.254) (xy 0.5334 0.2794)
				(xy -0.508 0.2794) (xy -0.5334 0.2794)
			)
			(stroke
				(width 0)
				(type default)
			)
			(fill no)
			(layer "F.CrtYd")
		)
		(pad "1" smd rect
			(at 0.40005 0 90)
			(size 0.4572 0.508)
			(layers "F.Cu" "F.Mask" "F.Paste")
			(net "P3V3_NODE1")
		)
		(pad "2" smd rect
			(at -0.40005 0 90)
			(size 0.4572 0.508)
			(layers "F.Cu" "F.Mask" "F.Paste")
			(net "GND")
		)
	)
	(footprint ""
		(layer "F.Cu")
		(at 140.27531 -111.507778 180)
		(property "Reference" "R20"
			(at -1.558036 -3.130804 0)
			(unlocked yes)
			(layer "F.SilkS")
			(effects
				(font
					(size 0.7874 0.5842)
					(thickness 0.1524)
				)
				(justify left)
			)
		)
		(property "Value" ""
			(at 0 0 180)
			(layer "F.Fab")
			(effects
				(font
					(size 1.27 1.27)
				)
			)
		)
		(duplicate_pad_numbers_are_jumpers no)
		(fp_line
			(start 0.7874 0.4064)
			(end -0.7874 0.4064)
			(stroke
				(width 0.1524)
				(type default)
			)
			(layer "F.SilkS")
		)
		(fp_line
			(start 0.7874 -0.4064)
			(end 0.7874 0.4064)
			(stroke
				(width 0.1524)
				(type default)
			)
			(layer "F.SilkS")
		)
		(fp_line
			(start -0.7874 0.4064)
			(end -0.7874 -0.4064)
			(stroke
				(width 0.1524)
				(type default)
			)
			(layer "F.SilkS")
		)
		(fp_line
			(start -0.7874 -0.4064)
			(end 0.7874 -0.4064)
			(stroke
				(width 0.1524)
				(type default)
			)
			(layer "F.SilkS")
		)
		(fp_poly
			(pts
				(xy -0.508 0.2794) (xy -0.508 0.2286) (xy -0.635 0.2286) (xy -0.635 -0.254) (xy -0.5334 -0.254)
				(xy -0.5334 -0.2794) (xy 0.5334 -0.2794) (xy 0.5334 -0.254) (xy 0.635 -0.254) (xy 0.635 0.254) (xy 0.5334 0.254)
				(xy 0.5334 0.2794)
			)
			(stroke
				(width 0)
				(type default)
			)
			(fill no)
			(layer "F.CrtYd")
		)
		(pad "1" smd rect
			(at 0.40005 0 180)
			(size 0.4572 0.508)
			(layers "F.Cu" "F.Mask" "F.Paste")
			(net "SEL_DOT_SRC5")
		)
		(pad "2" smd rect
			(at -0.40005 0 180)
			(size 0.4572 0.508)
			(layers "F.Cu" "F.Mask" "F.Paste")
			(net "P3V3_CLK_NODE1")
		)
	)
	(footprint ""
		(layer "F.Cu")
		(at 184.7596 -178.5112 180)
		(property "Reference" "R1316"
			(at -9.9822 -17.32407 0)
			(unlocked yes)
			(layer "F.SilkS")
			(effects
				(font
					(size 0.7874 0.5842)
					(thickness 0.1524)
				)
				(justify left)
			)
		)
		(property "Value" ""
			(at 0 0 180)
			(layer "F.Fab")
			(effects
				(font
					(size 1.27 1.27)
				)
			)
		)
		(duplicate_pad_numbers_are_jumpers no)
		(fp_line
			(start 0.7874 0.4064)
			(end -0.7874 0.4064)
			(stroke
				(width 0.1524)
				(type default)
			)
			(layer "F.SilkS")
		)
		(fp_line
			(start 0.7874 -0.4064)
			(end 0.7874 0.4064)
			(stroke
				(width 0.1524)
				(type default)
			)
			(layer "F.SilkS")
		)
		(fp_line
			(start -0.7874 0.4064)
			(end -0.7874 -0.4064)
			(stroke
				(width 0.1524)
				(type default)
			)
			(layer "F.SilkS")
		)
		(fp_line
			(start -0.7874 -0.4064)
			(end 0.7874 -0.4064)
			(stroke
				(width 0.1524)
				(type default)
			)
			(layer "F.SilkS")
		)
		(fp_poly
			(pts
				(xy -0.508 0.2794) (xy -0.508 0.2286) (xy -0.635 0.2286) (xy -0.635 -0.254) (xy -0.5334 -0.254)
				(xy -0.5334 -0.2794) (xy 0.5334 -0.2794) (xy 0.5334 -0.254) (xy 0.635 -0.254) (xy 0.635 0.254) (xy 0.5334 0.254)
				(xy 0.5334 0.2794)
			)
			(stroke
				(width 0)
				(type default)
			)
			(fill no)
			(layer "F.CrtYd")
		)
		(pad "1" smd rect
			(at 0.40005 0 180)
			(size 0.4572 0.508)
			(layers "F.Cu" "F.Mask" "F.Paste")
			(net "POWER_SW2_PWR_CTR_12V")
		)
		(pad "2" smd rect
			(at -0.40005 0 180)
			(size 0.4572 0.508)
			(layers "F.Cu" "F.Mask" "F.Paste")
			(net "POWER_SW2_PWR_CTR_12V_R")
		)
	)
	(footprint ""
		(layer "F.Cu")
		(at 157.074616 -138.878056)
		(property "Reference" "C565"
			(at 1.43764 -0.81026 0)
			(unlocked yes)
			(layer "F.SilkS")
			(effects
				(font
					(size 0.7874 0.5842)
					(thickness 0.1524)
				)
				(justify left)
			)
		)
		(property "Value" ""
			(at 0 0 0)
			(layer "F.Fab")
			(effects
				(font
					(size 1.27 1.27)
				)
			)
		)
		(duplicate_pad_numbers_are_jumpers no)
		(fp_line
			(start -0.7874 -0.4064)
			(end 0.7874 -0.4064)
			(stroke
				(width 0.1524)
				(type default)
			)
			(layer "F.SilkS")
		)
		(fp_line
			(start -0.7874 0.4064)
			(end -0.7874 -0.4064)
			(stroke
				(width 0.1524)
				(type default)
			)
			(layer "F.SilkS")
		)
		(fp_line
			(start 0 0.381)
			(end 0 -0.381)
			(stroke
				(width 0.1524)
				(type default)
			)
			(layer "F.SilkS")
		)
		(fp_line
			(start 0.7874 -0.4064)
			(end 0.7874 0.4064)
			(stroke
				(width 0.1524)
				(type default)
			)
			(layer "F.SilkS")
		)
		(fp_line
			(start 0.7874 0.4064)
			(end -0.7874 0.4064)
			(stroke
				(width 0.1524)
				(type default)
			)
			(layer "F.SilkS")
		)
		(fp_poly
			(pts
				(xy -0.5334 0.254) (xy -0.635 0.254) (xy -0.635 0.2286) (xy -0.635 -0.254) (xy -0.5334 -0.254) (xy -0.5334 -0.2794)
				(xy 0.5334 -0.2794) (xy 0.5334 -0.254) (xy 0.635 -0.254) (xy 0.635 0.254) (xy 0.5334 0.254) (xy 0.5334 0.2794)
				(xy -0.508 0.2794) (xy -0.5334 0.2794)
			)
			(stroke
				(width 0)
				(type default)
			)
			(fill no)
			(layer "F.CrtYd")
		)
		(pad "1" smd rect
			(at 0.40005 0)
			(size 0.4572 0.508)
			(layers "F.Cu" "F.Mask" "F.Paste")
			(net "P3V3_STB_NODE1")
		)
		(pad "2" smd rect
			(at -0.40005 0)
			(size 0.4572 0.508)
			(layers "F.Cu" "F.Mask" "F.Paste")
			(net "GND")
		)
	)
	(footprint ""
		(layer "F.Cu")
		(at 166.610538 -12.491974 90)
		(property "Reference" "R1213"
			(at -0.839724 -1.991868 90)
			(unlocked yes)
			(layer "F.SilkS")
			(effects
				(font
					(size 0.7874 0.5842)
					(thickness 0.1524)
				)
				(justify left)
			)
		)
		(property "Value" ""
			(at 0 0 90)
			(layer "F.Fab")
			(effects
				(font
					(size 1.27 1.27)
				)
			)
		)
		(duplicate_pad_numbers_are_jumpers no)
		(fp_line
			(start 0.7874 -0.4064)
			(end 0.7874 0.4064)
			(stroke
				(width 0.1524)
				(type default)
			)
			(layer "F.SilkS")
		)
		(fp_line
			(start -0.7874 -0.4064)
			(end 0.7874 -0.4064)
			(stroke
				(width 0.1524)
				(type default)
			)
			(layer "F.SilkS")
		)
		(fp_line
			(start 0.7874 0.4064)
			(end -0.7874 0.4064)
			(stroke
				(width 0.1524)
				(type default)
			)
			(layer "F.SilkS")
		)
		(fp_line
			(start -0.7874 0.4064)
			(end -0.7874 -0.4064)
			(stroke
				(width 0.1524)
				(type default)
			)
			(layer "F.SilkS")
		)
		(fp_poly
			(pts
				(xy -0.508 0.2794) (xy -0.508 0.2286) (xy -0.635 0.2286) (xy -0.635 -0.254) (xy -0.5334 -0.254)
				(xy -0.5334 -0.2794) (xy 0.5334 -0.2794) (xy 0.5334 -0.254) (xy 0.635 -0.254) (xy 0.635 0.254) (xy 0.5334 0.254)
				(xy 0.5334 0.2794)
			)
			(stroke
				(width 0)
				(type default)
			)
			(fill no)
			(layer "F.CrtYd")
		)
		(pad "1" smd rect
			(at 0.40005 0 90)
			(size 0.4572 0.508)
			(layers "F.Cu" "F.Mask" "F.Paste")
			(net "P3V3_NODE1")
		)
		(pad "2" smd rect
			(at -0.40005 0 90)
			(size 0.4572 0.508)
			(layers "F.Cu" "F.Mask" "F.Paste")
			(net "JTAG_CPLD3_TMS")
		)
	)
	(footprint ""
		(layer "F.Cu")
		(at 56.166766 -161.928556 -90)
		(property "Reference" "C390"
			(at 3.950462 0.292354 90)
			(unlocked yes)
			(layer "F.SilkS")
			(effects
				(font
					(size 0.7874 0.5842)
					(thickness 0.1524)
				)
				(justify left)
			)
		)
		(property "Value" ""
			(at 0 0 270)
			(layer "F.Fab")
			(effects
				(font
					(size 1.27 1.27)
				)
			)
		)
		(duplicate_pad_numbers_are_jumpers no)
		(fp_line
			(start -0.7874 0.4064)
			(end -0.7874 -0.4064)
			(stroke
				(width 0.1524)
				(type default)
			)
			(layer "F.SilkS")
		)
		(fp_line
			(start 0.7874 0.4064)
			(end -0.7874 0.4064)
			(stroke
				(width 0.1524)
				(type default)
			)
			(layer "F.SilkS")
		)
		(fp_line
			(start 0 0.381)
			(end 0 -0.381)
			(stroke
				(width 0.1524)
				(type default)
			)
			(layer "F.SilkS")
		)
		(fp_line
			(start -0.7874 -0.4064)
			(end 0.7874 -0.4064)
			(stroke
				(width 0.1524)
				(type default)
			)
			(layer "F.SilkS")
		)
		(fp_line
			(start 0.7874 -0.4064)
			(end 0.7874 0.4064)
			(stroke
				(width 0.1524)
				(type default)
			)
			(layer "F.SilkS")
		)
		(fp_poly
			(pts
				(xy -0.5334 0.254) (xy -0.635 0.254) (xy -0.635 0.2286) (xy -0.635 -0.254) (xy -0.5334 -0.254) (xy -0.5334 -0.2794)
				(xy 0.5334 -0.2794) (xy 0.5334 -0.254) (xy 0.635 -0.254) (xy 0.635 0.254) (xy 0.5334 0.254) (xy 0.5334 0.2794)
				(xy -0.508 0.2794) (xy -0.5334 0.2794)
			)
			(stroke
				(width 0)
				(type default)
			)
			(fill no)
			(layer "F.CrtYd")
		)
		(pad "1" smd rect
			(at 0.40005 0 270)
			(size 0.4572 0.508)
			(layers "F.Cu" "F.Mask" "F.Paste")
			(net "P3V3_NODE1")
		)
		(pad "2" smd rect
			(at -0.40005 0 270)
			(size 0.4572 0.508)
			(layers "F.Cu" "F.Mask" "F.Paste")
			(net "GND")
		)
	)
	(footprint ""
		(layer "F.Cu")
		(at 83.218528 -95.159068 180)
		(property "Reference" "C108"
			(at -3.723132 -1.801368 0)
			(unlocked yes)
			(layer "F.SilkS")
			(effects
				(font
					(size 0.7874 0.5842)
					(thickness 0.1524)
				)
			)
		)
		(property "Value" ""
			(at 0 0 180)
			(layer "F.Fab")
			(effects
				(font
					(size 1.27 1.27)
				)
			)
		)
		(duplicate_pad_numbers_are_jumpers no)
		(fp_line
			(start 1.2954 0.5842)
			(end -1.2954 0.5842)
			(stroke
				(width 0.1524)
				(type default)
			)
			(layer "F.SilkS")
		)
		(fp_line
			(start 1.2954 -0.5842)
			(end 1.2954 0.5842)
			(stroke
				(width 0.1524)
				(type default)
			)
			(layer "F.SilkS")
		)
		(fp_line
			(start 0 -0.5842)
			(end 0 0.5842)
			(stroke
				(width 0.1524)
				(type default)
			)
			(layer "F.SilkS")
		)
		(fp_line
			(start -1.2954 0.5842)
			(end -1.2954 -0.5842)
			(stroke
				(width 0.1524)
				(type default)
			)
			(layer "F.SilkS")
		)
		(fp_line
			(start -1.2954 -0.5842)
			(end 1.2954 -0.5842)
			(stroke
				(width 0.1524)
				(type default)
			)
			(layer "F.SilkS")
		)
		(fp_poly
			(pts
				(xy 0.8636 -0.4572) (xy 0.8636 -0.3556) (xy 1.143 -0.3556) (xy 1.143 0.3556) (xy 0.8636 0.3556)
				(xy 0.8636 0.4572) (xy -0.8636 0.4572) (xy -0.8636 0.3556) (xy -1.143 0.3556) (xy -1.143 -0.3556)
				(xy -0.8636 -0.3556) (xy -0.8636 -0.4572)
			)
			(stroke
				(width 0)
				(type default)
			)
			(fill no)
			(layer "F.CrtYd")
		)
		(fp_line
			(start 0.884936 0.504952)
			(end -0.884936 0.504952)
			(stroke
				(width 0.1)
				(type default)
			)
			(layer "F.Fab")
		)
		(fp_line
			(start 0.884936 -0.504952)
			(end 0.884936 0.504952)
			(stroke
				(width 0.1)
				(type default)
			)
			(layer "F.Fab")
		)
		(fp_line
			(start -0.884936 0.504952)
			(end -0.884936 -0.504952)
			(stroke
				(width 0.1)
				(type default)
			)
			(layer "F.Fab")
		)
		(fp_line
			(start -0.884936 -0.504952)
			(end 0.884936 -0.504952)
			(stroke
				(width 0.1)
				(type default)
			)
			(layer "F.Fab")
		)
		(pad "1" smd rect
			(at 0.7366 0 270)
			(size 0.7112 0.8128)
			(layers "F.Cu" "F.Mask" "F.Paste")
			(net "P3V3_SUS_NODE1")
		)
		(pad "2" smd rect
			(at -0.7366 0 270)
			(size 0.7112 0.8128)
			(layers "F.Cu" "F.Mask" "F.Paste")
			(net "GND")
		)
	)
	(footprint ""
		(layer "F.Cu")
		(at 5.82549 -152.74798 -90)
		(property "Reference" "R1262"
			(at 2.913888 4.023868 0)
			(unlocked yes)
			(layer "F.SilkS")
			(effects
				(font
					(size 0.7874 0.5842)
					(thickness 0.1524)
				)
				(justify left)
			)
		)
		(property "Value" ""
			(at 0 0 270)
			(layer "F.Fab")
			(effects
				(font
					(size 1.27 1.27)
				)
			)
		)
		(duplicate_pad_numbers_are_jumpers no)
		(fp_line
			(start -0.7874 0.4064)
			(end -0.7874 -0.4064)
			(stroke
				(width 0.1524)
				(type default)
			)
			(layer "F.SilkS")
		)
		(fp_line
			(start 0.7874 0.4064)
			(end -0.7874 0.4064)
			(stroke
				(width 0.1524)
				(type default)
			)
			(layer "F.SilkS")
		)
		(fp_line
			(start -0.7874 -0.4064)
			(end 0.7874 -0.4064)
			(stroke
				(width 0.1524)
				(type default)
			)
			(layer "F.SilkS")
		)
		(fp_line
			(start 0.7874 -0.4064)
			(end 0.7874 0.4064)
			(stroke
				(width 0.1524)
				(type default)
			)
			(layer "F.SilkS")
		)
		(fp_poly
			(pts
				(xy -0.508 0.2794) (xy -0.508 0.2286) (xy -0.635 0.2286) (xy -0.635 -0.254) (xy -0.5334 -0.254)
				(xy -0.5334 -0.2794) (xy 0.5334 -0.2794) (xy 0.5334 -0.254) (xy 0.635 -0.254) (xy 0.635 0.254) (xy 0.5334 0.254)
				(xy 0.5334 0.2794)
			)
			(stroke
				(width 0)
				(type default)
			)
			(fill no)
			(layer "F.CrtYd")
		)
		(pad "1" smd rect
			(at 0.40005 0 270)
			(size 0.4572 0.508)
			(layers "F.Cu" "F.Mask" "F.Paste")
			(net "P3V3_NODE1")
		)
		(pad "2" smd rect
			(at -0.40005 0 270)
			(size 0.4572 0.508)
			(layers "F.Cu" "F.Mask" "F.Paste")
			(net "UART_RI_P5_N")
		)
	)
	(footprint ""
		(layer "F.Cu")
		(at 42.992294 -7.57428 90)
		(property "Reference" "PQ2"
			(at 1.67132 -10.516108 90)
			(unlocked yes)
			(layer "F.SilkS")
			(effects
				(font
					(size 0.7874 0.5842)
					(thickness 0.1524)
				)
				(justify left)
			)
		)
		(property "Value" ""
			(at 0 0 90)
			(layer "F.Fab")
			(effects
				(font
					(size 1.27 1.27)
				)
			)
		)
		(duplicate_pad_numbers_are_jumpers no)
		(fp_line
			(start 4.341876 -0.525018)
			(end 4.341876 -0.294894)
			(stroke
				(width 0.1524)
				(type default)
			)
			(layer "F.SilkS")
		)
		(fp_line
			(start -0.157988 -0.525018)
			(end 4.341876 -0.525018)
			(stroke
				(width 0.1524)
				(type default)
			)
			(layer "F.SilkS")
		)
		(fp_line
			(start -0.157988 -0.294894)
			(end -0.157988 -0.525018)
			(stroke
				(width 0.1524)
				(type default)
			)
			(layer "F.SilkS")
		)
		(fp_line
			(start 4.341876 2.245106)
			(end 4.341876 2.47523)
			(stroke
				(width 0.1524)
				(type default)
			)
			(layer "F.SilkS")
		)
		(fp_line
			(start 4.341876 2.47523)
			(end -0.157988 2.47523)
			(stroke
				(width 0.1524)
				(type default)
			)
			(layer "F.SilkS")
		)
		(fp_line
			(start -0.157988 2.47523)
			(end -0.157988 2.245106)
			(stroke
				(width 0.1524)
				(type default)
			)
			(layer "F.SilkS")
		)
		(fp_poly
			(pts
				(xy -0.339598 0) (xy -1.355598 -0.508) (xy -1.355598 0.508)
			)
			(stroke
				(width 0)
				(type default)
			)
			(fill yes)
			(layer "F.SilkS")
		)
		(fp_poly
			(pts
				(xy -0.157988 -0.525018) (xy -0.157988 -0.294894) (xy -0.346456 -0.294894) (xy -0.346456 2.245106)
				(xy -0.157988 2.245106) (xy -0.157988 2.47523) (xy 4.341876 2.47523) (xy 4.341876 2.245106) (xy 4.530344 2.245106)
				(xy 4.530344 -0.294894) (xy 4.341876 -0.294894) (xy 4.341876 -0.525018)
			)
			(stroke
				(width 0)
				(type default)
			)
			(fill no)
			(layer "F.CrtYd")
		)
		(fp_line
			(start 4.341876 -0.525018)
			(end 4.341876 2.47523)
			(stroke
				(width 0.1)
				(type default)
			)
			(layer "F.Fab")
		)
		(fp_line
			(start -0.157988 -0.525018)
			(end 4.341876 -0.525018)
			(stroke
				(width 0.1)
				(type default)
			)
			(layer "F.Fab")
		)
		(fp_line
			(start 4.341876 2.47523)
			(end -0.157988 2.47523)
			(stroke
				(width 0.1)
				(type default)
			)
			(layer "F.Fab")
		)
		(fp_line
			(start -0.157988 2.47523)
			(end -0.157988 -0.525018)
			(stroke
				(width 0.1)
				(type default)
			)
			(layer "F.Fab")
		)
		(fp_circle
			(center 2.091944 0.975106)
			(end 2.091944 1.104646)
			(stroke
				(width 0.1)
				(type default)
			)
			(fill no)
			(layer "F.Fab")
		)
		(fp_poly
			(pts
				(xy -0.339598 0) (xy -1.355598 -0.508) (xy -1.355598 0.508)
			)
			(stroke
				(width 0)
				(type default)
			)
			(fill yes)
			(layer "F.Fab")
		)
		(pad "1" smd rect
			(at 0 0)
			(size 0.4318 0.5588)
			(layers "F.Cu" "F.Mask" "F.Paste")
			(net "SW_PV_VDDR_NODE1_DRVH")
		)
		(pad "2" smd rect
			(at 0 0.649986)
			(size 0.4318 0.5588)
			(layers "F.Cu" "F.Mask" "F.Paste")
			(net "SW_PV_VDDR_NODE1_VIN_FLT")
		)
		(pad "3" smd rect
			(at 0 1.300226)
			(size 0.4318 0.5588)
			(layers "F.Cu" "F.Mask" "F.Paste")
			(net "SW_PV_VDDR_NODE1_VIN_FLT")
		)
		(pad "4" smd rect
			(at 0 1.950212)
			(size 0.4318 0.5588)
			(layers "F.Cu" "F.Mask" "F.Paste")
			(net "SW_PV_VDDR_NODE1_VIN_FLT")
		)
		(pad "5-6-7" smd custom
			(at 4.181856 1.300226)
			(size 0.143764 0.143764)
			(layers "F.Cu" "F.Mask" "F.Paste")
			(net "GND")
			(options
				(clearance outline)
				(anchor circle)
			)
			(primitives
				(gr_poly
					(pts
						(xy -0.87503 -0.287528) (xy -0.87503 0.287528) (xy 0.87503 0.287528) (xy 0.87503 -0.287528) (xy 0.424942 -0.287528)
						(xy 0.424942 -0.180086) (xy 0.424942 -0.107442) (xy 0.225044 -0.107442) (xy 0.225044 -0.180086)
						(xy 0.225044 -0.287528) (xy -0.225044 -0.287528) (xy -0.225044 -0.180086) (xy -0.225044 -0.107442)
						(xy -0.424942 -0.107442) (xy -0.424942 -0.180086) (xy -0.424942 -0.287528) (xy -0.42545 -0.287528)
					)
					(width 0)
					(fill yes)
				)
			)
		)
		(pad "8" smd rect
			(at 4.181856 0)
			(size 0.4318 0.5588)
			(layers "F.Cu" "F.Mask" "F.Paste")
			(net "SW_PV_VDDR_NODE1_DRVL")
		)
		(pad "D1_EP" smd rect
			(at 0.901954 0.975106 90)
			(size 0.8382 2.5146)
			(layers "F.Cu" "F.Mask" "F.Paste")
			(net "SW_PV_VDDR_NODE1_VIN_FLT")
		)
		(pad "S1/D2_EP" smd rect
			(at 2.675128 0.975106 90)
			(size 2.032 2.5146)
			(layers "F.Cu" "F.Mask" "F.Paste")
			(net "SW_PV_VDDR_NODE1_PH")
		)
		(zone
			(layer "F.Cu")
			(hatch none 0.5)
			(connect_pads
				(clearance 0)
			)
			(min_thickness 0.25)
			(keepout
				(tracks allowed)
				(vias not_allowed)
				(pads allowed)
				(copperpour not_allowed)
				(footprints allowed)
			)
			(placement
				(enabled no)
				(sheetname "")
			)
			(fill
				(thermal_gap 0.5)
				(thermal_bridge_width 0.5)
				(island_removal_mode 0)
			)
			(polygon
				(pts
					(xy 45.456094 -7.92988) (xy 42.484294 -7.92988) (xy 42.484294 -11.40968) (xy 45.456094 -11.40968)
					(xy 45.456094 -8.03148) (xy 45.456094 -8.00608) (xy 45.303694 -8.00608) (xy 45.303694 -8.03148)
					(xy 45.303694 -8.97128) (xy 42.662094 -8.97128) (xy 42.662094 -9.17448) (xy 45.278294 -9.17448)
					(xy 45.278294 -11.33348) (xy 42.636694 -11.33348) (xy 42.636694 -7.98068) (xy 45.456094 -7.98068)
				)
			)
		)
	)
	(footprint ""
		(layer "F.Cu")
		(at 84.171282 -2.67462 180)
		(property "Reference" "PC131"
			(at -1.915922 -1.899666 0)
			(unlocked yes)
			(layer "F.SilkS")
			(effects
				(font
					(size 0.7874 0.5842)
					(thickness 0.1524)
				)
				(justify left)
			)
		)
		(property "Value" ""
			(at 0 0 180)
			(layer "F.Fab")
			(effects
				(font
					(size 1.27 1.27)
				)
			)
		)
		(duplicate_pad_numbers_are_jumpers no)
		(fp_line
			(start 1.905 0.8636)
			(end -1.905 0.8636)
			(stroke
				(width 0.1524)
				(type default)
			)
			(layer "F.SilkS")
		)
		(fp_line
			(start 1.905 -0.8636)
			(end 1.905 0.8636)
			(stroke
				(width 0.1524)
				(type default)
			)
			(layer "F.SilkS")
		)
		(fp_line
			(start 0 0.8382)
			(end 0 -0.8382)
			(stroke
				(width 0.1524)
				(type default)
			)
			(layer "F.SilkS")
		)
		(fp_line
			(start -1.905 0.8636)
			(end -1.905 -0.8636)
			(stroke
				(width 0.1524)
				(type default)
			)
			(layer "F.SilkS")
		)
		(fp_line
			(start -1.905 -0.8636)
			(end 1.905 -0.8636)
			(stroke
				(width 0.1524)
				(type default)
			)
			(layer "F.SilkS")
		)
		(fp_rect
			(start -1.524 0.7366)
			(end 1.524 -0.7366)
			(stroke
				(width 0)
				(type default)
			)
			(fill no)
			(layer "F.CrtYd")
		)
		(pad "1" smd rect
			(at 0.94996 0 180)
			(size 1.1176 1.3716)
			(layers "F.Cu" "F.Mask" "F.Paste")
			(net "P3V3_NODE1")
		)
		(pad "2" smd rect
			(at -0.94996 0 180)
			(size 1.1176 1.3716)
			(layers "F.Cu" "F.Mask" "F.Paste")
			(net "GND")
		)
	)
	(footprint ""
		(layer "F.Cu")
		(at 149.462998 -142.88643 -90)
		(property "Reference" "R570"
			(at -1.397508 0.624332 90)
			(unlocked yes)
			(layer "F.SilkS")
			(effects
				(font
					(size 0.635 0.4064)
					(thickness 0.1524)
				)
				(justify left)
			)
		)
		(property "Value" ""
			(at 0 0 270)
			(layer "F.Fab")
			(effects
				(font
					(size 1.27 1.27)
				)
			)
		)
		(duplicate_pad_numbers_are_jumpers no)
		(fp_line
			(start -0.7874 0.4064)
			(end -0.7874 -0.4064)
			(stroke
				(width 0.1524)
				(type default)
			)
			(layer "F.SilkS")
		)
		(fp_line
			(start 0.7874 0.4064)
			(end -0.7874 0.4064)
			(stroke
				(width 0.1524)
				(type default)
			)
			(layer "F.SilkS")
		)
		(fp_line
			(start -0.7874 -0.4064)
			(end 0.7874 -0.4064)
			(stroke
				(width 0.1524)
				(type default)
			)
			(layer "F.SilkS")
		)
		(fp_line
			(start 0.7874 -0.4064)
			(end 0.7874 0.4064)
			(stroke
				(width 0.1524)
				(type default)
			)
			(layer "F.SilkS")
		)
		(fp_poly
			(pts
				(xy -0.508 0.2794) (xy -0.508 0.2286) (xy -0.635 0.2286) (xy -0.635 -0.254) (xy -0.5334 -0.254)
				(xy -0.5334 -0.2794) (xy 0.5334 -0.2794) (xy 0.5334 -0.254) (xy 0.635 -0.254) (xy 0.635 0.254) (xy 0.5334 0.254)
				(xy 0.5334 0.2794)
			)
			(stroke
				(width 0)
				(type default)
			)
			(fill no)
			(layer "F.CrtYd")
		)
		(pad "1" smd rect
			(at 0.40005 0 270)
			(size 0.4572 0.508)
			(layers "F.Cu" "F.Mask" "F.Paste")
			(net "P3V3_NODE1")
		)
		(pad "2" smd rect
			(at -0.40005 0 270)
			(size 0.4572 0.508)
			(layers "F.Cu" "F.Mask" "F.Paste")
			(net "SMB_LAN2_CLK")
		)
	)
	(footprint ""
		(layer "F.Cu")
		(at 44.207176 -177.285904 180)
		(property "Reference" "C773"
			(at 0.978916 -132.638292 0)
			(unlocked yes)
			(layer "F.SilkS")
			(effects
				(font
					(size 0.7874 0.5842)
					(thickness 0.1524)
				)
				(justify left)
			)
		)
		(property "Value" ""
			(at 0 0 180)
			(layer "F.Fab")
			(effects
				(font
					(size 1.27 1.27)
				)
			)
		)
		(duplicate_pad_numbers_are_jumpers no)
		(fp_line
			(start 0.7874 0.4064)
			(end -0.7874 0.4064)
			(stroke
				(width 0.1524)
				(type default)
			)
			(layer "F.SilkS")
		)
		(fp_line
			(start 0.7874 -0.4064)
			(end 0.7874 0.4064)
			(stroke
				(width 0.1524)
				(type default)
			)
			(layer "F.SilkS")
		)
		(fp_line
			(start 0 0.381)
			(end 0 -0.381)
			(stroke
				(width 0.1524)
				(type default)
			)
			(layer "F.SilkS")
		)
		(fp_line
			(start -0.7874 0.4064)
			(end -0.7874 -0.4064)
			(stroke
				(width 0.1524)
				(type default)
			)
			(layer "F.SilkS")
		)
		(fp_line
			(start -0.7874 -0.4064)
			(end 0.7874 -0.4064)
			(stroke
				(width 0.1524)
				(type default)
			)
			(layer "F.SilkS")
		)
		(fp_poly
			(pts
				(xy -0.5334 0.254) (xy -0.635 0.254) (xy -0.635 0.2286) (xy -0.635 -0.254) (xy -0.5334 -0.254) (xy -0.5334 -0.2794)
				(xy 0.5334 -0.2794) (xy 0.5334 -0.254) (xy 0.635 -0.254) (xy 0.635 0.254) (xy 0.5334 0.254) (xy 0.5334 0.2794)
				(xy -0.508 0.2794) (xy -0.5334 0.2794)
			)
			(stroke
				(width 0)
				(type default)
			)
			(fill no)
			(layer "F.CrtYd")
		)
		(pad "1" smd rect
			(at 0.40005 0 180)
			(size 0.4572 0.508)
			(layers "F.Cu" "F.Mask" "F.Paste")
			(net "P12V_AUX")
		)
		(pad "2" smd rect
			(at -0.40005 0 180)
			(size 0.4572 0.508)
			(layers "F.Cu" "F.Mask" "F.Paste")
			(net "GND")
		)
	)
	(footprint ""
		(layer "F.Cu")
		(at 90.81262 -179.610512)
		(property "Reference" "R1252"
			(at 85.97392 76.338938 0)
			(unlocked yes)
			(layer "F.SilkS")
			(effects
				(font
					(size 0.7874 0.5842)
					(thickness 0.1524)
				)
				(justify left)
			)
		)
		(property "Value" ""
			(at 0 0 0)
			(layer "F.Fab")
			(effects
				(font
					(size 1.27 1.27)
				)
			)
		)
		(duplicate_pad_numbers_are_jumpers no)
		(fp_line
			(start -0.7874 -0.4064)
			(end 0.7874 -0.4064)
			(stroke
				(width 0.1524)
				(type default)
			)
			(layer "F.SilkS")
		)
		(fp_line
			(start -0.7874 0.4064)
			(end -0.7874 -0.4064)
			(stroke
				(width 0.1524)
				(type default)
			)
			(layer "F.SilkS")
		)
		(fp_line
			(start 0.7874 -0.4064)
			(end 0.7874 0.4064)
			(stroke
				(width 0.1524)
				(type default)
			)
			(layer "F.SilkS")
		)
		(fp_line
			(start 0.7874 0.4064)
			(end -0.7874 0.4064)
			(stroke
				(width 0.1524)
				(type default)
			)
			(layer "F.SilkS")
		)
		(fp_poly
			(pts
				(xy -0.508 0.2794) (xy -0.508 0.2286) (xy -0.635 0.2286) (xy -0.635 -0.254) (xy -0.5334 -0.254)
				(xy -0.5334 -0.2794) (xy 0.5334 -0.2794) (xy 0.5334 -0.254) (xy 0.635 -0.254) (xy 0.635 0.254) (xy 0.5334 0.254)
				(xy 0.5334 0.2794)
			)
			(stroke
				(width 0)
				(type default)
			)
			(fill no)
			(layer "F.CrtYd")
		)
		(pad "1" smd rect
			(at 0.40005 0)
			(size 0.4572 0.508)
			(layers "F.Cu" "F.Mask" "F.Paste")
			(net "CPLD_UART_RI_P4_N")
		)
		(pad "2" smd rect
			(at -0.40005 0)
			(size 0.4572 0.508)
			(layers "F.Cu" "F.Mask" "F.Paste")
			(net "P3V3_NODE1")
		)
	)
	(footprint ""
		(layer "F.Cu")
		(at 186.000136 -29.933392)
		(property "Reference" "CE2"
			(at -3.45948 0.831342 90)
			(unlocked yes)
			(layer "F.SilkS")
			(effects
				(font
					(size 0.7874 0.5842)
					(thickness 0.1524)
				)
				(justify left)
			)
		)
		(property "Value" ""
			(at 0 0 0)
			(layer "F.Fab")
			(effects
				(font
					(size 1.27 1.27)
				)
			)
		)
		(duplicate_pad_numbers_are_jumpers no)
		(fp_line
			(start -2.750058 -1.734058)
			(end -2.750058 2.750058)
			(stroke
				(width 0.1524)
				(type default)
			)
			(layer "F.SilkS")
		)
		(fp_line
			(start -2.750058 2.750058)
			(end 2.750058 2.750058)
			(stroke
				(width 0.1524)
				(type default)
			)
			(layer "F.SilkS")
		)
		(fp_line
			(start -1.734058 -2.750058)
			(end -2.750058 -1.734058)
			(stroke
				(width 0.1524)
				(type default)
			)
			(layer "F.SilkS")
		)
		(fp_line
			(start 1.734058 -2.750058)
			(end -1.734058 -2.750058)
			(stroke
				(width 0.1524)
				(type default)
			)
			(layer "F.SilkS")
		)
		(fp_line
			(start 2.750058 -1.734058)
			(end 1.734058 -2.750058)
			(stroke
				(width 0.1524)
				(type default)
			)
			(layer "F.SilkS")
		)
		(fp_line
			(start 2.750058 2.750058)
			(end 2.750058 -1.734058)
			(stroke
				(width 0.1524)
				(type default)
			)
			(layer "F.SilkS")
		)
		(fp_poly
			(pts
				(xy 2.750058 2.750058) (xy 0.8509 2.750058) (xy 0.8509 3.761994) (xy -0.8509 3.761994) (xy -0.8509 2.750058)
				(xy -2.750058 2.750058) (xy -2.750058 -2.750058) (xy -0.8509 -2.750058) (xy -0.8509 -3.761994) (xy 0.8509 -3.761994)
				(xy 0.8509 -2.750058) (xy 2.750058 -2.750058)
			)
			(stroke
				(width 0)
				(type default)
			)
			(fill no)
			(layer "F.CrtYd")
		)
		(fp_line
			(start -2.750058 -2.750058)
			(end -2.750058 2.750058)
			(stroke
				(width 0.1)
				(type default)
			)
			(layer "F.Fab")
		)
		(fp_line
			(start -2.750058 2.750058)
			(end 2.750058 2.750058)
			(stroke
				(width 0.1)
				(type default)
			)
			(layer "F.Fab")
		)
		(fp_line
			(start 2.750058 -2.750058)
			(end -2.750058 -2.750058)
			(stroke
				(width 0.1)
				(type default)
			)
			(layer "F.Fab")
		)
		(fp_line
			(start 2.750058 2.750058)
			(end 2.750058 -2.750058)
			(stroke
				(width 0.1)
				(type default)
			)
			(layer "F.Fab")
		)
		(fp_text user "1"
			(at -1.045464 -3.901186 0)
			(unlocked yes)
			(layer "F.SilkS")
			(effects
				(font
					(size 0.635 0.4064)
					(thickness 0.1524)
				)
			)
		)
		(fp_text user "2"
			(at -1.026922 4.12115 0)
			(unlocked yes)
			(layer "F.SilkS")
			(effects
				(font
					(size 0.635 0.4064)
					(thickness 0.1524)
				)
			)
		)
		(fp_text user "+"
			(at 2.151888 -4.699508 270)
			(unlocked yes)
			(layer "F.SilkS")
			(effects
				(font
					(size 1.6002 1.1938)
					(thickness 0.1524)
				)
				(justify left)
			)
		)
		(fp_text user "+"
			(at -0.8001 -4.89585 0)
			(unlocked yes)
			(layer "F.Fab")
			(effects
				(font
					(size 1.905 1.4224)
					(thickness 0.000001)
				)
				(justify left)
			)
		)
		(fp_text user "1"
			(at -0.041148 -4.064 90)
			(unlocked yes)
			(layer "F.Fab")
			(effects
				(font
					(size 0.7874 0.5842)
					(thickness 0.000001)
				)
			)
		)
		(fp_text user "2"
			(at -0.041148 4.2164 90)
			(unlocked yes)
			(layer "F.Fab")
			(effects
				(font
					(size 0.7874 0.5842)
					(thickness 0.000001)
				)
			)
		)
		(pad "1" smd oval
			(at 0 -2.199894 180)
			(size 1.6002 3.0226)
			(layers "F.Cu" "F.Mask" "F.Paste")
			(net "USBPWR_P0")
		)
		(pad "2" smd oval
			(at 0 2.199894 180)
			(size 1.6002 3.0226)
			(layers "F.Cu" "F.Mask" "F.Paste")
			(net "GND")
		)
	)
	(footprint ""
		(layer "F.Cu")
		(at 120.63476 -188.126624 -90)
		(property "Reference" "C742"
			(at -4.901184 0.175768 90)
			(unlocked yes)
			(layer "F.SilkS")
			(effects
				(font
					(size 0.7874 0.5842)
					(thickness 0.1524)
				)
				(justify left)
			)
		)
		(property "Value" ""
			(at 0 0 270)
			(layer "F.Fab")
			(effects
				(font
					(size 1.27 1.27)
				)
			)
		)
		(duplicate_pad_numbers_are_jumpers no)
		(fp_line
			(start -0.7874 0.4064)
			(end -0.7874 -0.4064)
			(stroke
				(width 0.1524)
				(type default)
			)
			(layer "F.SilkS")
		)
		(fp_line
			(start 0.7874 0.4064)
			(end -0.7874 0.4064)
			(stroke
				(width 0.1524)
				(type default)
			)
			(layer "F.SilkS")
		)
		(fp_line
			(start 0 0.381)
			(end 0 -0.381)
			(stroke
				(width 0.1524)
				(type default)
			)
			(layer "F.SilkS")
		)
		(fp_line
			(start -0.7874 -0.4064)
			(end 0.7874 -0.4064)
			(stroke
				(width 0.1524)
				(type default)
			)
			(layer "F.SilkS")
		)
		(fp_line
			(start 0.7874 -0.4064)
			(end 0.7874 0.4064)
			(stroke
				(width 0.1524)
				(type default)
			)
			(layer "F.SilkS")
		)
		(fp_poly
			(pts
				(xy -0.5334 0.254) (xy -0.635 0.254) (xy -0.635 0.2286) (xy -0.635 -0.254) (xy -0.5334 -0.254) (xy -0.5334 -0.2794)
				(xy 0.5334 -0.2794) (xy 0.5334 -0.254) (xy 0.635 -0.254) (xy 0.635 0.254) (xy 0.5334 0.254) (xy 0.5334 0.2794)
				(xy -0.508 0.2794) (xy -0.5334 0.2794)
			)
			(stroke
				(width 0)
				(type default)
			)
			(fill no)
			(layer "F.CrtYd")
		)
		(pad "1" smd rect
			(at 0.40005 0 270)
			(size 0.4572 0.508)
			(layers "F.Cu" "F.Mask" "F.Paste")
			(net "UART_T8_NODE1_RXD")
		)
		(pad "2" smd rect
			(at -0.40005 0 270)
			(size 0.4572 0.508)
			(layers "F.Cu" "F.Mask" "F.Paste")
			(net "GND")
		)
	)
	(footprint ""
		(layer "F.Cu")
		(at 91.17076 -15.804388 90)
		(property "Reference" "R189"
			(at 0.931164 0.263652 90)
			(unlocked yes)
			(layer "F.SilkS")
			(effects
				(font
					(size 0.7874 0.5842)
					(thickness 0.1524)
				)
				(justify left)
			)
		)
		(property "Value" ""
			(at 0 0 90)
			(layer "F.Fab")
			(effects
				(font
					(size 1.27 1.27)
				)
			)
		)
		(duplicate_pad_numbers_are_jumpers no)
		(fp_line
			(start 0.7874 -0.4064)
			(end 0.7874 0.4064)
			(stroke
				(width 0.1524)
				(type default)
			)
			(layer "F.SilkS")
		)
		(fp_line
			(start -0.7874 -0.4064)
			(end 0.7874 -0.4064)
			(stroke
				(width 0.1524)
				(type default)
			)
			(layer "F.SilkS")
		)
		(fp_line
			(start 0.7874 0.4064)
			(end -0.7874 0.4064)
			(stroke
				(width 0.1524)
				(type default)
			)
			(layer "F.SilkS")
		)
		(fp_line
			(start -0.7874 0.4064)
			(end -0.7874 -0.4064)
			(stroke
				(width 0.1524)
				(type default)
			)
			(layer "F.SilkS")
		)
		(fp_poly
			(pts
				(xy -0.508 0.2794) (xy -0.508 0.2286) (xy -0.635 0.2286) (xy -0.635 -0.254) (xy -0.5334 -0.254)
				(xy -0.5334 -0.2794) (xy 0.5334 -0.2794) (xy 0.5334 -0.254) (xy 0.635 -0.254) (xy 0.635 0.254) (xy 0.5334 0.254)
				(xy 0.5334 0.2794)
			)
			(stroke
				(width 0)
				(type default)
			)
			(fill no)
			(layer "F.CrtYd")
		)
		(pad "1" smd rect
			(at 0.40005 0 90)
			(size 0.4572 0.508)
			(layers "F.Cu" "F.Mask" "F.Paste")
			(net "LPC_CPU_NODE1_LAD3")
		)
		(pad "2" smd rect
			(at -0.40005 0 90)
			(size 0.4572 0.508)
			(layers "F.Cu" "F.Mask" "F.Paste")
			(net "LPC_CPU_TPM_LAD3")
		)
	)
	(footprint ""
		(layer "F.Cu")
		(at 138.729974 -20.799806 90)
		(property "Reference" "J8"
			(at -2.301494 -2.116328 90)
			(unlocked yes)
			(layer "F.SilkS")
			(effects
				(font
					(size 0.7874 0.5842)
					(thickness 0.1524)
				)
				(justify left)
			)
		)
		(property "Value" ""
			(at 0 0 90)
			(layer "F.Fab")
			(effects
				(font
					(size 1.27 1.27)
				)
			)
		)
		(duplicate_pad_numbers_are_jumpers no)
		(fp_line
			(start 2.54 -1.394968)
			(end 2.54 3.934968)
			(stroke
				(width 0.1524)
				(type default)
			)
			(layer "F.SilkS")
		)
		(fp_line
			(start -2.124964 -1.394968)
			(end -2.124964 3.934968)
			(stroke
				(width 0.124968)
				(type default)
			)
			(layer "F.SilkS")
		)
		(fp_line
			(start -2.249932 -1.394968)
			(end -2.249932 3.934968)
			(stroke
				(width 0.124968)
				(type default)
			)
			(layer "F.SilkS")
		)
		(fp_line
			(start -2.249932 -1.394968)
			(end -2.249932 3.934968)
			(stroke
				(width 0.124968)
				(type default)
			)
			(layer "F.SilkS")
		)
		(fp_line
			(start -2.3749 -1.394968)
			(end -2.3749 3.934968)
			(stroke
				(width 0.124968)
				(type default)
			)
			(layer "F.SilkS")
		)
		(fp_line
			(start -2.3749 -1.394968)
			(end -2.3749 3.934968)
			(stroke
				(width 0.124968)
				(type default)
			)
			(layer "F.SilkS")
		)
		(fp_line
			(start -2.500122 -1.394968)
			(end -2.500122 3.934968)
			(stroke
				(width 0.124968)
				(type default)
			)
			(layer "F.SilkS")
		)
		(fp_line
			(start -2.54 -1.394968)
			(end 2.54 -1.394968)
			(stroke
				(width 0.1524)
				(type default)
			)
			(layer "F.SilkS")
		)
		(fp_line
			(start -2.54 -1.394968)
			(end -2.54 3.934968)
			(stroke
				(width 0.1524)
				(type default)
			)
			(layer "F.SilkS")
		)
		(fp_line
			(start 2.54 3.934968)
			(end -2.54 3.934968)
			(stroke
				(width 0.1524)
				(type default)
			)
			(layer "F.SilkS")
		)
		(fp_line
			(start -1.500124 3.934968)
			(end -1.500124 -1.394968)
			(stroke
				(width 0.124968)
				(type default)
			)
			(layer "F.SilkS")
		)
		(fp_line
			(start -1.562608 3.934968)
			(end -1.562608 -1.394968)
			(stroke
				(width 0.124968)
				(type default)
			)
			(layer "F.SilkS")
		)
		(fp_line
			(start -1.625092 3.934968)
			(end -1.625092 -1.394968)
			(stroke
				(width 0.124968)
				(type default)
			)
			(layer "F.SilkS")
		)
		(fp_line
			(start -1.687576 3.934968)
			(end -1.687576 -1.394968)
			(stroke
				(width 0.124968)
				(type default)
			)
			(layer "F.SilkS")
		)
		(fp_line
			(start -1.75006 3.934968)
			(end -1.75006 -1.394968)
			(stroke
				(width 0.124968)
				(type default)
			)
			(layer "F.SilkS")
		)
		(fp_line
			(start -1.875028 3.934968)
			(end -1.875028 -1.394968)
			(stroke
				(width 0.124968)
				(type default)
			)
			(layer "F.SilkS")
		)
		(fp_line
			(start -1.937512 3.934968)
			(end -1.937512 -1.394968)
			(stroke
				(width 0.124968)
				(type default)
			)
			(layer "F.SilkS")
		)
		(fp_line
			(start -1.999996 3.934968)
			(end -1.999996 -1.394968)
			(stroke
				(width 0.124968)
				(type default)
			)
			(layer "F.SilkS")
		)
		(fp_line
			(start -2.06248 3.934968)
			(end -2.06248 -1.394968)
			(stroke
				(width 0.124968)
				(type default)
			)
			(layer "F.SilkS")
		)
		(fp_line
			(start -2.312416 3.934968)
			(end -2.312416 -1.394968)
			(stroke
				(width 0.124968)
				(type default)
			)
			(layer "F.SilkS")
		)
		(fp_line
			(start -2.54 3.934968)
			(end -2.54 -1.394968)
			(stroke
				(width 0.1524)
				(type default)
			)
			(layer "F.SilkS")
		)
		(fp_line
			(start -2.54 3.934968)
			(end -2.54 -1.394968)
			(stroke
				(width 0.1524)
				(type default)
			)
			(layer "F.SilkS")
		)
		(fp_poly
			(pts
				(xy -2.5908 0.0127) (xy -4.1656 0.4445) (xy -4.1656 -0.4445)
			)
			(stroke
				(width 0)
				(type default)
			)
			(fill yes)
			(layer "F.SilkS")
		)
		(fp_poly
			(pts
				(xy -0.8382 3.3782) (xy -0.8382 -0.8382) (xy 0.8382 -0.8382) (xy 0.8382 3.3782)
			)
			(stroke
				(width 0)
				(type default)
			)
			(fill no)
			(layer "B.CrtYd")
		)
		(fp_rect
			(start 2.54 3.934968)
			(end -2.54 -1.394968)
			(stroke
				(width 0)
				(type default)
			)
			(fill no)
			(layer "F.CrtYd")
		)
		(fp_line
			(start 2.54 -1.394968)
			(end 2.54 3.934968)
			(stroke
				(width 0.1)
				(type default)
			)
			(layer "F.Fab")
		)
		(fp_line
			(start -2.54 -1.394968)
			(end 2.54 -1.394968)
			(stroke
				(width 0.1)
				(type default)
			)
			(layer "F.Fab")
		)
		(fp_line
			(start 2.54 3.934968)
			(end -2.54 3.934968)
			(stroke
				(width 0.1)
				(type default)
			)
			(layer "F.Fab")
		)
		(fp_line
			(start -2.54 3.934968)
			(end -2.54 -1.394968)
			(stroke
				(width 0.1)
				(type default)
			)
			(layer "F.Fab")
		)
		(fp_poly
			(pts
				(xy -2.5908 0.0127) (xy -4.1656 0.4445) (xy -4.1656 -0.4445)
			)
			(stroke
				(width 0)
				(type default)
			)
			(fill yes)
			(layer "F.Fab")
		)
		(fp_text user "1"
			(at -3.208528 -0.965708 0)
			(unlocked yes)
			(layer "F.SilkS")
			(effects
				(font
					(size 0.635 0.4064)
					(thickness 0.1524)
				)
				(justify left)
			)
		)
		(fp_text user "2"
			(at -3.19278 1.975612 0)
			(unlocked yes)
			(layer "F.SilkS")
			(effects
				(font
					(size 0.635 0.4064)
					(thickness 0.1524)
				)
				(justify left)
			)
		)
		(fp_text user "1"
			(at 1.561846 0.507492 0)
			(unlocked yes)
			(layer "B.SilkS")
			(effects
				(font
					(size 0.7874 0.5842)
					(thickness 0.1524)
				)
				(justify left mirror)
			)
		)
		(fp_text user "2"
			(at 2.135124 2.927858 0)
			(unlocked yes)
			(layer "B.SilkS")
			(effects
				(font
					(size 0.7874 0.5842)
					(thickness 0.1524)
				)
				(justify left mirror)
			)
		)
		(fp_text user "1"
			(at -1.31953 -0.3302 180)
			(unlocked yes)
			(layer "B.Fab")
			(effects
				(font
					(size 0.7874 0.5842)
					(thickness 0.000001)
				)
				(justify left mirror)
			)
		)
		(fp_text user "2"
			(at -1.34493 2.3622 180)
			(unlocked yes)
			(layer "B.Fab")
			(effects
				(font
					(size 0.7874 0.5842)
					(thickness 0.000001)
				)
				(justify left mirror)
			)
		)
		(fp_text user "1"
			(at -3.114548 -0.2159 180)
			(unlocked yes)
			(layer "F.Fab")
			(effects
				(font
					(size 0.7874 0.5842)
					(thickness 0.000001)
				)
				(justify left)
			)
		)
		(fp_text user "2"
			(at -3.114548 2.8321 180)
			(unlocked yes)
			(layer "F.Fab")
			(effects
				(font
					(size 0.7874 0.5842)
					(thickness 0.000001)
				)
				(justify left)
			)
		)
		(pad "1" thru_hole rect
			(at 0 0 180)
			(size 1.5494 1.5494)
			(drill 1.0414)
			(layers "*.Cu" "*.Mask")
			(remove_unused_layers no)
			(net "GND")
			(clearance 0)
			(padstack
				(mode front_inner_back)
				(layer "Inner"
					(shape circle)
					(size 1.5494 1.5494)
					(clearance 0)
				)
				(layer "B.Cu"
					(shape rect)
					(size 1.5494 1.5494)
					(clearance 0)
				)
			)
		)
		(pad "2" thru_hole circle
			(at 0 2.54 180)
			(size 1.5494 1.5494)
			(drill 1.0414)
			(layers "*.Cu" "*.Mask")
			(remove_unused_layers no)
			(net "P5V_NODE1")
			(clearance 0)
		)
	)
	(footprint ""
		(layer "F.Cu")
		(at 70.035166 -111.801148 -90)
		(property "Reference" "Q37"
			(at 1.470914 -1.372616 90)
			(unlocked yes)
			(layer "F.SilkS")
			(effects
				(font
					(size 0.7874 0.5842)
					(thickness 0.1524)
				)
			)
		)
		(property "Value" ""
			(at 0 0 270)
			(layer "F.Fab")
			(effects
				(font
					(size 1.27 1.27)
				)
			)
		)
		(duplicate_pad_numbers_are_jumpers no)
		(fp_line
			(start -0.100076 2.474976)
			(end -0.100076 2.295906)
			(stroke
				(width 0.1524)
				(type default)
			)
			(layer "F.SilkS")
		)
		(fp_line
			(start 1.044448 2.474976)
			(end -0.100076 2.474976)
			(stroke
				(width 0.1524)
				(type default)
			)
			(layer "F.SilkS")
		)
		(fp_line
			(start 2.899918 2.474976)
			(end 1.755648 2.474976)
			(stroke
				(width 0.1524)
				(type default)
			)
			(layer "F.SilkS")
		)
		(fp_line
			(start 2.899918 2.295906)
			(end 2.899918 2.474976)
			(stroke
				(width 0.1524)
				(type default)
			)
			(layer "F.SilkS")
		)
		(fp_line
			(start -0.100076 -0.320294)
			(end -0.100076 -0.525018)
			(stroke
				(width 0.1524)
				(type default)
			)
			(layer "F.SilkS")
		)
		(fp_line
			(start -0.100076 -0.525018)
			(end 1.044448 -0.525018)
			(stroke
				(width 0.1524)
				(type default)
			)
			(layer "F.SilkS")
		)
		(fp_line
			(start 1.755648 -0.525018)
			(end 2.899918 -0.525018)
			(stroke
				(width 0.1524)
				(type default)
			)
			(layer "F.SilkS")
		)
		(fp_line
			(start 2.899918 -0.525018)
			(end 2.899918 -0.345694)
			(stroke
				(width 0.1524)
				(type default)
			)
			(layer "F.SilkS")
		)
		(fp_poly
			(pts
				(xy -0.25527 -1.65481) (xy 0.263652 -1.65481) (xy 0 -1.077468)
			)
			(stroke
				(width 0)
				(type default)
			)
			(fill yes)
			(layer "F.SilkS")
		)
		(fp_poly
			(pts
				(xy -0.100076 -0.525018) (xy -0.100076 -0.244094) (xy -0.301752 -0.244094) (xy -0.301752 2.194306)
				(xy -0.100076 2.194306) (xy -0.100076 2.474976) (xy 1.120648 2.474976) (xy 1.120648 2.651506) (xy 1.679448 2.651506)
				(xy 1.679448 2.474976) (xy 2.899918 2.474976) (xy 2.899918 2.219706) (xy 3.101848 2.219706) (xy 3.101848 -0.269494)
				(xy 2.899918 -0.269494) (xy 2.899918 -0.525018) (xy 1.679448 -0.525018) (xy 1.679448 -0.701294)
				(xy 1.120648 -0.701294) (xy 1.120648 -0.525018)
			)
			(stroke
				(width 0)
				(type default)
			)
			(fill no)
			(layer "F.CrtYd")
		)
		(fp_line
			(start -0.100076 2.474976)
			(end -0.100076 -0.525018)
			(stroke
				(width 0.1)
				(type default)
			)
			(layer "F.Fab")
		)
		(fp_line
			(start 2.899918 2.474976)
			(end -0.100076 2.474976)
			(stroke
				(width 0.1)
				(type default)
			)
			(layer "F.Fab")
		)
		(fp_line
			(start -0.100076 -0.525018)
			(end 2.899918 -0.525018)
			(stroke
				(width 0.1)
				(type default)
			)
			(layer "F.Fab")
		)
		(fp_line
			(start 2.899918 -0.525018)
			(end 2.899918 2.474976)
			(stroke
				(width 0.1)
				(type default)
			)
			(layer "F.Fab")
		)
		(pad "1" smd rect
			(at 0 0 180)
			(size 0.3556 0.508)
			(layers "F.Cu" "F.Mask" "F.Paste")
			(net "P1V8_NODE1")
		)
		(pad "2" smd rect
			(at 0 0.649986 180)
			(size 0.3556 0.508)
			(layers "F.Cu" "F.Mask" "F.Paste")
			(net "P1V8_NODE1")
		)
		(pad "3" smd rect
			(at 0 1.299972 180)
			(size 0.3556 0.508)
			(layers "F.Cu" "F.Mask" "F.Paste")
			(net "P1V8_NODE1")
		)
		(pad "4" smd rect
			(at 0 1.949958 180)
			(size 0.3556 0.508)
			(layers "F.Cu" "F.Mask" "F.Paste")
			(net "FM_CPLD_NODE1_P1V8_EN_LV")
		)
		(pad "5" smd custom
			(at 1.400048 0.975106 180)
			(size 0.569976 0.569976)
			(layers "F.Cu" "F.Mask" "F.Paste")
			(net "P1V8_STB_NODE1")
			(options
				(clearance outline)
				(anchor circle)
			)
			(primitives
				(gr_poly
					(pts
						(xy -1.225042 1.139952) (xy -1.225042 0.724916) (xy -1.605026 0.724916) (xy -1.605026 0.295148)
						(xy -1.225042 0.295148) (xy -1.225042 -0.839978) (xy -1.175004 -0.839978) (xy -1.175004 -1.139952)
						(xy -0.774954 -1.139952) (xy -0.774954 -0.839978) (xy -0.525018 -0.839978) (xy -0.525018 -1.139952)
						(xy -0.124968 -1.139952) (xy -0.124968 -0.839978) (xy 0.124968 -0.839978) (xy 0.124968 -1.139952)
						(xy 0.525018 -1.139952) (xy 0.525018 -0.839978) (xy 0.774954 -0.839978) (xy 0.774954 -1.139952)
						(xy 1.175004 -1.139952) (xy 1.175004 -0.839978) (xy 1.225042 -0.839978) (xy 1.225042 0.295148)
						(xy 1.605026 0.295148) (xy 1.605026 0.724916) (xy 1.225042 0.724916) (xy 1.225042 1.139952)
					)
					(width 0)
					(fill yes)
				)
			)
		)
		(zone
			(layer "F.Cu")
			(hatch none 0.5)
			(connect_pads
				(clearance 0)
			)
			(min_thickness 0.25)
			(keepout
				(tracks not_allowed)
				(vias allowed)
				(pads allowed)
				(copperpour not_allowed)
				(footprints allowed)
			)
			(placement
				(enabled no)
				(sheetname "")
			)
			(fill
				(thermal_gap 0.5)
				(thermal_bridge_width 0.5)
				(island_removal_mode 0)
			)
			(polygon
				(pts
					(xy 70.55866 -111.4679) (xy 67.56146 -111.4679) (xy 67.56146 -111.0869) (xy 70.55866 -111.0869)
				)
			)
		)
		(zone
			(layer "F.Cu")
			(hatch none 0.5)
			(connect_pads
				(clearance 0)
			)
			(min_thickness 0.25)
			(keepout
				(tracks allowed)
				(vias not_allowed)
				(pads allowed)
				(copperpour not_allowed)
				(footprints allowed)
			)
			(placement
				(enabled no)
				(sheetname "")
			)
			(fill
				(thermal_gap 0.5)
				(thermal_bridge_width 0.5)
				(island_removal_mode 0)
			)
			(polygon
				(pts
					(xy 70.55866 -111.0869) (xy 67.56146 -111.0869) (xy 67.56146 -111.4679) (xy 70.55866 -111.4679)
				)
			)
		)
	)
	(footprint ""
		(layer "F.Cu")
		(at 8.722614 -4.27228)
		(property "Reference" "U10"
			(at -3.361436 1.02743 90)
			(unlocked yes)
			(layer "F.SilkS")
			(effects
				(font
					(size 0.7874 0.5842)
					(thickness 0.1524)
				)
			)
		)
		(property "Value" ""
			(at 0 0 0)
			(layer "F.Fab")
			(effects
				(font
					(size 1.27 1.27)
				)
			)
		)
		(duplicate_pad_numbers_are_jumpers no)
		(fp_line
			(start -1.1176 -1.7272)
			(end -1.1176 -0.254)
			(stroke
				(width 0.1524)
				(type default)
			)
			(layer "F.SilkS")
		)
		(fp_line
			(start -1.1176 -1.7272)
			(end 1.1176 -1.7272)
			(stroke
				(width 0.1524)
				(type default)
			)
			(layer "F.SilkS")
		)
		(fp_line
			(start -1.1176 -0.254)
			(end -0.7366 0)
			(stroke
				(width 0.1524)
				(type default)
			)
			(layer "F.SilkS")
		)
		(fp_line
			(start -1.1176 0.254)
			(end -1.1176 1.7272)
			(stroke
				(width 0.1524)
				(type default)
			)
			(layer "F.SilkS")
		)
		(fp_line
			(start -0.7366 0)
			(end -1.1176 0.254)
			(stroke
				(width 0.1524)
				(type default)
			)
			(layer "F.SilkS")
		)
		(fp_line
			(start 1.1176 -1.7272)
			(end 1.1176 1.7272)
			(stroke
				(width 0.1524)
				(type default)
			)
			(layer "F.SilkS")
		)
		(fp_line
			(start 1.1176 1.7272)
			(end -1.1176 1.7272)
			(stroke
				(width 0.1524)
				(type default)
			)
			(layer "F.SilkS")
		)
		(fp_rect
			(start -1.1176 1.5748)
			(end 1.1176 -1.5748)
			(stroke
				(width 0)
				(type default)
			)
			(fill no)
			(layer "F.CrtYd")
		)
		(pad "1" smd rect
			(at -0.649986 0.999998)
			(size 0.3556 1.1176)
			(layers "F.Cu" "F.Mask" "F.Paste")
			(net "P3V3_STB_NODE1")
		)
		(pad "2" smd rect
			(at 0 0.999998)
			(size 0.3556 1.1176)
			(layers "F.Cu" "F.Mask" "F.Paste")
			(net "GND")
		)
		(pad "3" smd rect
			(at 0.649986 0.999998)
			(size 0.3556 1.1176)
			(layers "F.Cu" "F.Mask" "F.Paste")
			(net "SMB_MUX_CPU_ICS_NODE1_CLK")
		)
		(pad "4" smd rect
			(at 0.649986 -0.999998)
			(size 0.3556 1.1176)
			(layers "F.Cu" "F.Mask" "F.Paste")
			(net "SMB_MUX_CPU_ICS_NODE1_DAT")
		)
		(pad "5" smd rect
			(at 0 -0.999998)
			(size 0.3556 1.1176)
			(layers "F.Cu" "F.Mask" "F.Paste")
			(net "PV_VDDR_NODE1_VREF_RW")
		)
		(pad "6" smd rect
			(at -0.649986 -0.999998)
			(size 0.3556 1.1176)
			(layers "F.Cu" "F.Mask" "F.Paste")
			(net "PV_VDDR_NODE1")
		)
	)
	(footprint ""
		(layer "F.Cu")
		(at 15.808452 -48.052228)
		(property "Reference" "R788"
			(at 12.177268 4.144518 0)
			(unlocked yes)
			(layer "F.SilkS")
			(effects
				(font
					(size 0.7874 0.5842)
					(thickness 0.1524)
				)
				(justify left)
			)
		)
		(property "Value" ""
			(at 0 0 0)
			(layer "F.Fab")
			(effects
				(font
					(size 1.27 1.27)
				)
			)
		)
		(duplicate_pad_numbers_are_jumpers no)
		(fp_line
			(start -0.7874 -0.4064)
			(end 0.7874 -0.4064)
			(stroke
				(width 0.1524)
				(type default)
			)
			(layer "F.SilkS")
		)
		(fp_line
			(start -0.7874 0.4064)
			(end -0.7874 -0.4064)
			(stroke
				(width 0.1524)
				(type default)
			)
			(layer "F.SilkS")
		)
		(fp_line
			(start 0.7874 -0.4064)
			(end 0.7874 0.4064)
			(stroke
				(width 0.1524)
				(type default)
			)
			(layer "F.SilkS")
		)
		(fp_line
			(start 0.7874 0.4064)
			(end -0.7874 0.4064)
			(stroke
				(width 0.1524)
				(type default)
			)
			(layer "F.SilkS")
		)
		(fp_poly
			(pts
				(xy -0.508 0.2794) (xy -0.508 0.2286) (xy -0.635 0.2286) (xy -0.635 -0.254) (xy -0.5334 -0.254)
				(xy -0.5334 -0.2794) (xy 0.5334 -0.2794) (xy 0.5334 -0.254) (xy 0.635 -0.254) (xy 0.635 0.254) (xy 0.5334 0.254)
				(xy 0.5334 0.2794)
			)
			(stroke
				(width 0)
				(type default)
			)
			(fill no)
			(layer "F.CrtYd")
		)
		(pad "1" smd rect
			(at 0.40005 0)
			(size 0.4572 0.508)
			(layers "F.Cu" "F.Mask" "F.Paste")
			(net "CRT_G_L")
		)
		(pad "2" smd rect
			(at -0.40005 0)
			(size 0.4572 0.508)
			(layers "F.Cu" "F.Mask" "F.Paste")
			(net "CRT_G")
		)
	)
	(footprint ""
		(layer "F.Cu")
		(at 16.499332 -134.725918)
		(property "Reference" "PR27"
			(at -0.802894 -2.192274 0)
			(unlocked yes)
			(layer "F.SilkS")
			(effects
				(font
					(size 0.7874 0.5842)
					(thickness 0.1524)
				)
				(justify left)
			)
		)
		(property "Value" ""
			(at 0 0 0)
			(layer "F.Fab")
			(effects
				(font
					(size 1.27 1.27)
				)
			)
		)
		(duplicate_pad_numbers_are_jumpers no)
		(fp_line
			(start -0.7874 -0.4064)
			(end 0.7874 -0.4064)
			(stroke
				(width 0.1524)
				(type default)
			)
			(layer "F.SilkS")
		)
		(fp_line
			(start -0.7874 0.4064)
			(end -0.7874 -0.4064)
			(stroke
				(width 0.1524)
				(type default)
			)
			(layer "F.SilkS")
		)
		(fp_line
			(start 0.7874 -0.4064)
			(end 0.7874 0.4064)
			(stroke
				(width 0.1524)
				(type default)
			)
			(layer "F.SilkS")
		)
		(fp_line
			(start 0.7874 0.4064)
			(end -0.7874 0.4064)
			(stroke
				(width 0.1524)
				(type default)
			)
			(layer "F.SilkS")
		)
		(fp_poly
			(pts
				(xy -0.508 0.2794) (xy -0.508 0.2286) (xy -0.635 0.2286) (xy -0.635 -0.254) (xy -0.5334 -0.254)
				(xy -0.5334 -0.2794) (xy 0.5334 -0.2794) (xy 0.5334 -0.254) (xy 0.635 -0.254) (xy 0.635 0.254) (xy 0.5334 0.254)
				(xy 0.5334 0.2794)
			)
			(stroke
				(width 0)
				(type default)
			)
			(fill no)
			(layer "F.CrtYd")
		)
		(pad "1" smd rect
			(at 0.40005 0)
			(size 0.4572 0.508)
			(layers "F.Cu" "F.Mask" "F.Paste")
			(net "GND")
		)
		(pad "2" smd rect
			(at -0.40005 0)
			(size 0.4572 0.508)
			(layers "F.Cu" "F.Mask" "F.Paste")
			(net "VSENSE_P1V05_NODE1_N")
		)
	)
	(footprint ""
		(layer "F.Cu")
		(at 58.53176 -188.126624 90)
		(property "Reference" "C709"
			(at 4.548886 0.346202 90)
			(unlocked yes)
			(layer "F.SilkS")
			(effects
				(font
					(size 0.7874 0.5842)
					(thickness 0.1524)
				)
				(justify left)
			)
		)
		(property "Value" ""
			(at 0 0 90)
			(layer "F.Fab")
			(effects
				(font
					(size 1.27 1.27)
				)
			)
		)
		(duplicate_pad_numbers_are_jumpers no)
		(fp_line
			(start 0.7874 -0.4064)
			(end 0.7874 0.4064)
			(stroke
				(width 0.1524)
				(type default)
			)
			(layer "F.SilkS")
		)
		(fp_line
			(start -0.7874 -0.4064)
			(end 0.7874 -0.4064)
			(stroke
				(width 0.1524)
				(type default)
			)
			(layer "F.SilkS")
		)
		(fp_line
			(start 0 0.381)
			(end 0 -0.381)
			(stroke
				(width 0.1524)
				(type default)
			)
			(layer "F.SilkS")
		)
		(fp_line
			(start 0.7874 0.4064)
			(end -0.7874 0.4064)
			(stroke
				(width 0.1524)
				(type default)
			)
			(layer "F.SilkS")
		)
		(fp_line
			(start -0.7874 0.4064)
			(end -0.7874 -0.4064)
			(stroke
				(width 0.1524)
				(type default)
			)
			(layer "F.SilkS")
		)
		(fp_poly
			(pts
				(xy -0.5334 0.254) (xy -0.635 0.254) (xy -0.635 0.2286) (xy -0.635 -0.254) (xy -0.5334 -0.254) (xy -0.5334 -0.2794)
				(xy 0.5334 -0.2794) (xy 0.5334 -0.254) (xy 0.635 -0.254) (xy 0.635 0.254) (xy 0.5334 0.254) (xy 0.5334 0.2794)
				(xy -0.508 0.2794) (xy -0.5334 0.2794)
			)
			(stroke
				(width 0)
				(type default)
			)
			(fill no)
			(layer "F.CrtYd")
		)
		(pad "1" smd rect
			(at 0.40005 0 90)
			(size 0.4572 0.508)
			(layers "F.Cu" "F.Mask" "F.Paste")
			(net "UART_T2_NODE3_TXD_R")
		)
		(pad "2" smd rect
			(at -0.40005 0 90)
			(size 0.4572 0.508)
			(layers "F.Cu" "F.Mask" "F.Paste")
			(net "GND")
		)
	)
	(footprint ""
		(layer "F.Cu")
		(at 139.93876 -188.126624 90)
		(property "Reference" "C639"
			(at 5.519674 -0.323088 90)
			(unlocked yes)
			(layer "F.SilkS")
			(effects
				(font
					(size 0.7874 0.5842)
					(thickness 0.1524)
				)
				(justify left)
			)
		)
		(property "Value" ""
			(at 0 0 90)
			(layer "F.Fab")
			(effects
				(font
					(size 1.27 1.27)
				)
			)
		)
		(duplicate_pad_numbers_are_jumpers no)
		(fp_line
			(start 0.7874 -0.4064)
			(end 0.7874 0.4064)
			(stroke
				(width 0.1524)
				(type default)
			)
			(layer "F.SilkS")
		)
		(fp_line
			(start -0.7874 -0.4064)
			(end 0.7874 -0.4064)
			(stroke
				(width 0.1524)
				(type default)
			)
			(layer "F.SilkS")
		)
		(fp_line
			(start 0 0.381)
			(end 0 -0.381)
			(stroke
				(width 0.1524)
				(type default)
			)
			(layer "F.SilkS")
		)
		(fp_line
			(start 0.7874 0.4064)
			(end -0.7874 0.4064)
			(stroke
				(width 0.1524)
				(type default)
			)
			(layer "F.SilkS")
		)
		(fp_line
			(start -0.7874 0.4064)
			(end -0.7874 -0.4064)
			(stroke
				(width 0.1524)
				(type default)
			)
			(layer "F.SilkS")
		)
		(fp_poly
			(pts
				(xy -0.5334 0.254) (xy -0.635 0.254) (xy -0.635 0.2286) (xy -0.635 -0.254) (xy -0.5334 -0.254) (xy -0.5334 -0.2794)
				(xy 0.5334 -0.2794) (xy 0.5334 -0.254) (xy 0.635 -0.254) (xy 0.635 0.254) (xy 0.5334 0.254) (xy 0.5334 0.2794)
				(xy -0.508 0.2794) (xy -0.5334 0.2794)
			)
			(stroke
				(width 0)
				(type default)
			)
			(fill no)
			(layer "F.CrtYd")
		)
		(pad "1" smd rect
			(at 0.40005 0 90)
			(size 0.4572 0.508)
			(layers "F.Cu" "F.Mask" "F.Paste")
			(net "T10_NODE2_EN_R")
		)
		(pad "2" smd rect
			(at -0.40005 0 90)
			(size 0.4572 0.508)
			(layers "F.Cu" "F.Mask" "F.Paste")
			(net "GND")
		)
	)
	(footprint ""
		(layer "F.Cu")
		(at 36.478718 -113.177828 180)
		(property "Reference" "Q39"
			(at 3.812032 0.982472 90)
			(unlocked yes)
			(layer "F.SilkS")
			(effects
				(font
					(size 0.7874 0.5842)
					(thickness 0.1524)
				)
			)
		)
		(property "Value" ""
			(at 0 0 180)
			(layer "F.Fab")
			(effects
				(font
					(size 1.27 1.27)
				)
			)
		)
		(duplicate_pad_numbers_are_jumpers no)
		(fp_line
			(start 2.899918 2.474976)
			(end 1.755648 2.474976)
			(stroke
				(width 0.1524)
				(type default)
			)
			(layer "F.SilkS")
		)
		(fp_line
			(start 2.899918 2.295906)
			(end 2.899918 2.474976)
			(stroke
				(width 0.1524)
				(type default)
			)
			(layer "F.SilkS")
		)
		(fp_line
			(start 2.899918 -0.525018)
			(end 2.899918 -0.345694)
			(stroke
				(width 0.1524)
				(type default)
			)
			(layer "F.SilkS")
		)
		(fp_line
			(start 1.755648 -0.525018)
			(end 2.899918 -0.525018)
			(stroke
				(width 0.1524)
				(type default)
			)
			(layer "F.SilkS")
		)
		(fp_line
			(start 1.044448 2.474976)
			(end -0.100076 2.474976)
			(stroke
				(width 0.1524)
				(type default)
			)
			(layer "F.SilkS")
		)
		(fp_line
			(start -0.100076 2.474976)
			(end -0.100076 2.295906)
			(stroke
				(width 0.1524)
				(type default)
			)
			(layer "F.SilkS")
		)
		(fp_line
			(start -0.100076 -0.320294)
			(end -0.100076 -0.525018)
			(stroke
				(width 0.1524)
				(type default)
			)
			(layer "F.SilkS")
		)
		(fp_line
			(start -0.100076 -0.525018)
			(end 1.044448 -0.525018)
			(stroke
				(width 0.1524)
				(type default)
			)
			(layer "F.SilkS")
		)
		(fp_poly
			(pts
				(xy -0.350012 -1.286256) (xy 0.16891 -1.286256) (xy -0.094742 -0.708914)
			)
			(stroke
				(width 0)
				(type default)
			)
			(fill yes)
			(layer "F.SilkS")
		)
		(fp_poly
			(pts
				(xy -0.100076 -0.525018) (xy -0.100076 -0.244094) (xy -0.301752 -0.244094) (xy -0.301752 2.194306)
				(xy -0.100076 2.194306) (xy -0.100076 2.474976) (xy 1.120648 2.474976) (xy 1.120648 2.651506) (xy 1.679448 2.651506)
				(xy 1.679448 2.474976) (xy 2.899918 2.474976) (xy 2.899918 2.219706) (xy 3.101848 2.219706) (xy 3.101848 -0.269494)
				(xy 2.899918 -0.269494) (xy 2.899918 -0.525018) (xy 1.679448 -0.525018) (xy 1.679448 -0.701294)
				(xy 1.120648 -0.701294) (xy 1.120648 -0.525018)
			)
			(stroke
				(width 0)
				(type default)
			)
			(fill no)
			(layer "F.CrtYd")
		)
		(fp_line
			(start 2.899918 2.474976)
			(end -0.100076 2.474976)
			(stroke
				(width 0.1)
				(type default)
			)
			(layer "F.Fab")
		)
		(fp_line
			(start 2.899918 -0.525018)
			(end 2.899918 2.474976)
			(stroke
				(width 0.1)
				(type default)
			)
			(layer "F.Fab")
		)
		(fp_line
			(start -0.100076 2.474976)
			(end -0.100076 -0.525018)
			(stroke
				(width 0.1)
				(type default)
			)
			(layer "F.Fab")
		)
		(fp_line
			(start -0.100076 -0.525018)
			(end 2.899918 -0.525018)
			(stroke
				(width 0.1)
				(type default)
			)
			(layer "F.Fab")
		)
		(pad "1" smd rect
			(at 0 0 90)
			(size 0.3556 0.508)
			(layers "F.Cu" "F.Mask" "F.Paste")
			(net "P1V5_NODE1")
		)
		(pad "2" smd rect
			(at 0 0.649986 90)
			(size 0.3556 0.508)
			(layers "F.Cu" "F.Mask" "F.Paste")
			(net "P1V5_NODE1")
		)
		(pad "3" smd rect
			(at 0 1.299972 90)
			(size 0.3556 0.508)
			(layers "F.Cu" "F.Mask" "F.Paste")
			(net "P1V5_NODE1")
		)
		(pad "4" smd rect
			(at 0 1.949958 90)
			(size 0.3556 0.508)
			(layers "F.Cu" "F.Mask" "F.Paste")
			(net "FM_CPLD_NODE1_P1V5_EN_LV")
		)
		(pad "5" smd custom
			(at 1.400048 0.975106 90)
			(size 0.569976 0.569976)
			(layers "F.Cu" "F.Mask" "F.Paste")
			(net "P1V5_SUS_NODE1")
			(options
				(clearance outline)
				(anchor circle)
			)
			(primitives
				(gr_poly
					(pts
						(xy -1.225042 1.139952) (xy -1.225042 0.724916) (xy -1.605026 0.724916) (xy -1.605026 0.295148)
						(xy -1.225042 0.295148) (xy -1.225042 -0.839978) (xy -1.175004 -0.839978) (xy -1.175004 -1.139952)
						(xy -0.774954 -1.139952) (xy -0.774954 -0.839978) (xy -0.525018 -0.839978) (xy -0.525018 -1.139952)
						(xy -0.124968 -1.139952) (xy -0.124968 -0.839978) (xy 0.124968 -0.839978) (xy 0.124968 -1.139952)
						(xy 0.525018 -1.139952) (xy 0.525018 -0.839978) (xy 0.774954 -0.839978) (xy 0.774954 -1.139952)
						(xy 1.175004 -1.139952) (xy 1.175004 -0.839978) (xy 1.225042 -0.839978) (xy 1.225042 0.295148)
						(xy 1.605026 0.295148) (xy 1.605026 0.724916) (xy 1.225042 0.724916) (xy 1.225042 1.139952)
					)
					(width 0)
					(fill yes)
				)
			)
		)
		(zone
			(layer "F.Cu")
			(hatch none 0.5)
			(connect_pads
				(clearance 0)
			)
			(min_thickness 0.25)
			(keepout
				(tracks allowed)
				(vias not_allowed)
				(pads allowed)
				(copperpour not_allowed)
				(footprints allowed)
			)
			(placement
				(enabled no)
				(sheetname "")
			)
			(fill
				(thermal_gap 0.5)
				(thermal_bridge_width 0.5)
				(island_removal_mode 0)
			)
			(polygon
				(pts
					(xy 35.76447 -112.654334) (xy 35.76447 -115.651534) (xy 36.14547 -115.651534) (xy 36.14547 -112.654334)
				)
			)
		)
		(zone
			(layer "F.Cu")
			(hatch none 0.5)
			(connect_pads
				(clearance 0)
			)
			(min_thickness 0.25)
			(keepout
				(tracks not_allowed)
				(vias allowed)
				(pads allowed)
				(copperpour not_allowed)
				(footprints allowed)
			)
			(placement
				(enabled no)
				(sheetname "")
			)
			(fill
				(thermal_gap 0.5)
				(thermal_bridge_width 0.5)
				(island_removal_mode 0)
			)
			(polygon
				(pts
					(xy 36.14547 -112.654334) (xy 36.14547 -115.651534) (xy 35.76447 -115.651534) (xy 35.76447 -112.654334)
				)
			)
		)
	)
	(footprint ""
		(layer "F.Cu")
		(at 59.67476 -185.205624 90)
		(property "Reference" "C706"
			(at 4.006088 -0.367538 90)
			(unlocked yes)
			(layer "F.SilkS")
			(effects
				(font
					(size 0.7874 0.5842)
					(thickness 0.1524)
				)
				(justify left)
			)
		)
		(property "Value" ""
			(at 0 0 90)
			(layer "F.Fab")
			(effects
				(font
					(size 1.27 1.27)
				)
			)
		)
		(duplicate_pad_numbers_are_jumpers no)
		(fp_line
			(start 0.7874 -0.4064)
			(end 0.7874 0.4064)
			(stroke
				(width 0.1524)
				(type default)
			)
			(layer "F.SilkS")
		)
		(fp_line
			(start -0.7874 -0.4064)
			(end 0.7874 -0.4064)
			(stroke
				(width 0.1524)
				(type default)
			)
			(layer "F.SilkS")
		)
		(fp_line
			(start 0 0.381)
			(end 0 -0.381)
			(stroke
				(width 0.1524)
				(type default)
			)
			(layer "F.SilkS")
		)
		(fp_line
			(start 0.7874 0.4064)
			(end -0.7874 0.4064)
			(stroke
				(width 0.1524)
				(type default)
			)
			(layer "F.SilkS")
		)
		(fp_line
			(start -0.7874 0.4064)
			(end -0.7874 -0.4064)
			(stroke
				(width 0.1524)
				(type default)
			)
			(layer "F.SilkS")
		)
		(fp_poly
			(pts
				(xy -0.5334 0.254) (xy -0.635 0.254) (xy -0.635 0.2286) (xy -0.635 -0.254) (xy -0.5334 -0.254) (xy -0.5334 -0.2794)
				(xy 0.5334 -0.2794) (xy 0.5334 -0.254) (xy 0.635 -0.254) (xy 0.635 0.254) (xy 0.5334 0.254) (xy 0.5334 0.2794)
				(xy -0.508 0.2794) (xy -0.5334 0.2794)
			)
			(stroke
				(width 0)
				(type default)
			)
			(fill no)
			(layer "F.CrtYd")
		)
		(pad "1" smd rect
			(at 0.40005 0 90)
			(size 0.4572 0.508)
			(layers "F.Cu" "F.Mask" "F.Paste")
			(net "UART_T2_NODE3_RXD")
		)
		(pad "2" smd rect
			(at -0.40005 0 90)
			(size 0.4572 0.508)
			(layers "F.Cu" "F.Mask" "F.Paste")
			(net "GND")
		)
	)
	(footprint ""
		(layer "F.Cu")
		(at 15.248128 -58.485532 90)
		(property "Reference" "C507"
			(at -3.044952 -1.283462 90)
			(unlocked yes)
			(layer "F.SilkS")
			(effects
				(font
					(size 0.7874 0.5842)
					(thickness 0.1524)
				)
				(justify left)
			)
		)
		(property "Value" ""
			(at 0 0 90)
			(layer "F.Fab")
			(effects
				(font
					(size 1.27 1.27)
				)
			)
		)
		(duplicate_pad_numbers_are_jumpers no)
		(fp_line
			(start 0.7874 -0.4064)
			(end 0.7874 0.4064)
			(stroke
				(width 0.1524)
				(type default)
			)
			(layer "F.SilkS")
		)
		(fp_line
			(start -0.7874 -0.4064)
			(end 0.7874 -0.4064)
			(stroke
				(width 0.1524)
				(type default)
			)
			(layer "F.SilkS")
		)
		(fp_line
			(start 0 0.381)
			(end 0 -0.381)
			(stroke
				(width 0.1524)
				(type default)
			)
			(layer "F.SilkS")
		)
		(fp_line
			(start 0.7874 0.4064)
			(end -0.7874 0.4064)
			(stroke
				(width 0.1524)
				(type default)
			)
			(layer "F.SilkS")
		)
		(fp_line
			(start -0.7874 0.4064)
			(end -0.7874 -0.4064)
			(stroke
				(width 0.1524)
				(type default)
			)
			(layer "F.SilkS")
		)
		(fp_poly
			(pts
				(xy -0.5334 0.254) (xy -0.635 0.254) (xy -0.635 0.2286) (xy -0.635 -0.254) (xy -0.5334 -0.254) (xy -0.5334 -0.2794)
				(xy 0.5334 -0.2794) (xy 0.5334 -0.254) (xy 0.635 -0.254) (xy 0.635 0.254) (xy 0.5334 0.254) (xy 0.5334 0.2794)
				(xy -0.508 0.2794) (xy -0.5334 0.2794)
			)
			(stroke
				(width 0)
				(type default)
			)
			(fill no)
			(layer "F.CrtYd")
		)
		(pad "1" smd rect
			(at 0.40005 0 90)
			(size 0.4572 0.508)
			(layers "F.Cu" "F.Mask" "F.Paste")
			(net "CRT_VSYNC")
		)
		(pad "2" smd rect
			(at -0.40005 0 90)
			(size 0.4572 0.508)
			(layers "F.Cu" "F.Mask" "F.Paste")
			(net "GND")
		)
	)
	(footprint ""
		(layer "F.Cu")
		(at 110.60176 -188.126624 90)
		(property "Reference" "C650"
			(at 5.151882 0.791972 90)
			(unlocked yes)
			(layer "F.SilkS")
			(effects
				(font
					(size 0.7874 0.5842)
					(thickness 0.1524)
				)
				(justify left)
			)
		)
		(property "Value" ""
			(at 0 0 90)
			(layer "F.Fab")
			(effects
				(font
					(size 1.27 1.27)
				)
			)
		)
		(duplicate_pad_numbers_are_jumpers no)
		(fp_line
			(start 0.7874 -0.4064)
			(end 0.7874 0.4064)
			(stroke
				(width 0.1524)
				(type default)
			)
			(layer "F.SilkS")
		)
		(fp_line
			(start -0.7874 -0.4064)
			(end 0.7874 -0.4064)
			(stroke
				(width 0.1524)
				(type default)
			)
			(layer "F.SilkS")
		)
		(fp_line
			(start 0 0.381)
			(end 0 -0.381)
			(stroke
				(width 0.1524)
				(type default)
			)
			(layer "F.SilkS")
		)
		(fp_line
			(start 0.7874 0.4064)
			(end -0.7874 0.4064)
			(stroke
				(width 0.1524)
				(type default)
			)
			(layer "F.SilkS")
		)
		(fp_line
			(start -0.7874 0.4064)
			(end -0.7874 -0.4064)
			(stroke
				(width 0.1524)
				(type default)
			)
			(layer "F.SilkS")
		)
		(fp_poly
			(pts
				(xy -0.5334 0.254) (xy -0.635 0.254) (xy -0.635 0.2286) (xy -0.635 -0.254) (xy -0.5334 -0.254) (xy -0.5334 -0.2794)
				(xy 0.5334 -0.2794) (xy 0.5334 -0.254) (xy 0.635 -0.254) (xy 0.635 0.254) (xy 0.5334 0.254) (xy 0.5334 0.2794)
				(xy -0.508 0.2794) (xy -0.5334 0.2794)
			)
			(stroke
				(width 0)
				(type default)
			)
			(fill no)
			(layer "F.CrtYd")
		)
		(pad "1" smd rect
			(at 0.40005 0 90)
			(size 0.4572 0.508)
			(layers "F.Cu" "F.Mask" "F.Paste")
			(net "T6_NODE2_EN_R")
		)
		(pad "2" smd rect
			(at -0.40005 0 90)
			(size 0.4572 0.508)
			(layers "F.Cu" "F.Mask" "F.Paste")
			(net "GND")
		)
	)
	(footprint ""
		(layer "F.Cu")
		(at 24.375872 -94.661228 90)
		(property "Reference" "R1151"
			(at -1.1557 2.558542 90)
			(unlocked yes)
			(layer "F.SilkS")
			(effects
				(font
					(size 0.7874 0.5842)
					(thickness 0.1524)
				)
				(justify left)
			)
		)
		(property "Value" ""
			(at 0 0 90)
			(layer "F.Fab")
			(effects
				(font
					(size 1.27 1.27)
				)
			)
		)
		(duplicate_pad_numbers_are_jumpers no)
		(fp_line
			(start 0.7874 -0.4064)
			(end 0.7874 0.4064)
			(stroke
				(width 0.1524)
				(type default)
			)
			(layer "F.SilkS")
		)
		(fp_line
			(start -0.7874 -0.4064)
			(end 0.7874 -0.4064)
			(stroke
				(width 0.1524)
				(type default)
			)
			(layer "F.SilkS")
		)
		(fp_line
			(start 0.7874 0.4064)
			(end -0.7874 0.4064)
			(stroke
				(width 0.1524)
				(type default)
			)
			(layer "F.SilkS")
		)
		(fp_line
			(start -0.7874 0.4064)
			(end -0.7874 -0.4064)
			(stroke
				(width 0.1524)
				(type default)
			)
			(layer "F.SilkS")
		)
		(fp_poly
			(pts
				(xy -0.508 0.2794) (xy -0.508 0.2286) (xy -0.635 0.2286) (xy -0.635 -0.254) (xy -0.5334 -0.254)
				(xy -0.5334 -0.2794) (xy 0.5334 -0.2794) (xy 0.5334 -0.254) (xy 0.635 -0.254) (xy 0.635 0.254) (xy 0.5334 0.254)
				(xy 0.5334 0.2794)
			)
			(stroke
				(width 0)
				(type default)
			)
			(fill no)
			(layer "F.CrtYd")
		)
		(pad "1" smd rect
			(at 0.40005 0 90)
			(size 0.4572 0.508)
			(layers "F.Cu" "F.Mask" "F.Paste")
			(net "N43448372")
		)
		(pad "2" smd rect
			(at -0.40005 0 90)
			(size 0.4572 0.508)
			(layers "F.Cu" "F.Mask" "F.Paste")
			(net "GND")
		)
	)
	(footprint ""
		(layer "F.Cu")
		(at 20.413726 -64.072516 -90)
		(property "Reference" "R633"
			(at 0.250698 -2.623058 90)
			(unlocked yes)
			(layer "F.SilkS")
			(effects
				(font
					(size 0.7874 0.5842)
					(thickness 0.1524)
				)
				(justify left)
			)
		)
		(property "Value" ""
			(at 0 0 270)
			(layer "F.Fab")
			(effects
				(font
					(size 1.27 1.27)
				)
			)
		)
		(duplicate_pad_numbers_are_jumpers no)
		(fp_line
			(start -0.7874 0.4064)
			(end -0.7874 -0.4064)
			(stroke
				(width 0.1524)
				(type default)
			)
			(layer "F.SilkS")
		)
		(fp_line
			(start 0.7874 0.4064)
			(end -0.7874 0.4064)
			(stroke
				(width 0.1524)
				(type default)
			)
			(layer "F.SilkS")
		)
		(fp_line
			(start -0.7874 -0.4064)
			(end 0.7874 -0.4064)
			(stroke
				(width 0.1524)
				(type default)
			)
			(layer "F.SilkS")
		)
		(fp_line
			(start 0.7874 -0.4064)
			(end 0.7874 0.4064)
			(stroke
				(width 0.1524)
				(type default)
			)
			(layer "F.SilkS")
		)
		(fp_poly
			(pts
				(xy -0.508 0.2794) (xy -0.508 0.2286) (xy -0.635 0.2286) (xy -0.635 -0.254) (xy -0.5334 -0.254)
				(xy -0.5334 -0.2794) (xy 0.5334 -0.2794) (xy 0.5334 -0.254) (xy 0.635 -0.254) (xy 0.635 0.254) (xy 0.5334 0.254)
				(xy 0.5334 0.2794)
			)
			(stroke
				(width 0)
				(type default)
			)
			(fill no)
			(layer "F.CrtYd")
		)
		(pad "1" smd rect
			(at 0.40005 0 270)
			(size 0.4572 0.508)
			(layers "F.Cu" "F.Mask" "F.Paste")
			(net "P3V3_NODE1")
		)
		(pad "2" smd rect
			(at -0.40005 0 270)
			(size 0.4572 0.508)
			(layers "F.Cu" "F.Mask" "F.Paste")
			(net "SMB_BMC_NODE1_DDC_CLK")
		)
	)
	(footprint ""
		(layer "F.Cu")
		(at 172.961046 -135.132064)
		(property "Reference" "Q41"
			(at 13.231368 0.52451 0)
			(unlocked yes)
			(layer "F.SilkS")
			(effects
				(font
					(size 0.7874 0.5842)
					(thickness 0.1524)
				)
				(justify left)
			)
		)
		(property "Value" ""
			(at 0 0 0)
			(layer "F.Fab")
			(effects
				(font
					(size 1.27 1.27)
				)
			)
		)
		(duplicate_pad_numbers_are_jumpers no)
		(fp_line
			(start -0.5842 -0.5842)
			(end 2.584196 -0.5842)
			(stroke
				(width 0.1524)
				(type default)
			)
			(layer "F.SilkS")
		)
		(fp_line
			(start -0.5842 2.48412)
			(end -0.5842 -0.5842)
			(stroke
				(width 0.1524)
				(type default)
			)
			(layer "F.SilkS")
		)
		(fp_line
			(start 2.584196 -0.5842)
			(end 2.584196 2.48412)
			(stroke
				(width 0.1524)
				(type default)
			)
			(layer "F.SilkS")
		)
		(fp_line
			(start 2.584196 2.48412)
			(end -0.5842 2.48412)
			(stroke
				(width 0.1524)
				(type default)
			)
			(layer "F.SilkS")
		)
		(fp_poly
			(pts
				(xy -0.508 -0.4572) (xy 0.299974 -0.4572) (xy 0.299974 -0.54991) (xy 1.700022 -0.54991) (xy 1.700022 0.49276)
				(xy 2.507996 0.49276) (xy 2.507996 1.40716) (xy 1.700022 1.40716) (xy 1.700022 2.450084) (xy 0.299974 2.450084)
				(xy 0.299974 2.35712) (xy -0.508 2.35712)
			)
			(stroke
				(width 0)
				(type default)
			)
			(fill no)
			(layer "F.CrtYd")
		)
		(fp_line
			(start 0.299974 -0.54991)
			(end 1.700022 -0.54991)
			(stroke
				(width 0.1)
				(type default)
			)
			(layer "F.Fab")
		)
		(fp_line
			(start 0.299974 2.450084)
			(end 0.299974 -0.54991)
			(stroke
				(width 0.1)
				(type default)
			)
			(layer "F.Fab")
		)
		(fp_line
			(start 1.700022 -0.54991)
			(end 1.700022 2.450084)
			(stroke
				(width 0.1)
				(type default)
			)
			(layer "F.Fab")
		)
		(fp_line
			(start 1.700022 2.450084)
			(end 0.299974 2.450084)
			(stroke
				(width 0.1)
				(type default)
			)
			(layer "F.Fab")
		)
		(fp_text user "B"
			(at -0.333248 -1.066038 0)
			(unlocked yes)
			(layer "F.SilkS")
			(effects
				(font
					(size 0.635 0.4064)
					(thickness 0.1524)
				)
				(justify left)
			)
		)
		(fp_text user "E"
			(at 0.663448 1.959102 0)
			(unlocked yes)
			(layer "F.SilkS")
			(effects
				(font
					(size 0.635 0.4064)
					(thickness 0.1524)
				)
				(justify left)
			)
		)
		(fp_text user "C"
			(at 2.774442 0.893318 0)
			(unlocked yes)
			(layer "F.SilkS")
			(effects
				(font
					(size 0.635 0.4064)
					(thickness 0.1524)
				)
				(justify left)
			)
		)
		(fp_text user "E"
			(at -1.5748 1.95707 0)
			(unlocked yes)
			(layer "F.Fab")
			(effects
				(font
					(size 0.7874 0.5842)
					(thickness 0.000001)
				)
				(justify left)
			)
		)
		(fp_text user "B"
			(at -1.5494 0.00127 0)
			(unlocked yes)
			(layer "F.Fab")
			(effects
				(font
					(size 0.7874 0.5842)
					(thickness 0.000001)
				)
				(justify left)
			)
		)
		(fp_text user "C"
			(at 2.8702 0.99187 0)
			(unlocked yes)
			(layer "F.Fab")
			(effects
				(font
					(size 0.7874 0.5842)
					(thickness 0.000001)
				)
				(justify left)
			)
		)
		(pad "B" smd rect
			(at 0 0 90)
			(size 0.8128 0.9144)
			(layers "F.Cu" "F.Mask" "F.Paste")
			(net "N41777080")
		)
		(pad "C" smd rect
			(at 1.999996 0.94996 90)
			(size 0.8128 0.9144)
			(layers "F.Cu" "F.Mask" "F.Paste")
			(net "CPLD_CPU_THRMTRIP_N")
		)
		(pad "E" smd rect
			(at 0 1.89992 90)
			(size 0.8128 0.9144)
			(layers "F.Cu" "F.Mask" "F.Paste")
			(net "N41777073")
		)
	)
	(footprint ""
		(layer "F.Cu")
		(at 99.182428 -162.227768 90)
		(property "Reference" "R1127"
			(at -73.405492 87.879682 90)
			(unlocked yes)
			(layer "F.SilkS")
			(effects
				(font
					(size 0.7874 0.5842)
					(thickness 0.1524)
				)
				(justify left)
			)
		)
		(property "Value" ""
			(at 0 0 90)
			(layer "F.Fab")
			(effects
				(font
					(size 1.27 1.27)
				)
			)
		)
		(duplicate_pad_numbers_are_jumpers no)
		(fp_line
			(start 0.7874 -0.4064)
			(end 0.7874 0.4064)
			(stroke
				(width 0.1524)
				(type default)
			)
			(layer "F.SilkS")
		)
		(fp_line
			(start -0.7874 -0.4064)
			(end 0.7874 -0.4064)
			(stroke
				(width 0.1524)
				(type default)
			)
			(layer "F.SilkS")
		)
		(fp_line
			(start 0.7874 0.4064)
			(end -0.7874 0.4064)
			(stroke
				(width 0.1524)
				(type default)
			)
			(layer "F.SilkS")
		)
		(fp_line
			(start -0.7874 0.4064)
			(end -0.7874 -0.4064)
			(stroke
				(width 0.1524)
				(type default)
			)
			(layer "F.SilkS")
		)
		(fp_poly
			(pts
				(xy -0.508 0.2794) (xy -0.508 0.2286) (xy -0.635 0.2286) (xy -0.635 -0.254) (xy -0.5334 -0.254)
				(xy -0.5334 -0.2794) (xy 0.5334 -0.2794) (xy 0.5334 -0.254) (xy 0.635 -0.254) (xy 0.635 0.254) (xy 0.5334 0.254)
				(xy 0.5334 0.2794)
			)
			(stroke
				(width 0)
				(type default)
			)
			(fill no)
			(layer "F.CrtYd")
		)
		(pad "1" smd rect
			(at 0.40005 0 90)
			(size 0.4572 0.508)
			(layers "F.Cu" "F.Mask" "F.Paste")
			(net "N52411069")
		)
		(pad "2" smd rect
			(at -0.40005 0 90)
			(size 0.4572 0.508)
			(layers "F.Cu" "F.Mask" "F.Paste")
			(net "N52411040")
		)
	)
	(footprint ""
		(layer "F.Cu")
		(at 123.70816 -172.625512)
		(property "Reference" "C566"
			(at 30.127448 47.916338 0)
			(unlocked yes)
			(layer "F.SilkS")
			(effects
				(font
					(size 0.7874 0.5842)
					(thickness 0.1524)
				)
				(justify left)
			)
		)
		(property "Value" ""
			(at 0 0 0)
			(layer "F.Fab")
			(effects
				(font
					(size 1.27 1.27)
				)
			)
		)
		(duplicate_pad_numbers_are_jumpers no)
		(fp_line
			(start -0.7874 -0.4064)
			(end 0.7874 -0.4064)
			(stroke
				(width 0.1524)
				(type default)
			)
			(layer "F.SilkS")
		)
		(fp_line
			(start -0.7874 0.4064)
			(end -0.7874 -0.4064)
			(stroke
				(width 0.1524)
				(type default)
			)
			(layer "F.SilkS")
		)
		(fp_line
			(start 0 0.381)
			(end 0 -0.381)
			(stroke
				(width 0.1524)
				(type default)
			)
			(layer "F.SilkS")
		)
		(fp_line
			(start 0.7874 -0.4064)
			(end 0.7874 0.4064)
			(stroke
				(width 0.1524)
				(type default)
			)
			(layer "F.SilkS")
		)
		(fp_line
			(start 0.7874 0.4064)
			(end -0.7874 0.4064)
			(stroke
				(width 0.1524)
				(type default)
			)
			(layer "F.SilkS")
		)
		(fp_poly
			(pts
				(xy -0.5334 0.254) (xy -0.635 0.254) (xy -0.635 0.2286) (xy -0.635 -0.254) (xy -0.5334 -0.254) (xy -0.5334 -0.2794)
				(xy 0.5334 -0.2794) (xy 0.5334 -0.254) (xy 0.635 -0.254) (xy 0.635 0.254) (xy 0.5334 0.254) (xy 0.5334 0.2794)
				(xy -0.508 0.2794) (xy -0.5334 0.2794)
			)
			(stroke
				(width 0)
				(type default)
			)
			(fill no)
			(layer "F.CrtYd")
		)
		(pad "1" smd rect
			(at 0.40005 0)
			(size 0.4572 0.508)
			(layers "F.Cu" "F.Mask" "F.Paste")
			(net "GND")
		)
		(pad "2" smd rect
			(at -0.40005 0)
			(size 0.4572 0.508)
			(layers "F.Cu" "F.Mask" "F.Paste")
			(net "P3V3_NODE1")
		)
	)
	(footprint ""
		(layer "F.Cu")
		(at 79.984346 -77.187552)
		(property "Reference" "R74"
			(at -0.33655 16.248888 0)
			(unlocked yes)
			(layer "F.SilkS")
			(effects
				(font
					(size 0.7874 0.5842)
					(thickness 0.1524)
				)
				(justify left)
			)
		)
		(property "Value" ""
			(at 0 0 0)
			(layer "F.Fab")
			(effects
				(font
					(size 1.27 1.27)
				)
			)
		)
		(duplicate_pad_numbers_are_jumpers no)
		(fp_line
			(start -0.7874 -0.4064)
			(end 0.7874 -0.4064)
			(stroke
				(width 0.1524)
				(type default)
			)
			(layer "F.SilkS")
		)
		(fp_line
			(start -0.7874 0.4064)
			(end -0.7874 -0.4064)
			(stroke
				(width 0.1524)
				(type default)
			)
			(layer "F.SilkS")
		)
		(fp_line
			(start 0.7874 -0.4064)
			(end 0.7874 0.4064)
			(stroke
				(width 0.1524)
				(type default)
			)
			(layer "F.SilkS")
		)
		(fp_line
			(start 0.7874 0.4064)
			(end -0.7874 0.4064)
			(stroke
				(width 0.1524)
				(type default)
			)
			(layer "F.SilkS")
		)
		(fp_poly
			(pts
				(xy -0.508 0.2794) (xy -0.508 0.2286) (xy -0.635 0.2286) (xy -0.635 -0.254) (xy -0.5334 -0.254)
				(xy -0.5334 -0.2794) (xy 0.5334 -0.2794) (xy 0.5334 -0.254) (xy 0.635 -0.254) (xy 0.635 0.254) (xy 0.5334 0.254)
				(xy 0.5334 0.2794)
			)
			(stroke
				(width 0)
				(type default)
			)
			(fill no)
			(layer "F.CrtYd")
		)
		(pad "1" smd rect
			(at 0.40005 0)
			(size 0.4572 0.508)
			(layers "F.Cu" "F.Mask" "F.Paste")
			(net "P1V05_NODE1")
		)
		(pad "2" smd rect
			(at -0.40005 0)
			(size 0.4572 0.508)
			(layers "F.Cu" "F.Mask" "F.Paste")
			(net "XDP_SOC_CPU_NODE1_TMS")
		)
	)
	(footprint ""
		(layer "F.Cu")
		(at 108.31576 -188.126624 90)
		(property "Reference" "C656"
			(at 5.151882 0.791972 90)
			(unlocked yes)
			(layer "F.SilkS")
			(effects
				(font
					(size 0.7874 0.5842)
					(thickness 0.1524)
				)
				(justify left)
			)
		)
		(property "Value" ""
			(at 0 0 90)
			(layer "F.Fab")
			(effects
				(font
					(size 1.27 1.27)
				)
			)
		)
		(duplicate_pad_numbers_are_jumpers no)
		(fp_line
			(start 0.7874 -0.4064)
			(end 0.7874 0.4064)
			(stroke
				(width 0.1524)
				(type default)
			)
			(layer "F.SilkS")
		)
		(fp_line
			(start -0.7874 -0.4064)
			(end 0.7874 -0.4064)
			(stroke
				(width 0.1524)
				(type default)
			)
			(layer "F.SilkS")
		)
		(fp_line
			(start 0 0.381)
			(end 0 -0.381)
			(stroke
				(width 0.1524)
				(type default)
			)
			(layer "F.SilkS")
		)
		(fp_line
			(start 0.7874 0.4064)
			(end -0.7874 0.4064)
			(stroke
				(width 0.1524)
				(type default)
			)
			(layer "F.SilkS")
		)
		(fp_line
			(start -0.7874 0.4064)
			(end -0.7874 -0.4064)
			(stroke
				(width 0.1524)
				(type default)
			)
			(layer "F.SilkS")
		)
		(fp_poly
			(pts
				(xy -0.5334 0.254) (xy -0.635 0.254) (xy -0.635 0.2286) (xy -0.635 -0.254) (xy -0.5334 -0.254) (xy -0.5334 -0.2794)
				(xy 0.5334 -0.2794) (xy 0.5334 -0.254) (xy 0.635 -0.254) (xy 0.635 0.254) (xy 0.5334 0.254) (xy 0.5334 0.2794)
				(xy -0.508 0.2794) (xy -0.5334 0.2794)
			)
			(stroke
				(width 0)
				(type default)
			)
			(fill no)
			(layer "F.CrtYd")
		)
		(pad "1" smd rect
			(at 0.40005 0 90)
			(size 0.4572 0.508)
			(layers "F.Cu" "F.Mask" "F.Paste")
			(net "T6_NODE4_EN_R")
		)
		(pad "2" smd rect
			(at -0.40005 0 90)
			(size 0.4572 0.508)
			(layers "F.Cu" "F.Mask" "F.Paste")
			(net "GND")
		)
	)
	(footprint ""
		(layer "F.Cu")
		(at 83.84921 -124.536962 -90)
		(property "Reference" "TP174"
			(at 0 0 270)
			(layer "F.SilkS")
			(hide yes)
			(effects
				(font
					(size 1.27 1.27)
				)
			)
		)
		(property "Value" ""
			(at 0 0 270)
			(layer "F.Fab")
			(effects
				(font
					(size 1.27 1.27)
				)
			)
		)
		(duplicate_pad_numbers_are_jumpers no)
		(fp_poly
			(pts
				(arc
					(start 0 -0.3302)
					(mid 0 0.3302)
					(end 0 -0.3302)
				)
			)
			(stroke
				(width 0)
				(type default)
			)
			(fill no)
			(layer "B.CrtYd")
		)
		(pad "1" thru_hole circle
			(at 0 0 270)
			(size 0.508 0.508)
			(drill 0.254)
			(layers "*.Cu" "*.Mask")
			(remove_unused_layers no)
			(net "N53313325")
			(clearance 0.127)
			(thermal_gap 0.127)
			(padstack
				(mode front_inner_back)
				(layer "Inner"
					(shape circle)
					(size 0.508 0.508)
					(clearance 0.127)
				)
				(layer "B.Cu"
					(shape circle)
					(size 0.6604 0.6604)
					(clearance 0.0508)
				)
			)
		)
	)
	(footprint ""
		(layer "F.Cu")
		(at 13.79093 -127.21336 180)
		(property "Reference" "PC59"
			(at 3.473958 -0.133604 0)
			(unlocked yes)
			(layer "F.SilkS")
			(effects
				(font
					(size 0.7874 0.5842)
					(thickness 0.1524)
				)
			)
		)
		(property "Value" ""
			(at 0 0 180)
			(layer "F.Fab")
			(effects
				(font
					(size 1.27 1.27)
				)
			)
		)
		(duplicate_pad_numbers_are_jumpers no)
		(fp_line
			(start 1.2954 0.5842)
			(end -1.2954 0.5842)
			(stroke
				(width 0.1524)
				(type default)
			)
			(layer "F.SilkS")
		)
		(fp_line
			(start 1.2954 -0.5842)
			(end 1.2954 0.5842)
			(stroke
				(width 0.1524)
				(type default)
			)
			(layer "F.SilkS")
		)
		(fp_line
			(start 0 -0.5842)
			(end 0 0.5842)
			(stroke
				(width 0.1524)
				(type default)
			)
			(layer "F.SilkS")
		)
		(fp_line
			(start -1.2954 0.5842)
			(end -1.2954 -0.5842)
			(stroke
				(width 0.1524)
				(type default)
			)
			(layer "F.SilkS")
		)
		(fp_line
			(start -1.2954 -0.5842)
			(end 1.2954 -0.5842)
			(stroke
				(width 0.1524)
				(type default)
			)
			(layer "F.SilkS")
		)
		(fp_poly
			(pts
				(xy 0.8636 -0.4572) (xy 0.8636 -0.3556) (xy 1.143 -0.3556) (xy 1.143 0.3556) (xy 0.8636 0.3556)
				(xy 0.8636 0.4572) (xy -0.8636 0.4572) (xy -0.8636 0.3556) (xy -1.143 0.3556) (xy -1.143 -0.3556)
				(xy -0.8636 -0.3556) (xy -0.8636 -0.4572)
			)
			(stroke
				(width 0)
				(type default)
			)
			(fill no)
			(layer "F.CrtYd")
		)
		(fp_line
			(start 0.884936 0.504952)
			(end -0.884936 0.504952)
			(stroke
				(width 0.1)
				(type default)
			)
			(layer "F.Fab")
		)
		(fp_line
			(start 0.884936 -0.504952)
			(end 0.884936 0.504952)
			(stroke
				(width 0.1)
				(type default)
			)
			(layer "F.Fab")
		)
		(fp_line
			(start -0.884936 0.504952)
			(end -0.884936 -0.504952)
			(stroke
				(width 0.1)
				(type default)
			)
			(layer "F.Fab")
		)
		(fp_line
			(start -0.884936 -0.504952)
			(end 0.884936 -0.504952)
			(stroke
				(width 0.1)
				(type default)
			)
			(layer "F.Fab")
		)
		(pad "1" smd rect
			(at 0.7366 0 270)
			(size 0.7112 0.8128)
			(layers "F.Cu" "F.Mask" "F.Paste")
			(net "GND")
		)
		(pad "2" smd rect
			(at -0.7366 0 270)
			(size 0.7112 0.8128)
			(layers "F.Cu" "F.Mask" "F.Paste")
			(net "P5V_STB_NODE1")
		)
	)
	(footprint ""
		(layer "F.Cu")
		(at 163.990782 -72.313546 90)
		(property "Reference" "PJ3"
			(at 0.243586 3.007868 0)
			(unlocked yes)
			(layer "F.SilkS")
			(effects
				(font
					(size 0.7874 0.5842)
					(thickness 0.1524)
				)
				(justify left)
			)
		)
		(property "Value" ""
			(at 0 0 90)
			(layer "F.Fab")
			(effects
				(font
					(size 1.27 1.27)
				)
			)
		)
		(duplicate_pad_numbers_are_jumpers no)
		(fp_poly
			(pts
				(xy 0.2794 0.907796) (xy 0.254 0.907796) (xy 0.254 1.0414) (xy -0.254 1.0414) (xy -0.254 1.034796)
				(xy -0.254 0.933196) (xy -0.2794 0.933196) (xy -0.2794 -0.133604) (xy -0.254 -0.133604) (xy -0.254 -0.235204)
				(xy 0.254 -0.235204) (xy 0.254 -0.133604) (xy 0.2794 -0.133604)
			)
			(stroke
				(width 0)
				(type default)
			)
			(fill no)
			(layer "F.CrtYd")
		)
		(pad "1" smd custom
			(at 0 -0.000254 90)
			(size 0.127 0.127)
			(layers "F.Cu" "F.Mask" "F.Paste")
			(net "FM_CPLD_NODE1_P1V0_EN")
			(options
				(clearance outline)
				(anchor circle)
			)
			(primitives
				(gr_poly
					(pts
						(xy -0.127 0.508) (xy -0.127 -0.0508) (xy -0.254 -0.0508) (xy -0.254 -0.508) (xy 0.254 -0.508)
						(xy 0.254 -0.0508) (xy 0.127 -0.0508) (xy 0.127 0.508)
					)
					(width 0)
					(fill yes)
				)
			)
		)
		(pad "2" smd rect
			(at 0 0.799846 180)
			(size 0.4572 0.508)
			(layers "F.Cu" "F.Mask" "F.Paste")
			(net "N47241340")
		)
		(zone
			(layer "F.Cu")
			(hatch none 0.5)
			(connect_pads
				(clearance 0)
			)
			(min_thickness 0.25)
			(keepout
				(tracks allowed)
				(vias not_allowed)
				(pads allowed)
				(copperpour not_allowed)
				(footprints allowed)
			)
			(placement
				(enabled no)
				(sheetname "")
			)
			(fill
				(thermal_gap 0.5)
				(thermal_bridge_width 0.5)
				(island_removal_mode 0)
			)
			(polygon
				(pts
					(xy 165.076378 -72.008746) (xy 165.076378 -72.618346) (xy 163.704778 -72.618346) (xy 163.704778 -72.008746)
				)
			)
		)
	)
	(footprint ""
		(layer "F.Cu")
		(at 126.552452 -153.67635 90)
		(property "Reference" "R283"
			(at -111.020352 -58.8264 90)
			(unlocked yes)
			(layer "F.SilkS")
			(effects
				(font
					(size 0.7874 0.5842)
					(thickness 0.1524)
				)
				(justify left)
			)
		)
		(property "Value" ""
			(at 0 0 90)
			(layer "F.Fab")
			(effects
				(font
					(size 1.27 1.27)
				)
			)
		)
		(duplicate_pad_numbers_are_jumpers no)
		(fp_line
			(start 0.7874 -0.4064)
			(end 0.7874 0.4064)
			(stroke
				(width 0.1524)
				(type default)
			)
			(layer "F.SilkS")
		)
		(fp_line
			(start -0.7874 -0.4064)
			(end 0.7874 -0.4064)
			(stroke
				(width 0.1524)
				(type default)
			)
			(layer "F.SilkS")
		)
		(fp_line
			(start 0.7874 0.4064)
			(end -0.7874 0.4064)
			(stroke
				(width 0.1524)
				(type default)
			)
			(layer "F.SilkS")
		)
		(fp_line
			(start -0.7874 0.4064)
			(end -0.7874 -0.4064)
			(stroke
				(width 0.1524)
				(type default)
			)
			(layer "F.SilkS")
		)
		(fp_poly
			(pts
				(xy -0.508 0.2794) (xy -0.508 0.2286) (xy -0.635 0.2286) (xy -0.635 -0.254) (xy -0.5334 -0.254)
				(xy -0.5334 -0.2794) (xy 0.5334 -0.2794) (xy 0.5334 -0.254) (xy 0.635 -0.254) (xy 0.635 0.254) (xy 0.5334 0.254)
				(xy 0.5334 0.2794)
			)
			(stroke
				(width 0)
				(type default)
			)
			(fill no)
			(layer "F.CrtYd")
		)
		(pad "1" smd rect
			(at 0.40005 0 90)
			(size 0.4572 0.508)
			(layers "F.Cu" "F.Mask" "F.Paste")
			(net "P3V3_NODE1")
		)
		(pad "2" smd rect
			(at -0.40005 0 90)
			(size 0.4572 0.508)
			(layers "F.Cu" "F.Mask" "F.Paste")
			(net "PCIE_SW_TEST2")
		)
	)
	(footprint ""
		(layer "F.Cu")
		(at 168.87698 -171.55287 90)
		(property "Reference" "C564"
			(at -0.401828 0.795274 0)
			(unlocked yes)
			(layer "F.SilkS")
			(effects
				(font
					(size 0.7874 0.5842)
					(thickness 0.1524)
				)
				(justify left)
			)
		)
		(property "Value" ""
			(at 0 0 90)
			(layer "F.Fab")
			(effects
				(font
					(size 1.27 1.27)
				)
			)
		)
		(duplicate_pad_numbers_are_jumpers no)
		(fp_line
			(start 0.7874 -0.4064)
			(end 0.7874 0.4064)
			(stroke
				(width 0.1524)
				(type default)
			)
			(layer "F.SilkS")
		)
		(fp_line
			(start -0.7874 -0.4064)
			(end 0.7874 -0.4064)
			(stroke
				(width 0.1524)
				(type default)
			)
			(layer "F.SilkS")
		)
		(fp_line
			(start 0 0.381)
			(end 0 -0.381)
			(stroke
				(width 0.1524)
				(type default)
			)
			(layer "F.SilkS")
		)
		(fp_line
			(start 0.7874 0.4064)
			(end -0.7874 0.4064)
			(stroke
				(width 0.1524)
				(type default)
			)
			(layer "F.SilkS")
		)
		(fp_line
			(start -0.7874 0.4064)
			(end -0.7874 -0.4064)
			(stroke
				(width 0.1524)
				(type default)
			)
			(layer "F.SilkS")
		)
		(fp_poly
			(pts
				(xy -0.5334 0.254) (xy -0.635 0.254) (xy -0.635 0.2286) (xy -0.635 -0.254) (xy -0.5334 -0.254) (xy -0.5334 -0.2794)
				(xy 0.5334 -0.2794) (xy 0.5334 -0.254) (xy 0.635 -0.254) (xy 0.635 0.254) (xy 0.5334 0.254) (xy 0.5334 0.2794)
				(xy -0.508 0.2794) (xy -0.5334 0.2794)
			)
			(stroke
				(width 0)
				(type default)
			)
			(fill no)
			(layer "F.CrtYd")
		)
		(pad "1" smd rect
			(at 0.40005 0 90)
			(size 0.4572 0.508)
			(layers "F.Cu" "F.Mask" "F.Paste")
			(net "GND")
		)
		(pad "2" smd rect
			(at -0.40005 0 90)
			(size 0.4572 0.508)
			(layers "F.Cu" "F.Mask" "F.Paste")
			(net "N54365625")
		)
	)
	(footprint ""
		(layer "F.Cu")
		(at 91.102434 -183.778398 180)
		(property "Reference" "C693"
			(at 1.458214 7.22757 0)
			(unlocked yes)
			(layer "F.SilkS")
			(effects
				(font
					(size 0.7874 0.5842)
					(thickness 0.1524)
				)
				(justify left)
			)
		)
		(property "Value" ""
			(at 0 0 180)
			(layer "F.Fab")
			(effects
				(font
					(size 1.27 1.27)
				)
			)
		)
		(duplicate_pad_numbers_are_jumpers no)
		(fp_line
			(start 0.7874 0.4064)
			(end -0.7874 0.4064)
			(stroke
				(width 0.1524)
				(type default)
			)
			(layer "F.SilkS")
		)
		(fp_line
			(start 0.7874 -0.4064)
			(end 0.7874 0.4064)
			(stroke
				(width 0.1524)
				(type default)
			)
			(layer "F.SilkS")
		)
		(fp_line
			(start 0 0.381)
			(end 0 -0.381)
			(stroke
				(width 0.1524)
				(type default)
			)
			(layer "F.SilkS")
		)
		(fp_line
			(start -0.7874 0.4064)
			(end -0.7874 -0.4064)
			(stroke
				(width 0.1524)
				(type default)
			)
			(layer "F.SilkS")
		)
		(fp_line
			(start -0.7874 -0.4064)
			(end 0.7874 -0.4064)
			(stroke
				(width 0.1524)
				(type default)
			)
			(layer "F.SilkS")
		)
		(fp_poly
			(pts
				(xy -0.5334 0.254) (xy -0.635 0.254) (xy -0.635 0.2286) (xy -0.635 -0.254) (xy -0.5334 -0.254) (xy -0.5334 -0.2794)
				(xy 0.5334 -0.2794) (xy 0.5334 -0.254) (xy 0.635 -0.254) (xy 0.635 0.254) (xy 0.5334 0.254) (xy 0.5334 0.2794)
				(xy -0.508 0.2794) (xy -0.5334 0.2794)
			)
			(stroke
				(width 0)
				(type default)
			)
			(fill no)
			(layer "F.CrtYd")
		)
		(pad "1" smd rect
			(at 0.40005 0 180)
			(size 0.4572 0.508)
			(layers "F.Cu" "F.Mask" "F.Paste")
			(net "UART_T5_NODE4_TXD_R")
		)
		(pad "2" smd rect
			(at -0.40005 0 180)
			(size 0.4572 0.508)
			(layers "F.Cu" "F.Mask" "F.Paste")
			(net "GND")
		)
	)
	(footprint ""
		(layer "F.Cu")
		(at 118.34876 -175.426624 90)
		(property "Reference" "R798"
			(at -57.046622 32.819848 90)
			(unlocked yes)
			(layer "F.SilkS")
			(effects
				(font
					(size 0.7874 0.5842)
					(thickness 0.1524)
				)
				(justify left)
			)
		)
		(property "Value" ""
			(at 0 0 90)
			(layer "F.Fab")
			(effects
				(font
					(size 1.27 1.27)
				)
			)
		)
		(duplicate_pad_numbers_are_jumpers no)
		(fp_line
			(start 0.7874 -0.4064)
			(end 0.7874 0.4064)
			(stroke
				(width 0.1524)
				(type default)
			)
			(layer "F.SilkS")
		)
		(fp_line
			(start -0.7874 -0.4064)
			(end 0.7874 -0.4064)
			(stroke
				(width 0.1524)
				(type default)
			)
			(layer "F.SilkS")
		)
		(fp_line
			(start 0.7874 0.4064)
			(end -0.7874 0.4064)
			(stroke
				(width 0.1524)
				(type default)
			)
			(layer "F.SilkS")
		)
		(fp_line
			(start -0.7874 0.4064)
			(end -0.7874 -0.4064)
			(stroke
				(width 0.1524)
				(type default)
			)
			(layer "F.SilkS")
		)
		(fp_poly
			(pts
				(xy -0.508 0.2794) (xy -0.508 0.2286) (xy -0.635 0.2286) (xy -0.635 -0.254) (xy -0.5334 -0.254)
				(xy -0.5334 -0.2794) (xy 0.5334 -0.2794) (xy 0.5334 -0.254) (xy 0.635 -0.254) (xy 0.635 0.254) (xy 0.5334 0.254)
				(xy 0.5334 0.2794)
			)
			(stroke
				(width 0)
				(type default)
			)
			(fill no)
			(layer "F.CrtYd")
		)
		(pad "1" smd rect
			(at 0.40005 0 90)
			(size 0.4572 0.508)
			(layers "F.Cu" "F.Mask" "F.Paste")
			(net "N31328107")
		)
		(pad "2" smd rect
			(at -0.40005 0 90)
			(size 0.4572 0.508)
			(layers "F.Cu" "F.Mask" "F.Paste")
			(net "GND")
		)
	)
	(footprint ""
		(layer "F.Cu")
		(at 152.755854 -138.203432)
		(property "Reference" "R1067"
			(at -5.190236 1.955546 0)
			(unlocked yes)
			(layer "F.SilkS")
			(effects
				(font
					(size 0.7874 0.5842)
					(thickness 0.1524)
				)
				(justify left)
			)
		)
		(property "Value" ""
			(at 0 0 0)
			(layer "F.Fab")
			(effects
				(font
					(size 1.27 1.27)
				)
			)
		)
		(duplicate_pad_numbers_are_jumpers no)
		(fp_line
			(start -0.7874 -0.4064)
			(end 0.7874 -0.4064)
			(stroke
				(width 0.1524)
				(type default)
			)
			(layer "F.SilkS")
		)
		(fp_line
			(start -0.7874 0.4064)
			(end -0.7874 -0.4064)
			(stroke
				(width 0.1524)
				(type default)
			)
			(layer "F.SilkS")
		)
		(fp_line
			(start 0.7874 -0.4064)
			(end 0.7874 0.4064)
			(stroke
				(width 0.1524)
				(type default)
			)
			(layer "F.SilkS")
		)
		(fp_line
			(start 0.7874 0.4064)
			(end -0.7874 0.4064)
			(stroke
				(width 0.1524)
				(type default)
			)
			(layer "F.SilkS")
		)
		(fp_poly
			(pts
				(xy -0.508 0.2794) (xy -0.508 0.2286) (xy -0.635 0.2286) (xy -0.635 -0.254) (xy -0.5334 -0.254)
				(xy -0.5334 -0.2794) (xy 0.5334 -0.2794) (xy 0.5334 -0.254) (xy 0.635 -0.254) (xy 0.635 0.254) (xy 0.5334 0.254)
				(xy 0.5334 0.2794)
			)
			(stroke
				(width 0)
				(type default)
			)
			(fill no)
			(layer "F.CrtYd")
		)
		(pad "1" smd rect
			(at 0.40005 0)
			(size 0.4572 0.508)
			(layers "F.Cu" "F.Mask" "F.Paste")
			(net "RST_BTN_NODE1_C_L")
		)
		(pad "2" smd rect
			(at -0.40005 0)
			(size 0.4572 0.508)
			(layers "F.Cu" "F.Mask" "F.Paste")
			(net "RST_BTN_NODE1_L")
		)
	)
	(footprint ""
		(layer "F.Cu")
		(at 41.896792 -3.661918 90)
		(property "Reference" "PC74"
			(at -3.08229 -13.164566 90)
			(unlocked yes)
			(layer "F.SilkS")
			(effects
				(font
					(size 0.7874 0.5842)
					(thickness 0.1524)
				)
				(justify left)
			)
		)
		(property "Value" ""
			(at 0 0 90)
			(layer "F.Fab")
			(effects
				(font
					(size 1.27 1.27)
				)
			)
		)
		(duplicate_pad_numbers_are_jumpers no)
		(fp_line
			(start 2.2098 -0.9398)
			(end 2.2098 0.9398)
			(stroke
				(width 0.1524)
				(type default)
			)
			(layer "F.SilkS")
		)
		(fp_line
			(start 0 -0.9398)
			(end 0 0.9398)
			(stroke
				(width 0.1524)
				(type default)
			)
			(layer "F.SilkS")
		)
		(fp_line
			(start -2.2098 -0.9398)
			(end 2.2098 -0.9398)
			(stroke
				(width 0.1524)
				(type default)
			)
			(layer "F.SilkS")
		)
		(fp_line
			(start 2.2098 0.9398)
			(end -2.2098 0.9398)
			(stroke
				(width 0.1524)
				(type default)
			)
			(layer "F.SilkS")
		)
		(fp_line
			(start -2.2098 0.9398)
			(end -2.2098 -0.9398)
			(stroke
				(width 0.1524)
				(type default)
			)
			(layer "F.SilkS")
		)
		(fp_poly
			(pts
				(xy -1.6764 0.889) (xy -1.6764 0.7874) (xy -2.0574 0.7874) (xy -2.0574 -0.7874) (xy -1.6764 -0.7874)
				(xy -1.6764 -0.9398) (xy 1.6764 -0.9398) (xy 1.6764 -0.7874) (xy 2.0574 -0.7874) (xy 2.0574 0.7874)
				(xy 1.6764 0.7874) (xy 1.6764 0.9398) (xy -1.6764 0.9398)
			)
			(stroke
				(width 0)
				(type default)
			)
			(fill no)
			(layer "F.CrtYd")
		)
		(fp_line
			(start 1.700022 -0.899922)
			(end 1.700022 0.899922)
			(stroke
				(width 0.1)
				(type default)
			)
			(layer "F.Fab")
		)
		(fp_line
			(start -1.700022 -0.899922)
			(end 1.700022 -0.899922)
			(stroke
				(width 0.1)
				(type default)
			)
			(layer "F.Fab")
		)
		(fp_line
			(start 1.700022 0.899922)
			(end -1.700022 0.899922)
			(stroke
				(width 0.1)
				(type default)
			)
			(layer "F.Fab")
		)
		(fp_line
			(start -1.700022 0.899922)
			(end -1.700022 -0.899922)
			(stroke
				(width 0.1)
				(type default)
			)
			(layer "F.Fab")
		)
		(pad "1" smd rect
			(at 1.4732 0 90)
			(size 1.1684 1.5748)
			(layers "F.Cu" "F.Mask" "F.Paste")
			(net "SW_PV_VDDR_NODE1_VIN_FLT")
		)
		(pad "2" smd rect
			(at -1.4732 0 90)
			(size 1.1684 1.5748)
			(layers "F.Cu" "F.Mask" "F.Paste")
			(net "GND")
		)
	)
	(footprint ""
		(layer "F.Cu")
		(at 175.554894 -130.63982 90)
		(property "Reference" "R1037"
			(at -1.213866 12.029948 90)
			(unlocked yes)
			(layer "F.SilkS")
			(effects
				(font
					(size 0.7874 0.5842)
					(thickness 0.1524)
				)
				(justify left)
			)
		)
		(property "Value" ""
			(at 0 0 90)
			(layer "F.Fab")
			(effects
				(font
					(size 1.27 1.27)
				)
			)
		)
		(duplicate_pad_numbers_are_jumpers no)
		(fp_line
			(start 0.7874 -0.4064)
			(end 0.7874 0.4064)
			(stroke
				(width 0.1524)
				(type default)
			)
			(layer "F.SilkS")
		)
		(fp_line
			(start -0.7874 -0.4064)
			(end 0.7874 -0.4064)
			(stroke
				(width 0.1524)
				(type default)
			)
			(layer "F.SilkS")
		)
		(fp_line
			(start 0.7874 0.4064)
			(end -0.7874 0.4064)
			(stroke
				(width 0.1524)
				(type default)
			)
			(layer "F.SilkS")
		)
		(fp_line
			(start -0.7874 0.4064)
			(end -0.7874 -0.4064)
			(stroke
				(width 0.1524)
				(type default)
			)
			(layer "F.SilkS")
		)
		(fp_poly
			(pts
				(xy -0.508 0.2794) (xy -0.508 0.2286) (xy -0.635 0.2286) (xy -0.635 -0.254) (xy -0.5334 -0.254)
				(xy -0.5334 -0.2794) (xy 0.5334 -0.2794) (xy 0.5334 -0.254) (xy 0.635 -0.254) (xy 0.635 0.254) (xy 0.5334 0.254)
				(xy 0.5334 0.2794)
			)
			(stroke
				(width 0)
				(type default)
			)
			(fill no)
			(layer "F.CrtYd")
		)
		(pad "1" smd rect
			(at 0.40005 0 90)
			(size 0.4572 0.508)
			(layers "F.Cu" "F.Mask" "F.Paste")
			(net "GND")
		)
		(pad "2" smd rect
			(at -0.40005 0 90)
			(size 0.4572 0.508)
			(layers "F.Cu" "F.Mask" "F.Paste")
			(net "FM_CPLD_NODE1_DEBUG_MODE")
		)
	)
	(footprint ""
		(layer "F.Cu")
		(at 60.312554 -164.534596 90)
		(property "Reference" "R1236"
			(at 1.509776 0.12954 90)
			(unlocked yes)
			(layer "F.SilkS")
			(effects
				(font
					(size 0.7874 0.5842)
					(thickness 0.1524)
				)
				(justify left)
			)
		)
		(property "Value" ""
			(at 0 0 90)
			(layer "F.Fab")
			(effects
				(font
					(size 1.27 1.27)
				)
			)
		)
		(duplicate_pad_numbers_are_jumpers no)
		(fp_line
			(start 0.7874 -0.4064)
			(end 0.7874 0.4064)
			(stroke
				(width 0.1524)
				(type default)
			)
			(layer "F.SilkS")
		)
		(fp_line
			(start -0.7874 -0.4064)
			(end 0.7874 -0.4064)
			(stroke
				(width 0.1524)
				(type default)
			)
			(layer "F.SilkS")
		)
		(fp_line
			(start 0.7874 0.4064)
			(end -0.7874 0.4064)
			(stroke
				(width 0.1524)
				(type default)
			)
			(layer "F.SilkS")
		)
		(fp_line
			(start -0.7874 0.4064)
			(end -0.7874 -0.4064)
			(stroke
				(width 0.1524)
				(type default)
			)
			(layer "F.SilkS")
		)
		(fp_poly
			(pts
				(xy -0.508 0.2794) (xy -0.508 0.2286) (xy -0.635 0.2286) (xy -0.635 -0.254) (xy -0.5334 -0.254)
				(xy -0.5334 -0.2794) (xy 0.5334 -0.2794) (xy 0.5334 -0.254) (xy 0.635 -0.254) (xy 0.635 0.254) (xy 0.5334 0.254)
				(xy 0.5334 0.2794)
			)
			(stroke
				(width 0)
				(type default)
			)
			(fill no)
			(layer "F.CrtYd")
		)
		(pad "1" smd rect
			(at 0.40005 0 90)
			(size 0.4572 0.508)
			(layers "F.Cu" "F.Mask" "F.Paste")
			(net "GND")
		)
		(pad "2" smd rect
			(at -0.40005 0 90)
			(size 0.4572 0.508)
			(layers "F.Cu" "F.Mask" "F.Paste")
			(net "FM_CPLD_NODE1_P5V_EN")
		)
	)
	(footprint ""
		(layer "F.Cu")
		(at 66.225166 -96.709992 90)
		(property "Reference" "R65"
			(at -54.98719 28.439364 90)
			(unlocked yes)
			(layer "F.SilkS")
			(effects
				(font
					(size 0.7874 0.5842)
					(thickness 0.1524)
				)
				(justify left)
			)
		)
		(property "Value" ""
			(at 0 0 90)
			(layer "F.Fab")
			(effects
				(font
					(size 1.27 1.27)
				)
			)
		)
		(duplicate_pad_numbers_are_jumpers no)
		(fp_line
			(start 0.7874 -0.4064)
			(end 0.7874 0.4064)
			(stroke
				(width 0.1524)
				(type default)
			)
			(layer "F.SilkS")
		)
		(fp_line
			(start -0.7874 -0.4064)
			(end 0.7874 -0.4064)
			(stroke
				(width 0.1524)
				(type default)
			)
			(layer "F.SilkS")
		)
		(fp_line
			(start 0.7874 0.4064)
			(end -0.7874 0.4064)
			(stroke
				(width 0.1524)
				(type default)
			)
			(layer "F.SilkS")
		)
		(fp_line
			(start -0.7874 0.4064)
			(end -0.7874 -0.4064)
			(stroke
				(width 0.1524)
				(type default)
			)
			(layer "F.SilkS")
		)
		(fp_poly
			(pts
				(xy -0.508 0.2794) (xy -0.508 0.2286) (xy -0.635 0.2286) (xy -0.635 -0.254) (xy -0.5334 -0.254)
				(xy -0.5334 -0.2794) (xy 0.5334 -0.2794) (xy 0.5334 -0.254) (xy 0.635 -0.254) (xy 0.635 0.254) (xy 0.5334 0.254)
				(xy 0.5334 0.2794)
			)
			(stroke
				(width 0)
				(type default)
			)
			(fill no)
			(layer "F.CrtYd")
		)
		(pad "1" smd rect
			(at 0.40005 0 90)
			(size 0.4572 0.508)
			(layers "F.Cu" "F.Mask" "F.Paste")
			(net "LPC_CPU_NODE1_FRAME_L")
		)
		(pad "2" smd rect
			(at -0.40005 0 90)
			(size 0.4572 0.508)
			(layers "F.Cu" "F.Mask" "F.Paste")
			(net "LPC_CPU_NODE1_FRAME_L_R")
		)
	)
	(footprint ""
		(layer "F.Cu")
		(at 128.517904 -161.243772 180)
		(property "Reference" "R648"
			(at 61.71184 -109.770926 0)
			(unlocked yes)
			(layer "F.SilkS")
			(effects
				(font
					(size 0.7874 0.5842)
					(thickness 0.1524)
				)
				(justify left)
			)
		)
		(property "Value" ""
			(at 0 0 180)
			(layer "F.Fab")
			(effects
				(font
					(size 1.27 1.27)
				)
			)
		)
		(duplicate_pad_numbers_are_jumpers no)
		(fp_line
			(start 0.7874 0.4064)
			(end -0.7874 0.4064)
			(stroke
				(width 0.1524)
				(type default)
			)
			(layer "F.SilkS")
		)
		(fp_line
			(start 0.7874 -0.4064)
			(end 0.7874 0.4064)
			(stroke
				(width 0.1524)
				(type default)
			)
			(layer "F.SilkS")
		)
		(fp_line
			(start -0.7874 0.4064)
			(end -0.7874 -0.4064)
			(stroke
				(width 0.1524)
				(type default)
			)
			(layer "F.SilkS")
		)
		(fp_line
			(start -0.7874 -0.4064)
			(end 0.7874 -0.4064)
			(stroke
				(width 0.1524)
				(type default)
			)
			(layer "F.SilkS")
		)
		(fp_poly
			(pts
				(xy -0.508 0.2794) (xy -0.508 0.2286) (xy -0.635 0.2286) (xy -0.635 -0.254) (xy -0.5334 -0.254)
				(xy -0.5334 -0.2794) (xy 0.5334 -0.2794) (xy 0.5334 -0.254) (xy 0.635 -0.254) (xy 0.635 0.254) (xy 0.5334 0.254)
				(xy 0.5334 0.2794)
			)
			(stroke
				(width 0)
				(type default)
			)
			(fill no)
			(layer "F.CrtYd")
		)
		(pad "1" smd rect
			(at 0.40005 0 180)
			(size 0.4572 0.508)
			(layers "F.Cu" "F.Mask" "F.Paste")
			(net "I2C_PSU3_SCL")
		)
		(pad "2" smd rect
			(at -0.40005 0 180)
			(size 0.4572 0.508)
			(layers "F.Cu" "F.Mask" "F.Paste")
			(net "I2C_PSU3_SCL_MOS")
		)
	)
	(footprint ""
		(layer "F.Cu")
		(at 187.644278 -145.587466 -90)
		(property "Reference" "Q16"
			(at -4.113784 0.771906 0)
			(unlocked yes)
			(layer "F.SilkS")
			(effects
				(font
					(size 0.7874 0.5842)
					(thickness 0.1524)
				)
				(justify left)
			)
		)
		(property "Value" ""
			(at 0 0 270)
			(layer "F.Fab")
			(effects
				(font
					(size 1.27 1.27)
				)
			)
		)
		(duplicate_pad_numbers_are_jumpers no)
		(fp_line
			(start -3.3528 1.651)
			(end 3.3528 1.651)
			(stroke
				(width 0.1524)
				(type default)
			)
			(layer "F.SilkS")
		)
		(fp_line
			(start 3.3528 1.651)
			(end 3.3528 -1.651)
			(stroke
				(width 0.1524)
				(type default)
			)
			(layer "F.SilkS")
		)
		(fp_line
			(start -3.3528 -1.651)
			(end -3.3528 1.651)
			(stroke
				(width 0.1524)
				(type default)
			)
			(layer "F.SilkS")
		)
		(fp_line
			(start 3.3528 -1.651)
			(end -3.3528 -1.651)
			(stroke
				(width 0.1524)
				(type default)
			)
			(layer "F.SilkS")
		)
		(fp_poly
			(pts
				(xy -3.048 3.8354) (xy -3.048 1.8796) (xy -3.3528 1.8796) (xy -3.3528 -1.8796) (xy -1.905 -1.8796)
				(xy -1.905 -3.8354) (xy 1.905 -3.8354) (xy 1.905 -1.8796) (xy 3.3528 -1.8796) (xy 3.3528 1.8796)
				(xy 3.048 1.8796) (xy 3.048 3.8354)
			)
			(stroke
				(width 0)
				(type default)
			)
			(fill no)
			(layer "F.CrtYd")
		)
		(pad "1" smd rect
			(at -2.286 2.8321 270)
			(size 1.4986 2.0066)
			(layers "F.Cu" "F.Mask" "F.Paste")
			(net "LAN2_CTRL_P1V9")
		)
		(pad "2" smd rect
			(at 0 2.8321 270)
			(size 1.4986 2.0066)
			(layers "F.Cu" "F.Mask" "F.Paste")
			(net "P1V9_LAN2")
		)
		(pad "3" smd rect
			(at 2.286 2.8321 270)
			(size 1.4986 2.0066)
			(layers "F.Cu" "F.Mask" "F.Paste")
			(net "P3V3_NODE1")
		)
		(pad "4" smd rect
			(at 0 -2.8321)
			(size 2.0066 3.81)
			(layers "F.Cu" "F.Mask" "F.Paste")
			(net "P1V9_LAN2")
		)
	)
	(footprint ""
		(layer "F.Cu")
		(at 64.391794 -14.892782 -90)
		(property "Reference" "PC78"
			(at 0.018034 9.23036 90)
			(unlocked yes)
			(layer "F.SilkS")
			(effects
				(font
					(size 0.7874 0.5842)
					(thickness 0.1524)
				)
				(justify left)
			)
		)
		(property "Value" ""
			(at 0 0 270)
			(layer "F.Fab")
			(effects
				(font
					(size 1.27 1.27)
				)
			)
		)
		(duplicate_pad_numbers_are_jumpers no)
		(fp_line
			(start -0.7874 0.4064)
			(end -0.7874 -0.4064)
			(stroke
				(width 0.1524)
				(type default)
			)
			(layer "F.SilkS")
		)
		(fp_line
			(start 0.7874 0.4064)
			(end -0.7874 0.4064)
			(stroke
				(width 0.1524)
				(type default)
			)
			(layer "F.SilkS")
		)
		(fp_line
			(start 0 0.381)
			(end 0 -0.381)
			(stroke
				(width 0.1524)
				(type default)
			)
			(layer "F.SilkS")
		)
		(fp_line
			(start -0.7874 -0.4064)
			(end 0.7874 -0.4064)
			(stroke
				(width 0.1524)
				(type default)
			)
			(layer "F.SilkS")
		)
		(fp_line
			(start 0.7874 -0.4064)
			(end 0.7874 0.4064)
			(stroke
				(width 0.1524)
				(type default)
			)
			(layer "F.SilkS")
		)
		(fp_poly
			(pts
				(xy -0.5334 0.254) (xy -0.635 0.254) (xy -0.635 0.2286) (xy -0.635 -0.254) (xy -0.5334 -0.254) (xy -0.5334 -0.2794)
				(xy 0.5334 -0.2794) (xy 0.5334 -0.254) (xy 0.635 -0.254) (xy 0.635 0.254) (xy 0.5334 0.254) (xy 0.5334 0.2794)
				(xy -0.508 0.2794) (xy -0.5334 0.2794)
			)
			(stroke
				(width 0)
				(type default)
			)
			(fill no)
			(layer "F.CrtYd")
		)
		(pad "1" smd rect
			(at 0.40005 0 270)
			(size 0.4572 0.508)
			(layers "F.Cu" "F.Mask" "F.Paste")
			(net "PV_VDDR_NODE1")
		)
		(pad "2" smd rect
			(at -0.40005 0 270)
			(size 0.4572 0.508)
			(layers "F.Cu" "F.Mask" "F.Paste")
			(net "GND")
		)
	)
	(footprint ""
		(layer "F.Cu")
		(at 116.872258 -149.24278 180)
		(property "Reference" "R1249"
			(at 3.789172 -1.870456 0)
			(unlocked yes)
			(layer "F.SilkS")
			(effects
				(font
					(size 0.635 0.4064)
					(thickness 0.1524)
				)
				(justify left)
			)
		)
		(property "Value" ""
			(at 0 0 180)
			(layer "F.Fab")
			(effects
				(font
					(size 1.27 1.27)
				)
			)
		)
		(duplicate_pad_numbers_are_jumpers no)
		(fp_line
			(start 1.905 0.8636)
			(end -1.905 0.8636)
			(stroke
				(width 0.1524)
				(type default)
			)
			(layer "F.SilkS")
		)
		(fp_line
			(start 1.905 -0.8636)
			(end 1.905 0.8636)
			(stroke
				(width 0.1524)
				(type default)
			)
			(layer "F.SilkS")
		)
		(fp_line
			(start -1.905 0.8636)
			(end -1.905 -0.8636)
			(stroke
				(width 0.1524)
				(type default)
			)
			(layer "F.SilkS")
		)
		(fp_line
			(start -1.905 -0.8636)
			(end 1.905 -0.8636)
			(stroke
				(width 0.1524)
				(type default)
			)
			(layer "F.SilkS")
		)
		(fp_poly
			(pts
				(xy 1.524 0.6858) (xy 1.524 -0.6858) (xy 1.524 -0.7366) (xy -1.524 -0.7366) (xy -1.524 -0.6858)
				(xy -1.524 0.6858) (xy -1.524 0.7366) (xy 1.524 0.7366)
			)
			(stroke
				(width 0)
				(type default)
			)
			(fill no)
			(layer "F.CrtYd")
		)
		(pad "1" smd rect
			(at 0.94996 0 180)
			(size 1.1176 1.3716)
			(layers "F.Cu" "F.Mask" "F.Paste")
			(net "P12V_AUX")
		)
		(pad "2" smd rect
			(at -0.94996 0 180)
			(size 1.1176 1.3716)
			(layers "F.Cu" "F.Mask" "F.Paste")
			(net "N52998325")
		)
	)
	(footprint ""
		(layer "F.Cu")
		(at 60.81776 -185.205624 -90)
		(property "Reference" "R940"
			(at -4.006088 0.474218 90)
			(unlocked yes)
			(layer "F.SilkS")
			(effects
				(font
					(size 0.7874 0.5842)
					(thickness 0.1524)
				)
				(justify left)
			)
		)
		(property "Value" ""
			(at 0 0 270)
			(layer "F.Fab")
			(effects
				(font
					(size 1.27 1.27)
				)
			)
		)
		(duplicate_pad_numbers_are_jumpers no)
		(fp_line
			(start -0.7874 0.4064)
			(end -0.7874 -0.4064)
			(stroke
				(width 0.1524)
				(type default)
			)
			(layer "F.SilkS")
		)
		(fp_line
			(start 0.7874 0.4064)
			(end -0.7874 0.4064)
			(stroke
				(width 0.1524)
				(type default)
			)
			(layer "F.SilkS")
		)
		(fp_line
			(start -0.7874 -0.4064)
			(end 0.7874 -0.4064)
			(stroke
				(width 0.1524)
				(type default)
			)
			(layer "F.SilkS")
		)
		(fp_line
			(start 0.7874 -0.4064)
			(end 0.7874 0.4064)
			(stroke
				(width 0.1524)
				(type default)
			)
			(layer "F.SilkS")
		)
		(fp_poly
			(pts
				(xy -0.508 0.2794) (xy -0.508 0.2286) (xy -0.635 0.2286) (xy -0.635 -0.254) (xy -0.5334 -0.254)
				(xy -0.5334 -0.2794) (xy 0.5334 -0.2794) (xy 0.5334 -0.254) (xy 0.635 -0.254) (xy 0.635 0.254) (xy 0.5334 0.254)
				(xy 0.5334 0.2794)
			)
			(stroke
				(width 0)
				(type default)
			)
			(fill no)
			(layer "F.CrtYd")
		)
		(pad "1" smd rect
			(at 0.40005 0 270)
			(size 0.4572 0.508)
			(layers "F.Cu" "F.Mask" "F.Paste")
			(net "UART_T2_NODE2_TXD")
		)
		(pad "2" smd rect
			(at -0.40005 0 270)
			(size 0.4572 0.508)
			(layers "F.Cu" "F.Mask" "F.Paste")
			(net "UART_T2_NODE2_TXD_R")
		)
	)
	(footprint ""
		(layer "F.Cu")
		(at 114.50066 -140.193776 -90)
		(property "Reference" "PC104"
			(at -4.119626 -3.345942 90)
			(unlocked yes)
			(layer "F.SilkS")
			(effects
				(font
					(size 0.635 0.4064)
					(thickness 0.1524)
				)
				(justify left)
			)
		)
		(property "Value" ""
			(at 0 0 270)
			(layer "F.Fab")
			(effects
				(font
					(size 1.27 1.27)
				)
			)
		)
		(duplicate_pad_numbers_are_jumpers no)
		(fp_line
			(start -0.7874 0.4064)
			(end -0.7874 -0.4064)
			(stroke
				(width 0.1524)
				(type default)
			)
			(layer "F.SilkS")
		)
		(fp_line
			(start 0.7874 0.4064)
			(end -0.7874 0.4064)
			(stroke
				(width 0.1524)
				(type default)
			)
			(layer "F.SilkS")
		)
		(fp_line
			(start 0 0.381)
			(end 0 -0.381)
			(stroke
				(width 0.1524)
				(type default)
			)
			(layer "F.SilkS")
		)
		(fp_line
			(start -0.7874 -0.4064)
			(end 0.7874 -0.4064)
			(stroke
				(width 0.1524)
				(type default)
			)
			(layer "F.SilkS")
		)
		(fp_line
			(start 0.7874 -0.4064)
			(end 0.7874 0.4064)
			(stroke
				(width 0.1524)
				(type default)
			)
			(layer "F.SilkS")
		)
		(fp_poly
			(pts
				(xy -0.5334 0.254) (xy -0.635 0.254) (xy -0.635 0.2286) (xy -0.635 -0.254) (xy -0.5334 -0.254) (xy -0.5334 -0.2794)
				(xy 0.5334 -0.2794) (xy 0.5334 -0.254) (xy 0.635 -0.254) (xy 0.635 0.254) (xy 0.5334 0.254) (xy 0.5334 0.2794)
				(xy -0.508 0.2794) (xy -0.5334 0.2794)
			)
			(stroke
				(width 0)
				(type default)
			)
			(fill no)
			(layer "F.CrtYd")
		)
		(pad "1" smd rect
			(at 0.40005 0 270)
			(size 0.4572 0.508)
			(layers "F.Cu" "F.Mask" "F.Paste")
			(net "VSENSE_VSS_CPU_NODE1")
		)
		(pad "2" smd rect
			(at -0.40005 0 270)
			(size 0.4572 0.508)
			(layers "F.Cu" "F.Mask" "F.Paste")
			(net "VSENSE_VCC_CPU_NODE1")
		)
	)
	(footprint ""
		(layer "F.Cu")
		(at 19.72564 -130.328416 180)
		(property "Reference" "PC62"
			(at -1.49352 0.232156 0)
			(unlocked yes)
			(layer "F.SilkS")
			(effects
				(font
					(size 0.7874 0.5842)
					(thickness 0.1524)
				)
				(justify left)
			)
		)
		(property "Value" ""
			(at 0 0 180)
			(layer "F.Fab")
			(effects
				(font
					(size 1.27 1.27)
				)
			)
		)
		(duplicate_pad_numbers_are_jumpers no)
		(fp_line
			(start 0.7874 0.4064)
			(end -0.7874 0.4064)
			(stroke
				(width 0.1524)
				(type default)
			)
			(layer "F.SilkS")
		)
		(fp_line
			(start 0.7874 -0.4064)
			(end 0.7874 0.4064)
			(stroke
				(width 0.1524)
				(type default)
			)
			(layer "F.SilkS")
		)
		(fp_line
			(start 0 0.381)
			(end 0 -0.381)
			(stroke
				(width 0.1524)
				(type default)
			)
			(layer "F.SilkS")
		)
		(fp_line
			(start -0.7874 0.4064)
			(end -0.7874 -0.4064)
			(stroke
				(width 0.1524)
				(type default)
			)
			(layer "F.SilkS")
		)
		(fp_line
			(start -0.7874 -0.4064)
			(end 0.7874 -0.4064)
			(stroke
				(width 0.1524)
				(type default)
			)
			(layer "F.SilkS")
		)
		(fp_poly
			(pts
				(xy -0.5334 0.254) (xy -0.635 0.254) (xy -0.635 0.2286) (xy -0.635 -0.254) (xy -0.5334 -0.254) (xy -0.5334 -0.2794)
				(xy 0.5334 -0.2794) (xy 0.5334 -0.254) (xy 0.635 -0.254) (xy 0.635 0.254) (xy 0.5334 0.254) (xy 0.5334 0.2794)
				(xy -0.508 0.2794) (xy -0.5334 0.2794)
			)
			(stroke
				(width 0)
				(type default)
			)
			(fill no)
			(layer "F.CrtYd")
		)
		(pad "1" smd rect
			(at 0.40005 0 180)
			(size 0.4572 0.508)
			(layers "F.Cu" "F.Mask" "F.Paste")
			(net "P1V05_NODE1_EN")
		)
		(pad "2" smd rect
			(at -0.40005 0 180)
			(size 0.4572 0.508)
			(layers "F.Cu" "F.Mask" "F.Paste")
			(net "GND")
		)
	)
	(footprint ""
		(layer "F.Cu")
		(at 94.234762 -183.799988 180)
		(property "Reference" "R902"
			(at 1.206246 7.182612 0)
			(unlocked yes)
			(layer "F.SilkS")
			(effects
				(font
					(size 0.7874 0.5842)
					(thickness 0.1524)
				)
				(justify left)
			)
		)
		(property "Value" ""
			(at 0 0 180)
			(layer "F.Fab")
			(effects
				(font
					(size 1.27 1.27)
				)
			)
		)
		(duplicate_pad_numbers_are_jumpers no)
		(fp_line
			(start 0.7874 0.4064)
			(end -0.7874 0.4064)
			(stroke
				(width 0.1524)
				(type default)
			)
			(layer "F.SilkS")
		)
		(fp_line
			(start 0.7874 -0.4064)
			(end 0.7874 0.4064)
			(stroke
				(width 0.1524)
				(type default)
			)
			(layer "F.SilkS")
		)
		(fp_line
			(start -0.7874 0.4064)
			(end -0.7874 -0.4064)
			(stroke
				(width 0.1524)
				(type default)
			)
			(layer "F.SilkS")
		)
		(fp_line
			(start -0.7874 -0.4064)
			(end 0.7874 -0.4064)
			(stroke
				(width 0.1524)
				(type default)
			)
			(layer "F.SilkS")
		)
		(fp_poly
			(pts
				(xy -0.508 0.2794) (xy -0.508 0.2286) (xy -0.635 0.2286) (xy -0.635 -0.254) (xy -0.5334 -0.254)
				(xy -0.5334 -0.2794) (xy 0.5334 -0.2794) (xy 0.5334 -0.254) (xy 0.635 -0.254) (xy 0.635 0.254) (xy 0.5334 0.254)
				(xy 0.5334 0.2794)
			)
			(stroke
				(width 0)
				(type default)
			)
			(fill no)
			(layer "F.CrtYd")
		)
		(pad "1" smd rect
			(at 0.40005 0 180)
			(size 0.4572 0.508)
			(layers "F.Cu" "F.Mask" "F.Paste")
			(net "T5_NODE3_EN")
		)
		(pad "2" smd rect
			(at -0.40005 0 180)
			(size 0.4572 0.508)
			(layers "F.Cu" "F.Mask" "F.Paste")
			(net "T5_NODE3_EN_R")
		)
	)
	(footprint ""
		(layer "F.Cu")
		(at 40.24122 -145.83029 -90)
		(property "Reference" "R557"
			(at 0.886968 6.618732 90)
			(unlocked yes)
			(layer "F.SilkS")
			(effects
				(font
					(size 0.7874 0.5842)
					(thickness 0.1524)
				)
				(justify left)
			)
		)
		(property "Value" ""
			(at 0 0 270)
			(layer "F.Fab")
			(effects
				(font
					(size 1.27 1.27)
				)
			)
		)
		(duplicate_pad_numbers_are_jumpers no)
		(fp_line
			(start -0.7874 0.4064)
			(end -0.7874 -0.4064)
			(stroke
				(width 0.1524)
				(type default)
			)
			(layer "F.SilkS")
		)
		(fp_line
			(start 0.7874 0.4064)
			(end -0.7874 0.4064)
			(stroke
				(width 0.1524)
				(type default)
			)
			(layer "F.SilkS")
		)
		(fp_line
			(start -0.7874 -0.4064)
			(end 0.7874 -0.4064)
			(stroke
				(width 0.1524)
				(type default)
			)
			(layer "F.SilkS")
		)
		(fp_line
			(start 0.7874 -0.4064)
			(end 0.7874 0.4064)
			(stroke
				(width 0.1524)
				(type default)
			)
			(layer "F.SilkS")
		)
		(fp_poly
			(pts
				(xy -0.508 0.2794) (xy -0.508 0.2286) (xy -0.635 0.2286) (xy -0.635 -0.254) (xy -0.5334 -0.254)
				(xy -0.5334 -0.2794) (xy 0.5334 -0.2794) (xy 0.5334 -0.254) (xy 0.635 -0.254) (xy 0.635 0.254) (xy 0.5334 0.254)
				(xy 0.5334 0.2794)
			)
			(stroke
				(width 0)
				(type default)
			)
			(fill no)
			(layer "F.CrtYd")
		)
		(pad "1" smd rect
			(at 0.40005 0 270)
			(size 0.4572 0.508)
			(layers "F.Cu" "F.Mask" "F.Paste")
			(net "GND")
		)
		(pad "2" smd rect
			(at -0.40005 0 270)
			(size 0.4572 0.508)
			(layers "F.Cu" "F.Mask" "F.Paste")
			(net "LAN1_NC_SI_CRS_DV")
		)
	)
	(footprint ""
		(layer "F.Cu")
		(at 71.706486 -148.476462 90)
		(property "Reference" "R298"
			(at 1.233932 -0.176784 90)
			(unlocked yes)
			(layer "F.SilkS")
			(effects
				(font
					(size 0.7874 0.5842)
					(thickness 0.1524)
				)
				(justify left)
			)
		)
		(property "Value" ""
			(at 0 0 90)
			(layer "F.Fab")
			(effects
				(font
					(size 1.27 1.27)
				)
			)
		)
		(duplicate_pad_numbers_are_jumpers no)
		(fp_line
			(start 0.7874 -0.4064)
			(end 0.7874 0.4064)
			(stroke
				(width 0.1524)
				(type default)
			)
			(layer "F.SilkS")
		)
		(fp_line
			(start -0.7874 -0.4064)
			(end 0.7874 -0.4064)
			(stroke
				(width 0.1524)
				(type default)
			)
			(layer "F.SilkS")
		)
		(fp_line
			(start 0.7874 0.4064)
			(end -0.7874 0.4064)
			(stroke
				(width 0.1524)
				(type default)
			)
			(layer "F.SilkS")
		)
		(fp_line
			(start -0.7874 0.4064)
			(end -0.7874 -0.4064)
			(stroke
				(width 0.1524)
				(type default)
			)
			(layer "F.SilkS")
		)
		(fp_poly
			(pts
				(xy -0.508 0.2794) (xy -0.508 0.2286) (xy -0.635 0.2286) (xy -0.635 -0.254) (xy -0.5334 -0.254)
				(xy -0.5334 -0.2794) (xy 0.5334 -0.2794) (xy 0.5334 -0.254) (xy 0.635 -0.254) (xy 0.635 0.254) (xy 0.5334 0.254)
				(xy 0.5334 0.2794)
			)
			(stroke
				(width 0)
				(type default)
			)
			(fill no)
			(layer "F.CrtYd")
		)
		(pad "1" smd rect
			(at 0.40005 0 90)
			(size 0.4572 0.508)
			(layers "F.Cu" "F.Mask" "F.Paste")
			(net "P3V3_NODE1")
		)
		(pad "2" smd rect
			(at -0.40005 0 90)
			(size 0.4572 0.508)
			(layers "F.Cu" "F.Mask" "F.Paste")
			(net "BMC_NODE1_JTAG_TRST")
		)
	)
	(footprint ""
		(layer "F.Cu")
		(at 130.0988 -50.8508 90)
		(property "Reference" "R1323"
			(at 16.9164 30.81147 90)
			(unlocked yes)
			(layer "F.SilkS")
			(effects
				(font
					(size 0.7874 0.5842)
					(thickness 0.1524)
				)
				(justify left)
			)
		)
		(property "Value" ""
			(at 0 0 90)
			(layer "F.Fab")
			(effects
				(font
					(size 1.27 1.27)
				)
			)
		)
		(duplicate_pad_numbers_are_jumpers no)
		(fp_line
			(start 0.7874 -0.4064)
			(end 0.7874 0.4064)
			(stroke
				(width 0.1524)
				(type default)
			)
			(layer "F.SilkS")
		)
		(fp_line
			(start -0.7874 -0.4064)
			(end 0.7874 -0.4064)
			(stroke
				(width 0.1524)
				(type default)
			)
			(layer "F.SilkS")
		)
		(fp_line
			(start 0.7874 0.4064)
			(end -0.7874 0.4064)
			(stroke
				(width 0.1524)
				(type default)
			)
			(layer "F.SilkS")
		)
		(fp_line
			(start -0.7874 0.4064)
			(end -0.7874 -0.4064)
			(stroke
				(width 0.1524)
				(type default)
			)
			(layer "F.SilkS")
		)
		(fp_poly
			(pts
				(xy -0.508 0.2794) (xy -0.508 0.2286) (xy -0.635 0.2286) (xy -0.635 -0.254) (xy -0.5334 -0.254)
				(xy -0.5334 -0.2794) (xy 0.5334 -0.2794) (xy 0.5334 -0.254) (xy 0.635 -0.254) (xy 0.635 0.254) (xy 0.5334 0.254)
				(xy 0.5334 0.2794)
			)
			(stroke
				(width 0)
				(type default)
			)
			(fill no)
			(layer "F.CrtYd")
		)
		(pad "1" smd rect
			(at 0.40005 0 90)
			(size 0.4572 0.508)
			(layers "F.Cu" "F.Mask" "F.Paste")
			(net "P5V_NODE1")
		)
		(pad "2" smd rect
			(at -0.40005 0 90)
			(size 0.4572 0.508)
			(layers "F.Cu" "F.Mask" "F.Paste")
			(net "UART_DSR_P4_N")
		)
	)
	(footprint ""
		(layer "F.Cu")
		(at 91.486228 -133.213094 -90)
		(property "Reference" "D38"
			(at -3.544316 0.760476 90)
			(unlocked yes)
			(layer "F.SilkS")
			(effects
				(font
					(size 0.7874 0.5842)
					(thickness 0.1524)
				)
				(justify left)
			)
		)
		(property "Value" ""
			(at 0 0 270)
			(layer "F.Fab")
			(effects
				(font
					(size 1.27 1.27)
				)
			)
		)
		(duplicate_pad_numbers_are_jumpers no)
		(fp_line
			(start -1.3208 0.5588)
			(end -1.3208 -0.5588)
			(stroke
				(width 0.1524)
				(type default)
			)
			(layer "F.SilkS")
		)
		(fp_line
			(start 1.3208 0.5588)
			(end -1.3208 0.5588)
			(stroke
				(width 0.1524)
				(type default)
			)
			(layer "F.SilkS")
		)
		(fp_line
			(start 1.6256 0.5588)
			(end 1.6256 -0.5588)
			(stroke
				(width 0.1524)
				(type default)
			)
			(layer "F.SilkS")
		)
		(fp_line
			(start 1.778 0.5588)
			(end 1.3208 0.5588)
			(stroke
				(width 0.1524)
				(type default)
			)
			(layer "F.SilkS")
		)
		(fp_line
			(start -1.3208 -0.5588)
			(end 1.3208 -0.5588)
			(stroke
				(width 0.1524)
				(type default)
			)
			(layer "F.SilkS")
		)
		(fp_line
			(start 1.3208 -0.5588)
			(end 1.3208 0.5588)
			(stroke
				(width 0.1524)
				(type default)
			)
			(layer "F.SilkS")
		)
		(fp_line
			(start 1.4732 -0.5588)
			(end 1.4732 0.5588)
			(stroke
				(width 0.1524)
				(type default)
			)
			(layer "F.SilkS")
		)
		(fp_line
			(start 1.778 -0.5588)
			(end 1.778 0.5588)
			(stroke
				(width 0.1524)
				(type default)
			)
			(layer "F.SilkS")
		)
		(fp_line
			(start 1.778 -0.5588)
			(end 1.3208 -0.5588)
			(stroke
				(width 0.1524)
				(type default)
			)
			(layer "F.SilkS")
		)
		(fp_circle
			(center 2.4384 0)
			(end 2.4384 -0.413512)
			(stroke
				(width 0.1524)
				(type default)
			)
			(fill no)
			(layer "F.SilkS")
		)
		(fp_rect
			(start -1.1684 0.508)
			(end 1.1684 -0.508)
			(stroke
				(width 0)
				(type default)
			)
			(fill no)
			(layer "F.CrtYd")
		)
		(fp_text user "-"
			(at 2.9464 0.28067 270)
			(unlocked yes)
			(layer "F.SilkS")
			(effects
				(font
					(size 0.7874 0.5842)
					(thickness 0.1524)
				)
				(justify left)
			)
		)
		(pad "A" smd rect
			(at -0.750062 0 270)
			(size 0.8128 0.8128)
			(layers "F.Cu" "F.Mask" "F.Paste")
			(net "P3V3_NODE1")
		)
		(pad "C" smd rect
			(at 0.750062 0 270)
			(size 0.8128 0.8128)
			(layers "F.Cu" "F.Mask" "F.Paste")
			(net "N53313596")
		)
	)
	(footprint ""
		(layer "F.Cu")
		(at 141.593316 -160.439608 -90)
		(property "Reference" "OSC6"
			(at 110.800896 66.176906 90)
			(unlocked yes)
			(layer "F.SilkS")
			(effects
				(font
					(size 0.7874 0.5842)
					(thickness 0.1524)
				)
				(justify left)
			)
		)
		(property "Value" ""
			(at 0 0 270)
			(layer "F.Fab")
			(effects
				(font
					(size 1.27 1.27)
				)
			)
		)
		(duplicate_pad_numbers_are_jumpers no)
		(fp_line
			(start -0.6096 2.936494)
			(end 2.35966 2.936494)
			(stroke
				(width 0.1524)
				(type default)
			)
			(layer "F.SilkS")
		)
		(fp_line
			(start 2.35966 2.936494)
			(end 2.35966 -0.7366)
			(stroke
				(width 0.1524)
				(type default)
			)
			(layer "F.SilkS")
		)
		(fp_line
			(start -0.6096 -0.7366)
			(end -0.6096 2.936494)
			(stroke
				(width 0.1524)
				(type default)
			)
			(layer "F.SilkS")
		)
		(fp_line
			(start 2.35966 -0.7366)
			(end -0.6096 -0.7366)
			(stroke
				(width 0.1524)
				(type default)
			)
			(layer "F.SilkS")
		)
		(fp_poly
			(pts
				(xy -1.761998 -0.40132) (xy -1.761998 -1.41732) (xy -0.745998 -0.90932)
			)
			(stroke
				(width 0)
				(type default)
			)
			(fill yes)
			(layer "F.SilkS")
		)
		(fp_poly
			(pts
				(xy -0.5334 -0.6604) (xy 0.5334 -0.6604) (xy 0.5334 -0.575056) (xy 1.21666 -0.575056) (xy 1.21666 -0.6604)
				(xy 2.28346 -0.6604) (xy 2.28346 0.6604) (xy 2.199894 0.6604) (xy 2.199894 1.539494) (xy 2.28346 1.539494)
				(xy 2.28346 2.860294) (xy 1.21666 2.860294) (xy 1.21666 2.77495) (xy 0.5334 2.77495) (xy 0.5334 2.860294)
				(xy -0.5334 2.860294) (xy -0.5334 1.539494) (xy -0.450088 1.539494) (xy -0.450088 0.6604) (xy -0.5334 0.6604)
			)
			(stroke
				(width 0)
				(type default)
			)
			(fill no)
			(layer "F.CrtYd")
		)
		(fp_line
			(start -0.450088 2.77495)
			(end 2.199894 2.77495)
			(stroke
				(width 0.1)
				(type default)
			)
			(layer "F.Fab")
		)
		(fp_line
			(start 2.199894 2.77495)
			(end 2.199894 -0.575056)
			(stroke
				(width 0.1)
				(type default)
			)
			(layer "F.Fab")
		)
		(fp_line
			(start -0.450088 -0.575056)
			(end -0.450088 2.77495)
			(stroke
				(width 0.1)
				(type default)
			)
			(layer "F.Fab")
		)
		(fp_line
			(start 2.199894 -0.575056)
			(end -0.450088 -0.575056)
			(stroke
				(width 0.1)
				(type default)
			)
			(layer "F.Fab")
		)
		(fp_poly
			(pts
				(xy -1.843278 0.508) (xy -1.843278 -0.508) (xy -0.827278 0)
			)
			(stroke
				(width 0)
				(type default)
			)
			(fill yes)
			(layer "F.Fab")
		)
		(pad "1" smd rect
			(at 0 0 270)
			(size 0.9652 1.2192)
			(layers "F.Cu" "F.Mask" "F.Paste")
			(net "N31521709")
		)
		(pad "2" smd rect
			(at 0 2.199894 270)
			(size 0.9652 1.2192)
			(layers "F.Cu" "F.Mask" "F.Paste")
			(net "GND")
		)
		(pad "3" smd rect
			(at 1.75006 2.199894 270)
			(size 0.9652 1.2192)
			(layers "F.Cu" "F.Mask" "F.Paste")
			(net "N31521711")
		)
		(pad "4" smd rect
			(at 1.75006 0 270)
			(size 0.9652 1.2192)
			(layers "F.Cu" "F.Mask" "F.Paste")
			(net "P3V3_NODE1")
		)
	)
	(footprint ""
		(layer "F.Cu")
		(at 187.7695 -165.056566)
		(property "Reference" "R1279"
			(at -1.672844 5.279136 0)
			(unlocked yes)
			(layer "F.SilkS")
			(effects
				(font
					(size 0.7874 0.5842)
					(thickness 0.1524)
				)
				(justify left)
			)
		)
		(property "Value" ""
			(at 0 0 0)
			(layer "F.Fab")
			(effects
				(font
					(size 1.27 1.27)
				)
			)
		)
		(duplicate_pad_numbers_are_jumpers no)
		(fp_line
			(start -0.7874 -0.4064)
			(end 0.7874 -0.4064)
			(stroke
				(width 0.1524)
				(type default)
			)
			(layer "F.SilkS")
		)
		(fp_line
			(start -0.7874 0.4064)
			(end -0.7874 -0.4064)
			(stroke
				(width 0.1524)
				(type default)
			)
			(layer "F.SilkS")
		)
		(fp_line
			(start 0.7874 -0.4064)
			(end 0.7874 0.4064)
			(stroke
				(width 0.1524)
				(type default)
			)
			(layer "F.SilkS")
		)
		(fp_line
			(start 0.7874 0.4064)
			(end -0.7874 0.4064)
			(stroke
				(width 0.1524)
				(type default)
			)
			(layer "F.SilkS")
		)
		(fp_poly
			(pts
				(xy -0.508 0.2794) (xy -0.508 0.2286) (xy -0.635 0.2286) (xy -0.635 -0.254) (xy -0.5334 -0.254)
				(xy -0.5334 -0.2794) (xy 0.5334 -0.2794) (xy 0.5334 -0.254) (xy 0.635 -0.254) (xy 0.635 0.254) (xy 0.5334 0.254)
				(xy 0.5334 0.2794)
			)
			(stroke
				(width 0)
				(type default)
			)
			(fill no)
			(layer "F.CrtYd")
		)
		(pad "1" smd rect
			(at 0.40005 0)
			(size 0.4572 0.508)
			(layers "F.Cu" "F.Mask" "F.Paste")
			(net "N54134271")
		)
		(pad "2" smd rect
			(at -0.40005 0)
			(size 0.4572 0.508)
			(layers "F.Cu" "F.Mask" "F.Paste")
			(net "LAN2_P3_R")
		)
	)
	(footprint ""
		(layer "F.Cu")
		(at 114.746786 -65.40373)
		(property "Reference" "R221"
			(at 1.969516 -0.2286 0)
			(unlocked yes)
			(layer "F.SilkS")
			(effects
				(font
					(size 0.7874 0.5842)
					(thickness 0.1524)
				)
				(justify left)
			)
		)
		(property "Value" ""
			(at 0 0 0)
			(layer "F.Fab")
			(effects
				(font
					(size 1.27 1.27)
				)
			)
		)
		(duplicate_pad_numbers_are_jumpers no)
		(fp_line
			(start -0.7874 -0.4064)
			(end 0.7874 -0.4064)
			(stroke
				(width 0.1524)
				(type default)
			)
			(layer "F.SilkS")
		)
		(fp_line
			(start -0.7874 0.4064)
			(end -0.7874 -0.4064)
			(stroke
				(width 0.1524)
				(type default)
			)
			(layer "F.SilkS")
		)
		(fp_line
			(start 0.7874 -0.4064)
			(end 0.7874 0.4064)
			(stroke
				(width 0.1524)
				(type default)
			)
			(layer "F.SilkS")
		)
		(fp_line
			(start 0.7874 0.4064)
			(end -0.7874 0.4064)
			(stroke
				(width 0.1524)
				(type default)
			)
			(layer "F.SilkS")
		)
		(fp_poly
			(pts
				(xy -0.508 0.2794) (xy -0.508 0.2286) (xy -0.635 0.2286) (xy -0.635 -0.254) (xy -0.5334 -0.254)
				(xy -0.5334 -0.2794) (xy 0.5334 -0.2794) (xy 0.5334 -0.254) (xy 0.635 -0.254) (xy 0.635 0.254) (xy 0.5334 0.254)
				(xy 0.5334 0.2794)
			)
			(stroke
				(width 0)
				(type default)
			)
			(fill no)
			(layer "F.CrtYd")
		)
		(pad "1" smd rect
			(at 0.40005 0)
			(size 0.4572 0.508)
			(layers "F.Cu" "F.Mask" "F.Paste")
			(net "P1V05_NODE1")
		)
		(pad "2" smd rect
			(at -0.40005 0)
			(size 0.4572 0.508)
			(layers "F.Cu" "F.Mask" "F.Paste")
			(net "P1V05_STB_NODE1_XDP_B")
		)
	)
	(footprint ""
		(layer "F.Cu")
		(at 66.194686 -118.758462 90)
		(property "Reference" "R345"
			(at -4.988306 -0.996442 90)
			(unlocked yes)
			(layer "F.SilkS")
			(effects
				(font
					(size 0.7874 0.5842)
					(thickness 0.1524)
				)
				(justify left)
			)
		)
		(property "Value" ""
			(at 0 0 90)
			(layer "F.Fab")
			(effects
				(font
					(size 1.27 1.27)
				)
			)
		)
		(duplicate_pad_numbers_are_jumpers no)
		(fp_line
			(start 0.7874 -0.4064)
			(end 0.7874 0.4064)
			(stroke
				(width 0.1524)
				(type default)
			)
			(layer "F.SilkS")
		)
		(fp_line
			(start -0.7874 -0.4064)
			(end 0.7874 -0.4064)
			(stroke
				(width 0.1524)
				(type default)
			)
			(layer "F.SilkS")
		)
		(fp_line
			(start 0.7874 0.4064)
			(end -0.7874 0.4064)
			(stroke
				(width 0.1524)
				(type default)
			)
			(layer "F.SilkS")
		)
		(fp_line
			(start -0.7874 0.4064)
			(end -0.7874 -0.4064)
			(stroke
				(width 0.1524)
				(type default)
			)
			(layer "F.SilkS")
		)
		(fp_poly
			(pts
				(xy -0.508 0.2794) (xy -0.508 0.2286) (xy -0.635 0.2286) (xy -0.635 -0.254) (xy -0.5334 -0.254)
				(xy -0.5334 -0.2794) (xy 0.5334 -0.2794) (xy 0.5334 -0.254) (xy 0.635 -0.254) (xy 0.635 0.254) (xy 0.5334 0.254)
				(xy 0.5334 0.2794)
			)
			(stroke
				(width 0)
				(type default)
			)
			(fill no)
			(layer "F.CrtYd")
		)
		(pad "1" smd rect
			(at 0.40005 0 90)
			(size 0.4572 0.508)
			(layers "F.Cu" "F.Mask" "F.Paste")
			(net "P3V3_NODE1")
		)
		(pad "2" smd rect
			(at -0.40005 0 90)
			(size 0.4572 0.508)
			(layers "F.Cu" "F.Mask" "F.Paste")
			(net "PU_I2C_BMC_SDA")
		)
	)
	(footprint ""
		(layer "F.Cu")
		(at 33.212786 -184.2135)
		(property "Reference" "R1022"
			(at -5.280914 -5.227828 0)
			(unlocked yes)
			(layer "F.SilkS")
			(effects
				(font
					(size 0.7874 0.5842)
					(thickness 0.1524)
				)
				(justify left)
			)
		)
		(property "Value" ""
			(at 0 0 0)
			(layer "F.Fab")
			(effects
				(font
					(size 1.27 1.27)
				)
			)
		)
		(duplicate_pad_numbers_are_jumpers no)
		(fp_line
			(start -0.7874 -0.4064)
			(end 0.7874 -0.4064)
			(stroke
				(width 0.1524)
				(type default)
			)
			(layer "F.SilkS")
		)
		(fp_line
			(start -0.7874 0.4064)
			(end -0.7874 -0.4064)
			(stroke
				(width 0.1524)
				(type default)
			)
			(layer "F.SilkS")
		)
		(fp_line
			(start 0.7874 -0.4064)
			(end 0.7874 0.4064)
			(stroke
				(width 0.1524)
				(type default)
			)
			(layer "F.SilkS")
		)
		(fp_line
			(start 0.7874 0.4064)
			(end -0.7874 0.4064)
			(stroke
				(width 0.1524)
				(type default)
			)
			(layer "F.SilkS")
		)
		(fp_poly
			(pts
				(xy -0.508 0.2794) (xy -0.508 0.2286) (xy -0.635 0.2286) (xy -0.635 -0.254) (xy -0.5334 -0.254)
				(xy -0.5334 -0.2794) (xy 0.5334 -0.2794) (xy 0.5334 -0.254) (xy 0.635 -0.254) (xy 0.635 0.254) (xy 0.5334 0.254)
				(xy 0.5334 0.2794)
			)
			(stroke
				(width 0)
				(type default)
			)
			(fill no)
			(layer "F.CrtYd")
		)
		(pad "1" smd rect
			(at 0.40005 0)
			(size 0.4572 0.508)
			(layers "F.Cu" "F.Mask" "F.Paste")
			(net "P12V_AUX_EN")
		)
		(pad "2" smd rect
			(at -0.40005 0)
			(size 0.4572 0.508)
			(layers "F.Cu" "F.Mask" "F.Paste")
			(net "AGND_HSC_NODE1")
		)
	)
	(footprint ""
		(layer "F.Cu")
		(at 150.011892 -51.786028 90)
		(property "Reference" "C495"
			(at 16.091154 27.12847 90)
			(unlocked yes)
			(layer "F.SilkS")
			(effects
				(font
					(size 0.7874 0.5842)
					(thickness 0.1524)
				)
				(justify left)
			)
		)
		(property "Value" ""
			(at 0 0 90)
			(layer "F.Fab")
			(effects
				(font
					(size 1.27 1.27)
				)
			)
		)
		(duplicate_pad_numbers_are_jumpers no)
		(fp_line
			(start 0.7874 -0.4064)
			(end 0.7874 0.4064)
			(stroke
				(width 0.1524)
				(type default)
			)
			(layer "F.SilkS")
		)
		(fp_line
			(start -0.7874 -0.4064)
			(end 0.7874 -0.4064)
			(stroke
				(width 0.1524)
				(type default)
			)
			(layer "F.SilkS")
		)
		(fp_line
			(start 0 0.381)
			(end 0 -0.381)
			(stroke
				(width 0.1524)
				(type default)
			)
			(layer "F.SilkS")
		)
		(fp_line
			(start 0.7874 0.4064)
			(end -0.7874 0.4064)
			(stroke
				(width 0.1524)
				(type default)
			)
			(layer "F.SilkS")
		)
		(fp_line
			(start -0.7874 0.4064)
			(end -0.7874 -0.4064)
			(stroke
				(width 0.1524)
				(type default)
			)
			(layer "F.SilkS")
		)
		(fp_poly
			(pts
				(xy -0.5334 0.254) (xy -0.635 0.254) (xy -0.635 0.2286) (xy -0.635 -0.254) (xy -0.5334 -0.254) (xy -0.5334 -0.2794)
				(xy 0.5334 -0.2794) (xy 0.5334 -0.254) (xy 0.635 -0.254) (xy 0.635 0.254) (xy 0.5334 0.254) (xy 0.5334 0.2794)
				(xy -0.508 0.2794) (xy -0.5334 0.2794)
			)
			(stroke
				(width 0)
				(type default)
			)
			(fill no)
			(layer "F.CrtYd")
		)
		(pad "1" smd rect
			(at 0.40005 0 90)
			(size 0.4572 0.508)
			(layers "F.Cu" "F.Mask" "F.Paste")
			(net "SATA_P7")
		)
		(pad "2" smd rect
			(at -0.40005 0 90)
			(size 0.4572 0.508)
			(layers "F.Cu" "F.Mask" "F.Paste")
			(net "GND")
		)
	)
	(footprint ""
		(layer "F.Cu")
		(at 171.225972 -53.104542 -90)
		(property "Reference" "CE3"
			(at 3.443224 4.27101 90)
			(unlocked yes)
			(layer "F.SilkS")
			(effects
				(font
					(size 0.7874 0.5842)
					(thickness 0.1524)
				)
				(justify left)
			)
		)
		(property "Value" ""
			(at 0 0 270)
			(layer "F.Fab")
			(effects
				(font
					(size 1.27 1.27)
				)
			)
		)
		(duplicate_pad_numbers_are_jumpers no)
		(fp_line
			(start -2.750058 2.750058)
			(end 2.750058 2.750058)
			(stroke
				(width 0.1524)
				(type default)
			)
			(layer "F.SilkS")
		)
		(fp_line
			(start 2.750058 2.750058)
			(end 2.750058 -1.734058)
			(stroke
				(width 0.1524)
				(type default)
			)
			(layer "F.SilkS")
		)
		(fp_line
			(start -2.750058 -1.734058)
			(end -2.750058 2.750058)
			(stroke
				(width 0.1524)
				(type default)
			)
			(layer "F.SilkS")
		)
		(fp_line
			(start 2.750058 -1.734058)
			(end 1.734058 -2.750058)
			(stroke
				(width 0.1524)
				(type default)
			)
			(layer "F.SilkS")
		)
		(fp_line
			(start -1.734058 -2.750058)
			(end -2.750058 -1.734058)
			(stroke
				(width 0.1524)
				(type default)
			)
			(layer "F.SilkS")
		)
		(fp_line
			(start 1.734058 -2.750058)
			(end -1.734058 -2.750058)
			(stroke
				(width 0.1524)
				(type default)
			)
			(layer "F.SilkS")
		)
		(fp_poly
			(pts
				(xy 2.750058 2.750058) (xy 0.8509 2.750058) (xy 0.8509 3.761994) (xy -0.8509 3.761994) (xy -0.8509 2.750058)
				(xy -2.750058 2.750058) (xy -2.750058 -2.750058) (xy -0.8509 -2.750058) (xy -0.8509 -3.761994) (xy 0.8509 -3.761994)
				(xy 0.8509 -2.750058) (xy 2.750058 -2.750058)
			)
			(stroke
				(width 0)
				(type default)
			)
			(fill no)
			(layer "F.CrtYd")
		)
		(fp_line
			(start -2.750058 2.750058)
			(end 2.750058 2.750058)
			(stroke
				(width 0.1)
				(type default)
			)
			(layer "F.Fab")
		)
		(fp_line
			(start 2.750058 2.750058)
			(end 2.750058 -2.750058)
			(stroke
				(width 0.1)
				(type default)
			)
			(layer "F.Fab")
		)
		(fp_line
			(start -2.750058 -2.750058)
			(end -2.750058 2.750058)
			(stroke
				(width 0.1)
				(type default)
			)
			(layer "F.Fab")
		)
		(fp_line
			(start 2.750058 -2.750058)
			(end -2.750058 -2.750058)
			(stroke
				(width 0.1)
				(type default)
			)
			(layer "F.Fab")
		)
		(fp_text user "2"
			(at 0.027432 4.2164 0)
			(unlocked yes)
			(layer "F.SilkS")
			(effects
				(font
					(size 0.635 0.4064)
					(thickness 0.1524)
				)
			)
		)
		(fp_text user "+"
			(at -1.741678 -3.056128 0)
			(unlocked yes)
			(layer "F.SilkS")
			(effects
				(font
					(size 1.6002 1.1938)
					(thickness 0.1524)
				)
				(justify left)
			)
		)
		(fp_text user "1"
			(at 0.342138 -4.167124 0)
			(unlocked yes)
			(layer "F.SilkS")
			(effects
				(font
					(size 0.635 0.4064)
					(thickness 0.1524)
				)
			)
		)
		(fp_text user "2"
			(at -0.041148 4.2164 0)
			(unlocked yes)
			(layer "F.Fab")
			(effects
				(font
					(size 0.7874 0.5842)
					(thickness 0.000001)
				)
			)
		)
		(fp_text user "1"
			(at -0.041148 -4.064 0)
			(unlocked yes)
			(layer "F.Fab")
			(effects
				(font
					(size 0.7874 0.5842)
					(thickness 0.000001)
				)
			)
		)
		(fp_text user "+"
			(at -0.8001 -4.89585 270)
			(unlocked yes)
			(layer "F.Fab")
			(effects
				(font
					(size 1.905 1.4224)
					(thickness 0.000001)
				)
				(justify left)
			)
		)
		(pad "1" smd oval
			(at 0 -2.199894 90)
			(size 1.6002 3.0226)
			(layers "F.Cu" "F.Mask" "F.Paste")
			(net "USBPWR_P1")
		)
		(pad "2" smd oval
			(at 0 2.199894 90)
			(size 1.6002 3.0226)
			(layers "F.Cu" "F.Mask" "F.Paste")
			(net "GND")
		)
	)
	(footprint ""
		(layer "F.Cu")
		(at 13.053568 -125.62078)
		(property "Reference" "PC58"
			(at -4.324096 -0.442976 0)
			(unlocked yes)
			(layer "F.SilkS")
			(effects
				(font
					(size 0.7874 0.5842)
					(thickness 0.1524)
				)
				(justify left)
			)
		)
		(property "Value" ""
			(at 0 0 0)
			(layer "F.Fab")
			(effects
				(font
					(size 1.27 1.27)
				)
			)
		)
		(duplicate_pad_numbers_are_jumpers no)
		(fp_line
			(start -0.7874 -0.4064)
			(end 0.7874 -0.4064)
			(stroke
				(width 0.1524)
				(type default)
			)
			(layer "F.SilkS")
		)
		(fp_line
			(start -0.7874 0.4064)
			(end -0.7874 -0.4064)
			(stroke
				(width 0.1524)
				(type default)
			)
			(layer "F.SilkS")
		)
		(fp_line
			(start 0 0.381)
			(end 0 -0.381)
			(stroke
				(width 0.1524)
				(type default)
			)
			(layer "F.SilkS")
		)
		(fp_line
			(start 0.7874 -0.4064)
			(end 0.7874 0.4064)
			(stroke
				(width 0.1524)
				(type default)
			)
			(layer "F.SilkS")
		)
		(fp_line
			(start 0.7874 0.4064)
			(end -0.7874 0.4064)
			(stroke
				(width 0.1524)
				(type default)
			)
			(layer "F.SilkS")
		)
		(fp_poly
			(pts
				(xy -0.5334 0.254) (xy -0.635 0.254) (xy -0.635 0.2286) (xy -0.635 -0.254) (xy -0.5334 -0.254) (xy -0.5334 -0.2794)
				(xy 0.5334 -0.2794) (xy 0.5334 -0.254) (xy 0.635 -0.254) (xy 0.635 0.254) (xy 0.5334 0.254) (xy 0.5334 0.2794)
				(xy -0.508 0.2794) (xy -0.5334 0.2794)
			)
			(stroke
				(width 0)
				(type default)
			)
			(fill no)
			(layer "F.CrtYd")
		)
		(pad "1" smd rect
			(at 0.40005 0)
			(size 0.4572 0.508)
			(layers "F.Cu" "F.Mask" "F.Paste")
			(net "SW_P1V05_NODE1_VIN_FLT")
		)
		(pad "2" smd rect
			(at -0.40005 0)
			(size 0.4572 0.508)
			(layers "F.Cu" "F.Mask" "F.Paste")
			(net "GND")
		)
	)
	(footprint ""
		(layer "F.Cu")
		(at 163.261294 -123.07062 180)
		(property "Reference" "Q24"
			(at 5.640324 1.886712 0)
			(unlocked yes)
			(layer "F.SilkS")
			(effects
				(font
					(size 0.7874 0.5842)
					(thickness 0.1524)
				)
				(justify left)
			)
		)
		(property "Value" ""
			(at 0 0 180)
			(layer "F.Fab")
			(effects
				(font
					(size 1.27 1.27)
				)
			)
		)
		(duplicate_pad_numbers_are_jumpers no)
		(fp_line
			(start 2.584196 2.48412)
			(end -0.5842 2.48412)
			(stroke
				(width 0.1524)
				(type default)
			)
			(layer "F.SilkS")
		)
		(fp_line
			(start 2.584196 -0.5842)
			(end 2.584196 2.48412)
			(stroke
				(width 0.1524)
				(type default)
			)
			(layer "F.SilkS")
		)
		(fp_line
			(start -0.5842 2.48412)
			(end -0.5842 -0.5842)
			(stroke
				(width 0.1524)
				(type default)
			)
			(layer "F.SilkS")
		)
		(fp_line
			(start -0.5842 -0.5842)
			(end 2.584196 -0.5842)
			(stroke
				(width 0.1524)
				(type default)
			)
			(layer "F.SilkS")
		)
		(fp_poly
			(pts
				(xy -0.508 -0.4572) (xy 0.299974 -0.4572) (xy 0.299974 -0.54991) (xy 1.700022 -0.54991) (xy 1.700022 0.49276)
				(xy 2.507996 0.49276) (xy 2.507996 1.40716) (xy 1.700022 1.40716) (xy 1.700022 2.450084) (xy 0.299974 2.450084)
				(xy 0.299974 2.35712) (xy -0.508 2.35712)
			)
			(stroke
				(width 0)
				(type default)
			)
			(fill no)
			(layer "F.CrtYd")
		)
		(fp_line
			(start 1.700022 2.450084)
			(end 0.299974 2.450084)
			(stroke
				(width 0.1)
				(type default)
			)
			(layer "F.Fab")
		)
		(fp_line
			(start 1.700022 -0.54991)
			(end 1.700022 2.450084)
			(stroke
				(width 0.1)
				(type default)
			)
			(layer "F.Fab")
		)
		(fp_line
			(start 0.299974 2.450084)
			(end 0.299974 -0.54991)
			(stroke
				(width 0.1)
				(type default)
			)
			(layer "F.Fab")
		)
		(fp_line
			(start 0.299974 -0.54991)
			(end 1.700022 -0.54991)
			(stroke
				(width 0.1)
				(type default)
			)
			(layer "F.Fab")
		)
		(fp_text user "C"
			(at 3.233928 0.406908 0)
			(unlocked yes)
			(layer "F.SilkS")
			(effects
				(font
					(size 0.635 0.4064)
					(thickness 0.1524)
				)
				(justify left)
			)
		)
		(fp_text user "B"
			(at -0.737108 -0.099314 0)
			(unlocked yes)
			(layer "F.SilkS")
			(effects
				(font
					(size 0.635 0.4064)
					(thickness 0.1524)
				)
				(justify left)
			)
		)
		(fp_text user "E"
			(at -0.801624 1.227328 0)
			(unlocked yes)
			(layer "F.SilkS")
			(effects
				(font
					(size 0.635 0.4064)
					(thickness 0.1524)
				)
				(justify left)
			)
		)
		(fp_text user "C"
			(at 2.8702 0.99187 180)
			(unlocked yes)
			(layer "F.Fab")
			(effects
				(font
					(size 0.7874 0.5842)
					(thickness 0.000001)
				)
				(justify left)
			)
		)
		(fp_text user "B"
			(at -1.5494 0.00127 180)
			(unlocked yes)
			(layer "F.Fab")
			(effects
				(font
					(size 0.7874 0.5842)
					(thickness 0.000001)
				)
				(justify left)
			)
		)
		(fp_text user "E"
			(at -1.5748 1.95707 180)
			(unlocked yes)
			(layer "F.Fab")
			(effects
				(font
					(size 0.7874 0.5842)
					(thickness 0.000001)
				)
				(justify left)
			)
		)
		(pad "B" smd rect
			(at 0 0 270)
			(size 0.8128 0.9144)
			(layers "F.Cu" "F.Mask" "F.Paste")
			(net "FM_NODE1_DDR3_DRAM_POK_R_L")
		)
		(pad "C" smd rect
			(at 1.999996 0.94996 270)
			(size 0.8128 0.9144)
			(layers "F.Cu" "F.Mask" "F.Paste")
			(net "PWRGD_NODE1_DDR3_DRAM_POK")
		)
		(pad "E" smd rect
			(at 0 1.89992 270)
			(size 0.8128 0.9144)
			(layers "F.Cu" "F.Mask" "F.Paste")
			(net "GND")
		)
	)
	(footprint ""
		(layer "F.Cu")
		(at 15.301468 -54.773322 -90)
		(property "Reference" "C504"
			(at 1.05918 -14.450314 90)
			(unlocked yes)
			(layer "F.SilkS")
			(effects
				(font
					(size 0.7874 0.5842)
					(thickness 0.1524)
				)
			)
		)
		(property "Value" ""
			(at 0 0 270)
			(layer "F.Fab")
			(effects
				(font
					(size 1.27 1.27)
				)
			)
		)
		(duplicate_pad_numbers_are_jumpers no)
		(fp_line
			(start -1.2954 0.5842)
			(end -1.2954 -0.5842)
			(stroke
				(width 0.1524)
				(type default)
			)
			(layer "F.SilkS")
		)
		(fp_line
			(start 1.2954 0.5842)
			(end -1.2954 0.5842)
			(stroke
				(width 0.1524)
				(type default)
			)
			(layer "F.SilkS")
		)
		(fp_line
			(start -1.2954 -0.5842)
			(end 1.2954 -0.5842)
			(stroke
				(width 0.1524)
				(type default)
			)
			(layer "F.SilkS")
		)
		(fp_line
			(start 0 -0.5842)
			(end 0 0.5842)
			(stroke
				(width 0.1524)
				(type default)
			)
			(layer "F.SilkS")
		)
		(fp_line
			(start 1.2954 -0.5842)
			(end 1.2954 0.5842)
			(stroke
				(width 0.1524)
				(type default)
			)
			(layer "F.SilkS")
		)
		(fp_poly
			(pts
				(xy 0.8636 -0.4572) (xy 0.8636 -0.3556) (xy 1.143 -0.3556) (xy 1.143 0.3556) (xy 0.8636 0.3556)
				(xy 0.8636 0.4572) (xy -0.8636 0.4572) (xy -0.8636 0.3556) (xy -1.143 0.3556) (xy -1.143 -0.3556)
				(xy -0.8636 -0.3556) (xy -0.8636 -0.4572)
			)
			(stroke
				(width 0)
				(type default)
			)
			(fill no)
			(layer "F.CrtYd")
		)
		(fp_line
			(start -0.884936 0.504952)
			(end -0.884936 -0.504952)
			(stroke
				(width 0.1)
				(type default)
			)
			(layer "F.Fab")
		)
		(fp_line
			(start 0.884936 0.504952)
			(end -0.884936 0.504952)
			(stroke
				(width 0.1)
				(type default)
			)
			(layer "F.Fab")
		)
		(fp_line
			(start -0.884936 -0.504952)
			(end 0.884936 -0.504952)
			(stroke
				(width 0.1)
				(type default)
			)
			(layer "F.Fab")
		)
		(fp_line
			(start 0.884936 -0.504952)
			(end 0.884936 0.504952)
			(stroke
				(width 0.1)
				(type default)
			)
			(layer "F.Fab")
		)
		(pad "1" smd rect
			(at 0.7366 0)
			(size 0.7112 0.8128)
			(layers "F.Cu" "F.Mask" "F.Paste")
			(net "CRT_B")
		)
		(pad "2" smd rect
			(at -0.7366 0)
			(size 0.7112 0.8128)
			(layers "F.Cu" "F.Mask" "F.Paste")
			(net "GND")
		)
	)
	(footprint ""
		(layer "F.Cu")
		(at 129.27457 -26.569416 -90)
		(property "Reference" "R1141"
			(at 5.325618 -0.028448 90)
			(unlocked yes)
			(layer "F.SilkS")
			(effects
				(font
					(size 0.7874 0.5842)
					(thickness 0.1524)
				)
				(justify left)
			)
		)
		(property "Value" ""
			(at 0 0 270)
			(layer "F.Fab")
			(effects
				(font
					(size 1.27 1.27)
				)
			)
		)
		(duplicate_pad_numbers_are_jumpers no)
		(fp_line
			(start -0.7874 0.4064)
			(end -0.7874 -0.4064)
			(stroke
				(width 0.1524)
				(type default)
			)
			(layer "F.SilkS")
		)
		(fp_line
			(start 0.7874 0.4064)
			(end -0.7874 0.4064)
			(stroke
				(width 0.1524)
				(type default)
			)
			(layer "F.SilkS")
		)
		(fp_line
			(start -0.7874 -0.4064)
			(end 0.7874 -0.4064)
			(stroke
				(width 0.1524)
				(type default)
			)
			(layer "F.SilkS")
		)
		(fp_line
			(start 0.7874 -0.4064)
			(end 0.7874 0.4064)
			(stroke
				(width 0.1524)
				(type default)
			)
			(layer "F.SilkS")
		)
		(fp_poly
			(pts
				(xy -0.508 0.2794) (xy -0.508 0.2286) (xy -0.635 0.2286) (xy -0.635 -0.254) (xy -0.5334 -0.254)
				(xy -0.5334 -0.2794) (xy 0.5334 -0.2794) (xy 0.5334 -0.254) (xy 0.635 -0.254) (xy 0.635 0.254) (xy 0.5334 0.254)
				(xy 0.5334 0.2794)
			)
			(stroke
				(width 0)
				(type default)
			)
			(fill no)
			(layer "F.CrtYd")
		)
		(pad "1" smd rect
			(at 0.40005 0 270)
			(size 0.4572 0.508)
			(layers "F.Cu" "F.Mask" "F.Paste")
			(net "P3V3_STB_NODE1")
		)
		(pad "2" smd rect
			(at -0.40005 0 270)
			(size 0.4572 0.508)
			(layers "F.Cu" "F.Mask" "F.Paste")
			(net "SIO_PIN76")
		)
	)
	(footprint ""
		(layer "F.Cu")
		(at 113.215166 -135.285734 -90)
		(property "Reference" "PC108"
			(at -1.990852 -5.870448 90)
			(unlocked yes)
			(layer "F.SilkS")
			(effects
				(font
					(size 0.635 0.4064)
					(thickness 0.1524)
				)
				(justify left)
			)
		)
		(property "Value" ""
			(at 0 0 270)
			(layer "F.Fab")
			(effects
				(font
					(size 1.27 1.27)
				)
			)
		)
		(duplicate_pad_numbers_are_jumpers no)
		(fp_line
			(start -0.7874 0.4064)
			(end -0.7874 -0.4064)
			(stroke
				(width 0.1524)
				(type default)
			)
			(layer "F.SilkS")
		)
		(fp_line
			(start 0.7874 0.4064)
			(end -0.7874 0.4064)
			(stroke
				(width 0.1524)
				(type default)
			)
			(layer "F.SilkS")
		)
		(fp_line
			(start 0 0.381)
			(end 0 -0.381)
			(stroke
				(width 0.1524)
				(type default)
			)
			(layer "F.SilkS")
		)
		(fp_line
			(start -0.7874 -0.4064)
			(end 0.7874 -0.4064)
			(stroke
				(width 0.1524)
				(type default)
			)
			(layer "F.SilkS")
		)
		(fp_line
			(start 0.7874 -0.4064)
			(end 0.7874 0.4064)
			(stroke
				(width 0.1524)
				(type default)
			)
			(layer "F.SilkS")
		)
		(fp_poly
			(pts
				(xy -0.5334 0.254) (xy -0.635 0.254) (xy -0.635 0.2286) (xy -0.635 -0.254) (xy -0.5334 -0.254) (xy -0.5334 -0.2794)
				(xy 0.5334 -0.2794) (xy 0.5334 -0.254) (xy 0.635 -0.254) (xy 0.635 0.254) (xy 0.5334 0.254) (xy 0.5334 0.2794)
				(xy -0.508 0.2794) (xy -0.5334 0.2794)
			)
			(stroke
				(width 0)
				(type default)
			)
			(fill no)
			(layer "F.CrtYd")
		)
		(pad "1" smd rect
			(at 0.40005 0 270)
			(size 0.4572 0.508)
			(layers "F.Cu" "F.Mask" "F.Paste")
			(net "VR_PVCCP_NODE1_COMP")
		)
		(pad "2" smd rect
			(at -0.40005 0 270)
			(size 0.4572 0.508)
			(layers "F.Cu" "F.Mask" "F.Paste")
			(net "AGND_PVCCP_NODE1")
		)
	)
	(footprint ""
		(layer "F.Cu")
		(at 82.429096 -151.688292)
		(property "Reference" "PR3"
			(at 1.086104 0.663194 0)
			(unlocked yes)
			(layer "F.SilkS")
			(effects
				(font
					(size 0.7874 0.5842)
					(thickness 0.1524)
				)
				(justify left)
			)
		)
		(property "Value" ""
			(at 0 0 0)
			(layer "F.Fab")
			(effects
				(font
					(size 1.27 1.27)
				)
			)
		)
		(duplicate_pad_numbers_are_jumpers no)
		(fp_line
			(start -0.7874 -0.4064)
			(end 0.7874 -0.4064)
			(stroke
				(width 0.1524)
				(type default)
			)
			(layer "F.SilkS")
		)
		(fp_line
			(start -0.7874 0.4064)
			(end -0.7874 -0.4064)
			(stroke
				(width 0.1524)
				(type default)
			)
			(layer "F.SilkS")
		)
		(fp_line
			(start 0.7874 -0.4064)
			(end 0.7874 0.4064)
			(stroke
				(width 0.1524)
				(type default)
			)
			(layer "F.SilkS")
		)
		(fp_line
			(start 0.7874 0.4064)
			(end -0.7874 0.4064)
			(stroke
				(width 0.1524)
				(type default)
			)
			(layer "F.SilkS")
		)
		(fp_poly
			(pts
				(xy -0.508 0.2794) (xy -0.508 0.2286) (xy -0.635 0.2286) (xy -0.635 -0.254) (xy -0.5334 -0.254)
				(xy -0.5334 -0.2794) (xy 0.5334 -0.2794) (xy 0.5334 -0.254) (xy 0.635 -0.254) (xy 0.635 0.254) (xy 0.5334 0.254)
				(xy 0.5334 0.2794)
			)
			(stroke
				(width 0)
				(type default)
			)
			(fill no)
			(layer "F.CrtYd")
		)
		(pad "1" smd rect
			(at 0.40005 0)
			(size 0.4572 0.508)
			(layers "F.Cu" "F.Mask" "F.Paste")
			(net "P5V_STB_NODE1_FB")
		)
		(pad "2" smd rect
			(at -0.40005 0)
			(size 0.4572 0.508)
			(layers "F.Cu" "F.Mask" "F.Paste")
			(net "P5V_STB_NODE1")
		)
	)
	(footprint ""
		(layer "F.Cu")
		(at 35.243008 -185.604404)
		(property "Reference" "C767"
			(at -1.53162 -5.211064 0)
			(unlocked yes)
			(layer "F.SilkS")
			(effects
				(font
					(size 0.7874 0.5842)
					(thickness 0.1524)
				)
				(justify left)
			)
		)
		(property "Value" ""
			(at 0 0 0)
			(layer "F.Fab")
			(effects
				(font
					(size 1.27 1.27)
				)
			)
		)
		(duplicate_pad_numbers_are_jumpers no)
		(fp_line
			(start -0.7874 -0.4064)
			(end 0.7874 -0.4064)
			(stroke
				(width 0.1524)
				(type default)
			)
			(layer "F.SilkS")
		)
		(fp_line
			(start -0.7874 0.4064)
			(end -0.7874 -0.4064)
			(stroke
				(width 0.1524)
				(type default)
			)
			(layer "F.SilkS")
		)
		(fp_line
			(start 0 0.381)
			(end 0 -0.381)
			(stroke
				(width 0.1524)
				(type default)
			)
			(layer "F.SilkS")
		)
		(fp_line
			(start 0.7874 -0.4064)
			(end 0.7874 0.4064)
			(stroke
				(width 0.1524)
				(type default)
			)
			(layer "F.SilkS")
		)
		(fp_line
			(start 0.7874 0.4064)
			(end -0.7874 0.4064)
			(stroke
				(width 0.1524)
				(type default)
			)
			(layer "F.SilkS")
		)
		(fp_poly
			(pts
				(xy -0.5334 0.254) (xy -0.635 0.254) (xy -0.635 0.2286) (xy -0.635 -0.254) (xy -0.5334 -0.254) (xy -0.5334 -0.2794)
				(xy 0.5334 -0.2794) (xy 0.5334 -0.254) (xy 0.635 -0.254) (xy 0.635 0.254) (xy 0.5334 0.254) (xy 0.5334 0.2794)
				(xy -0.508 0.2794) (xy -0.5334 0.2794)
			)
			(stroke
				(width 0)
				(type default)
			)
			(fill no)
			(layer "F.CrtYd")
		)
		(pad "1" smd rect
			(at 0.40005 0)
			(size 0.4572 0.508)
			(layers "F.Cu" "F.Mask" "F.Paste")
			(net "P12V_PDB")
		)
		(pad "2" smd rect
			(at -0.40005 0)
			(size 0.4572 0.508)
			(layers "F.Cu" "F.Mask" "F.Paste")
			(net "GND")
		)
	)
	(footprint ""
		(layer "F.Cu")
		(at 114.849656 -111.43107 90)
		(property "Reference" "PC99"
			(at -1.293622 4.680204 0)
			(unlocked yes)
			(layer "F.SilkS")
			(effects
				(font
					(size 0.7874 0.5842)
					(thickness 0.1524)
				)
				(justify left)
			)
		)
		(property "Value" ""
			(at 0 0 90)
			(layer "F.Fab")
			(effects
				(font
					(size 1.27 1.27)
				)
			)
		)
		(duplicate_pad_numbers_are_jumpers no)
		(fp_line
			(start 2.249932 -4.533392)
			(end 2.249932 4.533392)
			(stroke
				(width 0.1524)
				(type default)
			)
			(layer "F.SilkS")
		)
		(fp_line
			(start -2.249932 -4.533392)
			(end 2.249932 -4.533392)
			(stroke
				(width 0.1524)
				(type default)
			)
			(layer "F.SilkS")
		)
		(fp_line
			(start 2.249932 4.533392)
			(end -2.249932 4.533392)
			(stroke
				(width 0.1524)
				(type default)
			)
			(layer "F.SilkS")
		)
		(fp_line
			(start -2.249932 4.533392)
			(end -2.249932 -4.533392)
			(stroke
				(width 0.1524)
				(type default)
			)
			(layer "F.SilkS")
		)
		(fp_poly
			(pts
				(xy 2.326132 -4.533392) (xy 2.326132 -5.39242) (xy -2.326132 -5.39242) (xy -2.326132 -4.533392)
			)
			(stroke
				(width 0)
				(type default)
			)
			(fill yes)
			(layer "F.SilkS")
		)
		(fp_poly
			(pts
				(xy -1.4605 4.457192) (xy -1.4605 3.750056) (xy -2.249932 3.750056) (xy -2.249932 -3.750056) (xy -1.4605 -3.750056)
				(xy -1.4605 -4.457192) (xy 1.4605 -4.457192) (xy 1.4605 -3.750056) (xy 2.249932 -3.750056) (xy 2.249932 3.750056)
				(xy 1.4605 3.750056) (xy 1.4605 4.457192)
			)
			(stroke
				(width 0)
				(type default)
			)
			(fill no)
			(layer "F.CrtYd")
		)
		(fp_line
			(start 2.249932 -3.750056)
			(end 2.249932 3.750056)
			(stroke
				(width 0.1)
				(type default)
			)
			(layer "F.Fab")
		)
		(fp_line
			(start -2.249932 -3.750056)
			(end 2.249932 -3.750056)
			(stroke
				(width 0.1)
				(type default)
			)
			(layer "F.Fab")
		)
		(fp_line
			(start 2.249932 3.750056)
			(end -2.249932 3.750056)
			(stroke
				(width 0.1)
				(type default)
			)
			(layer "F.Fab")
		)
		(fp_line
			(start -2.249932 3.750056)
			(end -2.249932 -3.750056)
			(stroke
				(width 0.1)
				(type default)
			)
			(layer "F.Fab")
		)
		(fp_text user "+"
			(at 0.29972 -5.594096 180)
			(unlocked yes)
			(layer "F.SilkS")
			(effects
				(font
					(size 1.6002 1.1938)
					(thickness 0.1524)
				)
				(justify left)
			)
		)
		(fp_text user "+"
			(at -0.786384 -6.322314 90)
			(unlocked yes)
			(layer "F.Fab")
			(effects
				(font
					(size 1.905 1.4224)
					(thickness 0.000001)
				)
				(justify left)
			)
		)
		(pad "1" smd rect
			(at 0 -3.199892)
			(size 2.413 2.8194)
			(layers "F.Cu" "F.Mask" "F.Paste")
			(net "PV_VCCP_NODE1")
		)
		(pad "2" smd rect
			(at 0 3.199892)
			(size 2.413 2.8194)
			(layers "F.Cu" "F.Mask" "F.Paste")
			(net "GND")
		)
	)
	(footprint ""
		(layer "F.Cu")
		(at 80.908652 -117.802406)
		(property "Reference" "C1121"
			(at -0.1016 4.228846 90)
			(unlocked yes)
			(layer "F.SilkS")
			(effects
				(font
					(size 0.7874 0.5842)
					(thickness 0.1524)
				)
				(justify left)
			)
		)
		(property "Value" ""
			(at 0 0 0)
			(layer "F.Fab")
			(effects
				(font
					(size 1.27 1.27)
				)
			)
		)
		(duplicate_pad_numbers_are_jumpers no)
		(fp_line
			(start -0.7874 -0.4064)
			(end 0.7874 -0.4064)
			(stroke
				(width 0.1524)
				(type default)
			)
			(layer "F.SilkS")
		)
		(fp_line
			(start -0.7874 0.4064)
			(end -0.7874 -0.4064)
			(stroke
				(width 0.1524)
				(type default)
			)
			(layer "F.SilkS")
		)
		(fp_line
			(start 0 0.381)
			(end 0 -0.381)
			(stroke
				(width 0.1524)
				(type default)
			)
			(layer "F.SilkS")
		)
		(fp_line
			(start 0.7874 -0.4064)
			(end 0.7874 0.4064)
			(stroke
				(width 0.1524)
				(type default)
			)
			(layer "F.SilkS")
		)
		(fp_line
			(start 0.7874 0.4064)
			(end -0.7874 0.4064)
			(stroke
				(width 0.1524)
				(type default)
			)
			(layer "F.SilkS")
		)
		(fp_poly
			(pts
				(xy -0.5334 0.254) (xy -0.635 0.254) (xy -0.635 0.2286) (xy -0.635 -0.254) (xy -0.5334 -0.254) (xy -0.5334 -0.2794)
				(xy 0.5334 -0.2794) (xy 0.5334 -0.254) (xy 0.635 -0.254) (xy 0.635 0.254) (xy 0.5334 0.254) (xy 0.5334 0.2794)
				(xy -0.508 0.2794) (xy -0.5334 0.2794)
			)
			(stroke
				(width 0)
				(type default)
			)
			(fill no)
			(layer "F.CrtYd")
		)
		(pad "1" smd rect
			(at 0.40005 0)
			(size 0.4572 0.508)
			(layers "F.Cu" "F.Mask" "F.Paste")
			(net "P3V3_NODE1")
		)
		(pad "2" smd rect
			(at -0.40005 0)
			(size 0.4572 0.508)
			(layers "F.Cu" "F.Mask" "F.Paste")
			(net "GND")
		)
	)
	(footprint ""
		(layer "F.Cu")
		(at 84.150708 -108.79963 -90)
		(property "Reference" "R1101"
			(at 1.906524 0.75438 0)
			(unlocked yes)
			(layer "F.SilkS")
			(effects
				(font
					(size 0.7874 0.5842)
					(thickness 0.1524)
				)
				(justify left)
			)
		)
		(property "Value" ""
			(at 0 0 270)
			(layer "F.Fab")
			(effects
				(font
					(size 1.27 1.27)
				)
			)
		)
		(duplicate_pad_numbers_are_jumpers no)
		(fp_line
			(start -0.7874 0.4064)
			(end -0.7874 -0.4064)
			(stroke
				(width 0.1524)
				(type default)
			)
			(layer "F.SilkS")
		)
		(fp_line
			(start 0.7874 0.4064)
			(end -0.7874 0.4064)
			(stroke
				(width 0.1524)
				(type default)
			)
			(layer "F.SilkS")
		)
		(fp_line
			(start -0.7874 -0.4064)
			(end 0.7874 -0.4064)
			(stroke
				(width 0.1524)
				(type default)
			)
			(layer "F.SilkS")
		)
		(fp_line
			(start 0.7874 -0.4064)
			(end 0.7874 0.4064)
			(stroke
				(width 0.1524)
				(type default)
			)
			(layer "F.SilkS")
		)
		(fp_poly
			(pts
				(xy -0.508 0.2794) (xy -0.508 0.2286) (xy -0.635 0.2286) (xy -0.635 -0.254) (xy -0.5334 -0.254)
				(xy -0.5334 -0.2794) (xy 0.5334 -0.2794) (xy 0.5334 -0.254) (xy 0.635 -0.254) (xy 0.635 0.254) (xy 0.5334 0.254)
				(xy 0.5334 0.2794)
			)
			(stroke
				(width 0)
				(type default)
			)
			(fill no)
			(layer "F.CrtYd")
		)
		(pad "1" smd rect
			(at 0.40005 0 270)
			(size 0.4572 0.508)
			(layers "F.Cu" "F.Mask" "F.Paste")
			(net "FM_CPLD_NODE1_P3V3_SUS_EN_G")
		)
		(pad "2" smd rect
			(at -0.40005 0 270)
			(size 0.4572 0.508)
			(layers "F.Cu" "F.Mask" "F.Paste")
			(net "P3V3_STB_NODE1")
		)
	)
	(footprint ""
		(layer "F.Cu")
		(at 169.71899 -41.165018 90)
		(property "Reference" "L43"
			(at -1.774952 -1.322832 0)
			(unlocked yes)
			(layer "F.SilkS")
			(effects
				(font
					(size 0.7874 0.5842)
					(thickness 0.1524)
				)
				(justify left)
			)
		)
		(property "Value" ""
			(at 0 0 90)
			(layer "F.Fab")
			(effects
				(font
					(size 1.27 1.27)
				)
			)
		)
		(duplicate_pad_numbers_are_jumpers no)
		(fp_line
			(start 0.989838 -2.0066)
			(end 0.989838 2.0066)
			(stroke
				(width 0.1524)
				(type default)
			)
			(layer "F.SilkS")
		)
		(fp_line
			(start -1.015238 -2.0066)
			(end 0.989838 -2.0066)
			(stroke
				(width 0.1524)
				(type default)
			)
			(layer "F.SilkS")
		)
		(fp_line
			(start 0.989838 2.0066)
			(end -1.015238 2.0066)
			(stroke
				(width 0.1524)
				(type default)
			)
			(layer "F.SilkS")
		)
		(fp_line
			(start -1.015238 2.0066)
			(end -1.015238 -2.0066)
			(stroke
				(width 0.1524)
				(type default)
			)
			(layer "F.SilkS")
		)
		(fp_poly
			(pts
				(xy -0.899922 -1.700022) (xy -0.899922 1.700022) (xy -0.8636 1.700022) (xy -0.8636 1.9304) (xy -0.127 1.9304)
				(xy -0.127 1.700022) (xy 0.127 1.700022) (xy 0.127 1.9304) (xy 0.8636 1.9304) (xy 0.8636 1.700022)
				(xy 0.899922 1.700022) (xy 0.899922 -1.700022) (xy 0.8636 -1.700022) (xy 0.8636 -1.9304) (xy 0.127 -1.9304)
				(xy 0.127 -1.700022) (xy -0.127 -1.700022) (xy -0.127 -1.9304) (xy -0.8636 -1.9304) (xy -0.8636 -1.700022)
			)
			(stroke
				(width 0)
				(type default)
			)
			(fill no)
			(layer "F.CrtYd")
		)
		(fp_line
			(start 0.899922 -1.700022)
			(end 0.899922 1.700022)
			(stroke
				(width 0.1)
				(type default)
			)
			(layer "F.Fab")
		)
		(fp_line
			(start -0.899922 -1.700022)
			(end 0.899922 -1.700022)
			(stroke
				(width 0.1)
				(type default)
			)
			(layer "F.Fab")
		)
		(fp_line
			(start 0.899922 1.700022)
			(end -0.899922 1.700022)
			(stroke
				(width 0.1)
				(type default)
			)
			(layer "F.Fab")
		)
		(fp_line
			(start -0.899922 1.700022)
			(end -0.899922 -1.700022)
			(stroke
				(width 0.1)
				(type default)
			)
			(layer "F.Fab")
		)
		(pad "1" smd rect
			(at -0.499872 -1.400048 90)
			(size 0.6096 0.9144)
			(layers "F.Cu" "F.Mask" "F.Paste")
			(net "USB1_DN")
		)
		(pad "2" smd rect
			(at -0.499872 1.400048 90)
			(size 0.6096 0.9144)
			(layers "F.Cu" "F.Mask" "F.Paste")
			(net "USB1_L_DN")
		)
		(pad "3" smd rect
			(at 0.499872 1.400048 90)
			(size 0.6096 0.9144)
			(layers "F.Cu" "F.Mask" "F.Paste")
			(net "USB1_L_DP")
		)
		(pad "4" smd rect
			(at 0.499872 -1.400048 90)
			(size 0.6096 0.9144)
			(layers "F.Cu" "F.Mask" "F.Paste")
			(net "USB1_DP")
		)
	)
	(footprint ""
		(layer "F.Cu")
		(at 45.339762 -185.552334 180)
		(property "Reference" "C604"
			(at -0.102616 3.141726 90)
			(unlocked yes)
			(layer "F.SilkS")
			(effects
				(font
					(size 0.7874 0.5842)
					(thickness 0.1524)
				)
				(justify left)
			)
		)
		(property "Value" ""
			(at 0 0 180)
			(layer "F.Fab")
			(effects
				(font
					(size 1.27 1.27)
				)
			)
		)
		(duplicate_pad_numbers_are_jumpers no)
		(fp_line
			(start 0.7874 0.4064)
			(end -0.7874 0.4064)
			(stroke
				(width 0.1524)
				(type default)
			)
			(layer "F.SilkS")
		)
		(fp_line
			(start 0.7874 -0.4064)
			(end 0.7874 0.4064)
			(stroke
				(width 0.1524)
				(type default)
			)
			(layer "F.SilkS")
		)
		(fp_line
			(start 0 0.381)
			(end 0 -0.381)
			(stroke
				(width 0.1524)
				(type default)
			)
			(layer "F.SilkS")
		)
		(fp_line
			(start -0.7874 0.4064)
			(end -0.7874 -0.4064)
			(stroke
				(width 0.1524)
				(type default)
			)
			(layer "F.SilkS")
		)
		(fp_line
			(start -0.7874 -0.4064)
			(end 0.7874 -0.4064)
			(stroke
				(width 0.1524)
				(type default)
			)
			(layer "F.SilkS")
		)
		(fp_poly
			(pts
				(xy -0.5334 0.254) (xy -0.635 0.254) (xy -0.635 0.2286) (xy -0.635 -0.254) (xy -0.5334 -0.254) (xy -0.5334 -0.2794)
				(xy 0.5334 -0.2794) (xy 0.5334 -0.254) (xy 0.635 -0.254) (xy 0.635 0.254) (xy 0.5334 0.254) (xy 0.5334 0.2794)
				(xy -0.508 0.2794) (xy -0.5334 0.2794)
			)
			(stroke
				(width 0)
				(type default)
			)
			(fill no)
			(layer "F.CrtYd")
		)
		(pad "1" smd rect
			(at 0.40005 0 180)
			(size 0.4572 0.508)
			(layers "F.Cu" "F.Mask" "F.Paste")
			(net "MATE_N")
		)
		(pad "2" smd rect
			(at -0.40005 0 180)
			(size 0.4572 0.508)
			(layers "F.Cu" "F.Mask" "F.Paste")
			(net "GND")
		)
	)
	(footprint ""
		(layer "F.Cu")
		(at 20.419314 -62.200536 90)
		(property "Reference" "R631"
			(at -1.28016 2.460498 90)
			(unlocked yes)
			(layer "F.SilkS")
			(effects
				(font
					(size 0.7874 0.5842)
					(thickness 0.1524)
				)
				(justify left)
			)
		)
		(property "Value" ""
			(at 0 0 90)
			(layer "F.Fab")
			(effects
				(font
					(size 1.27 1.27)
				)
			)
		)
		(duplicate_pad_numbers_are_jumpers no)
		(fp_line
			(start 0.7874 -0.4064)
			(end 0.7874 0.4064)
			(stroke
				(width 0.1524)
				(type default)
			)
			(layer "F.SilkS")
		)
		(fp_line
			(start -0.7874 -0.4064)
			(end 0.7874 -0.4064)
			(stroke
				(width 0.1524)
				(type default)
			)
			(layer "F.SilkS")
		)
		(fp_line
			(start 0.7874 0.4064)
			(end -0.7874 0.4064)
			(stroke
				(width 0.1524)
				(type default)
			)
			(layer "F.SilkS")
		)
		(fp_line
			(start -0.7874 0.4064)
			(end -0.7874 -0.4064)
			(stroke
				(width 0.1524)
				(type default)
			)
			(layer "F.SilkS")
		)
		(fp_poly
			(pts
				(xy -0.508 0.2794) (xy -0.508 0.2286) (xy -0.635 0.2286) (xy -0.635 -0.254) (xy -0.5334 -0.254)
				(xy -0.5334 -0.2794) (xy 0.5334 -0.2794) (xy 0.5334 -0.254) (xy 0.635 -0.254) (xy 0.635 0.254) (xy 0.5334 0.254)
				(xy 0.5334 0.2794)
			)
			(stroke
				(width 0)
				(type default)
			)
			(fill no)
			(layer "F.CrtYd")
		)
		(pad "1" smd rect
			(at 0.40005 0 90)
			(size 0.4572 0.508)
			(layers "F.Cu" "F.Mask" "F.Paste")
			(net "P3V3_NODE1")
		)
		(pad "2" smd rect
			(at -0.40005 0 90)
			(size 0.4572 0.508)
			(layers "F.Cu" "F.Mask" "F.Paste")
			(net "N21581283")
		)
	)
	(footprint ""
		(layer "F.Cu")
		(at 135.37057 -26.569416 -90)
		(property "Reference" "R1149"
			(at 5.325618 -0.255778 90)
			(unlocked yes)
			(layer "F.SilkS")
			(effects
				(font
					(size 0.7874 0.5842)
					(thickness 0.1524)
				)
				(justify left)
			)
		)
		(property "Value" ""
			(at 0 0 270)
			(layer "F.Fab")
			(effects
				(font
					(size 1.27 1.27)
				)
			)
		)
		(duplicate_pad_numbers_are_jumpers no)
		(fp_line
			(start -0.7874 0.4064)
			(end -0.7874 -0.4064)
			(stroke
				(width 0.1524)
				(type default)
			)
			(layer "F.SilkS")
		)
		(fp_line
			(start 0.7874 0.4064)
			(end -0.7874 0.4064)
			(stroke
				(width 0.1524)
				(type default)
			)
			(layer "F.SilkS")
		)
		(fp_line
			(start -0.7874 -0.4064)
			(end 0.7874 -0.4064)
			(stroke
				(width 0.1524)
				(type default)
			)
			(layer "F.SilkS")
		)
		(fp_line
			(start 0.7874 -0.4064)
			(end 0.7874 0.4064)
			(stroke
				(width 0.1524)
				(type default)
			)
			(layer "F.SilkS")
		)
		(fp_poly
			(pts
				(xy -0.508 0.2794) (xy -0.508 0.2286) (xy -0.635 0.2286) (xy -0.635 -0.254) (xy -0.5334 -0.254)
				(xy -0.5334 -0.2794) (xy 0.5334 -0.2794) (xy 0.5334 -0.254) (xy 0.635 -0.254) (xy 0.635 0.254) (xy 0.5334 0.254)
				(xy 0.5334 0.2794)
			)
			(stroke
				(width 0)
				(type default)
			)
			(fill no)
			(layer "F.CrtYd")
		)
		(pad "1" smd rect
			(at 0.40005 0 270)
			(size 0.4572 0.508)
			(layers "F.Cu" "F.Mask" "F.Paste")
			(net "P3V3_STB_NODE1")
		)
		(pad "2" smd rect
			(at -0.40005 0 270)
			(size 0.4572 0.508)
			(layers "F.Cu" "F.Mask" "F.Paste")
			(net "UART_RTS_P6_N")
		)
	)
	(footprint ""
		(layer "F.Cu")
		(at 25.000204 -26.800048)
		(property "Reference" "H9"
			(at 0 0 0)
			(layer "F.SilkS")
			(hide yes)
			(effects
				(font
					(size 1.27 1.27)
				)
			)
		)
		(property "Value" ""
			(at 0 0 0)
			(layer "F.Fab")
			(effects
				(font
					(size 1.27 1.27)
				)
			)
		)
		(duplicate_pad_numbers_are_jumpers no)
		(fp_poly
			(pts
				(arc
					(start 5.999734 5.050028)
					(mid 0 10.999933)
					(end -5.999734 5.050028)
				)
				(arc
					(start -5.999988 0.000254)
					(mid 0 -5.999988)
					(end 5.999988 0.000254)
				)
			)
			(stroke
				(width 0)
				(type default)
			)
			(fill no)
			(layer "B.CrtYd")
		)
		(fp_poly
			(pts
				(arc
					(start 5.999734 5.050028)
					(mid 0 10.999933)
					(end -5.999734 5.050028)
				)
				(arc
					(start -5.999988 0.000254)
					(mid 0 -5.999988)
					(end 5.999988 0.000254)
				)
			)
			(stroke
				(width 0)
				(type default)
			)
			(fill no)
			(layer "F.CrtYd")
		)
		(pad "" np_thru_hole circle
			(at 0 0)
			(size 3.6068 3.6068)
			(drill 3.6068)
			(layers "*.Cu" "*.Mask")
			(clearance 0.381)
			(thermal_gap 0.381)
		)
	)
	(footprint ""
		(layer "F.Cu")
		(at 64.864234 -152.974548)
		(property "Reference" "PC7"
			(at -32.356806 -5.850128 0)
			(unlocked yes)
			(layer "F.SilkS")
			(effects
				(font
					(size 0.7874 0.5842)
					(thickness 0.1524)
				)
				(justify left)
			)
		)
		(property "Value" ""
			(at 0 0 0)
			(layer "F.Fab")
			(effects
				(font
					(size 1.27 1.27)
				)
			)
		)
		(duplicate_pad_numbers_are_jumpers no)
		(fp_line
			(start -0.7874 -0.4064)
			(end 0.7874 -0.4064)
			(stroke
				(width 0.1524)
				(type default)
			)
			(layer "F.SilkS")
		)
		(fp_line
			(start -0.7874 0.4064)
			(end -0.7874 -0.4064)
			(stroke
				(width 0.1524)
				(type default)
			)
			(layer "F.SilkS")
		)
		(fp_line
			(start 0 0.381)
			(end 0 -0.381)
			(stroke
				(width 0.1524)
				(type default)
			)
			(layer "F.SilkS")
		)
		(fp_line
			(start 0.7874 -0.4064)
			(end 0.7874 0.4064)
			(stroke
				(width 0.1524)
				(type default)
			)
			(layer "F.SilkS")
		)
		(fp_line
			(start 0.7874 0.4064)
			(end -0.7874 0.4064)
			(stroke
				(width 0.1524)
				(type default)
			)
			(layer "F.SilkS")
		)
		(fp_poly
			(pts
				(xy -0.5334 0.254) (xy -0.635 0.254) (xy -0.635 0.2286) (xy -0.635 -0.254) (xy -0.5334 -0.254) (xy -0.5334 -0.2794)
				(xy 0.5334 -0.2794) (xy 0.5334 -0.254) (xy 0.635 -0.254) (xy 0.635 0.254) (xy 0.5334 0.254) (xy 0.5334 0.2794)
				(xy -0.508 0.2794) (xy -0.5334 0.2794)
			)
			(stroke
				(width 0)
				(type default)
			)
			(fill no)
			(layer "F.CrtYd")
		)
		(pad "1" smd rect
			(at 0.40005 0)
			(size 0.4572 0.508)
			(layers "F.Cu" "F.Mask" "F.Paste")
			(net "P5V_STB_NODE1")
		)
		(pad "2" smd rect
			(at -0.40005 0)
			(size 0.4572 0.508)
			(layers "F.Cu" "F.Mask" "F.Paste")
			(net "GND")
		)
	)
	(footprint ""
		(layer "F.Cu")
		(at 157.33776 -185.205624 -90)
		(property "Reference" "R823"
			(at -4.768088 -0.297942 90)
			(unlocked yes)
			(layer "F.SilkS")
			(effects
				(font
					(size 0.7874 0.5842)
					(thickness 0.1524)
				)
				(justify left)
			)
		)
		(property "Value" ""
			(at 0 0 270)
			(layer "F.Fab")
			(effects
				(font
					(size 1.27 1.27)
				)
			)
		)
		(duplicate_pad_numbers_are_jumpers no)
		(fp_line
			(start -0.7874 0.4064)
			(end -0.7874 -0.4064)
			(stroke
				(width 0.1524)
				(type default)
			)
			(layer "F.SilkS")
		)
		(fp_line
			(start 0.7874 0.4064)
			(end -0.7874 0.4064)
			(stroke
				(width 0.1524)
				(type default)
			)
			(layer "F.SilkS")
		)
		(fp_line
			(start -0.7874 -0.4064)
			(end 0.7874 -0.4064)
			(stroke
				(width 0.1524)
				(type default)
			)
			(layer "F.SilkS")
		)
		(fp_line
			(start 0.7874 -0.4064)
			(end 0.7874 0.4064)
			(stroke
				(width 0.1524)
				(type default)
			)
			(layer "F.SilkS")
		)
		(fp_poly
			(pts
				(xy -0.508 0.2794) (xy -0.508 0.2286) (xy -0.635 0.2286) (xy -0.635 -0.254) (xy -0.5334 -0.254)
				(xy -0.5334 -0.2794) (xy 0.5334 -0.2794) (xy 0.5334 -0.254) (xy 0.635 -0.254) (xy 0.635 0.254) (xy 0.5334 0.254)
				(xy 0.5334 0.2794)
			)
			(stroke
				(width 0)
				(type default)
			)
			(fill no)
			(layer "F.CrtYd")
		)
		(pad "1" smd rect
			(at 0.40005 0 270)
			(size 0.4572 0.508)
			(layers "F.Cu" "F.Mask" "F.Paste")
			(net "FAN2_TACH")
		)
		(pad "2" smd rect
			(at -0.40005 0 270)
			(size 0.4572 0.508)
			(layers "F.Cu" "F.Mask" "F.Paste")
			(net "FAN2_TACH_R")
		)
	)
	(footprint ""
		(layer "F.Cu")
		(at 150.478998 -142.88643 -90)
		(property "Reference" "R593"
			(at -1.435354 0.800354 90)
			(unlocked yes)
			(layer "F.SilkS")
			(effects
				(font
					(size 0.635 0.4064)
					(thickness 0.1524)
				)
				(justify left)
			)
		)
		(property "Value" ""
			(at 0 0 270)
			(layer "F.Fab")
			(effects
				(font
					(size 1.27 1.27)
				)
			)
		)
		(duplicate_pad_numbers_are_jumpers no)
		(fp_line
			(start -0.7874 0.4064)
			(end -0.7874 -0.4064)
			(stroke
				(width 0.1524)
				(type default)
			)
			(layer "F.SilkS")
		)
		(fp_line
			(start 0.7874 0.4064)
			(end -0.7874 0.4064)
			(stroke
				(width 0.1524)
				(type default)
			)
			(layer "F.SilkS")
		)
		(fp_line
			(start -0.7874 -0.4064)
			(end 0.7874 -0.4064)
			(stroke
				(width 0.1524)
				(type default)
			)
			(layer "F.SilkS")
		)
		(fp_line
			(start 0.7874 -0.4064)
			(end 0.7874 0.4064)
			(stroke
				(width 0.1524)
				(type default)
			)
			(layer "F.SilkS")
		)
		(fp_poly
			(pts
				(xy -0.508 0.2794) (xy -0.508 0.2286) (xy -0.635 0.2286) (xy -0.635 -0.254) (xy -0.5334 -0.254)
				(xy -0.5334 -0.2794) (xy 0.5334 -0.2794) (xy 0.5334 -0.254) (xy 0.635 -0.254) (xy 0.635 0.254) (xy 0.5334 0.254)
				(xy 0.5334 0.2794)
			)
			(stroke
				(width 0)
				(type default)
			)
			(fill no)
			(layer "F.CrtYd")
		)
		(pad "1" smd rect
			(at 0.40005 0 270)
			(size 0.4572 0.508)
			(layers "F.Cu" "F.Mask" "F.Paste")
			(net "SMB_PCH_SCL")
		)
		(pad "2" smd rect
			(at -0.40005 0 270)
			(size 0.4572 0.508)
			(layers "F.Cu" "F.Mask" "F.Paste")
			(net "SMB_LAN2_CLK")
		)
	)
	(footprint ""
		(layer "F.Cu")
		(at 150.649178 -73.937622 90)
		(property "Reference" "C332"
			(at -0.780034 2.370074 90)
			(unlocked yes)
			(layer "F.SilkS")
			(effects
				(font
					(size 0.7874 0.5842)
					(thickness 0.1524)
				)
				(justify left)
			)
		)
		(property "Value" ""
			(at 0 0 90)
			(layer "F.Fab")
			(effects
				(font
					(size 1.27 1.27)
				)
			)
		)
		(duplicate_pad_numbers_are_jumpers no)
		(fp_line
			(start 0.7874 -0.4064)
			(end 0.7874 0.4064)
			(stroke
				(width 0.1524)
				(type default)
			)
			(layer "F.SilkS")
		)
		(fp_line
			(start -0.7874 -0.4064)
			(end 0.7874 -0.4064)
			(stroke
				(width 0.1524)
				(type default)
			)
			(layer "F.SilkS")
		)
		(fp_line
			(start 0 0.381)
			(end 0 -0.381)
			(stroke
				(width 0.1524)
				(type default)
			)
			(layer "F.SilkS")
		)
		(fp_line
			(start 0.7874 0.4064)
			(end -0.7874 0.4064)
			(stroke
				(width 0.1524)
				(type default)
			)
			(layer "F.SilkS")
		)
		(fp_line
			(start -0.7874 0.4064)
			(end -0.7874 -0.4064)
			(stroke
				(width 0.1524)
				(type default)
			)
			(layer "F.SilkS")
		)
		(fp_poly
			(pts
				(xy -0.5334 0.254) (xy -0.635 0.254) (xy -0.635 0.2286) (xy -0.635 -0.254) (xy -0.5334 -0.254) (xy -0.5334 -0.2794)
				(xy 0.5334 -0.2794) (xy 0.5334 -0.254) (xy 0.635 -0.254) (xy 0.635 0.254) (xy 0.5334 0.254) (xy 0.5334 0.2794)
				(xy -0.508 0.2794) (xy -0.5334 0.2794)
			)
			(stroke
				(width 0)
				(type default)
			)
			(fill no)
			(layer "F.CrtYd")
		)
		(pad "1" smd rect
			(at 0.40005 0 90)
			(size 0.4572 0.508)
			(layers "F.Cu" "F.Mask" "F.Paste")
			(net "P2E_CPU_SATA_NODE1_RX_DN")
		)
		(pad "2" smd rect
			(at -0.40005 0 90)
			(size 0.4572 0.508)
			(layers "F.Cu" "F.Mask" "F.Paste")
			(net "P2E_CPU_SATA_NODE1_RX_C_DN")
		)
	)
	(footprint ""
		(layer "F.Cu")
		(at 114.046254 -61.255148)
		(property "Reference" "R229"
			(at 1.191768 1.859788 0)
			(unlocked yes)
			(layer "F.SilkS")
			(effects
				(font
					(size 0.7874 0.5842)
					(thickness 0.1524)
				)
				(justify left)
			)
		)
		(property "Value" ""
			(at 0 0 0)
			(layer "F.Fab")
			(effects
				(font
					(size 1.27 1.27)
				)
			)
		)
		(duplicate_pad_numbers_are_jumpers no)
		(fp_line
			(start -0.7874 -0.4064)
			(end 0.7874 -0.4064)
			(stroke
				(width 0.1524)
				(type default)
			)
			(layer "F.SilkS")
		)
		(fp_line
			(start -0.7874 0.4064)
			(end -0.7874 -0.4064)
			(stroke
				(width 0.1524)
				(type default)
			)
			(layer "F.SilkS")
		)
		(fp_line
			(start 0.7874 -0.4064)
			(end 0.7874 0.4064)
			(stroke
				(width 0.1524)
				(type default)
			)
			(layer "F.SilkS")
		)
		(fp_line
			(start 0.7874 0.4064)
			(end -0.7874 0.4064)
			(stroke
				(width 0.1524)
				(type default)
			)
			(layer "F.SilkS")
		)
		(fp_poly
			(pts
				(xy -0.508 0.2794) (xy -0.508 0.2286) (xy -0.635 0.2286) (xy -0.635 -0.254) (xy -0.5334 -0.254)
				(xy -0.5334 -0.2794) (xy 0.5334 -0.2794) (xy 0.5334 -0.254) (xy 0.635 -0.254) (xy 0.635 0.254) (xy 0.5334 0.254)
				(xy 0.5334 0.2794)
			)
			(stroke
				(width 0)
				(type default)
			)
			(fill no)
			(layer "F.CrtYd")
		)
		(pad "1" smd rect
			(at 0.40005 0)
			(size 0.4572 0.508)
			(layers "F.Cu" "F.Mask" "F.Paste")
			(net "GND")
		)
		(pad "2" smd rect
			(at -0.40005 0)
			(size 0.4572 0.508)
			(layers "F.Cu" "F.Mask" "F.Paste")
			(net "XDP_SOC_CPU_NODE1_TRST_L")
		)
	)
	(footprint ""
		(layer "F.Cu")
		(at 105.075228 -160.489138)
		(property "Reference" "R1129"
			(at 86.399624 70.566788 0)
			(unlocked yes)
			(layer "F.SilkS")
			(effects
				(font
					(size 0.7874 0.5842)
					(thickness 0.1524)
				)
				(justify left)
			)
		)
		(property "Value" ""
			(at 0 0 0)
			(layer "F.Fab")
			(effects
				(font
					(size 1.27 1.27)
				)
			)
		)
		(duplicate_pad_numbers_are_jumpers no)
		(fp_line
			(start -1.905 -0.8636)
			(end 1.905 -0.8636)
			(stroke
				(width 0.1524)
				(type default)
			)
			(layer "F.SilkS")
		)
		(fp_line
			(start -1.905 0.8636)
			(end -1.905 -0.8636)
			(stroke
				(width 0.1524)
				(type default)
			)
			(layer "F.SilkS")
		)
		(fp_line
			(start 1.905 -0.8636)
			(end 1.905 0.8636)
			(stroke
				(width 0.1524)
				(type default)
			)
			(layer "F.SilkS")
		)
		(fp_line
			(start 1.905 0.8636)
			(end -1.905 0.8636)
			(stroke
				(width 0.1524)
				(type default)
			)
			(layer "F.SilkS")
		)
		(fp_poly
			(pts
				(xy 1.524 0.6858) (xy 1.524 -0.6858) (xy 1.524 -0.7366) (xy -1.524 -0.7366) (xy -1.524 -0.6858)
				(xy -1.524 0.6858) (xy -1.524 0.7366) (xy 1.524 0.7366)
			)
			(stroke
				(width 0)
				(type default)
			)
			(fill no)
			(layer "F.CrtYd")
		)
		(pad "1" smd rect
			(at 0.94996 0)
			(size 1.1176 1.3716)
			(layers "F.Cu" "F.Mask" "F.Paste")
			(net "P12V_AUX")
		)
		(pad "2" smd rect
			(at -0.94996 0)
			(size 1.1176 1.3716)
			(layers "F.Cu" "F.Mask" "F.Paste")
			(net "N52411102")
		)
	)
	(footprint ""
		(layer "F.Cu")
		(at 139.93876 -185.205624 -90)
		(property "Reference" "R876"
			(at -4.768088 0.474472 90)
			(unlocked yes)
			(layer "F.SilkS")
			(effects
				(font
					(size 0.7874 0.5842)
					(thickness 0.1524)
				)
				(justify left)
			)
		)
		(property "Value" ""
			(at 0 0 270)
			(layer "F.Fab")
			(effects
				(font
					(size 1.27 1.27)
				)
			)
		)
		(duplicate_pad_numbers_are_jumpers no)
		(fp_line
			(start -0.7874 0.4064)
			(end -0.7874 -0.4064)
			(stroke
				(width 0.1524)
				(type default)
			)
			(layer "F.SilkS")
		)
		(fp_line
			(start 0.7874 0.4064)
			(end -0.7874 0.4064)
			(stroke
				(width 0.1524)
				(type default)
			)
			(layer "F.SilkS")
		)
		(fp_line
			(start -0.7874 -0.4064)
			(end 0.7874 -0.4064)
			(stroke
				(width 0.1524)
				(type default)
			)
			(layer "F.SilkS")
		)
		(fp_line
			(start 0.7874 -0.4064)
			(end 0.7874 0.4064)
			(stroke
				(width 0.1524)
				(type default)
			)
			(layer "F.SilkS")
		)
		(fp_poly
			(pts
				(xy -0.508 0.2794) (xy -0.508 0.2286) (xy -0.635 0.2286) (xy -0.635 -0.254) (xy -0.5334 -0.254)
				(xy -0.5334 -0.2794) (xy 0.5334 -0.2794) (xy 0.5334 -0.254) (xy 0.635 -0.254) (xy 0.635 0.254) (xy 0.5334 0.254)
				(xy 0.5334 0.2794)
			)
			(stroke
				(width 0)
				(type default)
			)
			(fill no)
			(layer "F.CrtYd")
		)
		(pad "1" smd rect
			(at 0.40005 0 270)
			(size 0.4572 0.508)
			(layers "F.Cu" "F.Mask" "F.Paste")
			(net "T10_NODE2_EN")
		)
		(pad "2" smd rect
			(at -0.40005 0 270)
			(size 0.4572 0.508)
			(layers "F.Cu" "F.Mask" "F.Paste")
			(net "T10_NODE2_EN_R")
		)
	)
	(footprint ""
		(layer "F.Cu")
		(at 5.076698 -97.303336 90)
		(property "Reference" "D28"
			(at 3.628644 0.295148 90)
			(unlocked yes)
			(layer "F.SilkS")
			(effects
				(font
					(size 0.7874 0.5842)
					(thickness 0.1524)
				)
				(justify left)
			)
		)
		(property "Value" ""
			(at 0 0 90)
			(layer "F.Fab")
			(effects
				(font
					(size 1.27 1.27)
				)
			)
		)
		(duplicate_pad_numbers_are_jumpers no)
		(fp_line
			(start 3.429 -1.397)
			(end -3.175 -1.397)
			(stroke
				(width 0.1524)
				(type default)
			)
			(layer "F.SilkS")
		)
		(fp_line
			(start 3.302 -1.397)
			(end 3.302 1.397)
			(stroke
				(width 0.1524)
				(type default)
			)
			(layer "F.SilkS")
		)
		(fp_line
			(start -3.175 -1.397)
			(end -3.175 1.397)
			(stroke
				(width 0.1524)
				(type default)
			)
			(layer "F.SilkS")
		)
		(fp_line
			(start 0.299974 -0.500126)
			(end 0.299974 0.500126)
			(stroke
				(width 0.1524)
				(type default)
			)
			(layer "F.SilkS")
		)
		(fp_line
			(start -0.299974 -0.500126)
			(end -0.299974 0.500126)
			(stroke
				(width 0.1524)
				(type default)
			)
			(layer "F.SilkS")
		)
		(fp_line
			(start 0.199898 0)
			(end -0.299974 -0.500126)
			(stroke
				(width 0.1524)
				(type default)
			)
			(layer "F.SilkS")
		)
		(fp_line
			(start -0.299974 0.500126)
			(end 0.199898 0)
			(stroke
				(width 0.1524)
				(type default)
			)
			(layer "F.SilkS")
		)
		(fp_line
			(start 3.429 1.397)
			(end 3.429 -1.397)
			(stroke
				(width 0.1524)
				(type default)
			)
			(layer "F.SilkS")
		)
		(fp_line
			(start 3.302 1.397)
			(end 3.299968 1.400048)
			(stroke
				(width 0.1524)
				(type default)
			)
			(layer "F.SilkS")
		)
		(fp_line
			(start 3.175 1.397)
			(end 3.175 -1.397)
			(stroke
				(width 0.1524)
				(type default)
			)
			(layer "F.SilkS")
		)
		(fp_line
			(start -3.175 1.397)
			(end 3.429 1.397)
			(stroke
				(width 0.1524)
				(type default)
			)
			(layer "F.SilkS")
		)
		(fp_poly
			(pts
				(xy -2.6416 1.397) (xy -2.6416 1.016) (xy -3.0226 1.016) (xy -3.0226 -1.016) (xy -2.667 -1.016)
				(xy -2.667 -1.397) (xy 2.667 -1.397) (xy 2.667 -1.016) (xy 3.0226 -1.016) (xy 3.0226 1.016) (xy 2.667 1.016)
				(xy 2.667 1.397)
			)
			(stroke
				(width 0)
				(type default)
			)
			(fill no)
			(layer "F.CrtYd")
		)
		(pad "1" smd rect
			(at -2.249932 0 270)
			(size 1.524 2.032)
			(layers "F.Cu" "F.Mask" "F.Paste")
			(net "P12V_DBG")
		)
		(pad "2" smd rect
			(at 2.249932 0 90)
			(size 1.524 2.032)
			(layers "F.Cu" "F.Mask" "F.Paste")
			(net "P12V_PDB")
		)
	)
	(footprint ""
		(layer "F.Cu")
		(at 167.626538 -12.491974 90)
		(property "Reference" "R1197"
			(at -0.857504 -1.986788 90)
			(unlocked yes)
			(layer "F.SilkS")
			(effects
				(font
					(size 0.7874 0.5842)
					(thickness 0.1524)
				)
				(justify left)
			)
		)
		(property "Value" ""
			(at 0 0 90)
			(layer "F.Fab")
			(effects
				(font
					(size 1.27 1.27)
				)
			)
		)
		(duplicate_pad_numbers_are_jumpers no)
		(fp_line
			(start 0.7874 -0.4064)
			(end 0.7874 0.4064)
			(stroke
				(width 0.1524)
				(type default)
			)
			(layer "F.SilkS")
		)
		(fp_line
			(start -0.7874 -0.4064)
			(end 0.7874 -0.4064)
			(stroke
				(width 0.1524)
				(type default)
			)
			(layer "F.SilkS")
		)
		(fp_line
			(start 0.7874 0.4064)
			(end -0.7874 0.4064)
			(stroke
				(width 0.1524)
				(type default)
			)
			(layer "F.SilkS")
		)
		(fp_line
			(start -0.7874 0.4064)
			(end -0.7874 -0.4064)
			(stroke
				(width 0.1524)
				(type default)
			)
			(layer "F.SilkS")
		)
		(fp_poly
			(pts
				(xy -0.508 0.2794) (xy -0.508 0.2286) (xy -0.635 0.2286) (xy -0.635 -0.254) (xy -0.5334 -0.254)
				(xy -0.5334 -0.2794) (xy 0.5334 -0.2794) (xy 0.5334 -0.254) (xy 0.635 -0.254) (xy 0.635 0.254) (xy 0.5334 0.254)
				(xy 0.5334 0.2794)
			)
			(stroke
				(width 0)
				(type default)
			)
			(fill no)
			(layer "F.CrtYd")
		)
		(pad "1" smd rect
			(at 0.40005 0 90)
			(size 0.4572 0.508)
			(layers "F.Cu" "F.Mask" "F.Paste")
			(net "SIO_JTAG_CPLD3_TMS")
		)
		(pad "2" smd rect
			(at -0.40005 0 90)
			(size 0.4572 0.508)
			(layers "F.Cu" "F.Mask" "F.Paste")
			(net "JTAG_CPLD3_TMS")
		)
	)
	(footprint ""
		(layer "F.Cu")
		(at 115.478814 -132.313934 -90)
		(property "Reference" "PC98"
			(at -0.481838 -4.604512 90)
			(unlocked yes)
			(layer "F.SilkS")
			(effects
				(font
					(size 0.7874 0.5842)
					(thickness 0.1524)
				)
			)
		)
		(property "Value" ""
			(at 0 0 270)
			(layer "F.Fab")
			(effects
				(font
					(size 1.27 1.27)
				)
			)
		)
		(duplicate_pad_numbers_are_jumpers no)
		(fp_line
			(start -1.2954 0.5842)
			(end -1.2954 -0.5842)
			(stroke
				(width 0.1524)
				(type default)
			)
			(layer "F.SilkS")
		)
		(fp_line
			(start 1.2954 0.5842)
			(end -1.2954 0.5842)
			(stroke
				(width 0.1524)
				(type default)
			)
			(layer "F.SilkS")
		)
		(fp_line
			(start -1.2954 -0.5842)
			(end 1.2954 -0.5842)
			(stroke
				(width 0.1524)
				(type default)
			)
			(layer "F.SilkS")
		)
		(fp_line
			(start 0 -0.5842)
			(end 0 0.5842)
			(stroke
				(width 0.1524)
				(type default)
			)
			(layer "F.SilkS")
		)
		(fp_line
			(start 1.2954 -0.5842)
			(end 1.2954 0.5842)
			(stroke
				(width 0.1524)
				(type default)
			)
			(layer "F.SilkS")
		)
		(fp_poly
			(pts
				(xy 0.8636 -0.4572) (xy 0.8636 -0.3556) (xy 1.143 -0.3556) (xy 1.143 0.3556) (xy 0.8636 0.3556)
				(xy 0.8636 0.4572) (xy -0.8636 0.4572) (xy -0.8636 0.3556) (xy -1.143 0.3556) (xy -1.143 -0.3556)
				(xy -0.8636 -0.3556) (xy -0.8636 -0.4572)
			)
			(stroke
				(width 0)
				(type default)
			)
			(fill no)
			(layer "F.CrtYd")
		)
		(fp_line
			(start -0.884936 0.504952)
			(end -0.884936 -0.504952)
			(stroke
				(width 0.1)
				(type default)
			)
			(layer "F.Fab")
		)
		(fp_line
			(start 0.884936 0.504952)
			(end -0.884936 0.504952)
			(stroke
				(width 0.1)
				(type default)
			)
			(layer "F.Fab")
		)
		(fp_line
			(start -0.884936 -0.504952)
			(end 0.884936 -0.504952)
			(stroke
				(width 0.1)
				(type default)
			)
			(layer "F.Fab")
		)
		(fp_line
			(start 0.884936 -0.504952)
			(end 0.884936 0.504952)
			(stroke
				(width 0.1)
				(type default)
			)
			(layer "F.Fab")
		)
		(pad "1" smd rect
			(at 0.7366 0)
			(size 0.7112 0.8128)
			(layers "F.Cu" "F.Mask" "F.Paste")
			(net "VR_PVCCP_NODE1_ISEN1P_CC")
		)
		(pad "2" smd rect
			(at -0.7366 0)
			(size 0.7112 0.8128)
			(layers "F.Cu" "F.Mask" "F.Paste")
			(net "ISENSE_PVCCP_NODE1_ISEN1N")
		)
	)
	(footprint ""
		(layer "F.Cu")
		(at 138.0236 -160.243774 -90)
		(property "Reference" "R1055"
			(at 109.132624 63.662814 90)
			(unlocked yes)
			(layer "F.SilkS")
			(effects
				(font
					(size 0.7874 0.5842)
					(thickness 0.1524)
				)
				(justify left)
			)
		)
		(property "Value" ""
			(at 0 0 270)
			(layer "F.Fab")
			(effects
				(font
					(size 1.27 1.27)
				)
			)
		)
		(duplicate_pad_numbers_are_jumpers no)
		(fp_line
			(start -0.7874 0.4064)
			(end -0.7874 -0.4064)
			(stroke
				(width 0.1524)
				(type default)
			)
			(layer "F.SilkS")
		)
		(fp_line
			(start 0.7874 0.4064)
			(end -0.7874 0.4064)
			(stroke
				(width 0.1524)
				(type default)
			)
			(layer "F.SilkS")
		)
		(fp_line
			(start -0.7874 -0.4064)
			(end 0.7874 -0.4064)
			(stroke
				(width 0.1524)
				(type default)
			)
			(layer "F.SilkS")
		)
		(fp_line
			(start 0.7874 -0.4064)
			(end 0.7874 0.4064)
			(stroke
				(width 0.1524)
				(type default)
			)
			(layer "F.SilkS")
		)
		(fp_poly
			(pts
				(xy -0.508 0.2794) (xy -0.508 0.2286) (xy -0.635 0.2286) (xy -0.635 -0.254) (xy -0.5334 -0.254)
				(xy -0.5334 -0.2794) (xy 0.5334 -0.2794) (xy 0.5334 -0.254) (xy 0.635 -0.254) (xy 0.635 0.254) (xy 0.5334 0.254)
				(xy 0.5334 0.2794)
			)
			(stroke
				(width 0)
				(type default)
			)
			(fill no)
			(layer "F.CrtYd")
		)
		(pad "1" smd rect
			(at 0.40005 0 270)
			(size 0.4572 0.508)
			(layers "F.Cu" "F.Mask" "F.Paste")
			(net "N31521711")
		)
		(pad "2" smd rect
			(at -0.40005 0 270)
			(size 0.4572 0.508)
			(layers "F.Cu" "F.Mask" "F.Paste")
			(net "CLK_33K_CPLD23")
		)
	)
	(footprint ""
		(layer "F.Cu")
		(at 134.486396 -130.487166 90)
		(property "Reference" "C190"
			(at -1.572768 2.173478 90)
			(unlocked yes)
			(layer "F.SilkS")
			(effects
				(font
					(size 0.7874 0.5842)
					(thickness 0.1524)
				)
				(justify left)
			)
		)
		(property "Value" ""
			(at 0 0 90)
			(layer "F.Fab")
			(effects
				(font
					(size 1.27 1.27)
				)
			)
		)
		(duplicate_pad_numbers_are_jumpers no)
		(fp_line
			(start 0.7874 -0.4064)
			(end 0.7874 0.4064)
			(stroke
				(width 0.1524)
				(type default)
			)
			(layer "F.SilkS")
		)
		(fp_line
			(start -0.7874 -0.4064)
			(end 0.7874 -0.4064)
			(stroke
				(width 0.1524)
				(type default)
			)
			(layer "F.SilkS")
		)
		(fp_line
			(start 0 0.381)
			(end 0 -0.381)
			(stroke
				(width 0.1524)
				(type default)
			)
			(layer "F.SilkS")
		)
		(fp_line
			(start 0.7874 0.4064)
			(end -0.7874 0.4064)
			(stroke
				(width 0.1524)
				(type default)
			)
			(layer "F.SilkS")
		)
		(fp_line
			(start -0.7874 0.4064)
			(end -0.7874 -0.4064)
			(stroke
				(width 0.1524)
				(type default)
			)
			(layer "F.SilkS")
		)
		(fp_poly
			(pts
				(xy -0.5334 0.254) (xy -0.635 0.254) (xy -0.635 0.2286) (xy -0.635 -0.254) (xy -0.5334 -0.254) (xy -0.5334 -0.2794)
				(xy 0.5334 -0.2794) (xy 0.5334 -0.254) (xy 0.635 -0.254) (xy 0.635 0.254) (xy 0.5334 0.254) (xy 0.5334 0.2794)
				(xy -0.508 0.2794) (xy -0.5334 0.2794)
			)
			(stroke
				(width 0)
				(type default)
			)
			(fill no)
			(layer "F.CrtYd")
		)
		(pad "1" smd rect
			(at 0.40005 0 90)
			(size 0.4572 0.508)
			(layers "F.Cu" "F.Mask" "F.Paste")
			(net "P2E_CPU_USB_NODE1_TX_C_DN")
		)
		(pad "2" smd rect
			(at -0.40005 0 90)
			(size 0.4572 0.508)
			(layers "F.Cu" "F.Mask" "F.Paste")
			(net "P2E_CPU_USB_NODE1_TX_DN")
		)
	)
	(footprint ""
		(layer "F.Cu")
		(at 126.845822 -113.104676)
		(property "Reference" "R7"
			(at -0.67183 -2.176526 0)
			(unlocked yes)
			(layer "F.SilkS")
			(effects
				(font
					(size 0.7874 0.5842)
					(thickness 0.1524)
				)
				(justify left)
			)
		)
		(property "Value" ""
			(at 0 0 0)
			(layer "F.Fab")
			(effects
				(font
					(size 1.27 1.27)
				)
			)
		)
		(duplicate_pad_numbers_are_jumpers no)
		(fp_line
			(start -0.7874 -0.4064)
			(end 0.7874 -0.4064)
			(stroke
				(width 0.1524)
				(type default)
			)
			(layer "F.SilkS")
		)
		(fp_line
			(start -0.7874 0.4064)
			(end -0.7874 -0.4064)
			(stroke
				(width 0.1524)
				(type default)
			)
			(layer "F.SilkS")
		)
		(fp_line
			(start 0.7874 -0.4064)
			(end 0.7874 0.4064)
			(stroke
				(width 0.1524)
				(type default)
			)
			(layer "F.SilkS")
		)
		(fp_line
			(start 0.7874 0.4064)
			(end -0.7874 0.4064)
			(stroke
				(width 0.1524)
				(type default)
			)
			(layer "F.SilkS")
		)
		(fp_poly
			(pts
				(xy -0.508 0.2794) (xy -0.508 0.2286) (xy -0.635 0.2286) (xy -0.635 -0.254) (xy -0.5334 -0.254)
				(xy -0.5334 -0.2794) (xy 0.5334 -0.2794) (xy 0.5334 -0.254) (xy 0.635 -0.254) (xy 0.635 0.254) (xy 0.5334 0.254)
				(xy 0.5334 0.2794)
			)
			(stroke
				(width 0)
				(type default)
			)
			(fill no)
			(layer "F.CrtYd")
		)
		(pad "1" smd rect
			(at 0.40005 0)
			(size 0.4572 0.508)
			(layers "F.Cu" "F.Mask" "F.Paste")
			(net "FM_CPLD_CLK_R_PG_NODE1_R")
		)
		(pad "2" smd rect
			(at -0.40005 0)
			(size 0.4572 0.508)
			(layers "F.Cu" "F.Mask" "F.Paste")
			(net "FM_CPLD_NODE1_CLK_PG")
		)
	)
	(footprint ""
		(layer "F.Cu")
		(at 66.750692 -107.316016 90)
		(property "Reference" "C848"
			(at -1.118616 7.779258 90)
			(unlocked yes)
			(layer "F.SilkS")
			(effects
				(font
					(size 0.7874 0.5842)
					(thickness 0.1524)
				)
				(justify left)
			)
		)
		(property "Value" ""
			(at 0 0 90)
			(layer "F.Fab")
			(effects
				(font
					(size 1.27 1.27)
				)
			)
		)
		(duplicate_pad_numbers_are_jumpers no)
		(fp_line
			(start 0.7874 -0.4064)
			(end 0.7874 0.4064)
			(stroke
				(width 0.1524)
				(type default)
			)
			(layer "F.SilkS")
		)
		(fp_line
			(start -0.7874 -0.4064)
			(end 0.7874 -0.4064)
			(stroke
				(width 0.1524)
				(type default)
			)
			(layer "F.SilkS")
		)
		(fp_line
			(start 0 0.381)
			(end 0 -0.381)
			(stroke
				(width 0.1524)
				(type default)
			)
			(layer "F.SilkS")
		)
		(fp_line
			(start 0.7874 0.4064)
			(end -0.7874 0.4064)
			(stroke
				(width 0.1524)
				(type default)
			)
			(layer "F.SilkS")
		)
		(fp_line
			(start -0.7874 0.4064)
			(end -0.7874 -0.4064)
			(stroke
				(width 0.1524)
				(type default)
			)
			(layer "F.SilkS")
		)
		(fp_poly
			(pts
				(xy -0.5334 0.254) (xy -0.635 0.254) (xy -0.635 0.2286) (xy -0.635 -0.254) (xy -0.5334 -0.254) (xy -0.5334 -0.2794)
				(xy 0.5334 -0.2794) (xy 0.5334 -0.254) (xy 0.635 -0.254) (xy 0.635 0.254) (xy 0.5334 0.254) (xy 0.5334 0.2794)
				(xy -0.508 0.2794) (xy -0.5334 0.2794)
			)
			(stroke
				(width 0)
				(type default)
			)
			(fill no)
			(layer "F.CrtYd")
		)
		(pad "1" smd rect
			(at 0.40005 0 90)
			(size 0.4572 0.508)
			(layers "F.Cu" "F.Mask" "F.Paste")
			(net "FM_CPLD_NODE1_P1V8_EN")
		)
		(pad "2" smd rect
			(at -0.40005 0 90)
			(size 0.4572 0.508)
			(layers "F.Cu" "F.Mask" "F.Paste")
			(net "GND")
		)
	)
	(footprint ""
		(layer "F.Cu")
		(at 82.587592 -154.80792 180)
		(property "Reference" "PC8"
			(at -1.15062 -0.239776 0)
			(unlocked yes)
			(layer "F.SilkS")
			(effects
				(font
					(size 0.7874 0.5842)
					(thickness 0.1524)
				)
				(justify left)
			)
		)
		(property "Value" ""
			(at 0 0 180)
			(layer "F.Fab")
			(effects
				(font
					(size 1.27 1.27)
				)
			)
		)
		(duplicate_pad_numbers_are_jumpers no)
		(fp_line
			(start 0.7874 0.4064)
			(end -0.7874 0.4064)
			(stroke
				(width 0.1524)
				(type default)
			)
			(layer "F.SilkS")
		)
		(fp_line
			(start 0.7874 -0.4064)
			(end 0.7874 0.4064)
			(stroke
				(width 0.1524)
				(type default)
			)
			(layer "F.SilkS")
		)
		(fp_line
			(start 0 0.381)
			(end 0 -0.381)
			(stroke
				(width 0.1524)
				(type default)
			)
			(layer "F.SilkS")
		)
		(fp_line
			(start -0.7874 0.4064)
			(end -0.7874 -0.4064)
			(stroke
				(width 0.1524)
				(type default)
			)
			(layer "F.SilkS")
		)
		(fp_line
			(start -0.7874 -0.4064)
			(end 0.7874 -0.4064)
			(stroke
				(width 0.1524)
				(type default)
			)
			(layer "F.SilkS")
		)
		(fp_poly
			(pts
				(xy -0.5334 0.254) (xy -0.635 0.254) (xy -0.635 0.2286) (xy -0.635 -0.254) (xy -0.5334 -0.254) (xy -0.5334 -0.2794)
				(xy 0.5334 -0.2794) (xy 0.5334 -0.254) (xy 0.635 -0.254) (xy 0.635 0.254) (xy 0.5334 0.254) (xy 0.5334 0.2794)
				(xy -0.508 0.2794) (xy -0.5334 0.2794)
			)
			(stroke
				(width 0)
				(type default)
			)
			(fill no)
			(layer "F.CrtYd")
		)
		(pad "1" smd rect
			(at 0.40005 0 180)
			(size 0.4572 0.508)
			(layers "F.Cu" "F.Mask" "F.Paste")
			(net "P5V_STB_NODE1_VREG5")
		)
		(pad "2" smd rect
			(at -0.40005 0 180)
			(size 0.4572 0.508)
			(layers "F.Cu" "F.Mask" "F.Paste")
			(net "GND")
		)
	)
	(footprint ""
		(layer "F.Cu")
		(at 155.356814 -66.498216)
		(property "Reference" "C489"
			(at -0.53086 2.179574 0)
			(unlocked yes)
			(layer "F.SilkS")
			(effects
				(font
					(size 0.7874 0.5842)
					(thickness 0.1524)
				)
				(justify left)
			)
		)
		(property "Value" ""
			(at 0 0 0)
			(layer "F.Fab")
			(effects
				(font
					(size 1.27 1.27)
				)
			)
		)
		(duplicate_pad_numbers_are_jumpers no)
		(fp_line
			(start -0.7874 -0.4064)
			(end 0.7874 -0.4064)
			(stroke
				(width 0.1524)
				(type default)
			)
			(layer "F.SilkS")
		)
		(fp_line
			(start -0.7874 0.4064)
			(end -0.7874 -0.4064)
			(stroke
				(width 0.1524)
				(type default)
			)
			(layer "F.SilkS")
		)
		(fp_line
			(start 0 0.381)
			(end 0 -0.381)
			(stroke
				(width 0.1524)
				(type default)
			)
			(layer "F.SilkS")
		)
		(fp_line
			(start 0.7874 -0.4064)
			(end 0.7874 0.4064)
			(stroke
				(width 0.1524)
				(type default)
			)
			(layer "F.SilkS")
		)
		(fp_line
			(start 0.7874 0.4064)
			(end -0.7874 0.4064)
			(stroke
				(width 0.1524)
				(type default)
			)
			(layer "F.SilkS")
		)
		(fp_poly
			(pts
				(xy -0.5334 0.254) (xy -0.635 0.254) (xy -0.635 0.2286) (xy -0.635 -0.254) (xy -0.5334 -0.254) (xy -0.5334 -0.2794)
				(xy 0.5334 -0.2794) (xy 0.5334 -0.254) (xy 0.635 -0.254) (xy 0.635 0.254) (xy 0.5334 0.254) (xy 0.5334 0.2794)
				(xy -0.508 0.2794) (xy -0.5334 0.2794)
			)
			(stroke
				(width 0)
				(type default)
			)
			(fill no)
			(layer "F.CrtYd")
		)
		(pad "1" smd rect
			(at 0.40005 0)
			(size 0.4572 0.508)
			(layers "F.Cu" "F.Mask" "F.Paste")
			(net "SATA_TX0_C_DP")
		)
		(pad "2" smd rect
			(at -0.40005 0)
			(size 0.4572 0.508)
			(layers "F.Cu" "F.Mask" "F.Paste")
			(net "SATA_A_NODE1_TX_P0")
		)
	)
	(footprint ""
		(layer "F.Cu")
		(at 114.393218 -138.394694 -90)
		(property "Reference" "PC109"
			(at -3.238246 -3.335528 90)
			(unlocked yes)
			(layer "F.SilkS")
			(effects
				(font
					(size 0.635 0.4064)
					(thickness 0.1524)
				)
				(justify left)
			)
		)
		(property "Value" ""
			(at 0 0 270)
			(layer "F.Fab")
			(effects
				(font
					(size 1.27 1.27)
				)
			)
		)
		(duplicate_pad_numbers_are_jumpers no)
		(fp_line
			(start -0.7874 0.4064)
			(end -0.7874 -0.4064)
			(stroke
				(width 0.1524)
				(type default)
			)
			(layer "F.SilkS")
		)
		(fp_line
			(start 0.7874 0.4064)
			(end -0.7874 0.4064)
			(stroke
				(width 0.1524)
				(type default)
			)
			(layer "F.SilkS")
		)
		(fp_line
			(start 0 0.381)
			(end 0 -0.381)
			(stroke
				(width 0.1524)
				(type default)
			)
			(layer "F.SilkS")
		)
		(fp_line
			(start -0.7874 -0.4064)
			(end 0.7874 -0.4064)
			(stroke
				(width 0.1524)
				(type default)
			)
			(layer "F.SilkS")
		)
		(fp_line
			(start 0.7874 -0.4064)
			(end 0.7874 0.4064)
			(stroke
				(width 0.1524)
				(type default)
			)
			(layer "F.SilkS")
		)
		(fp_poly
			(pts
				(xy -0.5334 0.254) (xy -0.635 0.254) (xy -0.635 0.2286) (xy -0.635 -0.254) (xy -0.5334 -0.254) (xy -0.5334 -0.2794)
				(xy 0.5334 -0.2794) (xy 0.5334 -0.254) (xy 0.635 -0.254) (xy 0.635 0.254) (xy 0.5334 0.254) (xy 0.5334 0.2794)
				(xy -0.508 0.2794) (xy -0.5334 0.2794)
			)
			(stroke
				(width 0)
				(type default)
			)
			(fill no)
			(layer "F.CrtYd")
		)
		(pad "1" smd rect
			(at 0.40005 0 270)
			(size 0.4572 0.508)
			(layers "F.Cu" "F.Mask" "F.Paste")
			(net "VR_PVCCP_NODE1_RGND")
		)
		(pad "2" smd rect
			(at -0.40005 0 270)
			(size 0.4572 0.508)
			(layers "F.Cu" "F.Mask" "F.Paste")
			(net "VR_PVCCP_NODE1_VSEN")
		)
	)
	(footprint ""
		(layer "F.Cu")
		(at 94.451932 -169.203624)
		(property "Reference" "R757"
			(at 86.67369 74.174096 0)
			(unlocked yes)
			(layer "F.SilkS")
			(effects
				(font
					(size 0.7874 0.5842)
					(thickness 0.1524)
				)
				(justify left)
			)
		)
		(property "Value" ""
			(at 0 0 0)
			(layer "F.Fab")
			(effects
				(font
					(size 1.27 1.27)
				)
			)
		)
		(duplicate_pad_numbers_are_jumpers no)
		(fp_line
			(start -0.7874 -0.4064)
			(end 0.7874 -0.4064)
			(stroke
				(width 0.1524)
				(type default)
			)
			(layer "F.SilkS")
		)
		(fp_line
			(start -0.7874 0.4064)
			(end -0.7874 -0.4064)
			(stroke
				(width 0.1524)
				(type default)
			)
			(layer "F.SilkS")
		)
		(fp_line
			(start 0.7874 -0.4064)
			(end 0.7874 0.4064)
			(stroke
				(width 0.1524)
				(type default)
			)
			(layer "F.SilkS")
		)
		(fp_line
			(start 0.7874 0.4064)
			(end -0.7874 0.4064)
			(stroke
				(width 0.1524)
				(type default)
			)
			(layer "F.SilkS")
		)
		(fp_poly
			(pts
				(xy -0.508 0.2794) (xy -0.508 0.2286) (xy -0.635 0.2286) (xy -0.635 -0.254) (xy -0.5334 -0.254)
				(xy -0.5334 -0.2794) (xy 0.5334 -0.2794) (xy 0.5334 -0.254) (xy 0.635 -0.254) (xy 0.635 0.254) (xy 0.5334 0.254)
				(xy 0.5334 0.2794)
			)
			(stroke
				(width 0)
				(type default)
			)
			(fill no)
			(layer "F.CrtYd")
		)
		(pad "1" smd rect
			(at 0.40005 0)
			(size 0.4572 0.508)
			(layers "F.Cu" "F.Mask" "F.Paste")
			(net "FAN2_TACH_IN")
		)
		(pad "2" smd rect
			(at -0.40005 0)
			(size 0.4572 0.508)
			(layers "F.Cu" "F.Mask" "F.Paste")
			(net "FAN2_TACH")
		)
	)
	(footprint ""
		(layer "F.Cu")
		(at 142.910052 -133.17855)
		(property "Reference" "R289"
			(at -3.280918 3.102864 0)
			(unlocked yes)
			(layer "F.SilkS")
			(effects
				(font
					(size 0.7874 0.5842)
					(thickness 0.1524)
				)
				(justify left)
			)
		)
		(property "Value" ""
			(at 0 0 0)
			(layer "F.Fab")
			(effects
				(font
					(size 1.27 1.27)
				)
			)
		)
		(duplicate_pad_numbers_are_jumpers no)
		(fp_line
			(start -0.7874 -0.4064)
			(end 0.7874 -0.4064)
			(stroke
				(width 0.1524)
				(type default)
			)
			(layer "F.SilkS")
		)
		(fp_line
			(start -0.7874 0.4064)
			(end -0.7874 -0.4064)
			(stroke
				(width 0.1524)
				(type default)
			)
			(layer "F.SilkS")
		)
		(fp_line
			(start 0.7874 -0.4064)
			(end 0.7874 0.4064)
			(stroke
				(width 0.1524)
				(type default)
			)
			(layer "F.SilkS")
		)
		(fp_line
			(start 0.7874 0.4064)
			(end -0.7874 0.4064)
			(stroke
				(width 0.1524)
				(type default)
			)
			(layer "F.SilkS")
		)
		(fp_poly
			(pts
				(xy -0.508 0.2794) (xy -0.508 0.2286) (xy -0.635 0.2286) (xy -0.635 -0.254) (xy -0.5334 -0.254)
				(xy -0.5334 -0.2794) (xy 0.5334 -0.2794) (xy 0.5334 -0.254) (xy 0.635 -0.254) (xy 0.635 0.254) (xy 0.5334 0.254)
				(xy 0.5334 0.2794)
			)
			(stroke
				(width 0)
				(type default)
			)
			(fill no)
			(layer "F.CrtYd")
		)
		(pad "1" smd rect
			(at 0.40005 0)
			(size 0.4572 0.508)
			(layers "F.Cu" "F.Mask" "F.Paste")
			(net "GND")
		)
		(pad "2" smd rect
			(at -0.40005 0)
			(size 0.4572 0.508)
			(layers "F.Cu" "F.Mask" "F.Paste")
			(net "PCIE_SW_TEST6")
		)
	)
	(footprint ""
		(layer "F.Cu")
		(at 165.011354 -183.051196 180)
		(property "Reference" "R1172"
			(at 5.204206 -0.410718 0)
			(unlocked yes)
			(layer "F.SilkS")
			(effects
				(font
					(size 0.7874 0.5842)
					(thickness 0.1524)
				)
				(justify left)
			)
		)
		(property "Value" ""
			(at 0 0 180)
			(layer "F.Fab")
			(effects
				(font
					(size 1.27 1.27)
				)
			)
		)
		(duplicate_pad_numbers_are_jumpers no)
		(fp_line
			(start 0.7874 0.4064)
			(end -0.7874 0.4064)
			(stroke
				(width 0.1524)
				(type default)
			)
			(layer "F.SilkS")
		)
		(fp_line
			(start 0.7874 -0.4064)
			(end 0.7874 0.4064)
			(stroke
				(width 0.1524)
				(type default)
			)
			(layer "F.SilkS")
		)
		(fp_line
			(start -0.7874 0.4064)
			(end -0.7874 -0.4064)
			(stroke
				(width 0.1524)
				(type default)
			)
			(layer "F.SilkS")
		)
		(fp_line
			(start -0.7874 -0.4064)
			(end 0.7874 -0.4064)
			(stroke
				(width 0.1524)
				(type default)
			)
			(layer "F.SilkS")
		)
		(fp_poly
			(pts
				(xy -0.508 0.2794) (xy -0.508 0.2286) (xy -0.635 0.2286) (xy -0.635 -0.254) (xy -0.5334 -0.254)
				(xy -0.5334 -0.2794) (xy 0.5334 -0.2794) (xy 0.5334 -0.254) (xy 0.635 -0.254) (xy 0.635 0.254) (xy 0.5334 0.254)
				(xy 0.5334 0.2794)
			)
			(stroke
				(width 0)
				(type default)
			)
			(fill no)
			(layer "F.CrtYd")
		)
		(pad "1" smd rect
			(at 0.40005 0 180)
			(size 0.4572 0.508)
			(layers "F.Cu" "F.Mask" "F.Paste")
			(net "CPLD_UART_RTS_P3_N")
		)
		(pad "2" smd rect
			(at -0.40005 0 180)
			(size 0.4572 0.508)
			(layers "F.Cu" "F.Mask" "F.Paste")
			(net "GND")
		)
	)
	(footprint ""
		(layer "F.Cu")
		(at 183.71185 -63.058294 90)
		(property "Reference" "J15"
			(at -8.60171 4.64947 0)
			(unlocked yes)
			(layer "F.SilkS")
			(effects
				(font
					(size 0.7874 0.5842)
					(thickness 0.1524)
				)
				(justify left)
			)
		)
		(property "Value" ""
			(at 0 0 90)
			(layer "F.Fab")
			(effects
				(font
					(size 1.27 1.27)
				)
			)
		)
		(duplicate_pad_numbers_are_jumpers no)
		(fp_line
			(start 4.953 -3.9878)
			(end -4.953 -3.9878)
			(stroke
				(width 0.1524)
				(type default)
			)
			(layer "F.SilkS")
		)
		(fp_line
			(start -7.62 -1.3716)
			(end -7.62 1.1176)
			(stroke
				(width 0.1524)
				(type default)
			)
			(layer "F.SilkS")
		)
		(fp_line
			(start 7.62 1.1176)
			(end 7.62 -1.3716)
			(stroke
				(width 0.1524)
				(type default)
			)
			(layer "F.SilkS")
		)
		(fp_line
			(start -7.62 4.318)
			(end -7.62 14.3764)
			(stroke
				(width 0.1524)
				(type default)
			)
			(layer "F.SilkS")
		)
		(fp_line
			(start 7.62 14.3764)
			(end 7.62 4.318)
			(stroke
				(width 0.1524)
				(type default)
			)
			(layer "F.SilkS")
		)
		(fp_line
			(start -7.62 14.3764)
			(end 7.62 14.3764)
			(stroke
				(width 0.1524)
				(type default)
			)
			(layer "F.SilkS")
		)
		(fp_poly
			(pts
				(xy -7.655052 0.031242) (xy -9.560052 -0.730758) (xy -9.560052 0.793242)
			)
			(stroke
				(width 0)
				(type default)
			)
			(fill yes)
			(layer "F.SilkS")
		)
		(fp_poly
			(pts
				(xy -4.2926 -3.4036) (xy 4.2926 -3.4036) (xy 4.2926 -1.8288) (xy -4.2926 -1.8288)
			)
			(stroke
				(width 0)
				(type default)
			)
			(fill no)
			(layer "B.CrtYd")
		)
		(fp_poly
			(pts
				(xy 4.2926 -0.7874) (xy -4.2926 -0.7874) (xy -4.2926 0.7874) (xy 4.2926 0.7874)
			)
			(stroke
				(width 0)
				(type default)
			)
			(fill no)
			(layer "B.CrtYd")
		)
		(fp_poly
			(pts
				(arc
					(start 6.5659 -4.8006)
					(mid 5.272743 -4.264957)
					(end 4.7371 -2.9718)
				)
				(arc
					(start 4.7371 -2.9464)
					(mid 5.265304 -1.671204)
					(end 6.5405 -1.143)
				)
				(arc
					(start 6.5913 -1.143)
					(mid 8.4201 -2.9718)
					(end 6.5913 -4.8006)
				)
			)
			(stroke
				(width 0)
				(type default)
			)
			(fill no)
			(layer "B.CrtYd")
		)
		(fp_poly
			(pts
				(arc
					(start -6.5786 -4.8006)
					(mid -7.871757 -4.264957)
					(end -8.4074 -2.9718)
				)
				(arc
					(start -8.4074 -2.9464)
					(mid -7.879196 -1.671204)
					(end -6.604 -1.143)
				)
				(arc
					(start -6.5532 -1.143)
					(mid -4.7244 -2.9718)
					(end -6.5532 -4.8006)
				)
			)
			(stroke
				(width 0)
				(type default)
			)
			(fill no)
			(layer "B.CrtYd")
		)
		(fp_poly
			(pts
				(arc
					(start 6.5659 0.889)
					(mid 5.272743 1.424643)
					(end 4.7371 2.7178)
				)
				(arc
					(start 4.7371 2.7432)
					(mid 5.265304 4.018396)
					(end 6.5405 4.5466)
				)
				(arc
					(start 6.5913 4.5466)
					(mid 8.4201 2.7178)
					(end 6.5913 0.889)
				)
			)
			(stroke
				(width 0)
				(type default)
			)
			(fill no)
			(layer "B.CrtYd")
		)
		(fp_poly
			(pts
				(arc
					(start -6.5913 0.889)
					(mid -7.884457 1.424643)
					(end -8.4201 2.7178)
				)
				(arc
					(start -8.4201 2.7432)
					(mid -7.891896 4.018396)
					(end -6.6167 4.5466)
				)
				(arc
					(start -6.5659 4.5466)
					(mid -4.7371 2.7178)
					(end -6.5659 0.889)
				)
			)
			(stroke
				(width 0)
				(type default)
			)
			(fill no)
			(layer "B.CrtYd")
		)
		(fp_rect
			(start -8.7376 14.4526)
			(end 8.7376 -4.9276)
			(stroke
				(width 0)
				(type default)
			)
			(fill no)
			(layer "F.CrtYd")
		)
		(fp_line
			(start 7.62 -3.9878)
			(end 7.62 14.3764)
			(stroke
				(width 0.1)
				(type default)
			)
			(layer "F.Fab")
		)
		(fp_line
			(start -7.62 -3.9878)
			(end 7.62 -3.9878)
			(stroke
				(width 0.1)
				(type default)
			)
			(layer "F.Fab")
		)
		(fp_line
			(start -7.62 4.318)
			(end -7.62 -3.9878)
			(stroke
				(width 0.1)
				(type default)
			)
			(layer "F.Fab")
		)
		(fp_line
			(start 7.62 14.3764)
			(end -7.62 14.3764)
			(stroke
				(width 0.1)
				(type default)
			)
			(layer "F.Fab")
		)
		(fp_line
			(start -7.62 14.3764)
			(end -7.62 4.318)
			(stroke
				(width 0.1)
				(type default)
			)
			(layer "F.Fab")
		)
		(fp_poly
			(pts
				(xy -8.5725 0) (xy -10.4775 -0.762) (xy -10.4775 0.762)
			)
			(stroke
				(width 0)
				(type default)
			)
			(fill yes)
			(layer "F.Fab")
		)
		(fp_text user "8"
			(at 4.047998 -5.137912 0)
			(unlocked yes)
			(layer "F.SilkS")
			(effects
				(font
					(size 0.7874 0.5842)
					(thickness 0.1524)
				)
				(justify left)
			)
		)
		(fp_text user "5"
			(at -4.461002 -4.756912 0)
			(unlocked yes)
			(layer "F.SilkS")
			(effects
				(font
					(size 0.7874 0.5842)
					(thickness 0.1524)
				)
				(justify left)
			)
		)
		(fp_text user "1"
			(at -8.271002 -0.819912 0)
			(unlocked yes)
			(layer "F.SilkS")
			(effects
				(font
					(size 0.7874 0.5842)
					(thickness 0.1524)
				)
				(justify left)
			)
		)
		(fp_text user "4"
			(at 8.226806 -0.026416 0)
			(unlocked yes)
			(layer "F.SilkS")
			(effects
				(font
					(size 0.7874 0.5842)
					(thickness 0.1524)
				)
				(justify left)
			)
		)
		(fp_text user "8"
			(at 3.557524 -3.736594 0)
			(unlocked yes)
			(layer "B.SilkS")
			(effects
				(font
					(size 0.7874 0.5842)
					(thickness 0.1524)
				)
				(justify left mirror)
			)
		)
		(fp_text user "5"
			(at -3.50647 -3.736594 0)
			(unlocked yes)
			(layer "B.SilkS")
			(effects
				(font
					(size 0.7874 0.5842)
					(thickness 0.1524)
				)
				(justify left mirror)
			)
		)
		(fp_text user "1"
			(at -3.482848 1.549654 0)
			(unlocked yes)
			(layer "B.SilkS")
			(effects
				(font
					(size 0.7874 0.5842)
					(thickness 0.1524)
				)
				(justify left mirror)
			)
		)
		(fp_text user "4"
			(at 3.60426 1.736852 0)
			(unlocked yes)
			(layer "B.SilkS")
			(effects
				(font
					(size 0.7874 0.5842)
					(thickness 0.1524)
				)
				(justify left mirror)
			)
		)
		(fp_text user "8"
			(at 3.9624 -5.5372 90)
			(unlocked yes)
			(layer "B.Fab")
			(effects
				(font
					(size 1.016 0.762)
					(thickness 0.000001)
				)
				(justify left mirror)
			)
		)
		(fp_text user "5"
			(at -3.0734 -5.5372 90)
			(unlocked yes)
			(layer "B.Fab")
			(effects
				(font
					(size 1.016 0.762)
					(thickness 0.000001)
				)
				(justify left mirror)
			)
		)
		(fp_text user "4"
			(at 5.334 -0.118618 90)
			(unlocked yes)
			(layer "B.Fab")
			(effects
				(font
					(size 1.016 0.762)
					(thickness 0.000001)
				)
				(justify left mirror)
			)
		)
		(fp_text user "1"
			(at -4.572 -0.118618 90)
			(unlocked yes)
			(layer "B.Fab")
			(effects
				(font
					(size 1.016 0.762)
					(thickness 0.000001)
				)
				(justify left mirror)
			)
		)
		(fp_text user "8"
			(at 3.175 -5.5372 90)
			(unlocked yes)
			(layer "F.Fab")
			(effects
				(font
					(size 1.016 0.762)
					(thickness 0.000001)
				)
				(justify left)
			)
		)
		(fp_text user "5"
			(at -3.81 -5.5372 90)
			(unlocked yes)
			(layer "F.Fab")
			(effects
				(font
					(size 1.016 0.762)
					(thickness 0.000001)
				)
				(justify left)
			)
		)
		(fp_text user "4"
			(at 8.001 -0.118618 90)
			(unlocked yes)
			(layer "F.Fab")
			(effects
				(font
					(size 1.016 0.762)
					(thickness 0.000001)
				)
				(justify left)
			)
		)
		(fp_text user "1"
			(at -8.763 -0.118618 90)
			(unlocked yes)
			(layer "F.Fab")
			(effects
				(font
					(size 1.016 0.762)
					(thickness 0.000001)
				)
				(justify left)
			)
		)
		(pad "1" thru_hole rect
			(at -3.5052 0 90)
			(size 1.4732 1.4732)
			(drill 1.016)
			(layers "*.Cu" "*.Mask")
			(remove_unused_layers no)
			(net "USBPWR_P1")
			(clearance 0.0254)
			(thermal_gap 0.0254)
			(padstack
				(mode front_inner_back)
				(layer "Inner"
					(shape circle)
					(size 1.4732 1.4732)
					(clearance 0.0254)
				)
				(layer "B.Cu"
					(shape rect)
					(size 1.4732 1.4732)
					(clearance 0.0254)
				)
			)
		)
		(pad "2" thru_hole circle
			(at -1.016 0 90)
			(size 1.4732 1.4732)
			(drill 1.016)
			(layers "*.Cu" "*.Mask")
			(remove_unused_layers no)
			(net "USB2_L_DN")
			(clearance 0.0254)
			(thermal_gap 0.0254)
		)
		(pad "3" thru_hole circle
			(at 1.016 0 90)
			(size 1.4732 1.4732)
			(drill 1.016)
			(layers "*.Cu" "*.Mask")
			(remove_unused_layers no)
			(net "USB2_L_DP")
			(clearance 0.0254)
			(thermal_gap 0.0254)
		)
		(pad "4" thru_hole circle
			(at 3.5052 0 90)
			(size 1.4732 1.4732)
			(drill 1.016)
			(layers "*.Cu" "*.Mask")
			(remove_unused_layers no)
			(net "GND")
			(clearance 0.0254)
			(thermal_gap 0.0254)
		)
		(pad "5" thru_hole circle
			(at -3.5052 -2.6162 90)
			(size 1.4732 1.4732)
			(drill 1.016)
			(layers "*.Cu" "*.Mask")
			(remove_unused_layers no)
			(net "USBPWR_P1")
			(clearance 0.0254)
			(thermal_gap 0.0254)
		)
		(pad "6" thru_hole circle
			(at -1.016 -2.6162 90)
			(size 1.4732 1.4732)
			(drill 1.016)
			(layers "*.Cu" "*.Mask")
			(remove_unused_layers no)
			(net "USB3_L_DN")
			(clearance 0.0254)
			(thermal_gap 0.0254)
		)
		(pad "7" thru_hole circle
			(at 1.016 -2.6162 90)
			(size 1.4732 1.4732)
			(drill 1.016)
			(layers "*.Cu" "*.Mask")
			(remove_unused_layers no)
			(net "USB3_L_DP")
			(clearance 0.0254)
			(thermal_gap 0.0254)
		)
		(pad "8" thru_hole circle
			(at 3.5052 -2.6162 90)
			(size 1.4732 1.4732)
			(drill 1.016)
			(layers "*.Cu" "*.Mask")
			(remove_unused_layers no)
			(net "GND")
			(clearance 0.0254)
			(thermal_gap 0.0254)
		)
		(pad "9" thru_hole circle
			(at -6.5786 2.7178 90)
			(size 3.556 3.556)
			(drill 2.286)
			(layers "*.Cu" "*.Mask")
			(remove_unused_layers no)
			(net "GND")
			(clearance -0.381)
		)
		(pad "10" thru_hole circle
			(at 6.5786 2.7178 90)
			(size 3.556 3.556)
			(drill 2.286)
			(layers "*.Cu" "*.Mask")
			(remove_unused_layers no)
			(net "GND")
			(clearance -0.381)
		)
		(pad "11" thru_hole circle
			(at -6.5786 -2.9718 90)
			(size 3.556 3.556)
			(drill 2.286)
			(layers "*.Cu" "*.Mask")
			(remove_unused_layers no)
			(net "GND")
			(clearance -0.381)
		)
		(pad "12" thru_hole circle
			(at 6.5786 -2.9718 90)
			(size 3.556 3.556)
			(drill 2.286)
			(layers "*.Cu" "*.Mask")
			(remove_unused_layers no)
			(net "GND")
			(clearance -0.381)
		)
	)
	(footprint ""
		(layer "F.Cu")
		(at 137.593578 -60.704222 180)
		(property "Reference" "R511"
			(at 0.823214 -4.858512 0)
			(unlocked yes)
			(layer "F.SilkS")
			(effects
				(font
					(size 0.7874 0.5842)
					(thickness 0.1524)
				)
				(justify left)
			)
		)
		(property "Value" ""
			(at 0 0 180)
			(layer "F.Fab")
			(effects
				(font
					(size 1.27 1.27)
				)
			)
		)
		(duplicate_pad_numbers_are_jumpers no)
		(fp_line
			(start 0.7874 0.4064)
			(end -0.7874 0.4064)
			(stroke
				(width 0.1524)
				(type default)
			)
			(layer "F.SilkS")
		)
		(fp_line
			(start 0.7874 -0.4064)
			(end 0.7874 0.4064)
			(stroke
				(width 0.1524)
				(type default)
			)
			(layer "F.SilkS")
		)
		(fp_line
			(start -0.7874 0.4064)
			(end -0.7874 -0.4064)
			(stroke
				(width 0.1524)
				(type default)
			)
			(layer "F.SilkS")
		)
		(fp_line
			(start -0.7874 -0.4064)
			(end 0.7874 -0.4064)
			(stroke
				(width 0.1524)
				(type default)
			)
			(layer "F.SilkS")
		)
		(fp_poly
			(pts
				(xy -0.508 0.2794) (xy -0.508 0.2286) (xy -0.635 0.2286) (xy -0.635 -0.254) (xy -0.5334 -0.254)
				(xy -0.5334 -0.2794) (xy 0.5334 -0.2794) (xy 0.5334 -0.254) (xy 0.635 -0.254) (xy 0.635 0.254) (xy 0.5334 0.254)
				(xy 0.5334 0.2794)
			)
			(stroke
				(width 0)
				(type default)
			)
			(fill no)
			(layer "F.CrtYd")
		)
		(pad "1" smd rect
			(at 0.40005 0 180)
			(size 0.4572 0.508)
			(layers "F.Cu" "F.Mask" "F.Paste")
			(net "P3V3_NODE1")
		)
		(pad "2" smd rect
			(at -0.40005 0 180)
			(size 0.4572 0.508)
			(layers "F.Cu" "F.Mask" "F.Paste")
			(net "SATA_NODE1_GPIO2")
		)
	)
	(footprint ""
		(layer "F.Cu")
		(at 124.757434 -50.075846 90)
		(property "Reference" "R621"
			(at 17.662906 32.213804 90)
			(unlocked yes)
			(layer "F.SilkS")
			(effects
				(font
					(size 0.7874 0.5842)
					(thickness 0.1524)
				)
				(justify left)
			)
		)
		(property "Value" ""
			(at 0 0 90)
			(layer "F.Fab")
			(effects
				(font
					(size 1.27 1.27)
				)
			)
		)
		(duplicate_pad_numbers_are_jumpers no)
		(fp_line
			(start 0.7874 -0.4064)
			(end 0.7874 0.4064)
			(stroke
				(width 0.1524)
				(type default)
			)
			(layer "F.SilkS")
		)
		(fp_line
			(start -0.7874 -0.4064)
			(end 0.7874 -0.4064)
			(stroke
				(width 0.1524)
				(type default)
			)
			(layer "F.SilkS")
		)
		(fp_line
			(start 0.7874 0.4064)
			(end -0.7874 0.4064)
			(stroke
				(width 0.1524)
				(type default)
			)
			(layer "F.SilkS")
		)
		(fp_line
			(start -0.7874 0.4064)
			(end -0.7874 -0.4064)
			(stroke
				(width 0.1524)
				(type default)
			)
			(layer "F.SilkS")
		)
		(fp_poly
			(pts
				(xy -0.508 0.2794) (xy -0.508 0.2286) (xy -0.635 0.2286) (xy -0.635 -0.254) (xy -0.5334 -0.254)
				(xy -0.5334 -0.2794) (xy 0.5334 -0.2794) (xy 0.5334 -0.254) (xy 0.635 -0.254) (xy 0.635 0.254) (xy 0.5334 0.254)
				(xy 0.5334 0.2794)
			)
			(stroke
				(width 0)
				(type default)
			)
			(fill no)
			(layer "F.CrtYd")
		)
		(pad "1" smd rect
			(at 0.40005 0 90)
			(size 0.4572 0.508)
			(layers "F.Cu" "F.Mask" "F.Paste")
			(net "FM_CPLD_NODE1_CPU_RESET_L")
		)
		(pad "2" smd rect
			(at -0.40005 0 90)
			(size 0.4572 0.508)
			(layers "F.Cu" "F.Mask" "F.Paste")
			(net "SIO_LRESET_N")
		)
	)
	(footprint ""
		(layer "F.Cu")
		(at 72.132698 -17.679416 90)
		(property "Reference" "C159"
			(at -4.60629 6.316472 90)
			(unlocked yes)
			(layer "F.SilkS")
			(effects
				(font
					(size 0.7874 0.5842)
					(thickness 0.1524)
				)
				(justify left)
			)
		)
		(property "Value" ""
			(at 0 0 90)
			(layer "F.Fab")
			(effects
				(font
					(size 1.27 1.27)
				)
			)
		)
		(duplicate_pad_numbers_are_jumpers no)
		(fp_line
			(start 0.7874 -0.4064)
			(end 0.7874 0.4064)
			(stroke
				(width 0.1524)
				(type default)
			)
			(layer "F.SilkS")
		)
		(fp_line
			(start -0.7874 -0.4064)
			(end 0.7874 -0.4064)
			(stroke
				(width 0.1524)
				(type default)
			)
			(layer "F.SilkS")
		)
		(fp_line
			(start 0 0.381)
			(end 0 -0.381)
			(stroke
				(width 0.1524)
				(type default)
			)
			(layer "F.SilkS")
		)
		(fp_line
			(start 0.7874 0.4064)
			(end -0.7874 0.4064)
			(stroke
				(width 0.1524)
				(type default)
			)
			(layer "F.SilkS")
		)
		(fp_line
			(start -0.7874 0.4064)
			(end -0.7874 -0.4064)
			(stroke
				(width 0.1524)
				(type default)
			)
			(layer "F.SilkS")
		)
		(fp_poly
			(pts
				(xy -0.5334 0.254) (xy -0.635 0.254) (xy -0.635 0.2286) (xy -0.635 -0.254) (xy -0.5334 -0.254) (xy -0.5334 -0.2794)
				(xy 0.5334 -0.2794) (xy 0.5334 -0.254) (xy 0.635 -0.254) (xy 0.635 0.254) (xy 0.5334 0.254) (xy 0.5334 0.2794)
				(xy -0.508 0.2794) (xy -0.5334 0.2794)
			)
			(stroke
				(width 0)
				(type default)
			)
			(fill no)
			(layer "F.CrtYd")
		)
		(pad "1" smd rect
			(at 0.40005 0 90)
			(size 0.4572 0.508)
			(layers "F.Cu" "F.Mask" "F.Paste")
			(net "PV_VDDR_NODE1")
		)
		(pad "2" smd rect
			(at -0.40005 0 90)
			(size 0.4572 0.508)
			(layers "F.Cu" "F.Mask" "F.Paste")
			(net "GND")
		)
	)
	(footprint ""
		(layer "F.Cu")
		(at 151.494998 -142.88643 -90)
		(property "Reference" "R569"
			(at -1.458214 1.006602 90)
			(unlocked yes)
			(layer "F.SilkS")
			(effects
				(font
					(size 0.635 0.4064)
					(thickness 0.1524)
				)
				(justify left)
			)
		)
		(property "Value" ""
			(at 0 0 270)
			(layer "F.Fab")
			(effects
				(font
					(size 1.27 1.27)
				)
			)
		)
		(duplicate_pad_numbers_are_jumpers no)
		(fp_line
			(start -0.7874 0.4064)
			(end -0.7874 -0.4064)
			(stroke
				(width 0.1524)
				(type default)
			)
			(layer "F.SilkS")
		)
		(fp_line
			(start 0.7874 0.4064)
			(end -0.7874 0.4064)
			(stroke
				(width 0.1524)
				(type default)
			)
			(layer "F.SilkS")
		)
		(fp_line
			(start -0.7874 -0.4064)
			(end 0.7874 -0.4064)
			(stroke
				(width 0.1524)
				(type default)
			)
			(layer "F.SilkS")
		)
		(fp_line
			(start 0.7874 -0.4064)
			(end 0.7874 0.4064)
			(stroke
				(width 0.1524)
				(type default)
			)
			(layer "F.SilkS")
		)
		(fp_poly
			(pts
				(xy -0.508 0.2794) (xy -0.508 0.2286) (xy -0.635 0.2286) (xy -0.635 -0.254) (xy -0.5334 -0.254)
				(xy -0.5334 -0.2794) (xy 0.5334 -0.2794) (xy 0.5334 -0.254) (xy 0.635 -0.254) (xy 0.635 0.254) (xy 0.5334 0.254)
				(xy 0.5334 0.2794)
			)
			(stroke
				(width 0)
				(type default)
			)
			(fill no)
			(layer "F.CrtYd")
		)
		(pad "1" smd rect
			(at 0.40005 0 270)
			(size 0.4572 0.508)
			(layers "F.Cu" "F.Mask" "F.Paste")
			(net "P3V3_NODE1")
		)
		(pad "2" smd rect
			(at -0.40005 0 270)
			(size 0.4572 0.508)
			(layers "F.Cu" "F.Mask" "F.Paste")
			(net "SMB_LAN2_ALT_N")
		)
	)
	(footprint ""
		(layer "F.Cu")
		(at 121.65076 -188.126624 -90)
		(property "Reference" "R979"
			(at -4.967986 0.237998 90)
			(unlocked yes)
			(layer "F.SilkS")
			(effects
				(font
					(size 0.7874 0.5842)
					(thickness 0.1524)
				)
				(justify left)
			)
		)
		(property "Value" ""
			(at 0 0 270)
			(layer "F.Fab")
			(effects
				(font
					(size 1.27 1.27)
				)
			)
		)
		(duplicate_pad_numbers_are_jumpers no)
		(fp_line
			(start -0.7874 0.4064)
			(end -0.7874 -0.4064)
			(stroke
				(width 0.1524)
				(type default)
			)
			(layer "F.SilkS")
		)
		(fp_line
			(start 0.7874 0.4064)
			(end -0.7874 0.4064)
			(stroke
				(width 0.1524)
				(type default)
			)
			(layer "F.SilkS")
		)
		(fp_line
			(start -0.7874 -0.4064)
			(end 0.7874 -0.4064)
			(stroke
				(width 0.1524)
				(type default)
			)
			(layer "F.SilkS")
		)
		(fp_line
			(start 0.7874 -0.4064)
			(end 0.7874 0.4064)
			(stroke
				(width 0.1524)
				(type default)
			)
			(layer "F.SilkS")
		)
		(fp_poly
			(pts
				(xy -0.508 0.2794) (xy -0.508 0.2286) (xy -0.635 0.2286) (xy -0.635 -0.254) (xy -0.5334 -0.254)
				(xy -0.5334 -0.2794) (xy 0.5334 -0.2794) (xy 0.5334 -0.254) (xy 0.635 -0.254) (xy 0.635 0.254) (xy 0.5334 0.254)
				(xy 0.5334 0.2794)
			)
			(stroke
				(width 0)
				(type default)
			)
			(fill no)
			(layer "F.CrtYd")
		)
		(pad "1" smd rect
			(at 0.40005 0 270)
			(size 0.4572 0.508)
			(layers "F.Cu" "F.Mask" "F.Paste")
			(net "UART_T8_NODE1_RXD")
		)
		(pad "2" smd rect
			(at -0.40005 0 270)
			(size 0.4572 0.508)
			(layers "F.Cu" "F.Mask" "F.Paste")
			(net "UART_T8_NODE1_RXD_R")
		)
	)
	(footprint ""
		(layer "F.Cu")
		(at 6.73862 -151.331168 180)
		(property "Reference" "R1300"
			(at -0.99822 -0.96647 0)
			(unlocked yes)
			(layer "F.SilkS")
			(effects
				(font
					(size 0.7874 0.5842)
					(thickness 0.1524)
				)
				(justify left)
			)
		)
		(property "Value" ""
			(at 0 0 180)
			(layer "F.Fab")
			(effects
				(font
					(size 1.27 1.27)
				)
			)
		)
		(duplicate_pad_numbers_are_jumpers no)
		(fp_line
			(start 0.7874 0.4064)
			(end -0.7874 0.4064)
			(stroke
				(width 0.1524)
				(type default)
			)
			(layer "F.SilkS")
		)
		(fp_line
			(start 0.7874 -0.4064)
			(end 0.7874 0.4064)
			(stroke
				(width 0.1524)
				(type default)
			)
			(layer "F.SilkS")
		)
		(fp_line
			(start -0.7874 0.4064)
			(end -0.7874 -0.4064)
			(stroke
				(width 0.1524)
				(type default)
			)
			(layer "F.SilkS")
		)
		(fp_line
			(start -0.7874 -0.4064)
			(end 0.7874 -0.4064)
			(stroke
				(width 0.1524)
				(type default)
			)
			(layer "F.SilkS")
		)
		(fp_poly
			(pts
				(xy -0.508 0.2794) (xy -0.508 0.2286) (xy -0.635 0.2286) (xy -0.635 -0.254) (xy -0.5334 -0.254)
				(xy -0.5334 -0.2794) (xy 0.5334 -0.2794) (xy 0.5334 -0.254) (xy 0.635 -0.254) (xy 0.635 0.254) (xy 0.5334 0.254)
				(xy 0.5334 0.2794)
			)
			(stroke
				(width 0)
				(type default)
			)
			(fill no)
			(layer "F.CrtYd")
		)
		(pad "1" smd rect
			(at 0.40005 0 180)
			(size 0.4572 0.508)
			(layers "F.Cu" "F.Mask" "F.Paste")
			(net "GND")
		)
		(pad "2" smd rect
			(at -0.40005 0 180)
			(size 0.4572 0.508)
			(layers "F.Cu" "F.Mask" "F.Paste")
			(net "N54310531")
		)
	)
	(footprint ""
		(layer "F.Cu")
		(at 140.34516 -117.006624)
		(property "Reference" "R18"
			(at -0.907796 -1.867408 0)
			(unlocked yes)
			(layer "F.SilkS")
			(effects
				(font
					(size 0.7874 0.5842)
					(thickness 0.1524)
				)
				(justify left)
			)
		)
		(property "Value" ""
			(at 0 0 0)
			(layer "F.Fab")
			(effects
				(font
					(size 1.27 1.27)
				)
			)
		)
		(duplicate_pad_numbers_are_jumpers no)
		(fp_line
			(start -0.7874 -0.4064)
			(end 0.7874 -0.4064)
			(stroke
				(width 0.1524)
				(type default)
			)
			(layer "F.SilkS")
		)
		(fp_line
			(start -0.7874 0.4064)
			(end -0.7874 -0.4064)
			(stroke
				(width 0.1524)
				(type default)
			)
			(layer "F.SilkS")
		)
		(fp_line
			(start 0.7874 -0.4064)
			(end 0.7874 0.4064)
			(stroke
				(width 0.1524)
				(type default)
			)
			(layer "F.SilkS")
		)
		(fp_line
			(start 0.7874 0.4064)
			(end -0.7874 0.4064)
			(stroke
				(width 0.1524)
				(type default)
			)
			(layer "F.SilkS")
		)
		(fp_poly
			(pts
				(xy -0.508 0.2794) (xy -0.508 0.2286) (xy -0.635 0.2286) (xy -0.635 -0.254) (xy -0.5334 -0.254)
				(xy -0.5334 -0.2794) (xy 0.5334 -0.2794) (xy 0.5334 -0.254) (xy 0.635 -0.254) (xy 0.635 0.254) (xy 0.5334 0.254)
				(xy 0.5334 0.2794)
			)
			(stroke
				(width 0)
				(type default)
			)
			(fill no)
			(layer "F.CrtYd")
		)
		(pad "1" smd rect
			(at 0.40005 0)
			(size 0.4572 0.508)
			(layers "F.Cu" "F.Mask" "F.Paste")
			(net "GND")
		)
		(pad "2" smd rect
			(at -0.40005 0)
			(size 0.4572 0.508)
			(layers "F.Cu" "F.Mask" "F.Paste")
			(net "SEL_PCI_27M")
		)
	)
	(footprint ""
		(layer "F.Cu")
		(at 193.717672 -148.789898 180)
		(property "Reference" "C473"
			(at -2.357374 0.092202 0)
			(unlocked yes)
			(layer "F.SilkS")
			(effects
				(font
					(size 0.7874 0.5842)
					(thickness 0.1524)
				)
				(justify left)
			)
		)
		(property "Value" ""
			(at 0 0 180)
			(layer "F.Fab")
			(effects
				(font
					(size 1.27 1.27)
				)
			)
		)
		(duplicate_pad_numbers_are_jumpers no)
		(fp_line
			(start 1.905 0.8636)
			(end -1.905 0.8636)
			(stroke
				(width 0.1524)
				(type default)
			)
			(layer "F.SilkS")
		)
		(fp_line
			(start 1.905 -0.8636)
			(end 1.905 0.8636)
			(stroke
				(width 0.1524)
				(type default)
			)
			(layer "F.SilkS")
		)
		(fp_line
			(start 0 0.8382)
			(end 0 -0.8382)
			(stroke
				(width 0.1524)
				(type default)
			)
			(layer "F.SilkS")
		)
		(fp_line
			(start -1.905 0.8636)
			(end -1.905 -0.8636)
			(stroke
				(width 0.1524)
				(type default)
			)
			(layer "F.SilkS")
		)
		(fp_line
			(start -1.905 -0.8636)
			(end 1.905 -0.8636)
			(stroke
				(width 0.1524)
				(type default)
			)
			(layer "F.SilkS")
		)
		(fp_rect
			(start -1.524 0.7366)
			(end 1.524 -0.7366)
			(stroke
				(width 0)
				(type default)
			)
			(fill no)
			(layer "F.CrtYd")
		)
		(pad "1" smd rect
			(at 0.94996 0 180)
			(size 1.1176 1.3716)
			(layers "F.Cu" "F.Mask" "F.Paste")
			(net "P1V9_LAN2")
		)
		(pad "2" smd rect
			(at -0.94996 0 180)
			(size 1.1176 1.3716)
			(layers "F.Cu" "F.Mask" "F.Paste")
			(net "GND")
		)
	)
	(footprint ""
		(layer "F.Cu")
		(at 69.96176 -188.126624 90)
		(property "Reference" "C716"
			(at 4.548886 -0.848868 90)
			(unlocked yes)
			(layer "F.SilkS")
			(effects
				(font
					(size 0.7874 0.5842)
					(thickness 0.1524)
				)
				(justify left)
			)
		)
		(property "Value" ""
			(at 0 0 90)
			(layer "F.Fab")
			(effects
				(font
					(size 1.27 1.27)
				)
			)
		)
		(duplicate_pad_numbers_are_jumpers no)
		(fp_line
			(start 0.7874 -0.4064)
			(end 0.7874 0.4064)
			(stroke
				(width 0.1524)
				(type default)
			)
			(layer "F.SilkS")
		)
		(fp_line
			(start -0.7874 -0.4064)
			(end 0.7874 -0.4064)
			(stroke
				(width 0.1524)
				(type default)
			)
			(layer "F.SilkS")
		)
		(fp_line
			(start 0 0.381)
			(end 0 -0.381)
			(stroke
				(width 0.1524)
				(type default)
			)
			(layer "F.SilkS")
		)
		(fp_line
			(start 0.7874 0.4064)
			(end -0.7874 0.4064)
			(stroke
				(width 0.1524)
				(type default)
			)
			(layer "F.SilkS")
		)
		(fp_line
			(start -0.7874 0.4064)
			(end -0.7874 -0.4064)
			(stroke
				(width 0.1524)
				(type default)
			)
			(layer "F.SilkS")
		)
		(fp_poly
			(pts
				(xy -0.5334 0.254) (xy -0.635 0.254) (xy -0.635 0.2286) (xy -0.635 -0.254) (xy -0.5334 -0.254) (xy -0.5334 -0.2794)
				(xy 0.5334 -0.2794) (xy 0.5334 -0.254) (xy 0.635 -0.254) (xy 0.635 0.254) (xy 0.5334 0.254) (xy 0.5334 0.2794)
				(xy -0.508 0.2794) (xy -0.5334 0.2794)
			)
			(stroke
				(width 0)
				(type default)
			)
			(fill no)
			(layer "F.CrtYd")
		)
		(pad "1" smd rect
			(at 0.40005 0 90)
			(size 0.4572 0.508)
			(layers "F.Cu" "F.Mask" "F.Paste")
			(net "UART_T4_NODE4_TXD_R")
		)
		(pad "2" smd rect
			(at -0.40005 0 90)
			(size 0.4572 0.508)
			(layers "F.Cu" "F.Mask" "F.Paste")
			(net "GND")
		)
	)
	(footprint ""
		(layer "F.Cu")
		(at 52.223162 -146.530822 180)
		(property "Reference" "R549"
			(at 2.1336 -5.284978 0)
			(unlocked yes)
			(layer "F.SilkS")
			(effects
				(font
					(size 0.7874 0.5842)
					(thickness 0.1524)
				)
				(justify left)
			)
		)
		(property "Value" ""
			(at 0 0 180)
			(layer "F.Fab")
			(effects
				(font
					(size 1.27 1.27)
				)
			)
		)
		(duplicate_pad_numbers_are_jumpers no)
		(fp_line
			(start 0.7874 0.4064)
			(end -0.7874 0.4064)
			(stroke
				(width 0.1524)
				(type default)
			)
			(layer "F.SilkS")
		)
		(fp_line
			(start 0.7874 -0.4064)
			(end 0.7874 0.4064)
			(stroke
				(width 0.1524)
				(type default)
			)
			(layer "F.SilkS")
		)
		(fp_line
			(start -0.7874 0.4064)
			(end -0.7874 -0.4064)
			(stroke
				(width 0.1524)
				(type default)
			)
			(layer "F.SilkS")
		)
		(fp_line
			(start -0.7874 -0.4064)
			(end 0.7874 -0.4064)
			(stroke
				(width 0.1524)
				(type default)
			)
			(layer "F.SilkS")
		)
		(fp_poly
			(pts
				(xy -0.508 0.2794) (xy -0.508 0.2286) (xy -0.635 0.2286) (xy -0.635 -0.254) (xy -0.5334 -0.254)
				(xy -0.5334 -0.2794) (xy 0.5334 -0.2794) (xy 0.5334 -0.254) (xy 0.635 -0.254) (xy 0.635 0.254) (xy 0.5334 0.254)
				(xy 0.5334 0.2794)
			)
			(stroke
				(width 0)
				(type default)
			)
			(fill no)
			(layer "F.CrtYd")
		)
		(pad "1" smd rect
			(at 0.40005 0 180)
			(size 0.4572 0.508)
			(layers "F.Cu" "F.Mask" "F.Paste")
			(net "SPI_LAN1_NVM_SO")
		)
		(pad "2" smd rect
			(at -0.40005 0 180)
			(size 0.4572 0.508)
			(layers "F.Cu" "F.Mask" "F.Paste")
			(net "LAN1_NVM_SO_R")
		)
	)
	(footprint ""
		(layer "F.Cu")
		(at 44.207176 -179.317904 180)
		(property "Reference" "C774"
			(at 0.96012 -132.59308 0)
			(unlocked yes)
			(layer "F.SilkS")
			(effects
				(font
					(size 0.7874 0.5842)
					(thickness 0.1524)
				)
				(justify left)
			)
		)
		(property "Value" ""
			(at 0 0 180)
			(layer "F.Fab")
			(effects
				(font
					(size 1.27 1.27)
				)
			)
		)
		(duplicate_pad_numbers_are_jumpers no)
		(fp_line
			(start 0.7874 0.4064)
			(end -0.7874 0.4064)
			(stroke
				(width 0.1524)
				(type default)
			)
			(layer "F.SilkS")
		)
		(fp_line
			(start 0.7874 -0.4064)
			(end 0.7874 0.4064)
			(stroke
				(width 0.1524)
				(type default)
			)
			(layer "F.SilkS")
		)
		(fp_line
			(start 0 0.381)
			(end 0 -0.381)
			(stroke
				(width 0.1524)
				(type default)
			)
			(layer "F.SilkS")
		)
		(fp_line
			(start -0.7874 0.4064)
			(end -0.7874 -0.4064)
			(stroke
				(width 0.1524)
				(type default)
			)
			(layer "F.SilkS")
		)
		(fp_line
			(start -0.7874 -0.4064)
			(end 0.7874 -0.4064)
			(stroke
				(width 0.1524)
				(type default)
			)
			(layer "F.SilkS")
		)
		(fp_poly
			(pts
				(xy -0.5334 0.254) (xy -0.635 0.254) (xy -0.635 0.2286) (xy -0.635 -0.254) (xy -0.5334 -0.254) (xy -0.5334 -0.2794)
				(xy 0.5334 -0.2794) (xy 0.5334 -0.254) (xy 0.635 -0.254) (xy 0.635 0.254) (xy 0.5334 0.254) (xy 0.5334 0.2794)
				(xy -0.508 0.2794) (xy -0.5334 0.2794)
			)
			(stroke
				(width 0)
				(type default)
			)
			(fill no)
			(layer "F.CrtYd")
		)
		(pad "1" smd rect
			(at 0.40005 0 180)
			(size 0.4572 0.508)
			(layers "F.Cu" "F.Mask" "F.Paste")
			(net "P12V_AUX")
		)
		(pad "2" smd rect
			(at -0.40005 0 180)
			(size 0.4572 0.508)
			(layers "F.Cu" "F.Mask" "F.Paste")
			(net "GND")
		)
	)
	(footprint ""
		(layer "F.Cu")
		(at 15.21968 -43.923204 90)
		(property "Reference" "C502"
			(at -7.91337 -0.69342 90)
			(unlocked yes)
			(layer "F.SilkS")
			(effects
				(font
					(size 0.7874 0.5842)
					(thickness 0.1524)
				)
			)
		)
		(property "Value" ""
			(at 0 0 90)
			(layer "F.Fab")
			(effects
				(font
					(size 1.27 1.27)
				)
			)
		)
		(duplicate_pad_numbers_are_jumpers no)
		(fp_line
			(start 1.2954 -0.5842)
			(end 1.2954 0.5842)
			(stroke
				(width 0.1524)
				(type default)
			)
			(layer "F.SilkS")
		)
		(fp_line
			(start 0 -0.5842)
			(end 0 0.5842)
			(stroke
				(width 0.1524)
				(type default)
			)
			(layer "F.SilkS")
		)
		(fp_line
			(start -1.2954 -0.5842)
			(end 1.2954 -0.5842)
			(stroke
				(width 0.1524)
				(type default)
			)
			(layer "F.SilkS")
		)
		(fp_line
			(start 1.2954 0.5842)
			(end -1.2954 0.5842)
			(stroke
				(width 0.1524)
				(type default)
			)
			(layer "F.SilkS")
		)
		(fp_line
			(start -1.2954 0.5842)
			(end -1.2954 -0.5842)
			(stroke
				(width 0.1524)
				(type default)
			)
			(layer "F.SilkS")
		)
		(fp_poly
			(pts
				(xy 0.8636 -0.4572) (xy 0.8636 -0.3556) (xy 1.143 -0.3556) (xy 1.143 0.3556) (xy 0.8636 0.3556)
				(xy 0.8636 0.4572) (xy -0.8636 0.4572) (xy -0.8636 0.3556) (xy -1.143 0.3556) (xy -1.143 -0.3556)
				(xy -0.8636 -0.3556) (xy -0.8636 -0.4572)
			)
			(stroke
				(width 0)
				(type default)
			)
			(fill no)
			(layer "F.CrtYd")
		)
		(fp_line
			(start 0.884936 -0.504952)
			(end 0.884936 0.504952)
			(stroke
				(width 0.1)
				(type default)
			)
			(layer "F.Fab")
		)
		(fp_line
			(start -0.884936 -0.504952)
			(end 0.884936 -0.504952)
			(stroke
				(width 0.1)
				(type default)
			)
			(layer "F.Fab")
		)
		(fp_line
			(start 0.884936 0.504952)
			(end -0.884936 0.504952)
			(stroke
				(width 0.1)
				(type default)
			)
			(layer "F.Fab")
		)
		(fp_line
			(start -0.884936 0.504952)
			(end -0.884936 -0.504952)
			(stroke
				(width 0.1)
				(type default)
			)
			(layer "F.Fab")
		)
		(pad "1" smd rect
			(at 0.7366 0 180)
			(size 0.7112 0.8128)
			(layers "F.Cu" "F.Mask" "F.Paste")
			(net "CRT_R")
		)
		(pad "2" smd rect
			(at -0.7366 0 180)
			(size 0.7112 0.8128)
			(layers "F.Cu" "F.Mask" "F.Paste")
			(net "GND")
		)
	)
	(footprint ""
		(layer "F.Cu")
		(at 83.460082 -88.702134)
		(property "Reference" "R136"
			(at -1.235202 1.075944 0)
			(unlocked yes)
			(layer "F.SilkS")
			(effects
				(font
					(size 0.635 0.4064)
					(thickness 0.1524)
				)
				(justify left)
			)
		)
		(property "Value" ""
			(at 0 0 0)
			(layer "F.Fab")
			(effects
				(font
					(size 1.27 1.27)
				)
			)
		)
		(duplicate_pad_numbers_are_jumpers no)
		(fp_line
			(start -0.7874 -0.4064)
			(end 0.7874 -0.4064)
			(stroke
				(width 0.1524)
				(type default)
			)
			(layer "F.SilkS")
		)
		(fp_line
			(start -0.7874 0.4064)
			(end -0.7874 -0.4064)
			(stroke
				(width 0.1524)
				(type default)
			)
			(layer "F.SilkS")
		)
		(fp_line
			(start 0.7874 -0.4064)
			(end 0.7874 0.4064)
			(stroke
				(width 0.1524)
				(type default)
			)
			(layer "F.SilkS")
		)
		(fp_line
			(start 0.7874 0.4064)
			(end -0.7874 0.4064)
			(stroke
				(width 0.1524)
				(type default)
			)
			(layer "F.SilkS")
		)
		(fp_poly
			(pts
				(xy -0.508 0.2794) (xy -0.508 0.2286) (xy -0.635 0.2286) (xy -0.635 -0.254) (xy -0.5334 -0.254)
				(xy -0.5334 -0.2794) (xy 0.5334 -0.2794) (xy 0.5334 -0.254) (xy 0.635 -0.254) (xy 0.635 0.254) (xy 0.5334 0.254)
				(xy 0.5334 0.2794)
			)
			(stroke
				(width 0)
				(type default)
			)
			(fill no)
			(layer "F.CrtYd")
		)
		(pad "1" smd rect
			(at 0.40005 0)
			(size 0.4572 0.508)
			(layers "F.Cu" "F.Mask" "F.Paste")
			(net "P3V3_SUS_NODE1")
		)
		(pad "2" smd rect
			(at -0.40005 0)
			(size 0.4572 0.508)
			(layers "F.Cu" "F.Mask" "F.Paste")
			(net "FM_CPU_NODE1_SLPRDY_L")
		)
	)
	(footprint ""
		(layer "F.Cu")
		(at 189.221872 -7.457694)
		(property "Reference" "J32"
			(at -0.921766 -2.167382 0)
			(unlocked yes)
			(layer "F.SilkS")
			(effects
				(font
					(size 0.7874 0.5842)
					(thickness 0.1524)
				)
				(justify left)
			)
		)
		(property "Value" ""
			(at 0 0 0)
			(layer "F.Fab")
			(effects
				(font
					(size 1.27 1.27)
				)
			)
		)
		(duplicate_pad_numbers_are_jumpers no)
		(fp_line
			(start -2.739898 -1.27)
			(end -2.739898 1.27)
			(stroke
				(width 0.1524)
				(type default)
			)
			(layer "F.SilkS")
		)
		(fp_line
			(start -2.739898 1.27)
			(end -2.690114 1.27)
			(stroke
				(width 0.1524)
				(type default)
			)
			(layer "F.SilkS")
		)
		(fp_line
			(start -2.739898 1.27)
			(end 2.739898 1.27)
			(stroke
				(width 0.1524)
				(type default)
			)
			(layer "F.SilkS")
		)
		(fp_line
			(start 2.739898 -1.27)
			(end -2.739898 -1.27)
			(stroke
				(width 0.1524)
				(type default)
			)
			(layer "F.SilkS")
		)
		(fp_line
			(start 2.739898 1.27)
			(end 2.739898 -1.27)
			(stroke
				(width 0.1524)
				(type default)
			)
			(layer "F.SilkS")
		)
		(fp_poly
			(pts
				(xy -1.2192 1.7653) (xy -1.9558 3.5687) (xy -0.5842 3.5687)
			)
			(stroke
				(width 0)
				(type default)
			)
			(fill yes)
			(layer "F.SilkS")
		)
		(fp_rect
			(start -2.1844 0.9144)
			(end 2.1844 -0.9144)
			(stroke
				(width 0)
				(type default)
			)
			(fill no)
			(layer "B.CrtYd")
		)
		(fp_poly
			(pts
				(xy -2.739898 1.27) (xy 2.739898 1.27) (xy 2.739898 -1.27) (xy -2.739898 -1.27)
			)
			(stroke
				(width 0)
				(type default)
			)
			(fill no)
			(layer "F.CrtYd")
		)
		(fp_line
			(start -2.739898 -1.27)
			(end -2.739898 1.27)
			(stroke
				(width 0.1)
				(type default)
			)
			(layer "F.Fab")
		)
		(fp_line
			(start -2.739898 1.27)
			(end -2.690114 1.27)
			(stroke
				(width 0.1)
				(type default)
			)
			(layer "F.Fab")
		)
		(fp_line
			(start -2.739898 1.27)
			(end 2.739898 1.27)
			(stroke
				(width 0.1)
				(type default)
			)
			(layer "F.Fab")
		)
		(fp_line
			(start 2.739898 -1.27)
			(end -2.739898 -1.27)
			(stroke
				(width 0.1)
				(type default)
			)
			(layer "F.Fab")
		)
		(fp_line
			(start 2.739898 1.27)
			(end 2.739898 -1.27)
			(stroke
				(width 0.1)
				(type default)
			)
			(layer "F.Fab")
		)
		(fp_poly
			(pts
				(xy -1.2192 1.7653) (xy -1.9558 3.5687) (xy -0.5842 3.5687)
			)
			(stroke
				(width 0)
				(type default)
			)
			(fill yes)
			(layer "F.Fab")
		)
		(fp_text user "1"
			(at -1.916938 1.964944 0)
			(unlocked yes)
			(layer "F.SilkS")
			(effects
				(font
					(size 0.7874 0.5842)
					(thickness 0.1524)
				)
				(justify left)
			)
		)
		(fp_text user "2"
			(at 2.78638 -0.63373 0)
			(unlocked yes)
			(layer "F.SilkS")
			(effects
				(font
					(size 0.7874 0.5842)
					(thickness 0.1524)
				)
				(justify left)
			)
		)
		(fp_text user "1"
			(at -0.685292 -1.810766 0)
			(unlocked yes)
			(layer "B.SilkS")
			(effects
				(font
					(size 0.7874 0.5842)
					(thickness 0.1524)
				)
				(justify left mirror)
			)
		)
		(fp_text user "2"
			(at 1.589024 -1.810766 0)
			(unlocked yes)
			(layer "B.SilkS")
			(effects
				(font
					(size 0.7874 0.5842)
					(thickness 0.1524)
				)
				(justify left mirror)
			)
		)
		(fp_text user "1"
			(at -1.9431 -0.18669 0)
			(unlocked yes)
			(layer "B.Fab")
			(effects
				(font
					(size 1.6002 1.1938)
					(thickness 0.000001)
				)
				(justify left mirror)
			)
		)
		(fp_text user "2"
			(at 3.1369 -0.18669 0)
			(unlocked yes)
			(layer "B.Fab")
			(effects
				(font
					(size 1.6002 1.1938)
					(thickness 0.000001)
				)
				(justify left mirror)
			)
		)
		(fp_text user "1"
			(at -2.8829 2.48031 0)
			(unlocked yes)
			(layer "F.Fab")
			(effects
				(font
					(size 1.6002 1.1938)
					(thickness 0.000001)
				)
				(justify left)
			)
		)
		(fp_text user "2"
			(at 0.6731 2.48031 0)
			(unlocked yes)
			(layer "F.Fab")
			(effects
				(font
					(size 1.6002 1.1938)
					(thickness 0.000001)
				)
				(justify left)
			)
		)
		(pad "1" thru_hole rect
			(at -1.27 0)
			(size 1.7272 1.7272)
			(drill 1.2192)
			(layers "*.Cu" "*.Mask")
			(remove_unused_layers no)
			(net "TACKOVER_EN_N")
			(clearance 0)
			(padstack
				(mode front_inner_back)
				(layer "Inner"
					(shape circle)
					(size 1.7272 1.7272)
					(clearance 0)
				)
				(layer "B.Cu"
					(shape rect)
					(size 1.7272 1.7272)
					(clearance 0)
				)
			)
		)
		(pad "2" thru_hole circle
			(at 1.27 0)
			(size 1.7272 1.7272)
			(drill 1.2192)
			(layers "*.Cu" "*.Mask")
			(remove_unused_layers no)
			(net "GND")
			(clearance 0)
		)
	)
	(footprint ""
		(layer "F.Cu")
		(at 124.063252 -26.574242 90)
		(property "Reference" "C486"
			(at -5.330444 0.16637 90)
			(unlocked yes)
			(layer "F.SilkS")
			(effects
				(font
					(size 0.7874 0.5842)
					(thickness 0.1524)
				)
				(justify left)
			)
		)
		(property "Value" ""
			(at 0 0 90)
			(layer "F.Fab")
			(effects
				(font
					(size 1.27 1.27)
				)
			)
		)
		(duplicate_pad_numbers_are_jumpers no)
		(fp_line
			(start 0.7874 -0.4064)
			(end 0.7874 0.4064)
			(stroke
				(width 0.1524)
				(type default)
			)
			(layer "F.SilkS")
		)
		(fp_line
			(start -0.7874 -0.4064)
			(end 0.7874 -0.4064)
			(stroke
				(width 0.1524)
				(type default)
			)
			(layer "F.SilkS")
		)
		(fp_line
			(start 0 0.381)
			(end 0 -0.381)
			(stroke
				(width 0.1524)
				(type default)
			)
			(layer "F.SilkS")
		)
		(fp_line
			(start 0.7874 0.4064)
			(end -0.7874 0.4064)
			(stroke
				(width 0.1524)
				(type default)
			)
			(layer "F.SilkS")
		)
		(fp_line
			(start -0.7874 0.4064)
			(end -0.7874 -0.4064)
			(stroke
				(width 0.1524)
				(type default)
			)
			(layer "F.SilkS")
		)
		(fp_poly
			(pts
				(xy -0.5334 0.254) (xy -0.635 0.254) (xy -0.635 0.2286) (xy -0.635 -0.254) (xy -0.5334 -0.254) (xy -0.5334 -0.2794)
				(xy 0.5334 -0.2794) (xy 0.5334 -0.254) (xy 0.635 -0.254) (xy 0.635 0.254) (xy 0.5334 0.254) (xy 0.5334 0.2794)
				(xy -0.508 0.2794) (xy -0.5334 0.2794)
			)
			(stroke
				(width 0)
				(type default)
			)
			(fill no)
			(layer "F.CrtYd")
		)
		(pad "1" smd rect
			(at 0.40005 0 90)
			(size 0.4572 0.508)
			(layers "F.Cu" "F.Mask" "F.Paste")
			(net "SIO_VBAT")
		)
		(pad "2" smd rect
			(at -0.40005 0 90)
			(size 0.4572 0.508)
			(layers "F.Cu" "F.Mask" "F.Paste")
			(net "GND")
		)
	)
	(footprint ""
		(layer "F.Cu")
		(at 169.643552 -56.98109)
		(property "Reference" "R269"
			(at -6.518148 0.01524 0)
			(unlocked yes)
			(layer "F.SilkS")
			(effects
				(font
					(size 0.7874 0.5842)
					(thickness 0.1524)
				)
				(justify left)
			)
		)
		(property "Value" ""
			(at 0 0 0)
			(layer "F.Fab")
			(effects
				(font
					(size 1.27 1.27)
				)
			)
		)
		(duplicate_pad_numbers_are_jumpers no)
		(fp_line
			(start -0.7874 -0.4064)
			(end 0.7874 -0.4064)
			(stroke
				(width 0.1524)
				(type default)
			)
			(layer "F.SilkS")
		)
		(fp_line
			(start -0.7874 0.4064)
			(end -0.7874 -0.4064)
			(stroke
				(width 0.1524)
				(type default)
			)
			(layer "F.SilkS")
		)
		(fp_line
			(start 0.7874 -0.4064)
			(end 0.7874 0.4064)
			(stroke
				(width 0.1524)
				(type default)
			)
			(layer "F.SilkS")
		)
		(fp_line
			(start 0.7874 0.4064)
			(end -0.7874 0.4064)
			(stroke
				(width 0.1524)
				(type default)
			)
			(layer "F.SilkS")
		)
		(fp_poly
			(pts
				(xy -0.508 0.2794) (xy -0.508 0.2286) (xy -0.635 0.2286) (xy -0.635 -0.254) (xy -0.5334 -0.254)
				(xy -0.5334 -0.2794) (xy 0.5334 -0.2794) (xy 0.5334 -0.254) (xy 0.635 -0.254) (xy 0.635 0.254) (xy 0.5334 0.254)
				(xy 0.5334 0.2794)
			)
			(stroke
				(width 0)
				(type default)
			)
			(fill no)
			(layer "F.CrtYd")
		)
		(pad "1" smd rect
			(at 0.40005 0)
			(size 0.4572 0.508)
			(layers "F.Cu" "F.Mask" "F.Paste")
			(net "USB2_L_DN")
		)
		(pad "2" smd rect
			(at -0.40005 0)
			(size 0.4572 0.508)
			(layers "F.Cu" "F.Mask" "F.Paste")
			(net "USB2_DN")
		)
	)
	(footprint ""
		(layer "F.Cu")
		(at 167.369744 -91.326208 90)
		(property "Reference" "Y3"
			(at -2.329688 1.194308 0)
			(unlocked yes)
			(layer "F.SilkS")
			(effects
				(font
					(size 0.7874 0.5842)
					(thickness 0.1524)
				)
				(justify left)
			)
		)
		(property "Value" ""
			(at 0 0 90)
			(layer "F.Fab")
			(effects
				(font
					(size 1.27 1.27)
				)
			)
		)
		(duplicate_pad_numbers_are_jumpers no)
		(fp_line
			(start 1.700022 -0.700024)
			(end 1.3716 -0.700024)
			(stroke
				(width 0.1524)
				(type default)
			)
			(layer "F.SilkS")
		)
		(fp_line
			(start -1.397 -0.700024)
			(end -1.700022 -0.700024)
			(stroke
				(width 0.1524)
				(type default)
			)
			(layer "F.SilkS")
		)
		(fp_line
			(start -1.700022 -0.700024)
			(end -1.700022 4.499864)
			(stroke
				(width 0.1524)
				(type default)
			)
			(layer "F.SilkS")
		)
		(fp_line
			(start 1.700022 4.499864)
			(end 1.700022 -0.700024)
			(stroke
				(width 0.1524)
				(type default)
			)
			(layer "F.SilkS")
		)
		(fp_line
			(start 1.3589 4.499864)
			(end 1.700022 4.499864)
			(stroke
				(width 0.1524)
				(type default)
			)
			(layer "F.SilkS")
		)
		(fp_line
			(start -1.700022 4.499864)
			(end -1.397 4.499864)
			(stroke
				(width 0.1524)
				(type default)
			)
			(layer "F.SilkS")
		)
		(fp_poly
			(pts
				(xy 0.233172 -1.826768) (xy -0.436372 -1.826768) (xy -0.114554 -1.018032)
			)
			(stroke
				(width 0)
				(type default)
			)
			(fill yes)
			(layer "F.SilkS")
		)
		(fp_poly
			(pts
				(xy -1.700022 -0.700024) (xy -1.700022 4.499864) (xy -1.27 4.499864) (xy -1.27 4.77012) (xy 1.27 4.77012)
				(xy 1.27 4.499864) (xy 1.700022 4.499864) (xy 1.700022 -0.700024) (xy 1.27 -0.700024) (xy 1.27 -0.97028)
				(xy -1.27 -0.97028) (xy -1.27 -0.700024)
			)
			(stroke
				(width 0)
				(type default)
			)
			(fill no)
			(layer "F.CrtYd")
		)
		(fp_line
			(start 1.700022 -0.700024)
			(end 1.700022 4.499864)
			(stroke
				(width 0.1)
				(type default)
			)
			(layer "F.Fab")
		)
		(fp_line
			(start -1.700022 -0.700024)
			(end 1.700022 -0.700024)
			(stroke
				(width 0.1)
				(type default)
			)
			(layer "F.Fab")
		)
		(fp_line
			(start 1.700022 4.499864)
			(end -1.700022 4.499864)
			(stroke
				(width 0.1)
				(type default)
			)
			(layer "F.Fab")
		)
		(fp_line
			(start -1.700022 4.499864)
			(end -1.700022 -0.700024)
			(stroke
				(width 0.1)
				(type default)
			)
			(layer "F.Fab")
		)
		(fp_poly
			(pts
				(xy 0.233172 -1.826768) (xy -0.436372 -1.826768) (xy -0.114554 -1.018032)
			)
			(stroke
				(width 0)
				(type default)
			)
			(fill yes)
			(layer "F.Fab")
		)
		(fp_text user "1"
			(at 0.576072 -1.455928 0)
			(unlocked yes)
			(layer "F.SilkS")
			(effects
				(font
					(size 0.635 0.4064)
					(thickness 0.1524)
				)
				(justify left)
			)
		)
		(fp_text user "2"
			(at 0.456184 4.836414 0)
			(unlocked yes)
			(layer "F.SilkS")
			(effects
				(font
					(size 0.635 0.4064)
					(thickness 0.1524)
				)
				(justify left)
			)
		)
		(fp_text user "1"
			(at 0.627888 -1.32588 0)
			(unlocked yes)
			(layer "F.Fab")
			(effects
				(font
					(size 0.635 0.4064)
					(thickness 0.000001)
				)
				(justify left)
			)
		)
		(fp_text user "2"
			(at 0.048768 4.7498 0)
			(unlocked yes)
			(layer "F.Fab")
			(effects
				(font
					(size 0.635 0.4064)
					(thickness 0.000001)
				)
				(justify left)
			)
		)
		(pad "1" smd rect
			(at 0 0)
			(size 1.8034 2.413)
			(layers "F.Cu" "F.Mask" "F.Paste")
			(net "USB_NODE1_XTA2")
		)
		(pad "2" smd rect
			(at 0 3.800094)
			(size 1.8034 2.413)
			(layers "F.Cu" "F.Mask" "F.Paste")
			(net "USB_NODE1_XTA1")
		)
	)
	(footprint ""
		(layer "F.Cu")
		(at 111.87176 -169.577512 180)
		(property "Reference" "R667"
			(at 1.96088 10.468356 0)
			(unlocked yes)
			(layer "F.SilkS")
			(effects
				(font
					(size 0.7874 0.5842)
					(thickness 0.1524)
				)
				(justify left)
			)
		)
		(property "Value" ""
			(at 0 0 180)
			(layer "F.Fab")
			(effects
				(font
					(size 1.27 1.27)
				)
			)
		)
		(duplicate_pad_numbers_are_jumpers no)
		(fp_line
			(start 0.7874 0.4064)
			(end -0.7874 0.4064)
			(stroke
				(width 0.1524)
				(type default)
			)
			(layer "F.SilkS")
		)
		(fp_line
			(start 0.7874 -0.4064)
			(end 0.7874 0.4064)
			(stroke
				(width 0.1524)
				(type default)
			)
			(layer "F.SilkS")
		)
		(fp_line
			(start -0.7874 0.4064)
			(end -0.7874 -0.4064)
			(stroke
				(width 0.1524)
				(type default)
			)
			(layer "F.SilkS")
		)
		(fp_line
			(start -0.7874 -0.4064)
			(end 0.7874 -0.4064)
			(stroke
				(width 0.1524)
				(type default)
			)
			(layer "F.SilkS")
		)
		(fp_poly
			(pts
				(xy -0.508 0.2794) (xy -0.508 0.2286) (xy -0.635 0.2286) (xy -0.635 -0.254) (xy -0.5334 -0.254)
				(xy -0.5334 -0.2794) (xy 0.5334 -0.2794) (xy 0.5334 -0.254) (xy 0.635 -0.254) (xy 0.635 0.254) (xy 0.5334 0.254)
				(xy 0.5334 0.2794)
			)
			(stroke
				(width 0)
				(type default)
			)
			(fill no)
			(layer "F.CrtYd")
		)
		(pad "1" smd rect
			(at 0.40005 0 180)
			(size 0.4572 0.508)
			(layers "F.Cu" "F.Mask" "F.Paste")
			(net "P3V3_NODE1")
		)
		(pad "2" smd rect
			(at -0.40005 0 180)
			(size 0.4572 0.508)
			(layers "F.Cu" "F.Mask" "F.Paste")
			(net "I2C_PSU2_SCL_MOS")
		)
	)
	(footprint ""
		(layer "F.Cu")
		(at 166.715694 -121.57202 180)
		(property "Reference" "R1045"
			(at 2.798064 -9.851644 0)
			(unlocked yes)
			(layer "F.SilkS")
			(effects
				(font
					(size 0.7874 0.5842)
					(thickness 0.1524)
				)
				(justify left)
			)
		)
		(property "Value" ""
			(at 0 0 180)
			(layer "F.Fab")
			(effects
				(font
					(size 1.27 1.27)
				)
			)
		)
		(duplicate_pad_numbers_are_jumpers no)
		(fp_line
			(start 0.7874 0.4064)
			(end -0.7874 0.4064)
			(stroke
				(width 0.1524)
				(type default)
			)
			(layer "F.SilkS")
		)
		(fp_line
			(start 0.7874 -0.4064)
			(end 0.7874 0.4064)
			(stroke
				(width 0.1524)
				(type default)
			)
			(layer "F.SilkS")
		)
		(fp_line
			(start -0.7874 0.4064)
			(end -0.7874 -0.4064)
			(stroke
				(width 0.1524)
				(type default)
			)
			(layer "F.SilkS")
		)
		(fp_line
			(start -0.7874 -0.4064)
			(end 0.7874 -0.4064)
			(stroke
				(width 0.1524)
				(type default)
			)
			(layer "F.SilkS")
		)
		(fp_poly
			(pts
				(xy -0.508 0.2794) (xy -0.508 0.2286) (xy -0.635 0.2286) (xy -0.635 -0.254) (xy -0.5334 -0.254)
				(xy -0.5334 -0.2794) (xy 0.5334 -0.2794) (xy 0.5334 -0.254) (xy 0.635 -0.254) (xy 0.635 0.254) (xy 0.5334 0.254)
				(xy 0.5334 0.2794)
			)
			(stroke
				(width 0)
				(type default)
			)
			(fill no)
			(layer "F.CrtYd")
		)
		(pad "1" smd rect
			(at 0.40005 0 180)
			(size 0.4572 0.508)
			(layers "F.Cu" "F.Mask" "F.Paste")
			(net "FM_NODE1_DDR3_SYSPWRGD_R_L")
		)
		(pad "2" smd rect
			(at -0.40005 0 180)
			(size 0.4572 0.508)
			(layers "F.Cu" "F.Mask" "F.Paste")
			(net "FM_NODE1_DDR3_SYSPWRGD_L")
		)
	)
	(footprint ""
		(layer "F.Cu")
		(at 191.389 -120.65 180)
		(property "Reference" "R1266"
			(at -0.2032 -2.64287 0)
			(unlocked yes)
			(layer "F.SilkS")
			(effects
				(font
					(size 0.7874 0.5842)
					(thickness 0.1524)
				)
				(justify left)
			)
		)
		(property "Value" ""
			(at 0 0 180)
			(layer "F.Fab")
			(effects
				(font
					(size 1.27 1.27)
				)
			)
		)
		(duplicate_pad_numbers_are_jumpers no)
		(fp_line
			(start 0.7874 0.4064)
			(end -0.7874 0.4064)
			(stroke
				(width 0.1524)
				(type default)
			)
			(layer "F.SilkS")
		)
		(fp_line
			(start 0.7874 -0.4064)
			(end 0.7874 0.4064)
			(stroke
				(width 0.1524)
				(type default)
			)
			(layer "F.SilkS")
		)
		(fp_line
			(start -0.7874 0.4064)
			(end -0.7874 -0.4064)
			(stroke
				(width 0.1524)
				(type default)
			)
			(layer "F.SilkS")
		)
		(fp_line
			(start -0.7874 -0.4064)
			(end 0.7874 -0.4064)
			(stroke
				(width 0.1524)
				(type default)
			)
			(layer "F.SilkS")
		)
		(fp_poly
			(pts
				(xy -0.508 0.2794) (xy -0.508 0.2286) (xy -0.635 0.2286) (xy -0.635 -0.254) (xy -0.5334 -0.254)
				(xy -0.5334 -0.2794) (xy 0.5334 -0.2794) (xy 0.5334 -0.254) (xy 0.635 -0.254) (xy 0.635 0.254) (xy 0.5334 0.254)
				(xy 0.5334 0.2794)
			)
			(stroke
				(width 0)
				(type default)
			)
			(fill no)
			(layer "F.CrtYd")
		)
		(pad "1" smd rect
			(at 0.40005 0 180)
			(size 0.4572 0.508)
			(layers "F.Cu" "F.Mask" "F.Paste")
			(net "SIO_JTAG_CPLD1_TDI")
		)
		(pad "2" smd rect
			(at -0.40005 0 180)
			(size 0.4572 0.508)
			(layers "F.Cu" "F.Mask" "F.Paste")
			(net "GND")
		)
	)
	(footprint ""
		(layer "F.Cu")
		(at 100.471732 -166.113206 -90)
		(property "Reference" "U70"
			(at 68.287392 -87.225124 0)
			(unlocked yes)
			(layer "F.SilkS")
			(effects
				(font
					(size 0.7874 0.5842)
					(thickness 0.1524)
				)
			)
		)
		(property "Value" ""
			(at 0 0 270)
			(layer "F.Fab")
			(effects
				(font
					(size 1.27 1.27)
				)
			)
		)
		(duplicate_pad_numbers_are_jumpers no)
		(fp_line
			(start -2.4892 1.524)
			(end -2.4892 0.5588)
			(stroke
				(width 0.1524)
				(type default)
			)
			(layer "F.SilkS")
		)
		(fp_line
			(start 2.4892 1.524)
			(end -2.4892 1.524)
			(stroke
				(width 0.1524)
				(type default)
			)
			(layer "F.SilkS")
		)
		(fp_line
			(start -2.4892 0.5588)
			(end -1.9304 0)
			(stroke
				(width 0.1524)
				(type default)
			)
			(layer "F.SilkS")
		)
		(fp_line
			(start -1.9304 0)
			(end -2.4892 -0.5588)
			(stroke
				(width 0.1524)
				(type default)
			)
			(layer "F.SilkS")
		)
		(fp_line
			(start -2.4892 -0.5588)
			(end -2.4892 -1.524)
			(stroke
				(width 0.1524)
				(type default)
			)
			(layer "F.SilkS")
		)
		(fp_line
			(start -2.4892 -1.524)
			(end 2.4892 -1.524)
			(stroke
				(width 0.1524)
				(type default)
			)
			(layer "F.SilkS")
		)
		(fp_line
			(start 2.4892 -1.524)
			(end 2.4892 1.524)
			(stroke
				(width 0.1524)
				(type default)
			)
			(layer "F.SilkS")
		)
		(fp_circle
			(center -1.905 1.016)
			(end -1.905 0.762)
			(stroke
				(width 0.1524)
				(type default)
			)
			(fill no)
			(layer "F.SilkS")
		)
		(fp_poly
			(pts
				(xy -2.4003 3.5179) (xy -2.4003 2.0066) (xy -2.4892 2.0066) (xy -2.4892 -2.0066) (xy -2.4003 -2.0066)
				(xy -2.4003 -3.5179) (xy 2.4003 -3.5179) (xy 2.4003 -2.0066) (xy 2.4892 -2.0066) (xy 2.4892 2.0066)
				(xy 2.4003 2.0066) (xy 2.4003 3.5179)
			)
			(stroke
				(width 0)
				(type default)
			)
			(fill no)
			(layer "F.CrtYd")
		)
		(pad "1" smd rect
			(at -2.2225 2.7432 270)
			(size 0.3556 1.5494)
			(layers "F.Cu" "F.Mask" "F.Paste")
			(net "I2C_SCL_FANCTRL2_R")
		)
		(pad "2" smd rect
			(at -1.5875 2.7432 270)
			(size 0.3556 1.5494)
			(layers "F.Cu" "F.Mask" "F.Paste")
			(net "GND")
		)
		(pad "3" smd rect
			(at -0.9525 2.7432 270)
			(size 0.3556 1.5494)
			(layers "F.Cu" "F.Mask" "F.Paste")
			(net "P3V3_NODE1")
		)
		(pad "4" smd rect
			(at -0.3175 2.7432 270)
			(size 0.3556 1.5494)
			(layers "F.Cu" "F.Mask" "F.Paste")
			(net "PU_FAN_TACH")
		)
		(pad "5" smd rect
			(at 0.3175 2.7432 270)
			(size 0.3556 1.5494)
			(layers "F.Cu" "F.Mask" "F.Paste")
			(net "Net_2252")
		)
		(pad "6" smd rect
			(at 0.9525 2.7432 270)
			(size 0.3556 1.5494)
			(layers "F.Cu" "F.Mask" "F.Paste")
			(net "FAN5_TACH_IN")
		)
		(pad "7" smd rect
			(at 1.5875 2.7432 270)
			(size 0.3556 1.5494)
			(layers "F.Cu" "F.Mask" "F.Paste")
			(net "FAN6_TACH_IN")
		)
		(pad "8" smd rect
			(at 2.2225 2.7432 270)
			(size 0.3556 1.5494)
			(layers "F.Cu" "F.Mask" "F.Paste")
			(net "Net_2251")
		)
		(pad "9" smd rect
			(at 2.2225 -2.7432 270)
			(size 0.3556 1.5494)
			(layers "F.Cu" "F.Mask" "F.Paste")
			(net "PU_FAN_TACH")
		)
		(pad "10" smd rect
			(at 1.5875 -2.7432 270)
			(size 0.3556 1.5494)
			(layers "F.Cu" "F.Mask" "F.Paste")
			(net "Net_2250")
		)
		(pad "11" smd rect
			(at 0.9525 -2.7432 270)
			(size 0.3556 1.5494)
			(layers "F.Cu" "F.Mask" "F.Paste")
			(net "FNACTRL2_ADD")
		)
		(pad "12" smd rect
			(at 0.3175 -2.7432 270)
			(size 0.3556 1.5494)
			(layers "F.Cu" "F.Mask" "F.Paste")
			(net "FNACTRL2_TMP_IN")
		)
		(pad "13" smd rect
			(at -0.3175 -2.7432 270)
			(size 0.3556 1.5494)
			(layers "F.Cu" "F.Mask" "F.Paste")
			(net "FNACTRL2_T_ST")
		)
		(pad "14" smd rect
			(at -0.9525 -2.7432 270)
			(size 0.3556 1.5494)
			(layers "F.Cu" "F.Mask" "F.Paste")
			(net "I2C_ALERT_FNACTRL2_N")
		)
		(pad "15" smd rect
			(at -1.5875 -2.7432 270)
			(size 0.3556 1.5494)
			(layers "F.Cu" "F.Mask" "F.Paste")
			(net "Net_2253")
		)
		(pad "16" smd rect
			(at -2.2225 -2.7432 270)
			(size 0.3556 1.5494)
			(layers "F.Cu" "F.Mask" "F.Paste")
			(net "I2C_SDA_FANCTRL2_R")
		)
	)
	(footprint ""
		(layer "F.Cu")
		(at 152.67051 -147.041362)
		(property "Reference" "C528"
			(at -1.316482 -3.967226 0)
			(unlocked yes)
			(layer "F.SilkS")
			(effects
				(font
					(size 0.635 0.4064)
					(thickness 0.1524)
				)
				(justify left)
			)
		)
		(property "Value" ""
			(at 0 0 0)
			(layer "F.Fab")
			(effects
				(font
					(size 1.27 1.27)
				)
			)
		)
		(duplicate_pad_numbers_are_jumpers no)
		(fp_line
			(start -0.7874 -0.4064)
			(end 0.7874 -0.4064)
			(stroke
				(width 0.1524)
				(type default)
			)
			(layer "F.SilkS")
		)
		(fp_line
			(start -0.7874 0.4064)
			(end -0.7874 -0.4064)
			(stroke
				(width 0.1524)
				(type default)
			)
			(layer "F.SilkS")
		)
		(fp_line
			(start 0 0.381)
			(end 0 -0.381)
			(stroke
				(width 0.1524)
				(type default)
			)
			(layer "F.SilkS")
		)
		(fp_line
			(start 0.7874 -0.4064)
			(end 0.7874 0.4064)
			(stroke
				(width 0.1524)
				(type default)
			)
			(layer "F.SilkS")
		)
		(fp_line
			(start 0.7874 0.4064)
			(end -0.7874 0.4064)
			(stroke
				(width 0.1524)
				(type default)
			)
			(layer "F.SilkS")
		)
		(fp_poly
			(pts
				(xy -0.5334 0.254) (xy -0.635 0.254) (xy -0.635 0.2286) (xy -0.635 -0.254) (xy -0.5334 -0.254) (xy -0.5334 -0.2794)
				(xy 0.5334 -0.2794) (xy 0.5334 -0.254) (xy 0.635 -0.254) (xy 0.635 0.254) (xy 0.5334 0.254) (xy 0.5334 0.2794)
				(xy -0.508 0.2794) (xy -0.5334 0.2794)
			)
			(stroke
				(width 0)
				(type default)
			)
			(fill no)
			(layer "F.CrtYd")
		)
		(pad "1" smd rect
			(at 0.40005 0)
			(size 0.4572 0.508)
			(layers "F.Cu" "F.Mask" "F.Paste")
			(net "LAN2_LED_LINK_100_N")
		)
		(pad "2" smd rect
			(at -0.40005 0)
			(size 0.4572 0.508)
			(layers "F.Cu" "F.Mask" "F.Paste")
			(net "GND")
		)
	)
	(footprint ""
		(layer "F.Cu")
		(at 187.7695 -163.024566)
		(property "Reference" "R1277"
			(at -1.685544 5.368544 0)
			(unlocked yes)
			(layer "F.SilkS")
			(effects
				(font
					(size 0.7874 0.5842)
					(thickness 0.1524)
				)
				(justify left)
			)
		)
		(property "Value" ""
			(at 0 0 0)
			(layer "F.Fab")
			(effects
				(font
					(size 1.27 1.27)
				)
			)
		)
		(duplicate_pad_numbers_are_jumpers no)
		(fp_line
			(start -0.7874 -0.4064)
			(end 0.7874 -0.4064)
			(stroke
				(width 0.1524)
				(type default)
			)
			(layer "F.SilkS")
		)
		(fp_line
			(start -0.7874 0.4064)
			(end -0.7874 -0.4064)
			(stroke
				(width 0.1524)
				(type default)
			)
			(layer "F.SilkS")
		)
		(fp_line
			(start 0.7874 -0.4064)
			(end 0.7874 0.4064)
			(stroke
				(width 0.1524)
				(type default)
			)
			(layer "F.SilkS")
		)
		(fp_line
			(start 0.7874 0.4064)
			(end -0.7874 0.4064)
			(stroke
				(width 0.1524)
				(type default)
			)
			(layer "F.SilkS")
		)
		(fp_poly
			(pts
				(xy -0.508 0.2794) (xy -0.508 0.2286) (xy -0.635 0.2286) (xy -0.635 -0.254) (xy -0.5334 -0.254)
				(xy -0.5334 -0.2794) (xy 0.5334 -0.2794) (xy 0.5334 -0.254) (xy 0.635 -0.254) (xy 0.635 0.254) (xy 0.5334 0.254)
				(xy 0.5334 0.2794)
			)
			(stroke
				(width 0)
				(type default)
			)
			(fill no)
			(layer "F.CrtYd")
		)
		(pad "1" smd rect
			(at 0.40005 0)
			(size 0.4572 0.508)
			(layers "F.Cu" "F.Mask" "F.Paste")
			(net "N54134271")
		)
		(pad "2" smd rect
			(at -0.40005 0)
			(size 0.4572 0.508)
			(layers "F.Cu" "F.Mask" "F.Paste")
			(net "LAN2_P1_R")
		)
	)
	(footprint ""
		(layer "F.Cu")
		(at 131.230878 -51.45151 -90)
		(property "Reference" "R1164"
			(at -16.31569 -30.669992 90)
			(unlocked yes)
			(layer "F.SilkS")
			(effects
				(font
					(size 0.7874 0.5842)
					(thickness 0.1524)
				)
				(justify left)
			)
		)
		(property "Value" ""
			(at 0 0 270)
			(layer "F.Fab")
			(effects
				(font
					(size 1.27 1.27)
				)
			)
		)
		(duplicate_pad_numbers_are_jumpers no)
		(fp_line
			(start -0.7874 0.4064)
			(end -0.7874 -0.4064)
			(stroke
				(width 0.1524)
				(type default)
			)
			(layer "F.SilkS")
		)
		(fp_line
			(start 0.7874 0.4064)
			(end -0.7874 0.4064)
			(stroke
				(width 0.1524)
				(type default)
			)
			(layer "F.SilkS")
		)
		(fp_line
			(start -0.7874 -0.4064)
			(end 0.7874 -0.4064)
			(stroke
				(width 0.1524)
				(type default)
			)
			(layer "F.SilkS")
		)
		(fp_line
			(start 0.7874 -0.4064)
			(end 0.7874 0.4064)
			(stroke
				(width 0.1524)
				(type default)
			)
			(layer "F.SilkS")
		)
		(fp_poly
			(pts
				(xy -0.508 0.2794) (xy -0.508 0.2286) (xy -0.635 0.2286) (xy -0.635 -0.254) (xy -0.5334 -0.254)
				(xy -0.5334 -0.2794) (xy 0.5334 -0.2794) (xy 0.5334 -0.254) (xy 0.635 -0.254) (xy 0.635 0.254) (xy 0.5334 0.254)
				(xy 0.5334 0.2794)
			)
			(stroke
				(width 0)
				(type default)
			)
			(fill no)
			(layer "F.CrtYd")
		)
		(pad "1" smd rect
			(at 0.40005 0 270)
			(size 0.4572 0.508)
			(layers "F.Cu" "F.Mask" "F.Paste")
			(net "UART_RTS_P4_R_N")
		)
		(pad "2" smd rect
			(at -0.40005 0 270)
			(size 0.4572 0.508)
			(layers "F.Cu" "F.Mask" "F.Paste")
			(net "UART_RTS_P4_N")
		)
	)
	(footprint ""
		(layer "F.Cu")
		(at 18.746724 -146.512534)
		(property "Reference" "C413"
			(at -5.747004 0.141986 0)
			(unlocked yes)
			(layer "F.SilkS")
			(effects
				(font
					(size 0.7874 0.5842)
					(thickness 0.1524)
				)
				(justify left)
			)
		)
		(property "Value" ""
			(at 0 0 0)
			(layer "F.Fab")
			(effects
				(font
					(size 1.27 1.27)
				)
			)
		)
		(duplicate_pad_numbers_are_jumpers no)
		(fp_line
			(start -1.905 -0.8636)
			(end 1.905 -0.8636)
			(stroke
				(width 0.1524)
				(type default)
			)
			(layer "F.SilkS")
		)
		(fp_line
			(start -1.905 0.8636)
			(end -1.905 -0.8636)
			(stroke
				(width 0.1524)
				(type default)
			)
			(layer "F.SilkS")
		)
		(fp_line
			(start 0 0.8382)
			(end 0 -0.8382)
			(stroke
				(width 0.1524)
				(type default)
			)
			(layer "F.SilkS")
		)
		(fp_line
			(start 1.905 -0.8636)
			(end 1.905 0.8636)
			(stroke
				(width 0.1524)
				(type default)
			)
			(layer "F.SilkS")
		)
		(fp_line
			(start 1.905 0.8636)
			(end -1.905 0.8636)
			(stroke
				(width 0.1524)
				(type default)
			)
			(layer "F.SilkS")
		)
		(fp_rect
			(start -1.524 0.7366)
			(end 1.524 -0.7366)
			(stroke
				(width 0)
				(type default)
			)
			(fill no)
			(layer "F.CrtYd")
		)
		(pad "1" smd rect
			(at 0.94996 0)
			(size 1.1176 1.3716)
			(layers "F.Cu" "F.Mask" "F.Paste")
			(net "P3V3_NODE1")
		)
		(pad "2" smd rect
			(at -0.94996 0)
			(size 1.1176 1.3716)
			(layers "F.Cu" "F.Mask" "F.Paste")
			(net "GND")
		)
	)
	(footprint ""
		(layer "F.Cu")
		(at 34.318956 -19.453352)
		(property "Reference" "R217"
			(at -3.041396 1.304798 0)
			(unlocked yes)
			(layer "F.SilkS")
			(effects
				(font
					(size 0.7874 0.5842)
					(thickness 0.1524)
				)
				(justify left)
			)
		)
		(property "Value" ""
			(at 0 0 0)
			(layer "F.Fab")
			(effects
				(font
					(size 1.27 1.27)
				)
			)
		)
		(duplicate_pad_numbers_are_jumpers no)
		(fp_line
			(start -0.7874 -0.4064)
			(end 0.7874 -0.4064)
			(stroke
				(width 0.1524)
				(type default)
			)
			(layer "F.SilkS")
		)
		(fp_line
			(start -0.7874 0.4064)
			(end -0.7874 -0.4064)
			(stroke
				(width 0.1524)
				(type default)
			)
			(layer "F.SilkS")
		)
		(fp_line
			(start 0.7874 -0.4064)
			(end 0.7874 0.4064)
			(stroke
				(width 0.1524)
				(type default)
			)
			(layer "F.SilkS")
		)
		(fp_line
			(start 0.7874 0.4064)
			(end -0.7874 0.4064)
			(stroke
				(width 0.1524)
				(type default)
			)
			(layer "F.SilkS")
		)
		(fp_poly
			(pts
				(xy -0.508 0.2794) (xy -0.508 0.2286) (xy -0.635 0.2286) (xy -0.635 -0.254) (xy -0.5334 -0.254)
				(xy -0.5334 -0.2794) (xy 0.5334 -0.2794) (xy 0.5334 -0.254) (xy 0.635 -0.254) (xy 0.635 0.254) (xy 0.5334 0.254)
				(xy 0.5334 0.2794)
			)
			(stroke
				(width 0)
				(type default)
			)
			(fill no)
			(layer "F.CrtYd")
		)
		(pad "1" smd rect
			(at 0.40005 0)
			(size 0.4572 0.508)
			(layers "F.Cu" "F.Mask" "F.Paste")
			(net "P1V5_NODE1_DDR3_VREF0_D")
		)
		(pad "2" smd rect
			(at -0.40005 0)
			(size 0.4572 0.508)
			(layers "F.Cu" "F.Mask" "F.Paste")
			(net "PV_VDDR_NODE1_VREF_LM321")
		)
	)
	(footprint ""
		(layer "F.Cu")
		(at 14.359382 -157.329378 180)
		(property "Reference" "R1274"
			(at 1.619504 -2.323846 0)
			(unlocked yes)
			(layer "F.SilkS")
			(effects
				(font
					(size 0.7874 0.5842)
					(thickness 0.1524)
				)
				(justify left)
			)
		)
		(property "Value" ""
			(at 0 0 180)
			(layer "F.Fab")
			(effects
				(font
					(size 1.27 1.27)
				)
			)
		)
		(duplicate_pad_numbers_are_jumpers no)
		(fp_line
			(start 0.7874 0.4064)
			(end -0.7874 0.4064)
			(stroke
				(width 0.1524)
				(type default)
			)
			(layer "F.SilkS")
		)
		(fp_line
			(start 0.7874 -0.4064)
			(end 0.7874 0.4064)
			(stroke
				(width 0.1524)
				(type default)
			)
			(layer "F.SilkS")
		)
		(fp_line
			(start -0.7874 0.4064)
			(end -0.7874 -0.4064)
			(stroke
				(width 0.1524)
				(type default)
			)
			(layer "F.SilkS")
		)
		(fp_line
			(start -0.7874 -0.4064)
			(end 0.7874 -0.4064)
			(stroke
				(width 0.1524)
				(type default)
			)
			(layer "F.SilkS")
		)
		(fp_poly
			(pts
				(xy -0.508 0.2794) (xy -0.508 0.2286) (xy -0.635 0.2286) (xy -0.635 -0.254) (xy -0.5334 -0.254)
				(xy -0.5334 -0.2794) (xy 0.5334 -0.2794) (xy 0.5334 -0.254) (xy 0.635 -0.254) (xy 0.635 0.254) (xy 0.5334 0.254)
				(xy 0.5334 0.2794)
			)
			(stroke
				(width 0)
				(type default)
			)
			(fill no)
			(layer "F.CrtYd")
		)
		(pad "1" smd rect
			(at 0.40005 0 180)
			(size 0.4572 0.508)
			(layers "F.Cu" "F.Mask" "F.Paste")
			(net "N54065132")
		)
		(pad "2" smd rect
			(at -0.40005 0 180)
			(size 0.4572 0.508)
			(layers "F.Cu" "F.Mask" "F.Paste")
			(net "LAN1_P2_R")
		)
	)
	(footprint ""
		(layer "F.Cu")
		(at 90.81262 -178.594512 180)
		(property "Reference" "R810"
			(at -85.97392 -76.296012 0)
			(unlocked yes)
			(layer "F.SilkS")
			(effects
				(font
					(size 0.7874 0.5842)
					(thickness 0.1524)
				)
				(justify left)
			)
		)
		(property "Value" ""
			(at 0 0 180)
			(layer "F.Fab")
			(effects
				(font
					(size 1.27 1.27)
				)
			)
		)
		(duplicate_pad_numbers_are_jumpers no)
		(fp_line
			(start 0.7874 0.4064)
			(end -0.7874 0.4064)
			(stroke
				(width 0.1524)
				(type default)
			)
			(layer "F.SilkS")
		)
		(fp_line
			(start 0.7874 -0.4064)
			(end 0.7874 0.4064)
			(stroke
				(width 0.1524)
				(type default)
			)
			(layer "F.SilkS")
		)
		(fp_line
			(start -0.7874 0.4064)
			(end -0.7874 -0.4064)
			(stroke
				(width 0.1524)
				(type default)
			)
			(layer "F.SilkS")
		)
		(fp_line
			(start -0.7874 -0.4064)
			(end 0.7874 -0.4064)
			(stroke
				(width 0.1524)
				(type default)
			)
			(layer "F.SilkS")
		)
		(fp_poly
			(pts
				(xy -0.508 0.2794) (xy -0.508 0.2286) (xy -0.635 0.2286) (xy -0.635 -0.254) (xy -0.5334 -0.254)
				(xy -0.5334 -0.2794) (xy 0.5334 -0.2794) (xy 0.5334 -0.254) (xy 0.635 -0.254) (xy 0.635 0.254) (xy 0.5334 0.254)
				(xy 0.5334 0.2794)
			)
			(stroke
				(width 0)
				(type default)
			)
			(fill no)
			(layer "F.CrtYd")
		)
		(pad "1" smd rect
			(at 0.40005 0 180)
			(size 0.4572 0.508)
			(layers "F.Cu" "F.Mask" "F.Paste")
			(net "CPLD_UART_RI_P4_N")
		)
		(pad "2" smd rect
			(at -0.40005 0 180)
			(size 0.4572 0.508)
			(layers "F.Cu" "F.Mask" "F.Paste")
			(net "GND")
		)
	)
	(footprint ""
		(layer "F.Cu")
		(at 151.309578 -57.249822 -90)
		(property "Reference" "R518"
			(at -14.50213 -26.0858 90)
			(unlocked yes)
			(layer "F.SilkS")
			(effects
				(font
					(size 0.7874 0.5842)
					(thickness 0.1524)
				)
				(justify left)
			)
		)
		(property "Value" ""
			(at 0 0 270)
			(layer "F.Fab")
			(effects
				(font
					(size 1.27 1.27)
				)
			)
		)
		(duplicate_pad_numbers_are_jumpers no)
		(fp_line
			(start -0.7874 0.4064)
			(end -0.7874 -0.4064)
			(stroke
				(width 0.1524)
				(type default)
			)
			(layer "F.SilkS")
		)
		(fp_line
			(start 0.7874 0.4064)
			(end -0.7874 0.4064)
			(stroke
				(width 0.1524)
				(type default)
			)
			(layer "F.SilkS")
		)
		(fp_line
			(start -0.7874 -0.4064)
			(end 0.7874 -0.4064)
			(stroke
				(width 0.1524)
				(type default)
			)
			(layer "F.SilkS")
		)
		(fp_line
			(start 0.7874 -0.4064)
			(end 0.7874 0.4064)
			(stroke
				(width 0.1524)
				(type default)
			)
			(layer "F.SilkS")
		)
		(fp_poly
			(pts
				(xy -0.508 0.2794) (xy -0.508 0.2286) (xy -0.635 0.2286) (xy -0.635 -0.254) (xy -0.5334 -0.254)
				(xy -0.5334 -0.2794) (xy 0.5334 -0.2794) (xy 0.5334 -0.254) (xy 0.635 -0.254) (xy 0.635 0.254) (xy 0.5334 0.254)
				(xy 0.5334 0.2794)
			)
			(stroke
				(width 0)
				(type default)
			)
			(fill no)
			(layer "F.CrtYd")
		)
		(pad "1" smd rect
			(at 0.40005 0 270)
			(size 0.4572 0.508)
			(layers "F.Cu" "F.Mask" "F.Paste")
			(net "GND")
		)
		(pad "2" smd rect
			(at -0.40005 0 270)
			(size 0.4572 0.508)
			(layers "F.Cu" "F.Mask" "F.Paste")
			(net "SATA_NODE1_GPIO5")
		)
	)
	(footprint ""
		(layer "F.Cu")
		(at 12.95908 -119.88419)
		(property "Reference" "PR22"
			(at -5.507228 -1.311402 0)
			(unlocked yes)
			(layer "F.SilkS")
			(effects
				(font
					(size 0.7874 0.5842)
					(thickness 0.1524)
				)
				(justify left)
			)
		)
		(property "Value" ""
			(at 0 0 0)
			(layer "F.Fab")
			(effects
				(font
					(size 1.27 1.27)
				)
			)
		)
		(duplicate_pad_numbers_are_jumpers no)
		(fp_line
			(start -2.2098 -0.9398)
			(end 2.2098 -0.9398)
			(stroke
				(width 0.1524)
				(type default)
			)
			(layer "F.SilkS")
		)
		(fp_line
			(start -2.2098 0.9398)
			(end -2.2098 -0.9398)
			(stroke
				(width 0.1524)
				(type default)
			)
			(layer "F.SilkS")
		)
		(fp_line
			(start 2.2098 -0.9398)
			(end 2.2098 0.9398)
			(stroke
				(width 0.1524)
				(type default)
			)
			(layer "F.SilkS")
		)
		(fp_line
			(start 2.2098 0.9398)
			(end -2.2098 0.9398)
			(stroke
				(width 0.1524)
				(type default)
			)
			(layer "F.SilkS")
		)
		(fp_poly
			(pts
				(xy 2.0574 0.8382) (xy 2.0574 -0.8382) (xy 2.0574 -0.9398) (xy -2.0574 -0.9398) (xy -2.0574 -0.8382)
				(xy -2.0574 0.8382) (xy -2.0574 0.9398) (xy 2.0574 0.9398)
			)
			(stroke
				(width 0)
				(type default)
			)
			(fill no)
			(layer "F.CrtYd")
		)
		(pad "1" smd rect
			(at 1.4732 0)
			(size 1.1684 1.5748)
			(layers "F.Cu" "F.Mask" "F.Paste")
			(net "SW_P1V05_NODE1_VIN_FLT")
		)
		(pad "2" smd rect
			(at -1.4732 0)
			(size 1.1684 1.5748)
			(layers "F.Cu" "F.Mask" "F.Paste")
			(net "P12V_AUX")
		)
	)
	(footprint ""
		(layer "F.Cu")
		(at 144.51076 -185.205624 -90)
		(property "Reference" "R996"
			(at -4.768088 0.535432 90)
			(unlocked yes)
			(layer "F.SilkS")
			(effects
				(font
					(size 0.7874 0.5842)
					(thickness 0.1524)
				)
				(justify left)
			)
		)
		(property "Value" ""
			(at 0 0 270)
			(layer "F.Fab")
			(effects
				(font
					(size 1.27 1.27)
				)
			)
		)
		(duplicate_pad_numbers_are_jumpers no)
		(fp_line
			(start -0.7874 0.4064)
			(end -0.7874 -0.4064)
			(stroke
				(width 0.1524)
				(type default)
			)
			(layer "F.SilkS")
		)
		(fp_line
			(start 0.7874 0.4064)
			(end -0.7874 0.4064)
			(stroke
				(width 0.1524)
				(type default)
			)
			(layer "F.SilkS")
		)
		(fp_line
			(start -0.7874 -0.4064)
			(end 0.7874 -0.4064)
			(stroke
				(width 0.1524)
				(type default)
			)
			(layer "F.SilkS")
		)
		(fp_line
			(start 0.7874 -0.4064)
			(end 0.7874 0.4064)
			(stroke
				(width 0.1524)
				(type default)
			)
			(layer "F.SilkS")
		)
		(fp_poly
			(pts
				(xy -0.508 0.2794) (xy -0.508 0.2286) (xy -0.635 0.2286) (xy -0.635 -0.254) (xy -0.5334 -0.254)
				(xy -0.5334 -0.2794) (xy 0.5334 -0.2794) (xy 0.5334 -0.254) (xy 0.635 -0.254) (xy 0.635 0.254) (xy 0.5334 0.254)
				(xy 0.5334 0.2794)
			)
			(stroke
				(width 0)
				(type default)
			)
			(fill no)
			(layer "F.CrtYd")
		)
		(pad "1" smd rect
			(at 0.40005 0 270)
			(size 0.4572 0.508)
			(layers "F.Cu" "F.Mask" "F.Paste")
			(net "UART_T12_NODE3_TXD")
		)
		(pad "2" smd rect
			(at -0.40005 0 270)
			(size 0.4572 0.508)
			(layers "F.Cu" "F.Mask" "F.Paste")
			(net "UART_T12_NODE3_TXD_R")
		)
	)
	(footprint ""
		(layer "F.Cu")
		(at 126.60122 -174.667926)
		(property "Reference" "C900"
			(at -0.903732 -1.136396 0)
			(unlocked yes)
			(layer "F.SilkS")
			(effects
				(font
					(size 0.7874 0.5842)
					(thickness 0.1524)
				)
				(justify left)
			)
		)
		(property "Value" ""
			(at 0 0 0)
			(layer "F.Fab")
			(effects
				(font
					(size 1.27 1.27)
				)
			)
		)
		(duplicate_pad_numbers_are_jumpers no)
		(fp_line
			(start -0.7874 -0.4064)
			(end 0.7874 -0.4064)
			(stroke
				(width 0.1524)
				(type default)
			)
			(layer "F.SilkS")
		)
		(fp_line
			(start -0.7874 0.4064)
			(end -0.7874 -0.4064)
			(stroke
				(width 0.1524)
				(type default)
			)
			(layer "F.SilkS")
		)
		(fp_line
			(start 0 0.381)
			(end 0 -0.381)
			(stroke
				(width 0.1524)
				(type default)
			)
			(layer "F.SilkS")
		)
		(fp_line
			(start 0.7874 -0.4064)
			(end 0.7874 0.4064)
			(stroke
				(width 0.1524)
				(type default)
			)
			(layer "F.SilkS")
		)
		(fp_line
			(start 0.7874 0.4064)
			(end -0.7874 0.4064)
			(stroke
				(width 0.1524)
				(type default)
			)
			(layer "F.SilkS")
		)
		(fp_poly
			(pts
				(xy -0.5334 0.254) (xy -0.635 0.254) (xy -0.635 0.2286) (xy -0.635 -0.254) (xy -0.5334 -0.254) (xy -0.5334 -0.2794)
				(xy 0.5334 -0.2794) (xy 0.5334 -0.254) (xy 0.635 -0.254) (xy 0.635 0.254) (xy 0.5334 0.254) (xy 0.5334 0.2794)
				(xy -0.508 0.2794) (xy -0.5334 0.2794)
			)
			(stroke
				(width 0)
				(type default)
			)
			(fill no)
			(layer "F.CrtYd")
		)
		(pad "1" smd rect
			(at 0.40005 0)
			(size 0.4572 0.508)
			(layers "F.Cu" "F.Mask" "F.Paste")
			(net "P3V3_NODE1")
		)
		(pad "2" smd rect
			(at -0.40005 0)
			(size 0.4572 0.508)
			(layers "F.Cu" "F.Mask" "F.Paste")
			(net "GND")
		)
	)
	(footprint ""
		(layer "F.Cu")
		(at 33.212786 -185.3565)
		(property "Reference" "C778"
			(at -5.207254 -5.227066 0)
			(unlocked yes)
			(layer "F.SilkS")
			(effects
				(font
					(size 0.7874 0.5842)
					(thickness 0.1524)
				)
				(justify left)
			)
		)
		(property "Value" ""
			(at 0 0 0)
			(layer "F.Fab")
			(effects
				(font
					(size 1.27 1.27)
				)
			)
		)
		(duplicate_pad_numbers_are_jumpers no)
		(fp_line
			(start -0.7874 -0.4064)
			(end 0.7874 -0.4064)
			(stroke
				(width 0.1524)
				(type default)
			)
			(layer "F.SilkS")
		)
		(fp_line
			(start -0.7874 0.4064)
			(end -0.7874 -0.4064)
			(stroke
				(width 0.1524)
				(type default)
			)
			(layer "F.SilkS")
		)
		(fp_line
			(start 0 0.381)
			(end 0 -0.381)
			(stroke
				(width 0.1524)
				(type default)
			)
			(layer "F.SilkS")
		)
		(fp_line
			(start 0.7874 -0.4064)
			(end 0.7874 0.4064)
			(stroke
				(width 0.1524)
				(type default)
			)
			(layer "F.SilkS")
		)
		(fp_line
			(start 0.7874 0.4064)
			(end -0.7874 0.4064)
			(stroke
				(width 0.1524)
				(type default)
			)
			(layer "F.SilkS")
		)
		(fp_poly
			(pts
				(xy -0.5334 0.254) (xy -0.635 0.254) (xy -0.635 0.2286) (xy -0.635 -0.254) (xy -0.5334 -0.254) (xy -0.5334 -0.2794)
				(xy 0.5334 -0.2794) (xy 0.5334 -0.254) (xy 0.635 -0.254) (xy 0.635 0.254) (xy 0.5334 0.254) (xy 0.5334 0.2794)
				(xy -0.508 0.2794) (xy -0.5334 0.2794)
			)
			(stroke
				(width 0)
				(type default)
			)
			(fill no)
			(layer "F.CrtYd")
		)
		(pad "1" smd rect
			(at 0.40005 0)
			(size 0.4572 0.508)
			(layers "F.Cu" "F.Mask" "F.Paste")
			(net "P12V_AUX_EN")
		)
		(pad "2" smd rect
			(at -0.40005 0)
			(size 0.4572 0.508)
			(layers "F.Cu" "F.Mask" "F.Paste")
			(net "AGND_HSC_NODE1")
		)
	)
	(footprint ""
		(layer "F.Cu")
		(at 162.924998 -144.46123 180)
		(property "Reference" "C437"
			(at 0.840994 0.993648 0)
			(unlocked yes)
			(layer "F.SilkS")
			(effects
				(font
					(size 0.7874 0.5842)
					(thickness 0.1524)
				)
				(justify left)
			)
		)
		(property "Value" ""
			(at 0 0 180)
			(layer "F.Fab")
			(effects
				(font
					(size 1.27 1.27)
				)
			)
		)
		(duplicate_pad_numbers_are_jumpers no)
		(fp_line
			(start 0.7874 0.4064)
			(end -0.7874 0.4064)
			(stroke
				(width 0.1524)
				(type default)
			)
			(layer "F.SilkS")
		)
		(fp_line
			(start 0.7874 -0.4064)
			(end 0.7874 0.4064)
			(stroke
				(width 0.1524)
				(type default)
			)
			(layer "F.SilkS")
		)
		(fp_line
			(start 0 0.381)
			(end 0 -0.381)
			(stroke
				(width 0.1524)
				(type default)
			)
			(layer "F.SilkS")
		)
		(fp_line
			(start -0.7874 0.4064)
			(end -0.7874 -0.4064)
			(stroke
				(width 0.1524)
				(type default)
			)
			(layer "F.SilkS")
		)
		(fp_line
			(start -0.7874 -0.4064)
			(end 0.7874 -0.4064)
			(stroke
				(width 0.1524)
				(type default)
			)
			(layer "F.SilkS")
		)
		(fp_poly
			(pts
				(xy -0.5334 0.254) (xy -0.635 0.254) (xy -0.635 0.2286) (xy -0.635 -0.254) (xy -0.5334 -0.254) (xy -0.5334 -0.2794)
				(xy 0.5334 -0.2794) (xy 0.5334 -0.254) (xy 0.635 -0.254) (xy 0.635 0.254) (xy 0.5334 0.254) (xy 0.5334 0.2794)
				(xy -0.508 0.2794) (xy -0.5334 0.2794)
			)
			(stroke
				(width 0)
				(type default)
			)
			(fill no)
			(layer "F.CrtYd")
		)
		(pad "1" smd rect
			(at 0.40005 0 180)
			(size 0.4572 0.508)
			(layers "F.Cu" "F.Mask" "F.Paste")
			(net "LAN2_XTAL_IN")
		)
		(pad "2" smd rect
			(at -0.40005 0 180)
			(size 0.4572 0.508)
			(layers "F.Cu" "F.Mask" "F.Paste")
			(net "GND")
		)
	)
	(footprint ""
		(layer "F.Cu")
		(at 107.29976 -188.126624 -90)
		(property "Reference" "R933"
			(at -5.151882 -0.78486 90)
			(unlocked yes)
			(layer "F.SilkS")
			(effects
				(font
					(size 0.7874 0.5842)
					(thickness 0.1524)
				)
				(justify left)
			)
		)
		(property "Value" ""
			(at 0 0 270)
			(layer "F.Fab")
			(effects
				(font
					(size 1.27 1.27)
				)
			)
		)
		(duplicate_pad_numbers_are_jumpers no)
		(fp_line
			(start -0.7874 0.4064)
			(end -0.7874 -0.4064)
			(stroke
				(width 0.1524)
				(type default)
			)
			(layer "F.SilkS")
		)
		(fp_line
			(start 0.7874 0.4064)
			(end -0.7874 0.4064)
			(stroke
				(width 0.1524)
				(type default)
			)
			(layer "F.SilkS")
		)
		(fp_line
			(start -0.7874 -0.4064)
			(end 0.7874 -0.4064)
			(stroke
				(width 0.1524)
				(type default)
			)
			(layer "F.SilkS")
		)
		(fp_line
			(start 0.7874 -0.4064)
			(end 0.7874 0.4064)
			(stroke
				(width 0.1524)
				(type default)
			)
			(layer "F.SilkS")
		)
		(fp_poly
			(pts
				(xy -0.508 0.2794) (xy -0.508 0.2286) (xy -0.635 0.2286) (xy -0.635 -0.254) (xy -0.5334 -0.254)
				(xy -0.5334 -0.2794) (xy 0.5334 -0.2794) (xy 0.5334 -0.254) (xy 0.635 -0.254) (xy 0.635 0.254) (xy 0.5334 0.254)
				(xy 0.5334 0.2794)
			)
			(stroke
				(width 0)
				(type default)
			)
			(fill no)
			(layer "F.CrtYd")
		)
		(pad "1" smd rect
			(at 0.40005 0 270)
			(size 0.4572 0.508)
			(layers "F.Cu" "F.Mask" "F.Paste")
			(net "UART_T6_NODE1_RXD")
		)
		(pad "2" smd rect
			(at -0.40005 0 270)
			(size 0.4572 0.508)
			(layers "F.Cu" "F.Mask" "F.Paste")
			(net "UART_T6_NODE1_RXD_R")
		)
	)
	(footprint ""
		(layer "F.Cu")
		(at 94.451932 -177.354992)
		(property "Reference" "R753"
			(at 86.67369 74.174096 0)
			(unlocked yes)
			(layer "F.SilkS")
			(effects
				(font
					(size 0.7874 0.5842)
					(thickness 0.1524)
				)
				(justify left)
			)
		)
		(property "Value" ""
			(at 0 0 0)
			(layer "F.Fab")
			(effects
				(font
					(size 1.27 1.27)
				)
			)
		)
		(duplicate_pad_numbers_are_jumpers no)
		(fp_line
			(start -0.7874 -0.4064)
			(end 0.7874 -0.4064)
			(stroke
				(width 0.1524)
				(type default)
			)
			(layer "F.SilkS")
		)
		(fp_line
			(start -0.7874 0.4064)
			(end -0.7874 -0.4064)
			(stroke
				(width 0.1524)
				(type default)
			)
			(layer "F.SilkS")
		)
		(fp_line
			(start 0.7874 -0.4064)
			(end 0.7874 0.4064)
			(stroke
				(width 0.1524)
				(type default)
			)
			(layer "F.SilkS")
		)
		(fp_line
			(start 0.7874 0.4064)
			(end -0.7874 0.4064)
			(stroke
				(width 0.1524)
				(type default)
			)
			(layer "F.SilkS")
		)
		(fp_poly
			(pts
				(xy -0.508 0.2794) (xy -0.508 0.2286) (xy -0.635 0.2286) (xy -0.635 -0.254) (xy -0.5334 -0.254)
				(xy -0.5334 -0.2794) (xy 0.5334 -0.2794) (xy 0.5334 -0.254) (xy 0.635 -0.254) (xy 0.635 0.254) (xy 0.5334 0.254)
				(xy 0.5334 0.2794)
			)
			(stroke
				(width 0)
				(type default)
			)
			(fill no)
			(layer "F.CrtYd")
		)
		(pad "1" smd rect
			(at 0.40005 0)
			(size 0.4572 0.508)
			(layers "F.Cu" "F.Mask" "F.Paste")
			(net "N21698939")
		)
		(pad "2" smd rect
			(at -0.40005 0)
			(size 0.4572 0.508)
			(layers "F.Cu" "F.Mask" "F.Paste")
			(net "GND")
		)
	)
	(footprint ""
		(layer "F.Cu")
		(at 36.195 -117.943122 -90)
		(property "Reference" "Q40"
			(at -2.407666 0.58674 0)
			(unlocked yes)
			(layer "F.SilkS")
			(effects
				(font
					(size 0.7874 0.5842)
					(thickness 0.1524)
				)
			)
		)
		(property "Value" ""
			(at 0 0 270)
			(layer "F.Fab")
			(effects
				(font
					(size 1.27 1.27)
				)
			)
		)
		(duplicate_pad_numbers_are_jumpers no)
		(fp_line
			(start -1.603248 1.500124)
			(end -1.603248 -1.500124)
			(stroke
				(width 0.1524)
				(type default)
			)
			(layer "F.SilkS")
		)
		(fp_line
			(start 1.603248 1.500124)
			(end -1.603248 1.500124)
			(stroke
				(width 0.1524)
				(type default)
			)
			(layer "F.SilkS")
		)
		(fp_line
			(start -1.603248 -1.500124)
			(end 1.603248 -1.500124)
			(stroke
				(width 0.1524)
				(type default)
			)
			(layer "F.SilkS")
		)
		(fp_line
			(start 1.603248 -1.500124)
			(end 1.603248 1.500124)
			(stroke
				(width 0.1524)
				(type default)
			)
			(layer "F.SilkS")
		)
		(fp_poly
			(pts
				(xy -0.700024 -1.500124) (xy -0.700024 -1.40716) (xy -1.507998 -1.40716) (xy -1.507998 -0.49276)
				(xy -0.700024 -0.49276) (xy -0.700024 0.47244) (xy -1.507998 0.47244) (xy -1.507998 1.41224) (xy -0.700024 1.41224)
				(xy -0.700024 1.500124) (xy 0.700024 1.500124) (xy 0.700024 0.47244) (xy 1.514602 0.47244) (xy 1.514602 -0.46736)
				(xy 0.700024 -0.46736) (xy 0.700024 -1.500124)
			)
			(stroke
				(width 0)
				(type default)
			)
			(fill no)
			(layer "F.CrtYd")
		)
		(fp_line
			(start -0.700024 1.500124)
			(end -0.700024 -1.500124)
			(stroke
				(width 0.1)
				(type default)
			)
			(layer "F.Fab")
		)
		(fp_line
			(start 0.700024 1.500124)
			(end -0.700024 1.500124)
			(stroke
				(width 0.1)
				(type default)
			)
			(layer "F.Fab")
		)
		(fp_line
			(start -0.700024 -1.500124)
			(end 0.700024 -1.500124)
			(stroke
				(width 0.1)
				(type default)
			)
			(layer "F.Fab")
		)
		(fp_line
			(start 0.700024 -1.500124)
			(end 0.700024 1.500124)
			(stroke
				(width 0.1)
				(type default)
			)
			(layer "F.Fab")
		)
		(fp_text user "D"
			(at 1.039114 1.901698 0)
			(unlocked yes)
			(layer "F.SilkS")
			(effects
				(font
					(size 0.635 0.4064)
					(thickness 0.1524)
				)
			)
		)
		(fp_text user "S"
			(at -0.344932 1.689608 0)
			(unlocked yes)
			(layer "F.SilkS")
			(effects
				(font
					(size 0.635 0.4064)
					(thickness 0.1524)
				)
			)
		)
		(fp_text user "G"
			(at -1.79832 -1.857248 0)
			(unlocked yes)
			(layer "F.SilkS")
			(effects
				(font
					(size 0.635 0.4064)
					(thickness 0.1524)
				)
			)
		)
		(fp_text user "S"
			(at -1.025906 2.0066 180)
			(unlocked yes)
			(layer "F.Fab")
			(effects
				(font
					(size 0.7874 0.5842)
					(thickness 0.000001)
				)
			)
		)
		(fp_text user "D"
			(at 2.098294 0.1016 180)
			(unlocked yes)
			(layer "F.Fab")
			(effects
				(font
					(size 0.7874 0.5842)
					(thickness 0.000001)
				)
			)
		)
		(fp_text user "G"
			(at -1.051306 -2.032 180)
			(unlocked yes)
			(layer "F.Fab")
			(effects
				(font
					(size 0.7874 0.5842)
					(thickness 0.000001)
				)
			)
		)
		(pad "D" smd rect
			(at 0.999998 0 180)
			(size 0.8128 0.9144)
			(layers "F.Cu" "F.Mask" "F.Paste")
			(net "FM_CPLD_NODE1_P1V5_EN_LV")
		)
		(pad "G" smd rect
			(at -0.999998 -0.94996 180)
			(size 0.8128 0.9144)
			(layers "F.Cu" "F.Mask" "F.Paste")
			(net "FM_CPLD_NODE1_P1V5_EN_G")
		)
		(pad "S" smd rect
			(at -0.999998 0.94996 180)
			(size 0.8128 0.9144)
			(layers "F.Cu" "F.Mask" "F.Paste")
			(net "FM_CPLD_NODE1_P1V5_EN")
		)
	)
	(footprint ""
		(layer "F.Cu")
		(at 163.252404 -119.684546 180)
		(property "Reference" "Q26"
			(at 4.910074 2.14376 0)
			(unlocked yes)
			(layer "F.SilkS")
			(effects
				(font
					(size 0.7874 0.5842)
					(thickness 0.1524)
				)
				(justify left)
			)
		)
		(property "Value" ""
			(at 0 0 180)
			(layer "F.Fab")
			(effects
				(font
					(size 1.27 1.27)
				)
			)
		)
		(duplicate_pad_numbers_are_jumpers no)
		(fp_line
			(start 2.584196 2.48412)
			(end -0.5842 2.48412)
			(stroke
				(width 0.1524)
				(type default)
			)
			(layer "F.SilkS")
		)
		(fp_line
			(start 2.584196 -0.5842)
			(end 2.584196 2.48412)
			(stroke
				(width 0.1524)
				(type default)
			)
			(layer "F.SilkS")
		)
		(fp_line
			(start -0.5842 2.48412)
			(end -0.5842 -0.5842)
			(stroke
				(width 0.1524)
				(type default)
			)
			(layer "F.SilkS")
		)
		(fp_line
			(start -0.5842 -0.5842)
			(end 2.584196 -0.5842)
			(stroke
				(width 0.1524)
				(type default)
			)
			(layer "F.SilkS")
		)
		(fp_poly
			(pts
				(xy -0.508 -0.4572) (xy 0.299974 -0.4572) (xy 0.299974 -0.54991) (xy 1.700022 -0.54991) (xy 1.700022 0.49276)
				(xy 2.507996 0.49276) (xy 2.507996 1.40716) (xy 1.700022 1.40716) (xy 1.700022 2.450084) (xy 0.299974 2.450084)
				(xy 0.299974 2.35712) (xy -0.508 2.35712)
			)
			(stroke
				(width 0)
				(type default)
			)
			(fill no)
			(layer "F.CrtYd")
		)
		(fp_line
			(start 1.700022 2.450084)
			(end 0.299974 2.450084)
			(stroke
				(width 0.1)
				(type default)
			)
			(layer "F.Fab")
		)
		(fp_line
			(start 1.700022 -0.54991)
			(end 1.700022 2.450084)
			(stroke
				(width 0.1)
				(type default)
			)
			(layer "F.Fab")
		)
		(fp_line
			(start 0.299974 2.450084)
			(end 0.299974 -0.54991)
			(stroke
				(width 0.1)
				(type default)
			)
			(layer "F.Fab")
		)
		(fp_line
			(start 0.299974 -0.54991)
			(end 1.700022 -0.54991)
			(stroke
				(width 0.1)
				(type default)
			)
			(layer "F.Fab")
		)
		(fp_text user "C"
			(at 3.228086 1.035558 0)
			(unlocked yes)
			(layer "F.SilkS")
			(effects
				(font
					(size 0.635 0.4064)
					(thickness 0.1524)
				)
				(justify left)
			)
		)
		(fp_text user "B"
			(at -0.752094 -0.042164 0)
			(unlocked yes)
			(layer "F.SilkS")
			(effects
				(font
					(size 0.635 0.4064)
					(thickness 0.1524)
				)
				(justify left)
			)
		)
		(fp_text user "E"
			(at -1.111504 1.892554 0)
			(unlocked yes)
			(layer "F.SilkS")
			(effects
				(font
					(size 0.635 0.4064)
					(thickness 0.1524)
				)
				(justify left)
			)
		)
		(fp_text user "C"
			(at 2.8702 0.99187 180)
			(unlocked yes)
			(layer "F.Fab")
			(effects
				(font
					(size 0.7874 0.5842)
					(thickness 0.000001)
				)
				(justify left)
			)
		)
		(fp_text user "B"
			(at -1.5494 0.00127 180)
			(unlocked yes)
			(layer "F.Fab")
			(effects
				(font
					(size 0.7874 0.5842)
					(thickness 0.000001)
				)
				(justify left)
			)
		)
		(fp_text user "E"
			(at -1.5748 1.95707 180)
			(unlocked yes)
			(layer "F.Fab")
			(effects
				(font
					(size 0.7874 0.5842)
					(thickness 0.000001)
				)
				(justify left)
			)
		)
		(pad "B" smd rect
			(at 0 0 270)
			(size 0.8128 0.9144)
			(layers "F.Cu" "F.Mask" "F.Paste")
			(net "FM_NODE1_DDR3_SYSPWRGD_R_L")
		)
		(pad "C" smd rect
			(at 1.999996 0.94996 270)
			(size 0.8128 0.9144)
			(layers "F.Cu" "F.Mask" "F.Paste")
			(net "PWRGD_NODE1_DDR3_SYSPWRGD")
		)
		(pad "E" smd rect
			(at 0 1.89992 270)
			(size 0.8128 0.9144)
			(layers "F.Cu" "F.Mask" "F.Paste")
			(net "GND")
		)
	)
	(footprint ""
		(layer "F.Cu")
		(at 17.801336 -59.41568 90)
		(property "Reference" "U50"
			(at 1.163574 3.801872 0)
			(unlocked yes)
			(layer "F.SilkS")
			(effects
				(font
					(size 0.7874 0.5842)
					(thickness 0.1524)
				)
			)
		)
		(property "Value" ""
			(at 0 0 90)
			(layer "F.Fab")
			(effects
				(font
					(size 1.27 1.27)
				)
			)
		)
		(duplicate_pad_numbers_are_jumpers no)
		(fp_line
			(start 1.651 -1.905)
			(end 1.651 1.905)
			(stroke
				(width 0.1524)
				(type default)
			)
			(layer "F.SilkS")
		)
		(fp_line
			(start -1.651 -1.905)
			(end 1.651 -1.905)
			(stroke
				(width 0.1524)
				(type default)
			)
			(layer "F.SilkS")
		)
		(fp_line
			(start 1.651 1.905)
			(end -1.651 1.905)
			(stroke
				(width 0.1524)
				(type default)
			)
			(layer "F.SilkS")
		)
		(fp_line
			(start -1.651 1.905)
			(end -1.651 -1.905)
			(stroke
				(width 0.1524)
				(type default)
			)
			(layer "F.SilkS")
		)
		(fp_poly
			(pts
				(xy -1.524 0.7112) (xy -1.524 1.7526) (xy -0.508 1.7526) (xy -0.508 0.6985) (xy 0.508 0.6985) (xy 0.508 1.7526)
				(xy 1.524 1.7526) (xy 1.524 0.6985) (xy 1.524 -0.6985) (xy 0.508 -0.6985) (xy 0.508 -1.7526) (xy -0.508 -1.7526)
				(xy -0.508 -0.6985) (xy -1.524 -0.6985) (xy -1.524 0.6985)
			)
			(stroke
				(width 0)
				(type default)
			)
			(fill no)
			(layer "F.CrtYd")
		)
		(fp_text user "3"
			(at 1.13919 -1.13538 0)
			(unlocked yes)
			(layer "F.SilkS")
			(effects
				(font
					(size 0.635 0.4064)
					(thickness 0.1524)
				)
			)
		)
		(fp_text user "2"
			(at 1.058164 2.152396 0)
			(unlocked yes)
			(layer "F.SilkS")
			(effects
				(font
					(size 0.635 0.4064)
					(thickness 0.1524)
				)
			)
		)
		(fp_text user "1"
			(at -0.301752 2.556764 0)
			(unlocked yes)
			(layer "F.SilkS")
			(effects
				(font
					(size 0.635 0.4064)
					(thickness 0.1524)
				)
			)
		)
		(pad "1" smd rect
			(at -1.016 1.1176 90)
			(size 1.016 1.27)
			(layers "F.Cu" "F.Mask" "F.Paste")
			(net "GND")
		)
		(pad "2" smd rect
			(at 1.016 1.1176 90)
			(size 1.016 1.27)
			(layers "F.Cu" "F.Mask" "F.Paste")
			(net "P5V_CRT")
		)
		(pad "3" smd rect
			(at 0 -1.1176 90)
			(size 1.016 1.27)
			(layers "F.Cu" "F.Mask" "F.Paste")
			(net "CRT_VSYNC")
		)
	)
	(footprint ""
		(layer "F.Cu")
		(at 11.12012 -4.721352 180)
		(property "Reference" "R472"
			(at 1.137412 -2.351024 0)
			(unlocked yes)
			(layer "F.SilkS")
			(effects
				(font
					(size 0.7874 0.5842)
					(thickness 0.1524)
				)
				(justify left)
			)
		)
		(property "Value" ""
			(at 0 0 180)
			(layer "F.Fab")
			(effects
				(font
					(size 1.27 1.27)
				)
			)
		)
		(duplicate_pad_numbers_are_jumpers no)
		(fp_line
			(start 0.7874 0.4064)
			(end -0.7874 0.4064)
			(stroke
				(width 0.1524)
				(type default)
			)
			(layer "F.SilkS")
		)
		(fp_line
			(start 0.7874 -0.4064)
			(end 0.7874 0.4064)
			(stroke
				(width 0.1524)
				(type default)
			)
			(layer "F.SilkS")
		)
		(fp_line
			(start -0.7874 0.4064)
			(end -0.7874 -0.4064)
			(stroke
				(width 0.1524)
				(type default)
			)
			(layer "F.SilkS")
		)
		(fp_line
			(start -0.7874 -0.4064)
			(end 0.7874 -0.4064)
			(stroke
				(width 0.1524)
				(type default)
			)
			(layer "F.SilkS")
		)
		(fp_poly
			(pts
				(xy -0.508 0.2794) (xy -0.508 0.2286) (xy -0.635 0.2286) (xy -0.635 -0.254) (xy -0.5334 -0.254)
				(xy -0.5334 -0.2794) (xy 0.5334 -0.2794) (xy 0.5334 -0.254) (xy 0.635 -0.254) (xy 0.635 0.254) (xy 0.5334 0.254)
				(xy 0.5334 0.2794)
			)
			(stroke
				(width 0)
				(type default)
			)
			(fill no)
			(layer "F.CrtYd")
		)
		(pad "1" smd rect
			(at 0.40005 0 180)
			(size 0.4572 0.508)
			(layers "F.Cu" "F.Mask" "F.Paste")
			(net "SMB_MUX_CPU_ICS_NODE1_DAT")
		)
		(pad "2" smd rect
			(at -0.40005 0 180)
			(size 0.4572 0.508)
			(layers "F.Cu" "F.Mask" "F.Paste")
			(net "SMB_DIMM_NODE1_DAT")
		)
	)
	(footprint ""
		(layer "F.Cu")
		(at 120.61444 -148.67509 -90)
		(property "Reference" "Q46"
			(at 2.976118 -0.862076 90)
			(unlocked yes)
			(layer "F.SilkS")
			(effects
				(font
					(size 0.7874 0.5842)
					(thickness 0.1524)
				)
			)
		)
		(property "Value" ""
			(at 0 0 270)
			(layer "F.Fab")
			(effects
				(font
					(size 1.27 1.27)
				)
			)
		)
		(duplicate_pad_numbers_are_jumpers no)
		(fp_line
			(start -1.488186 1.500124)
			(end -1.488186 -1.500124)
			(stroke
				(width 0.1524)
				(type default)
			)
			(layer "F.SilkS")
		)
		(fp_line
			(start 1.488186 1.500124)
			(end -1.488186 1.500124)
			(stroke
				(width 0.1524)
				(type default)
			)
			(layer "F.SilkS")
		)
		(fp_line
			(start -1.488186 -1.500124)
			(end 1.488186 -1.500124)
			(stroke
				(width 0.1524)
				(type default)
			)
			(layer "F.SilkS")
		)
		(fp_line
			(start 1.488186 -1.500124)
			(end 1.488186 1.500124)
			(stroke
				(width 0.1524)
				(type default)
			)
			(layer "F.SilkS")
		)
		(fp_poly
			(pts
				(xy -0.700024 1.500124) (xy 0.700024 1.500124) (xy 0.700024 0.3556) (xy 1.4224 0.3556) (xy 1.4224 -0.3556)
				(xy 0.700024 -0.3556) (xy 0.700024 -1.500124) (xy -0.700024 -1.500124) (xy -0.700024 -1.3208) (xy -1.4224 -1.3208)
				(xy -1.4224 -0.5842) (xy -0.700024 -0.5842) (xy -0.700024 0.5842) (xy -1.4224 0.5842) (xy -1.4224 1.3208)
				(xy -0.700024 1.3208)
			)
			(stroke
				(width 0)
				(type default)
			)
			(fill no)
			(layer "F.CrtYd")
		)
		(fp_line
			(start -0.700024 1.500124)
			(end -0.700024 -1.500124)
			(stroke
				(width 0.1)
				(type default)
			)
			(layer "F.Fab")
		)
		(fp_line
			(start 0.700024 1.500124)
			(end -0.700024 1.500124)
			(stroke
				(width 0.1)
				(type default)
			)
			(layer "F.Fab")
		)
		(fp_line
			(start -0.700024 -1.500124)
			(end 0.700024 -1.500124)
			(stroke
				(width 0.1)
				(type default)
			)
			(layer "F.Fab")
		)
		(fp_line
			(start 0.700024 -1.500124)
			(end 0.700024 1.500124)
			(stroke
				(width 0.1)
				(type default)
			)
			(layer "F.Fab")
		)
		(fp_text user "2"
			(at -1.352042 1.6129 0)
			(unlocked yes)
			(layer "F.SilkS")
			(effects
				(font
					(size 0.635 0.4064)
					(thickness 0.1524)
				)
			)
		)
		(fp_text user "1"
			(at -0.298958 -1.702308 0)
			(unlocked yes)
			(layer "F.SilkS")
			(effects
				(font
					(size 0.635 0.4064)
					(thickness 0.1524)
				)
			)
		)
		(fp_text user "3"
			(at 1.230884 -1.908556 0)
			(unlocked yes)
			(layer "F.SilkS")
			(effects
				(font
					(size 0.635 0.4064)
					(thickness 0.1524)
				)
			)
		)
		(fp_text user "2"
			(at -0.90805 1.8542 180)
			(unlocked yes)
			(layer "F.Fab")
			(effects
				(font
					(size 0.7874 0.5842)
					(thickness 0.000001)
				)
			)
		)
		(fp_text user "3"
			(at 2.15773 0 180)
			(unlocked yes)
			(layer "F.Fab")
			(effects
				(font
					(size 0.7874 0.5842)
					(thickness 0.000001)
				)
			)
		)
		(fp_text user "1"
			(at -0.90805 -1.8034 180)
			(unlocked yes)
			(layer "F.Fab")
			(effects
				(font
					(size 0.7874 0.5842)
					(thickness 0.000001)
				)
			)
		)
		(pad "1" smd rect
			(at -0.999998 -0.94996 180)
			(size 0.6096 0.7112)
			(layers "F.Cu" "F.Mask" "F.Paste")
			(net "N52998345")
		)
		(pad "2" smd rect
			(at -0.999998 0.94996 180)
			(size 0.6096 0.7112)
			(layers "F.Cu" "F.Mask" "F.Paste")
			(net "N52998325")
		)
		(pad "3" smd rect
			(at 0.999998 0 180)
			(size 0.6096 0.7112)
			(layers "F.Cu" "F.Mask" "F.Paste")
			(net "POWER_SW3_PWR_CTR_12V")
		)
	)
	(footprint ""
		(layer "F.Cu")
		(at 6.83387 -161.141156 180)
		(property "Reference" "U55"
			(at 2.39903 4.611878 0)
			(unlocked yes)
			(layer "F.SilkS")
			(effects
				(font
					(size 0.7874 0.5842)
					(thickness 0.1524)
				)
				(justify left)
			)
		)
		(property "Value" ""
			(at 0 0 180)
			(layer "F.Fab")
			(effects
				(font
					(size 1.27 1.27)
				)
			)
		)
		(duplicate_pad_numbers_are_jumpers no)
		(fp_line
			(start 4.9022 2.0066)
			(end -4.9022 2.0066)
			(stroke
				(width 0.1524)
				(type default)
			)
			(layer "F.SilkS")
		)
		(fp_line
			(start 4.9022 -2.0066)
			(end 4.9022 2.0066)
			(stroke
				(width 0.1524)
				(type default)
			)
			(layer "F.SilkS")
		)
		(fp_line
			(start -4.318 0)
			(end -4.9022 -0.5842)
			(stroke
				(width 0.1524)
				(type default)
			)
			(layer "F.SilkS")
		)
		(fp_line
			(start -4.9022 2.0066)
			(end -4.9022 0.5842)
			(stroke
				(width 0.1524)
				(type default)
			)
			(layer "F.SilkS")
		)
		(fp_line
			(start -4.9022 0.5842)
			(end -4.318 0)
			(stroke
				(width 0.1524)
				(type default)
			)
			(layer "F.SilkS")
		)
		(fp_line
			(start -4.9022 -0.5842)
			(end -4.9022 -2.0066)
			(stroke
				(width 0.1524)
				(type default)
			)
			(layer "F.SilkS")
		)
		(fp_line
			(start -4.9022 -2.0066)
			(end 4.9022 -2.0066)
			(stroke
				(width 0.1524)
				(type default)
			)
			(layer "F.SilkS")
		)
		(fp_circle
			(center -4.318 1.524)
			(end -4.572 1.524)
			(stroke
				(width 0.1524)
				(type default)
			)
			(fill no)
			(layer "F.SilkS")
		)
		(fp_rect
			(start -4.9022 3.6703)
			(end 4.9022 -3.6703)
			(stroke
				(width 0)
				(type default)
			)
			(fill no)
			(layer "F.CrtYd")
		)
		(pad "1" smd rect
			(at -4.225036 2.921 180)
			(size 0.3556 1.4986)
			(layers "F.Cu" "F.Mask" "F.Paste")
			(net "N54258523")
		)
		(pad "2" smd rect
			(at -3.57505 2.921 180)
			(size 0.3556 1.4986)
			(layers "F.Cu" "F.Mask" "F.Paste")
			(net "N54258525")
		)
		(pad "3" smd rect
			(at -2.925064 2.921 180)
			(size 0.3556 1.4986)
			(layers "F.Cu" "F.Mask" "F.Paste")
			(net "N54258537")
		)
		(pad "4" smd rect
			(at -2.275078 2.921 180)
			(size 0.3556 1.4986)
			(layers "F.Cu" "F.Mask" "F.Paste")
			(net "UART_RX_P5_L")
		)
		(pad "5" smd rect
			(at -1.625092 2.921 180)
			(size 0.3556 1.4986)
			(layers "F.Cu" "F.Mask" "F.Paste")
			(net "UART_RI_P5_L_N")
		)
		(pad "6" smd rect
			(at -0.975106 2.921 180)
			(size 0.3556 1.4986)
			(layers "F.Cu" "F.Mask" "F.Paste")
			(net "UART_DSR_P5_L_N")
		)
		(pad "7" smd rect
			(at -0.32512 2.921 180)
			(size 0.3556 1.4986)
			(layers "F.Cu" "F.Mask" "F.Paste")
			(net "UART_CTS_P5_L_N")
		)
		(pad "8" smd rect
			(at 0.32512 2.921 180)
			(size 0.3556 1.4986)
			(layers "F.Cu" "F.Mask" "F.Paste")
			(net "N54258454")
		)
		(pad "9" smd rect
			(at 0.975106 2.921 180)
			(size 0.3556 1.4986)
			(layers "F.Cu" "F.Mask" "F.Paste")
			(net "UART_RTS_P5_L_N")
		)
		(pad "10" smd rect
			(at 1.625092 2.921 180)
			(size 0.3556 1.4986)
			(layers "F.Cu" "F.Mask" "F.Paste")
			(net "UART_TX_P5_L")
		)
		(pad "11" smd rect
			(at 2.275078 2.921 180)
			(size 0.3556 1.4986)
			(layers "F.Cu" "F.Mask" "F.Paste")
			(net "UART_DTR_P5_L_N")
		)
		(pad "12" smd rect
			(at 2.925064 2.921 180)
			(size 0.3556 1.4986)
			(layers "F.Cu" "F.Mask" "F.Paste")
			(net "UART_DTR_P5_N")
		)
		(pad "13" smd rect
			(at 3.57505 2.921 180)
			(size 0.3556 1.4986)
			(layers "F.Cu" "F.Mask" "F.Paste")
			(net "UART_TX_P5")
		)
		(pad "14" smd rect
			(at 4.225036 2.921 180)
			(size 0.3556 1.4986)
			(layers "F.Cu" "F.Mask" "F.Paste")
			(net "UART_RTS_P5_N")
		)
		(pad "15" smd rect
			(at 4.225036 -2.921 180)
			(size 0.3556 1.4986)
			(layers "F.Cu" "F.Mask" "F.Paste")
			(net "Net_2306")
		)
		(pad "16" smd rect
			(at 3.57505 -2.921 180)
			(size 0.3556 1.4986)
			(layers "F.Cu" "F.Mask" "F.Paste")
			(net "UART_CTS_P5_N")
		)
		(pad "17" smd rect
			(at 2.925064 -2.921 180)
			(size 0.3556 1.4986)
			(layers "F.Cu" "F.Mask" "F.Paste")
			(net "UART_DSR_P5_N")
		)
		(pad "18" smd rect
			(at 2.275078 -2.921 180)
			(size 0.3556 1.4986)
			(layers "F.Cu" "F.Mask" "F.Paste")
			(net "UART_RI_P5_LS_N")
		)
		(pad "19" smd rect
			(at 1.625092 -2.921 180)
			(size 0.3556 1.4986)
			(layers "F.Cu" "F.Mask" "F.Paste")
			(net "UART_RX_P5")
		)
		(pad "20" smd rect
			(at 0.975106 -2.921 180)
			(size 0.3556 1.4986)
			(layers "F.Cu" "F.Mask" "F.Paste")
			(net "Net_2307")
		)
		(pad "21" smd rect
			(at 0.32512 -2.921 180)
			(size 0.3556 1.4986)
			(layers "F.Cu" "F.Mask" "F.Paste")
			(net "Net_2308")
		)
		(pad "22" smd rect
			(at -0.32512 -2.921 180)
			(size 0.3556 1.4986)
			(layers "F.Cu" "F.Mask" "F.Paste")
			(net "N54258476")
		)
		(pad "23" smd rect
			(at -0.975106 -2.921 180)
			(size 0.3556 1.4986)
			(layers "F.Cu" "F.Mask" "F.Paste")
			(net "N54258474")
		)
		(pad "24" smd rect
			(at -1.625092 -2.921 180)
			(size 0.3556 1.4986)
			(layers "F.Cu" "F.Mask" "F.Paste")
			(net "N54258515")
		)
		(pad "25" smd rect
			(at -2.275078 -2.921 180)
			(size 0.3556 1.4986)
			(layers "F.Cu" "F.Mask" "F.Paste")
			(net "GND")
		)
		(pad "26" smd rect
			(at -2.925064 -2.921 180)
			(size 0.3556 1.4986)
			(layers "F.Cu" "F.Mask" "F.Paste")
			(net "P3V3_NODE1")
		)
		(pad "27" smd rect
			(at -3.57505 -2.921 180)
			(size 0.3556 1.4986)
			(layers "F.Cu" "F.Mask" "F.Paste")
			(net "N54258535")
		)
		(pad "28" smd rect
			(at -4.225036 -2.921 180)
			(size 0.3556 1.4986)
			(layers "F.Cu" "F.Mask" "F.Paste")
			(net "N54258513")
		)
	)
	(footprint ""
		(layer "F.Cu")
		(at 82.429096 -152.684734)
		(property "Reference" "PC10"
			(at 1.086104 0.562356 0)
			(unlocked yes)
			(layer "F.SilkS")
			(effects
				(font
					(size 0.7874 0.5842)
					(thickness 0.1524)
				)
				(justify left)
			)
		)
		(property "Value" ""
			(at 0 0 0)
			(layer "F.Fab")
			(effects
				(font
					(size 1.27 1.27)
				)
			)
		)
		(duplicate_pad_numbers_are_jumpers no)
		(fp_line
			(start -0.7874 -0.4064)
			(end 0.7874 -0.4064)
			(stroke
				(width 0.1524)
				(type default)
			)
			(layer "F.SilkS")
		)
		(fp_line
			(start -0.7874 0.4064)
			(end -0.7874 -0.4064)
			(stroke
				(width 0.1524)
				(type default)
			)
			(layer "F.SilkS")
		)
		(fp_line
			(start 0 0.381)
			(end 0 -0.381)
			(stroke
				(width 0.1524)
				(type default)
			)
			(layer "F.SilkS")
		)
		(fp_line
			(start 0.7874 -0.4064)
			(end 0.7874 0.4064)
			(stroke
				(width 0.1524)
				(type default)
			)
			(layer "F.SilkS")
		)
		(fp_line
			(start 0.7874 0.4064)
			(end -0.7874 0.4064)
			(stroke
				(width 0.1524)
				(type default)
			)
			(layer "F.SilkS")
		)
		(fp_poly
			(pts
				(xy -0.5334 0.254) (xy -0.635 0.254) (xy -0.635 0.2286) (xy -0.635 -0.254) (xy -0.5334 -0.254) (xy -0.5334 -0.2794)
				(xy 0.5334 -0.2794) (xy 0.5334 -0.254) (xy 0.635 -0.254) (xy 0.635 0.254) (xy 0.5334 0.254) (xy 0.5334 0.2794)
				(xy -0.508 0.2794) (xy -0.5334 0.2794)
			)
			(stroke
				(width 0)
				(type default)
			)
			(fill no)
			(layer "F.CrtYd")
		)
		(pad "1" smd rect
			(at 0.40005 0)
			(size 0.4572 0.508)
			(layers "F.Cu" "F.Mask" "F.Paste")
			(net "P5V_STB_NODE1_FB")
		)
		(pad "2" smd rect
			(at -0.40005 0)
			(size 0.4572 0.508)
			(layers "F.Cu" "F.Mask" "F.Paste")
			(net "P5V_STB_NODE1")
		)
	)
	(footprint ""
		(layer "F.Cu")
		(at 66.53276 -185.205624 -90)
		(property "Reference" "R877"
			(at -4.006088 0.786892 90)
			(unlocked yes)
			(layer "F.SilkS")
			(effects
				(font
					(size 0.7874 0.5842)
					(thickness 0.1524)
				)
				(justify left)
			)
		)
		(property "Value" ""
			(at 0 0 270)
			(layer "F.Fab")
			(effects
				(font
					(size 1.27 1.27)
				)
			)
		)
		(duplicate_pad_numbers_are_jumpers no)
		(fp_line
			(start -0.7874 0.4064)
			(end -0.7874 -0.4064)
			(stroke
				(width 0.1524)
				(type default)
			)
			(layer "F.SilkS")
		)
		(fp_line
			(start 0.7874 0.4064)
			(end -0.7874 0.4064)
			(stroke
				(width 0.1524)
				(type default)
			)
			(layer "F.SilkS")
		)
		(fp_line
			(start -0.7874 -0.4064)
			(end 0.7874 -0.4064)
			(stroke
				(width 0.1524)
				(type default)
			)
			(layer "F.SilkS")
		)
		(fp_line
			(start 0.7874 -0.4064)
			(end 0.7874 0.4064)
			(stroke
				(width 0.1524)
				(type default)
			)
			(layer "F.SilkS")
		)
		(fp_poly
			(pts
				(xy -0.508 0.2794) (xy -0.508 0.2286) (xy -0.635 0.2286) (xy -0.635 -0.254) (xy -0.5334 -0.254)
				(xy -0.5334 -0.2794) (xy 0.5334 -0.2794) (xy 0.5334 -0.254) (xy 0.635 -0.254) (xy 0.635 0.254) (xy 0.5334 0.254)
				(xy 0.5334 0.2794)
			)
			(stroke
				(width 0)
				(type default)
			)
			(fill no)
			(layer "F.CrtYd")
		)
		(pad "1" smd rect
			(at 0.40005 0 270)
			(size 0.4572 0.508)
			(layers "F.Cu" "F.Mask" "F.Paste")
			(net "T2_NODE3_EN")
		)
		(pad "2" smd rect
			(at -0.40005 0 270)
			(size 0.4572 0.508)
			(layers "F.Cu" "F.Mask" "F.Paste")
			(net "T2_NODE3_EN_R")
		)
	)
	(footprint ""
		(layer "F.Cu")
		(at 64.718692 -107.316016 90)
		(property "Reference" "R1113"
			(at -1.128014 7.713472 90)
			(unlocked yes)
			(layer "F.SilkS")
			(effects
				(font
					(size 0.7874 0.5842)
					(thickness 0.1524)
				)
				(justify left)
			)
		)
		(property "Value" ""
			(at 0 0 90)
			(layer "F.Fab")
			(effects
				(font
					(size 1.27 1.27)
				)
			)
		)
		(duplicate_pad_numbers_are_jumpers no)
		(fp_line
			(start 0.7874 -0.4064)
			(end 0.7874 0.4064)
			(stroke
				(width 0.1524)
				(type default)
			)
			(layer "F.SilkS")
		)
		(fp_line
			(start -0.7874 -0.4064)
			(end 0.7874 -0.4064)
			(stroke
				(width 0.1524)
				(type default)
			)
			(layer "F.SilkS")
		)
		(fp_line
			(start 0.7874 0.4064)
			(end -0.7874 0.4064)
			(stroke
				(width 0.1524)
				(type default)
			)
			(layer "F.SilkS")
		)
		(fp_line
			(start -0.7874 0.4064)
			(end -0.7874 -0.4064)
			(stroke
				(width 0.1524)
				(type default)
			)
			(layer "F.SilkS")
		)
		(fp_poly
			(pts
				(xy -0.508 0.2794) (xy -0.508 0.2286) (xy -0.635 0.2286) (xy -0.635 -0.254) (xy -0.5334 -0.254)
				(xy -0.5334 -0.2794) (xy 0.5334 -0.2794) (xy 0.5334 -0.254) (xy 0.635 -0.254) (xy 0.635 0.254) (xy 0.5334 0.254)
				(xy 0.5334 0.2794)
			)
			(stroke
				(width 0)
				(type default)
			)
			(fill no)
			(layer "F.CrtYd")
		)
		(pad "1" smd rect
			(at 0.40005 0 90)
			(size 0.4572 0.508)
			(layers "F.Cu" "F.Mask" "F.Paste")
			(net "FM_CPLD_NODE1_P1V8_EN_G")
		)
		(pad "2" smd rect
			(at -0.40005 0 90)
			(size 0.4572 0.508)
			(layers "F.Cu" "F.Mask" "F.Paste")
			(net "P3V3_STB_NODE1")
		)
	)
	(footprint ""
		(layer "F.Cu")
		(at 69.755004 -168.695624)
		(property "Reference" "C582"
			(at -4.408424 0.897636 0)
			(unlocked yes)
			(layer "F.SilkS")
			(effects
				(font
					(size 0.7874 0.5842)
					(thickness 0.1524)
				)
				(justify left)
			)
		)
		(property "Value" ""
			(at 0 0 0)
			(layer "F.Fab")
			(effects
				(font
					(size 1.27 1.27)
				)
			)
		)
		(duplicate_pad_numbers_are_jumpers no)
		(fp_line
			(start -0.7874 -0.4064)
			(end 0.7874 -0.4064)
			(stroke
				(width 0.1524)
				(type default)
			)
			(layer "F.SilkS")
		)
		(fp_line
			(start -0.7874 0.4064)
			(end -0.7874 -0.4064)
			(stroke
				(width 0.1524)
				(type default)
			)
			(layer "F.SilkS")
		)
		(fp_line
			(start 0 0.381)
			(end 0 -0.381)
			(stroke
				(width 0.1524)
				(type default)
			)
			(layer "F.SilkS")
		)
		(fp_line
			(start 0.7874 -0.4064)
			(end 0.7874 0.4064)
			(stroke
				(width 0.1524)
				(type default)
			)
			(layer "F.SilkS")
		)
		(fp_line
			(start 0.7874 0.4064)
			(end -0.7874 0.4064)
			(stroke
				(width 0.1524)
				(type default)
			)
			(layer "F.SilkS")
		)
		(fp_poly
			(pts
				(xy -0.5334 0.254) (xy -0.635 0.254) (xy -0.635 0.2286) (xy -0.635 -0.254) (xy -0.5334 -0.254) (xy -0.5334 -0.2794)
				(xy 0.5334 -0.2794) (xy 0.5334 -0.254) (xy 0.635 -0.254) (xy 0.635 0.254) (xy 0.5334 0.254) (xy 0.5334 0.2794)
				(xy -0.508 0.2794) (xy -0.5334 0.2794)
			)
			(stroke
				(width 0)
				(type default)
			)
			(fill no)
			(layer "F.CrtYd")
		)
		(pad "1" smd rect
			(at 0.40005 0)
			(size 0.4572 0.508)
			(layers "F.Cu" "F.Mask" "F.Paste")
			(net "P3V3_NODE1")
		)
		(pad "2" smd rect
			(at -0.40005 0)
			(size 0.4572 0.508)
			(layers "F.Cu" "F.Mask" "F.Paste")
			(net "GND")
		)
	)
	(footprint ""
		(layer "F.Cu")
		(at 90.81262 -180.626512 180)
		(property "Reference" "R811"
			(at -85.97646 -76.399644 0)
			(unlocked yes)
			(layer "F.SilkS")
			(effects
				(font
					(size 0.7874 0.5842)
					(thickness 0.1524)
				)
				(justify left)
			)
		)
		(property "Value" ""
			(at 0 0 180)
			(layer "F.Fab")
			(effects
				(font
					(size 1.27 1.27)
				)
			)
		)
		(duplicate_pad_numbers_are_jumpers no)
		(fp_line
			(start 0.7874 0.4064)
			(end -0.7874 0.4064)
			(stroke
				(width 0.1524)
				(type default)
			)
			(layer "F.SilkS")
		)
		(fp_line
			(start 0.7874 -0.4064)
			(end 0.7874 0.4064)
			(stroke
				(width 0.1524)
				(type default)
			)
			(layer "F.SilkS")
		)
		(fp_line
			(start -0.7874 0.4064)
			(end -0.7874 -0.4064)
			(stroke
				(width 0.1524)
				(type default)
			)
			(layer "F.SilkS")
		)
		(fp_line
			(start -0.7874 -0.4064)
			(end 0.7874 -0.4064)
			(stroke
				(width 0.1524)
				(type default)
			)
			(layer "F.SilkS")
		)
		(fp_poly
			(pts
				(xy -0.508 0.2794) (xy -0.508 0.2286) (xy -0.635 0.2286) (xy -0.635 -0.254) (xy -0.5334 -0.254)
				(xy -0.5334 -0.2794) (xy 0.5334 -0.2794) (xy 0.5334 -0.254) (xy 0.635 -0.254) (xy 0.635 0.254) (xy 0.5334 0.254)
				(xy 0.5334 0.2794)
			)
			(stroke
				(width 0)
				(type default)
			)
			(fill no)
			(layer "F.CrtYd")
		)
		(pad "1" smd rect
			(at 0.40005 0 180)
			(size 0.4572 0.508)
			(layers "F.Cu" "F.Mask" "F.Paste")
			(net "CPLD_UART_DTR_P4_N")
		)
		(pad "2" smd rect
			(at -0.40005 0 180)
			(size 0.4572 0.508)
			(layers "F.Cu" "F.Mask" "F.Paste")
			(net "GND")
		)
	)
	(footprint ""
		(layer "F.Cu")
		(at 89.954862 -17.60347)
		(property "Reference" "R207"
			(at -3.960622 0.11938 0)
			(unlocked yes)
			(layer "F.SilkS")
			(effects
				(font
					(size 0.7874 0.5842)
					(thickness 0.1524)
				)
				(justify left)
			)
		)
		(property "Value" ""
			(at 0 0 0)
			(layer "F.Fab")
			(effects
				(font
					(size 1.27 1.27)
				)
			)
		)
		(duplicate_pad_numbers_are_jumpers no)
		(fp_line
			(start -0.7874 -0.4064)
			(end 0.7874 -0.4064)
			(stroke
				(width 0.1524)
				(type default)
			)
			(layer "F.SilkS")
		)
		(fp_line
			(start -0.7874 0.4064)
			(end -0.7874 -0.4064)
			(stroke
				(width 0.1524)
				(type default)
			)
			(layer "F.SilkS")
		)
		(fp_line
			(start 0.7874 -0.4064)
			(end 0.7874 0.4064)
			(stroke
				(width 0.1524)
				(type default)
			)
			(layer "F.SilkS")
		)
		(fp_line
			(start 0.7874 0.4064)
			(end -0.7874 0.4064)
			(stroke
				(width 0.1524)
				(type default)
			)
			(layer "F.SilkS")
		)
		(fp_poly
			(pts
				(xy -0.508 0.2794) (xy -0.508 0.2286) (xy -0.635 0.2286) (xy -0.635 -0.254) (xy -0.5334 -0.254)
				(xy -0.5334 -0.2794) (xy 0.5334 -0.2794) (xy 0.5334 -0.254) (xy 0.635 -0.254) (xy 0.635 0.254) (xy 0.5334 0.254)
				(xy 0.5334 0.2794)
			)
			(stroke
				(width 0)
				(type default)
			)
			(fill no)
			(layer "F.CrtYd")
		)
		(pad "1" smd rect
			(at 0.40005 0)
			(size 0.4572 0.508)
			(layers "F.Cu" "F.Mask" "F.Paste")
			(net "GND")
		)
		(pad "2" smd rect
			(at -0.40005 0)
			(size 0.4572 0.508)
			(layers "F.Cu" "F.Mask" "F.Paste")
			(net "PD_NODE1_DM5")
		)
	)
	(footprint ""
		(layer "F.Cu")
		(at 183.2356 -188.4172 -90)
		(property "Reference" "R1292"
			(at -1.143 -0.17907 90)
			(unlocked yes)
			(layer "F.SilkS")
			(effects
				(font
					(size 0.7874 0.5842)
					(thickness 0.1524)
				)
				(justify left)
			)
		)
		(property "Value" ""
			(at 0 0 270)
			(layer "F.Fab")
			(effects
				(font
					(size 1.27 1.27)
				)
			)
		)
		(duplicate_pad_numbers_are_jumpers no)
		(fp_line
			(start -0.7874 0.4064)
			(end -0.7874 -0.4064)
			(stroke
				(width 0.1524)
				(type default)
			)
			(layer "F.SilkS")
		)
		(fp_line
			(start 0.7874 0.4064)
			(end -0.7874 0.4064)
			(stroke
				(width 0.1524)
				(type default)
			)
			(layer "F.SilkS")
		)
		(fp_line
			(start -0.7874 -0.4064)
			(end 0.7874 -0.4064)
			(stroke
				(width 0.1524)
				(type default)
			)
			(layer "F.SilkS")
		)
		(fp_line
			(start 0.7874 -0.4064)
			(end 0.7874 0.4064)
			(stroke
				(width 0.1524)
				(type default)
			)
			(layer "F.SilkS")
		)
		(fp_poly
			(pts
				(xy -0.508 0.2794) (xy -0.508 0.2286) (xy -0.635 0.2286) (xy -0.635 -0.254) (xy -0.5334 -0.254)
				(xy -0.5334 -0.2794) (xy 0.5334 -0.2794) (xy 0.5334 -0.254) (xy 0.635 -0.254) (xy 0.635 0.254) (xy 0.5334 0.254)
				(xy 0.5334 0.2794)
			)
			(stroke
				(width 0)
				(type default)
			)
			(fill no)
			(layer "F.CrtYd")
		)
		(pad "1" smd rect
			(at 0.40005 0 270)
			(size 0.4572 0.508)
			(layers "F.Cu" "F.Mask" "F.Paste")
			(net "POWER_SW1_PWR_CTR_12V")
		)
		(pad "2" smd rect
			(at -0.40005 0 270)
			(size 0.4572 0.508)
			(layers "F.Cu" "F.Mask" "F.Paste")
			(net "POWER_SW1_PWR_CTR_12V_R")
		)
	)
	(footprint ""
		(layer "F.Cu")
		(at 80.24876 -188.126624 90)
		(property "Reference" "C664"
			(at 4.548886 -1.749298 90)
			(unlocked yes)
			(layer "F.SilkS")
			(effects
				(font
					(size 0.7874 0.5842)
					(thickness 0.1524)
				)
				(justify left)
			)
		)
		(property "Value" ""
			(at 0 0 90)
			(layer "F.Fab")
			(effects
				(font
					(size 1.27 1.27)
				)
			)
		)
		(duplicate_pad_numbers_are_jumpers no)
		(fp_line
			(start 0.7874 -0.4064)
			(end 0.7874 0.4064)
			(stroke
				(width 0.1524)
				(type default)
			)
			(layer "F.SilkS")
		)
		(fp_line
			(start -0.7874 -0.4064)
			(end 0.7874 -0.4064)
			(stroke
				(width 0.1524)
				(type default)
			)
			(layer "F.SilkS")
		)
		(fp_line
			(start 0 0.381)
			(end 0 -0.381)
			(stroke
				(width 0.1524)
				(type default)
			)
			(layer "F.SilkS")
		)
		(fp_line
			(start 0.7874 0.4064)
			(end -0.7874 0.4064)
			(stroke
				(width 0.1524)
				(type default)
			)
			(layer "F.SilkS")
		)
		(fp_line
			(start -0.7874 0.4064)
			(end -0.7874 -0.4064)
			(stroke
				(width 0.1524)
				(type default)
			)
			(layer "F.SilkS")
		)
		(fp_poly
			(pts
				(xy -0.5334 0.254) (xy -0.635 0.254) (xy -0.635 0.2286) (xy -0.635 -0.254) (xy -0.5334 -0.254) (xy -0.5334 -0.2794)
				(xy 0.5334 -0.2794) (xy 0.5334 -0.254) (xy 0.635 -0.254) (xy 0.635 0.254) (xy 0.5334 0.254) (xy 0.5334 0.2794)
				(xy -0.508 0.2794) (xy -0.5334 0.2794)
			)
			(stroke
				(width 0)
				(type default)
			)
			(fill no)
			(layer "F.CrtYd")
		)
		(pad "1" smd rect
			(at 0.40005 0 90)
			(size 0.4572 0.508)
			(layers "F.Cu" "F.Mask" "F.Paste")
			(net "T4_NODE3_EN_R")
		)
		(pad "2" smd rect
			(at -0.40005 0 90)
			(size 0.4572 0.508)
			(layers "F.Cu" "F.Mask" "F.Paste")
			(net "GND")
		)
	)
	(footprint ""
		(layer "F.Cu")
		(at 20.915376 -49.716182 90)
		(property "Reference" "U45"
			(at 0.307086 4.860544 0)
			(unlocked yes)
			(layer "F.SilkS")
			(effects
				(font
					(size 0.7874 0.5842)
					(thickness 0.1524)
				)
			)
		)
		(property "Value" ""
			(at 0 0 90)
			(layer "F.Fab")
			(effects
				(font
					(size 1.27 1.27)
				)
			)
		)
		(duplicate_pad_numbers_are_jumpers no)
		(fp_line
			(start 1.651 -1.905)
			(end 1.651 1.905)
			(stroke
				(width 0.1524)
				(type default)
			)
			(layer "F.SilkS")
		)
		(fp_line
			(start -1.651 -1.905)
			(end 1.651 -1.905)
			(stroke
				(width 0.1524)
				(type default)
			)
			(layer "F.SilkS")
		)
		(fp_line
			(start 1.651 1.905)
			(end -1.651 1.905)
			(stroke
				(width 0.1524)
				(type default)
			)
			(layer "F.SilkS")
		)
		(fp_line
			(start -1.651 1.905)
			(end -1.651 -1.905)
			(stroke
				(width 0.1524)
				(type default)
			)
			(layer "F.SilkS")
		)
		(fp_poly
			(pts
				(xy -1.524 0.7112) (xy -1.524 1.7526) (xy -0.508 1.7526) (xy -0.508 0.6985) (xy 0.508 0.6985) (xy 0.508 1.7526)
				(xy 1.524 1.7526) (xy 1.524 0.6985) (xy 1.524 -0.6985) (xy 0.508 -0.6985) (xy 0.508 -1.7526) (xy -0.508 -1.7526)
				(xy -0.508 -0.6985) (xy -1.524 -0.6985) (xy -1.524 0.6985)
			)
			(stroke
				(width 0)
				(type default)
			)
			(fill no)
			(layer "F.CrtYd")
		)
		(fp_text user "3"
			(at 2.001012 -1.593088 90)
			(unlocked yes)
			(layer "F.SilkS")
			(effects
				(font
					(size 0.635 0.4064)
					(thickness 0.1524)
				)
			)
		)
		(fp_text user "2"
			(at 1.420114 2.46888 90)
			(unlocked yes)
			(layer "F.SilkS")
			(effects
				(font
					(size 0.635 0.4064)
					(thickness 0.1524)
				)
			)
		)
		(fp_text user "1"
			(at 0.161798 2.515362 90)
			(unlocked yes)
			(layer "F.SilkS")
			(effects
				(font
					(size 0.635 0.4064)
					(thickness 0.1524)
				)
			)
		)
		(pad "1" smd rect
			(at -1.016 1.1176 90)
			(size 1.016 1.27)
			(layers "F.Cu" "F.Mask" "F.Paste")
			(net "GND")
		)
		(pad "2" smd rect
			(at 1.016 1.1176 90)
			(size 1.016 1.27)
			(layers "F.Cu" "F.Mask" "F.Paste")
			(net "P5V_CRT")
		)
		(pad "3" smd rect
			(at 0 -1.1176 90)
			(size 1.016 1.27)
			(layers "F.Cu" "F.Mask" "F.Paste")
			(net "CRT_G")
		)
	)
	(footprint ""
		(layer "F.Cu")
		(at 57.38876 -188.126624 -90)
		(property "Reference" "R949"
			(at -4.548886 -0.391922 90)
			(unlocked yes)
			(layer "F.SilkS")
			(effects
				(font
					(size 0.7874 0.5842)
					(thickness 0.1524)
				)
				(justify left)
			)
		)
		(property "Value" ""
			(at 0 0 270)
			(layer "F.Fab")
			(effects
				(font
					(size 1.27 1.27)
				)
			)
		)
		(duplicate_pad_numbers_are_jumpers no)
		(fp_line
			(start -0.7874 0.4064)
			(end -0.7874 -0.4064)
			(stroke
				(width 0.1524)
				(type default)
			)
			(layer "F.SilkS")
		)
		(fp_line
			(start 0.7874 0.4064)
			(end -0.7874 0.4064)
			(stroke
				(width 0.1524)
				(type default)
			)
			(layer "F.SilkS")
		)
		(fp_line
			(start -0.7874 -0.4064)
			(end 0.7874 -0.4064)
			(stroke
				(width 0.1524)
				(type default)
			)
			(layer "F.SilkS")
		)
		(fp_line
			(start 0.7874 -0.4064)
			(end 0.7874 0.4064)
			(stroke
				(width 0.1524)
				(type default)
			)
			(layer "F.SilkS")
		)
		(fp_poly
			(pts
				(xy -0.508 0.2794) (xy -0.508 0.2286) (xy -0.635 0.2286) (xy -0.635 -0.254) (xy -0.5334 -0.254)
				(xy -0.5334 -0.2794) (xy 0.5334 -0.2794) (xy 0.5334 -0.254) (xy 0.635 -0.254) (xy 0.635 0.254) (xy 0.5334 0.254)
				(xy 0.5334 0.2794)
			)
			(stroke
				(width 0)
				(type default)
			)
			(fill no)
			(layer "F.CrtYd")
		)
		(pad "1" smd rect
			(at 0.40005 0 270)
			(size 0.4572 0.508)
			(layers "F.Cu" "F.Mask" "F.Paste")
			(net "UART_T2_NODE4_RXD")
		)
		(pad "2" smd rect
			(at -0.40005 0 270)
			(size 0.4572 0.508)
			(layers "F.Cu" "F.Mask" "F.Paste")
			(net "UART_T2_NODE4_RXD_R")
		)
	)
	(footprint ""
		(layer "F.Cu")
		(at 50.75936 -4.347464 90)
		(property "Reference" "PR32"
			(at -0.395224 1.775206 90)
			(unlocked yes)
			(layer "F.SilkS")
			(effects
				(font
					(size 0.7874 0.5842)
					(thickness 0.1524)
				)
				(justify left)
			)
		)
		(property "Value" ""
			(at 0 0 90)
			(layer "F.Fab")
			(effects
				(font
					(size 1.27 1.27)
				)
			)
		)
		(duplicate_pad_numbers_are_jumpers no)
		(fp_line
			(start 2.2098 -0.9398)
			(end 2.2098 0.9398)
			(stroke
				(width 0.1524)
				(type default)
			)
			(layer "F.SilkS")
		)
		(fp_line
			(start -2.2098 -0.9398)
			(end 2.2098 -0.9398)
			(stroke
				(width 0.1524)
				(type default)
			)
			(layer "F.SilkS")
		)
		(fp_line
			(start 2.2098 0.9398)
			(end -2.2098 0.9398)
			(stroke
				(width 0.1524)
				(type default)
			)
			(layer "F.SilkS")
		)
		(fp_line
			(start -2.2098 0.9398)
			(end -2.2098 -0.9398)
			(stroke
				(width 0.1524)
				(type default)
			)
			(layer "F.SilkS")
		)
		(fp_poly
			(pts
				(xy 2.0574 0.8382) (xy 2.0574 -0.8382) (xy 2.0574 -0.9398) (xy -2.0574 -0.9398) (xy -2.0574 -0.8382)
				(xy -2.0574 0.8382) (xy -2.0574 0.9398) (xy 2.0574 0.9398)
			)
			(stroke
				(width 0)
				(type default)
			)
			(fill no)
			(layer "F.CrtYd")
		)
		(pad "1" smd rect
			(at 1.4732 0 90)
			(size 1.1684 1.5748)
			(layers "F.Cu" "F.Mask" "F.Paste")
			(net "SW_PV_VDDR_NODE1_VIN_FLT")
		)
		(pad "2" smd rect
			(at -1.4732 0 90)
			(size 1.1684 1.5748)
			(layers "F.Cu" "F.Mask" "F.Paste")
			(net "P12V_AUX")
		)
	)
	(footprint ""
		(layer "F.Cu")
		(at 151.113998 -156.34843 180)
		(property "Reference" "C436"
			(at -0.933958 1.048258 0)
			(unlocked yes)
			(layer "F.SilkS")
			(effects
				(font
					(size 0.7874 0.5842)
					(thickness 0.1524)
				)
				(justify left)
			)
		)
		(property "Value" ""
			(at 0 0 180)
			(layer "F.Fab")
			(effects
				(font
					(size 1.27 1.27)
				)
			)
		)
		(duplicate_pad_numbers_are_jumpers no)
		(fp_line
			(start 0.7874 0.4064)
			(end -0.7874 0.4064)
			(stroke
				(width 0.1524)
				(type default)
			)
			(layer "F.SilkS")
		)
		(fp_line
			(start 0.7874 -0.4064)
			(end 0.7874 0.4064)
			(stroke
				(width 0.1524)
				(type default)
			)
			(layer "F.SilkS")
		)
		(fp_line
			(start 0 0.381)
			(end 0 -0.381)
			(stroke
				(width 0.1524)
				(type default)
			)
			(layer "F.SilkS")
		)
		(fp_line
			(start -0.7874 0.4064)
			(end -0.7874 -0.4064)
			(stroke
				(width 0.1524)
				(type default)
			)
			(layer "F.SilkS")
		)
		(fp_line
			(start -0.7874 -0.4064)
			(end 0.7874 -0.4064)
			(stroke
				(width 0.1524)
				(type default)
			)
			(layer "F.SilkS")
		)
		(fp_poly
			(pts
				(xy -0.5334 0.254) (xy -0.635 0.254) (xy -0.635 0.2286) (xy -0.635 -0.254) (xy -0.5334 -0.254) (xy -0.5334 -0.2794)
				(xy 0.5334 -0.2794) (xy 0.5334 -0.254) (xy 0.635 -0.254) (xy 0.635 0.254) (xy 0.5334 0.254) (xy 0.5334 0.2794)
				(xy -0.508 0.2794) (xy -0.5334 0.2794)
			)
			(stroke
				(width 0)
				(type default)
			)
			(fill no)
			(layer "F.CrtYd")
		)
		(pad "1" smd rect
			(at 0.40005 0 180)
			(size 0.4572 0.508)
			(layers "F.Cu" "F.Mask" "F.Paste")
			(net "P2E_CPU_NIC2_NODE1_RX_DN")
		)
		(pad "2" smd rect
			(at -0.40005 0 180)
			(size 0.4572 0.508)
			(layers "F.Cu" "F.Mask" "F.Paste")
			(net "PCIE_LAN2_RX_C_DN")
		)
	)
	(footprint ""
		(layer "F.Cu")
		(at 150.47976 -185.205624 -90)
		(property "Reference" "R984"
			(at -4.768088 -0.259588 90)
			(unlocked yes)
			(layer "F.SilkS")
			(effects
				(font
					(size 0.7874 0.5842)
					(thickness 0.1524)
				)
				(justify left)
			)
		)
		(property "Value" ""
			(at 0 0 270)
			(layer "F.Fab")
			(effects
				(font
					(size 1.27 1.27)
				)
			)
		)
		(duplicate_pad_numbers_are_jumpers no)
		(fp_line
			(start -0.7874 0.4064)
			(end -0.7874 -0.4064)
			(stroke
				(width 0.1524)
				(type default)
			)
			(layer "F.SilkS")
		)
		(fp_line
			(start 0.7874 0.4064)
			(end -0.7874 0.4064)
			(stroke
				(width 0.1524)
				(type default)
			)
			(layer "F.SilkS")
		)
		(fp_line
			(start -0.7874 -0.4064)
			(end 0.7874 -0.4064)
			(stroke
				(width 0.1524)
				(type default)
			)
			(layer "F.SilkS")
		)
		(fp_line
			(start 0.7874 -0.4064)
			(end 0.7874 0.4064)
			(stroke
				(width 0.1524)
				(type default)
			)
			(layer "F.SilkS")
		)
		(fp_poly
			(pts
				(xy -0.508 0.2794) (xy -0.508 0.2286) (xy -0.635 0.2286) (xy -0.635 -0.254) (xy -0.5334 -0.254)
				(xy -0.5334 -0.2794) (xy 0.5334 -0.2794) (xy 0.5334 -0.254) (xy 0.635 -0.254) (xy 0.635 0.254) (xy 0.5334 0.254)
				(xy 0.5334 0.2794)
			)
			(stroke
				(width 0)
				(type default)
			)
			(fill no)
			(layer "F.CrtYd")
		)
		(pad "1" smd rect
			(at 0.40005 0 270)
			(size 0.4572 0.508)
			(layers "F.Cu" "F.Mask" "F.Paste")
			(net "UART_T12_NODE1_TXD")
		)
		(pad "2" smd rect
			(at -0.40005 0 270)
			(size 0.4572 0.508)
			(layers "F.Cu" "F.Mask" "F.Paste")
			(net "UART_T12_NODE1_TXD_R")
		)
	)
	(footprint ""
		(layer "F.Cu")
		(at 62.08776 -178.804824 180)
		(property "Reference" "U97"
			(at 11.201908 -132.653786 90)
			(unlocked yes)
			(layer "F.SilkS")
			(effects
				(font
					(size 0.7874 0.5842)
					(thickness 0.1524)
				)
			)
		)
		(property "Value" ""
			(at 0 0 180)
			(layer "F.Fab")
			(effects
				(font
					(size 1.27 1.27)
				)
			)
		)
		(duplicate_pad_numbers_are_jumpers no)
		(fp_line
			(start 1.651 1.905)
			(end -1.651 1.905)
			(stroke
				(width 0.1524)
				(type default)
			)
			(layer "F.SilkS")
		)
		(fp_line
			(start 1.651 -1.905)
			(end 1.651 1.905)
			(stroke
				(width 0.1524)
				(type default)
			)
			(layer "F.SilkS")
		)
		(fp_line
			(start -1.651 1.905)
			(end -1.651 -1.905)
			(stroke
				(width 0.1524)
				(type default)
			)
			(layer "F.SilkS")
		)
		(fp_line
			(start -1.651 -1.905)
			(end 1.651 -1.905)
			(stroke
				(width 0.1524)
				(type default)
			)
			(layer "F.SilkS")
		)
		(fp_poly
			(pts
				(xy -1.524 0.7112) (xy -1.524 1.7526) (xy -0.508 1.7526) (xy -0.508 0.6985) (xy 0.508 0.6985) (xy 0.508 1.7526)
				(xy 1.524 1.7526) (xy 1.524 0.6985) (xy 1.524 -0.6985) (xy 0.508 -0.6985) (xy 0.508 -1.7526) (xy -0.508 -1.7526)
				(xy -0.508 -0.6985) (xy -1.524 -0.6985) (xy -1.524 0.6985)
			)
			(stroke
				(width 0)
				(type default)
			)
			(fill no)
			(layer "F.CrtYd")
		)
		(fp_text user "S"
			(at 0.762508 2.487168 0)
			(unlocked yes)
			(layer "F.SilkS")
			(effects
				(font
					(size 0.635 0.4064)
					(thickness 0.1524)
				)
			)
		)
		(fp_text user "D"
			(at 0.095758 -2.441956 0)
			(unlocked yes)
			(layer "F.SilkS")
			(effects
				(font
					(size 0.635 0.4064)
					(thickness 0.1524)
				)
			)
		)
		(fp_text user "G"
			(at -0.380492 2.487168 0)
			(unlocked yes)
			(layer "F.SilkS")
			(effects
				(font
					(size 0.635 0.4064)
					(thickness 0.1524)
				)
			)
		)
		(pad "D" smd rect
			(at 0 -1.1176 180)
			(size 1.016 1.27)
			(layers "F.Cu" "F.Mask" "F.Paste")
			(net "PSU_DC_OK_N")
		)
		(pad "G" smd rect
			(at -1.016 1.1176 180)
			(size 1.016 1.27)
			(layers "F.Cu" "F.Mask" "F.Paste")
			(net "PSU2_DC_OK_R_BUF")
		)
		(pad "S" smd rect
			(at 1.016 1.1176 180)
			(size 1.016 1.27)
			(layers "F.Cu" "F.Mask" "F.Paste")
			(net "GND")
		)
	)
	(footprint ""
		(layer "F.Cu")
		(at 71.116698 -17.679416 90)
		(property "Reference" "C160"
			(at -4.797552 6.316472 90)
			(unlocked yes)
			(layer "F.SilkS")
			(effects
				(font
					(size 0.7874 0.5842)
					(thickness 0.1524)
				)
				(justify left)
			)
		)
		(property "Value" ""
			(at 0 0 90)
			(layer "F.Fab")
			(effects
				(font
					(size 1.27 1.27)
				)
			)
		)
		(duplicate_pad_numbers_are_jumpers no)
		(fp_line
			(start 0.7874 -0.4064)
			(end 0.7874 0.4064)
			(stroke
				(width 0.1524)
				(type default)
			)
			(layer "F.SilkS")
		)
		(fp_line
			(start -0.7874 -0.4064)
			(end 0.7874 -0.4064)
			(stroke
				(width 0.1524)
				(type default)
			)
			(layer "F.SilkS")
		)
		(fp_line
			(start 0 0.381)
			(end 0 -0.381)
			(stroke
				(width 0.1524)
				(type default)
			)
			(layer "F.SilkS")
		)
		(fp_line
			(start 0.7874 0.4064)
			(end -0.7874 0.4064)
			(stroke
				(width 0.1524)
				(type default)
			)
			(layer "F.SilkS")
		)
		(fp_line
			(start -0.7874 0.4064)
			(end -0.7874 -0.4064)
			(stroke
				(width 0.1524)
				(type default)
			)
			(layer "F.SilkS")
		)
		(fp_poly
			(pts
				(xy -0.5334 0.254) (xy -0.635 0.254) (xy -0.635 0.2286) (xy -0.635 -0.254) (xy -0.5334 -0.254) (xy -0.5334 -0.2794)
				(xy 0.5334 -0.2794) (xy 0.5334 -0.254) (xy 0.635 -0.254) (xy 0.635 0.254) (xy 0.5334 0.254) (xy 0.5334 0.2794)
				(xy -0.508 0.2794) (xy -0.5334 0.2794)
			)
			(stroke
				(width 0)
				(type default)
			)
			(fill no)
			(layer "F.CrtYd")
		)
		(pad "1" smd rect
			(at 0.40005 0 90)
			(size 0.4572 0.508)
			(layers "F.Cu" "F.Mask" "F.Paste")
			(net "PV_VDDR_NODE1")
		)
		(pad "2" smd rect
			(at -0.40005 0 90)
			(size 0.4572 0.508)
			(layers "F.Cu" "F.Mask" "F.Paste")
			(net "GND")
		)
	)
	(footprint ""
		(layer "F.Cu")
		(at 51.67376 -182.238142 90)
		(property "Reference" "C602"
			(at -133.313932 -3.637788 90)
			(unlocked yes)
			(layer "F.SilkS")
			(effects
				(font
					(size 0.7874 0.5842)
					(thickness 0.1524)
				)
				(justify left)
			)
		)
		(property "Value" ""
			(at 0 0 90)
			(layer "F.Fab")
			(effects
				(font
					(size 1.27 1.27)
				)
			)
		)
		(duplicate_pad_numbers_are_jumpers no)
		(fp_line
			(start 0.7874 -0.4064)
			(end 0.7874 0.4064)
			(stroke
				(width 0.1524)
				(type default)
			)
			(layer "F.SilkS")
		)
		(fp_line
			(start -0.7874 -0.4064)
			(end 0.7874 -0.4064)
			(stroke
				(width 0.1524)
				(type default)
			)
			(layer "F.SilkS")
		)
		(fp_line
			(start 0 0.381)
			(end 0 -0.381)
			(stroke
				(width 0.1524)
				(type default)
			)
			(layer "F.SilkS")
		)
		(fp_line
			(start 0.7874 0.4064)
			(end -0.7874 0.4064)
			(stroke
				(width 0.1524)
				(type default)
			)
			(layer "F.SilkS")
		)
		(fp_line
			(start -0.7874 0.4064)
			(end -0.7874 -0.4064)
			(stroke
				(width 0.1524)
				(type default)
			)
			(layer "F.SilkS")
		)
		(fp_poly
			(pts
				(xy -0.5334 0.254) (xy -0.635 0.254) (xy -0.635 0.2286) (xy -0.635 -0.254) (xy -0.5334 -0.254) (xy -0.5334 -0.2794)
				(xy 0.5334 -0.2794) (xy 0.5334 -0.254) (xy 0.635 -0.254) (xy 0.635 0.254) (xy 0.5334 0.254) (xy 0.5334 0.2794)
				(xy -0.508 0.2794) (xy -0.5334 0.2794)
			)
			(stroke
				(width 0)
				(type default)
			)
			(fill no)
			(layer "F.CrtYd")
		)
		(pad "1" smd rect
			(at 0.40005 0 90)
			(size 0.4572 0.508)
			(layers "F.Cu" "F.Mask" "F.Paste")
			(net "PSU2_AC_OK")
		)
		(pad "2" smd rect
			(at -0.40005 0 90)
			(size 0.4572 0.508)
			(layers "F.Cu" "F.Mask" "F.Paste")
			(net "GND")
		)
	)
	(footprint ""
		(layer "F.Cu")
		(at 74.53376 -185.205624 -90)
		(property "Reference" "R941"
			(at -4.006088 1.302258 90)
			(unlocked yes)
			(layer "F.SilkS")
			(effects
				(font
					(size 0.7874 0.5842)
					(thickness 0.1524)
				)
				(justify left)
			)
		)
		(property "Value" ""
			(at 0 0 270)
			(layer "F.Fab")
			(effects
				(font
					(size 1.27 1.27)
				)
			)
		)
		(duplicate_pad_numbers_are_jumpers no)
		(fp_line
			(start -0.7874 0.4064)
			(end -0.7874 -0.4064)
			(stroke
				(width 0.1524)
				(type default)
			)
			(layer "F.SilkS")
		)
		(fp_line
			(start 0.7874 0.4064)
			(end -0.7874 0.4064)
			(stroke
				(width 0.1524)
				(type default)
			)
			(layer "F.SilkS")
		)
		(fp_line
			(start -0.7874 -0.4064)
			(end 0.7874 -0.4064)
			(stroke
				(width 0.1524)
				(type default)
			)
			(layer "F.SilkS")
		)
		(fp_line
			(start 0.7874 -0.4064)
			(end 0.7874 0.4064)
			(stroke
				(width 0.1524)
				(type default)
			)
			(layer "F.SilkS")
		)
		(fp_poly
			(pts
				(xy -0.508 0.2794) (xy -0.508 0.2286) (xy -0.635 0.2286) (xy -0.635 -0.254) (xy -0.5334 -0.254)
				(xy -0.5334 -0.2794) (xy 0.5334 -0.2794) (xy 0.5334 -0.254) (xy 0.635 -0.254) (xy 0.635 0.254) (xy 0.5334 0.254)
				(xy 0.5334 0.2794)
			)
			(stroke
				(width 0)
				(type default)
			)
			(fill no)
			(layer "F.CrtYd")
		)
		(pad "1" smd rect
			(at 0.40005 0 270)
			(size 0.4572 0.508)
			(layers "F.Cu" "F.Mask" "F.Paste")
			(net "UART_T4_NODE2_TXD")
		)
		(pad "2" smd rect
			(at -0.40005 0 270)
			(size 0.4572 0.508)
			(layers "F.Cu" "F.Mask" "F.Paste")
			(net "UART_T4_NODE2_TXD_R")
		)
	)
	(footprint ""
		(layer "F.Cu")
		(at 12.949174 -16.260572 -90)
		(property "Reference" "R651"
			(at 1.500124 6.253734 90)
			(unlocked yes)
			(layer "F.SilkS")
			(effects
				(font
					(size 0.7874 0.5842)
					(thickness 0.1524)
				)
				(justify left)
			)
		)
		(property "Value" ""
			(at 0 0 270)
			(layer "F.Fab")
			(effects
				(font
					(size 1.27 1.27)
				)
			)
		)
		(duplicate_pad_numbers_are_jumpers no)
		(fp_line
			(start -0.7874 0.4064)
			(end -0.7874 -0.4064)
			(stroke
				(width 0.1524)
				(type default)
			)
			(layer "F.SilkS")
		)
		(fp_line
			(start 0.7874 0.4064)
			(end -0.7874 0.4064)
			(stroke
				(width 0.1524)
				(type default)
			)
			(layer "F.SilkS")
		)
		(fp_line
			(start -0.7874 -0.4064)
			(end 0.7874 -0.4064)
			(stroke
				(width 0.1524)
				(type default)
			)
			(layer "F.SilkS")
		)
		(fp_line
			(start 0.7874 -0.4064)
			(end 0.7874 0.4064)
			(stroke
				(width 0.1524)
				(type default)
			)
			(layer "F.SilkS")
		)
		(fp_poly
			(pts
				(xy -0.508 0.2794) (xy -0.508 0.2286) (xy -0.635 0.2286) (xy -0.635 -0.254) (xy -0.5334 -0.254)
				(xy -0.5334 -0.2794) (xy 0.5334 -0.2794) (xy 0.5334 -0.254) (xy 0.635 -0.254) (xy 0.635 0.254) (xy 0.5334 0.254)
				(xy 0.5334 0.2794)
			)
			(stroke
				(width 0)
				(type default)
			)
			(fill no)
			(layer "F.CrtYd")
		)
		(pad "1" smd rect
			(at 0.40005 0 270)
			(size 0.4572 0.508)
			(layers "F.Cu" "F.Mask" "F.Paste")
			(net "P3V3_NODE1")
		)
		(pad "2" smd rect
			(at -0.40005 0 270)
			(size 0.4572 0.508)
			(layers "F.Cu" "F.Mask" "F.Paste")
			(net "N54251487")
		)
	)
	(footprint ""
		(layer "F.Cu")
		(at 186.202828 -116.961666 180)
		(property "Reference" "R1246"
			(at -1.249172 0.994664 0)
			(unlocked yes)
			(layer "F.SilkS")
			(effects
				(font
					(size 0.7874 0.5842)
					(thickness 0.1524)
				)
				(justify left)
			)
		)
		(property "Value" ""
			(at 0 0 180)
			(layer "F.Fab")
			(effects
				(font
					(size 1.27 1.27)
				)
			)
		)
		(duplicate_pad_numbers_are_jumpers no)
		(fp_line
			(start 0.7874 0.4064)
			(end -0.7874 0.4064)
			(stroke
				(width 0.1524)
				(type default)
			)
			(layer "F.SilkS")
		)
		(fp_line
			(start 0.7874 -0.4064)
			(end 0.7874 0.4064)
			(stroke
				(width 0.1524)
				(type default)
			)
			(layer "F.SilkS")
		)
		(fp_line
			(start -0.7874 0.4064)
			(end -0.7874 -0.4064)
			(stroke
				(width 0.1524)
				(type default)
			)
			(layer "F.SilkS")
		)
		(fp_line
			(start -0.7874 -0.4064)
			(end 0.7874 -0.4064)
			(stroke
				(width 0.1524)
				(type default)
			)
			(layer "F.SilkS")
		)
		(fp_poly
			(pts
				(xy -0.508 0.2794) (xy -0.508 0.2286) (xy -0.635 0.2286) (xy -0.635 -0.254) (xy -0.5334 -0.254)
				(xy -0.5334 -0.2794) (xy 0.5334 -0.2794) (xy 0.5334 -0.254) (xy 0.635 -0.254) (xy 0.635 0.254) (xy 0.5334 0.254)
				(xy 0.5334 0.2794)
			)
			(stroke
				(width 0)
				(type default)
			)
			(fill no)
			(layer "F.CrtYd")
		)
		(pad "1" smd rect
			(at 0.40005 0 180)
			(size 0.4572 0.508)
			(layers "F.Cu" "F.Mask" "F.Paste")
			(net "PWRGD_NODE1_P5V_STB_PG_CPLD")
		)
		(pad "2" smd rect
			(at -0.40005 0 180)
			(size 0.4572 0.508)
			(layers "F.Cu" "F.Mask" "F.Paste")
			(net "PWRGD_NODE1_P5V_STB_PG")
		)
	)
	(footprint ""
		(layer "F.Cu")
		(at 18.381472 -74.207878 90)
		(property "Reference" "C498"
			(at 1.69672 -0.072898 90)
			(unlocked yes)
			(layer "F.SilkS")
			(effects
				(font
					(size 0.7874 0.5842)
					(thickness 0.1524)
				)
				(justify left)
			)
		)
		(property "Value" ""
			(at 0 0 90)
			(layer "F.Fab")
			(effects
				(font
					(size 1.27 1.27)
				)
			)
		)
		(duplicate_pad_numbers_are_jumpers no)
		(fp_line
			(start 0.7874 -0.4064)
			(end 0.7874 0.4064)
			(stroke
				(width 0.1524)
				(type default)
			)
			(layer "F.SilkS")
		)
		(fp_line
			(start -0.7874 -0.4064)
			(end 0.7874 -0.4064)
			(stroke
				(width 0.1524)
				(type default)
			)
			(layer "F.SilkS")
		)
		(fp_line
			(start 0 0.381)
			(end 0 -0.381)
			(stroke
				(width 0.1524)
				(type default)
			)
			(layer "F.SilkS")
		)
		(fp_line
			(start 0.7874 0.4064)
			(end -0.7874 0.4064)
			(stroke
				(width 0.1524)
				(type default)
			)
			(layer "F.SilkS")
		)
		(fp_line
			(start -0.7874 0.4064)
			(end -0.7874 -0.4064)
			(stroke
				(width 0.1524)
				(type default)
			)
			(layer "F.SilkS")
		)
		(fp_poly
			(pts
				(xy -0.5334 0.254) (xy -0.635 0.254) (xy -0.635 0.2286) (xy -0.635 -0.254) (xy -0.5334 -0.254) (xy -0.5334 -0.2794)
				(xy 0.5334 -0.2794) (xy 0.5334 -0.254) (xy 0.635 -0.254) (xy 0.635 0.254) (xy 0.5334 0.254) (xy 0.5334 0.2794)
				(xy -0.508 0.2794) (xy -0.5334 0.2794)
			)
			(stroke
				(width 0)
				(type default)
			)
			(fill no)
			(layer "F.CrtYd")
		)
		(pad "1" smd rect
			(at 0.40005 0 90)
			(size 0.4572 0.508)
			(layers "F.Cu" "F.Mask" "F.Paste")
			(net "VCC5_CRTXX")
		)
		(pad "2" smd rect
			(at -0.40005 0 90)
			(size 0.4572 0.508)
			(layers "F.Cu" "F.Mask" "F.Paste")
			(net "GND")
		)
	)
	(footprint ""
		(layer "F.Cu")
		(at 123.70816 -170.587416)
		(property "Reference" "R674"
			(at 30.127448 47.889922 0)
			(unlocked yes)
			(layer "F.SilkS")
			(effects
				(font
					(size 0.7874 0.5842)
					(thickness 0.1524)
				)
				(justify left)
			)
		)
		(property "Value" ""
			(at 0 0 0)
			(layer "F.Fab")
			(effects
				(font
					(size 1.27 1.27)
				)
			)
		)
		(duplicate_pad_numbers_are_jumpers no)
		(fp_line
			(start -0.7874 -0.4064)
			(end 0.7874 -0.4064)
			(stroke
				(width 0.1524)
				(type default)
			)
			(layer "F.SilkS")
		)
		(fp_line
			(start -0.7874 0.4064)
			(end -0.7874 -0.4064)
			(stroke
				(width 0.1524)
				(type default)
			)
			(layer "F.SilkS")
		)
		(fp_line
			(start 0.7874 -0.4064)
			(end 0.7874 0.4064)
			(stroke
				(width 0.1524)
				(type default)
			)
			(layer "F.SilkS")
		)
		(fp_line
			(start 0.7874 0.4064)
			(end -0.7874 0.4064)
			(stroke
				(width 0.1524)
				(type default)
			)
			(layer "F.SilkS")
		)
		(fp_poly
			(pts
				(xy -0.508 0.2794) (xy -0.508 0.2286) (xy -0.635 0.2286) (xy -0.635 -0.254) (xy -0.5334 -0.254)
				(xy -0.5334 -0.2794) (xy 0.5334 -0.2794) (xy 0.5334 -0.254) (xy 0.635 -0.254) (xy 0.635 0.254) (xy 0.5334 0.254)
				(xy 0.5334 0.2794)
			)
			(stroke
				(width 0)
				(type default)
			)
			(fill no)
			(layer "F.CrtYd")
		)
		(pad "1" smd rect
			(at 0.40005 0)
			(size 0.4572 0.508)
			(layers "F.Cu" "F.Mask" "F.Paste")
			(net "P3V3_NODE1")
		)
		(pad "2" smd rect
			(at -0.40005 0)
			(size 0.4572 0.508)
			(layers "F.Cu" "F.Mask" "F.Paste")
			(net "PU_I2C_SDA4")
		)
	)
	(footprint ""
		(layer "F.Cu")
		(at 42.252646 -113.038636 180)
		(property "Reference" "PR7"
			(at 1.472692 4.630928 0)
			(unlocked yes)
			(layer "F.SilkS")
			(effects
				(font
					(size 0.7874 0.5842)
					(thickness 0.1524)
				)
				(justify left)
			)
		)
		(property "Value" ""
			(at 0 0 180)
			(layer "F.Fab")
			(effects
				(font
					(size 1.27 1.27)
				)
			)
		)
		(duplicate_pad_numbers_are_jumpers no)
		(fp_line
			(start 0.7874 0.4064)
			(end -0.7874 0.4064)
			(stroke
				(width 0.1524)
				(type default)
			)
			(layer "F.SilkS")
		)
		(fp_line
			(start 0.7874 -0.4064)
			(end 0.7874 0.4064)
			(stroke
				(width 0.1524)
				(type default)
			)
			(layer "F.SilkS")
		)
		(fp_line
			(start -0.7874 0.4064)
			(end -0.7874 -0.4064)
			(stroke
				(width 0.1524)
				(type default)
			)
			(layer "F.SilkS")
		)
		(fp_line
			(start -0.7874 -0.4064)
			(end 0.7874 -0.4064)
			(stroke
				(width 0.1524)
				(type default)
			)
			(layer "F.SilkS")
		)
		(fp_poly
			(pts
				(xy -0.508 0.2794) (xy -0.508 0.2286) (xy -0.635 0.2286) (xy -0.635 -0.254) (xy -0.5334 -0.254)
				(xy -0.5334 -0.2794) (xy 0.5334 -0.2794) (xy 0.5334 -0.254) (xy 0.635 -0.254) (xy 0.635 0.254) (xy 0.5334 0.254)
				(xy 0.5334 0.2794)
			)
			(stroke
				(width 0)
				(type default)
			)
			(fill no)
			(layer "F.CrtYd")
		)
		(pad "1" smd rect
			(at 0.40005 0 180)
			(size 0.4572 0.508)
			(layers "F.Cu" "F.Mask" "F.Paste")
			(net "P3V3_STB_NODE1_FB")
		)
		(pad "2" smd rect
			(at -0.40005 0 180)
			(size 0.4572 0.508)
			(layers "F.Cu" "F.Mask" "F.Paste")
			(net "P3V3_STB_NODE1")
		)
	)
	(footprint ""
		(layer "F.Cu")
		(at 137.287 -51.435 -90)
		(property "Reference" "R1155"
			(at -16.3322 -30.68447 90)
			(unlocked yes)
			(layer "F.SilkS")
			(effects
				(font
					(size 0.7874 0.5842)
					(thickness 0.1524)
				)
				(justify left)
			)
		)
		(property "Value" ""
			(at 0 0 270)
			(layer "F.Fab")
			(effects
				(font
					(size 1.27 1.27)
				)
			)
		)
		(duplicate_pad_numbers_are_jumpers no)
		(fp_line
			(start -0.7874 0.4064)
			(end -0.7874 -0.4064)
			(stroke
				(width 0.1524)
				(type default)
			)
			(layer "F.SilkS")
		)
		(fp_line
			(start 0.7874 0.4064)
			(end -0.7874 0.4064)
			(stroke
				(width 0.1524)
				(type default)
			)
			(layer "F.SilkS")
		)
		(fp_line
			(start -0.7874 -0.4064)
			(end 0.7874 -0.4064)
			(stroke
				(width 0.1524)
				(type default)
			)
			(layer "F.SilkS")
		)
		(fp_line
			(start 0.7874 -0.4064)
			(end 0.7874 0.4064)
			(stroke
				(width 0.1524)
				(type default)
			)
			(layer "F.SilkS")
		)
		(fp_poly
			(pts
				(xy -0.508 0.2794) (xy -0.508 0.2286) (xy -0.635 0.2286) (xy -0.635 -0.254) (xy -0.5334 -0.254)
				(xy -0.5334 -0.2794) (xy 0.5334 -0.2794) (xy 0.5334 -0.254) (xy 0.635 -0.254) (xy 0.635 0.254) (xy 0.5334 0.254)
				(xy 0.5334 0.2794)
			)
			(stroke
				(width 0)
				(type default)
			)
			(fill no)
			(layer "F.CrtYd")
		)
		(pad "1" smd rect
			(at 0.40005 0 270)
			(size 0.4572 0.508)
			(layers "F.Cu" "F.Mask" "F.Paste")
			(net "UART_DTR_P3_R_N")
		)
		(pad "2" smd rect
			(at -0.40005 0 270)
			(size 0.4572 0.508)
			(layers "F.Cu" "F.Mask" "F.Paste")
			(net "UART_DTR_P3_N")
		)
	)
	(footprint ""
		(layer "F.Cu")
		(at 21.913342 -53.302408 90)
		(property "Reference" "U48"
			(at -2.97942 13.753338 0)
			(unlocked yes)
			(layer "F.SilkS")
			(effects
				(font
					(size 0.7874 0.5842)
					(thickness 0.1524)
				)
			)
		)
		(property "Value" ""
			(at 0 0 90)
			(layer "F.Fab")
			(effects
				(font
					(size 1.27 1.27)
				)
			)
		)
		(duplicate_pad_numbers_are_jumpers no)
		(fp_line
			(start 1.651 -1.905)
			(end 1.651 1.905)
			(stroke
				(width 0.1524)
				(type default)
			)
			(layer "F.SilkS")
		)
		(fp_line
			(start -1.651 -1.905)
			(end 1.651 -1.905)
			(stroke
				(width 0.1524)
				(type default)
			)
			(layer "F.SilkS")
		)
		(fp_line
			(start 1.651 1.905)
			(end -1.651 1.905)
			(stroke
				(width 0.1524)
				(type default)
			)
			(layer "F.SilkS")
		)
		(fp_line
			(start -1.651 1.905)
			(end -1.651 -1.905)
			(stroke
				(width 0.1524)
				(type default)
			)
			(layer "F.SilkS")
		)
		(fp_poly
			(pts
				(xy -1.524 0.7112) (xy -1.524 1.7526) (xy -0.508 1.7526) (xy -0.508 0.6985) (xy 0.508 0.6985) (xy 0.508 1.7526)
				(xy 1.524 1.7526) (xy 1.524 0.6985) (xy 1.524 -0.6985) (xy 0.508 -0.6985) (xy 0.508 -1.7526) (xy -0.508 -1.7526)
				(xy -0.508 -0.6985) (xy -1.524 -0.6985) (xy -1.524 0.6985)
			)
			(stroke
				(width 0)
				(type default)
			)
			(fill no)
			(layer "F.CrtYd")
		)
		(fp_text user "3"
			(at 0.104902 -2.27965 0)
			(unlocked yes)
			(layer "F.SilkS")
			(effects
				(font
					(size 0.635 0.4064)
					(thickness 0.1524)
				)
			)
		)
		(fp_text user "1"
			(at -1.199896 2.222246 0)
			(unlocked yes)
			(layer "F.SilkS")
			(effects
				(font
					(size 0.635 0.4064)
					(thickness 0.1524)
				)
			)
		)
		(fp_text user "2"
			(at 0.561594 2.27838 0)
			(unlocked yes)
			(layer "F.SilkS")
			(effects
				(font
					(size 0.635 0.4064)
					(thickness 0.1524)
				)
			)
		)
		(pad "1" smd rect
			(at -1.016 1.1176 90)
			(size 1.016 1.27)
			(layers "F.Cu" "F.Mask" "F.Paste")
			(net "GND")
		)
		(pad "2" smd rect
			(at 1.016 1.1176 90)
			(size 1.016 1.27)
			(layers "F.Cu" "F.Mask" "F.Paste")
			(net "P5V_CRT")
		)
		(pad "3" smd rect
			(at 0 -1.1176 90)
			(size 1.016 1.27)
			(layers "F.Cu" "F.Mask" "F.Paste")
			(net "CRT_HSYNC")
		)
	)
	(footprint ""
		(layer "F.Cu")
		(at 48.955452 -170.821604)
		(property "Reference" "C621"
			(at -8.508492 131.261612 0)
			(unlocked yes)
			(layer "F.SilkS")
			(effects
				(font
					(size 0.7874 0.5842)
					(thickness 0.1524)
				)
				(justify left)
			)
		)
		(property "Value" ""
			(at 0 0 0)
			(layer "F.Fab")
			(effects
				(font
					(size 1.27 1.27)
				)
			)
		)
		(duplicate_pad_numbers_are_jumpers no)
		(fp_line
			(start -0.7874 -0.4064)
			(end 0.7874 -0.4064)
			(stroke
				(width 0.1524)
				(type default)
			)
			(layer "F.SilkS")
		)
		(fp_line
			(start -0.7874 0.4064)
			(end -0.7874 -0.4064)
			(stroke
				(width 0.1524)
				(type default)
			)
			(layer "F.SilkS")
		)
		(fp_line
			(start 0 0.381)
			(end 0 -0.381)
			(stroke
				(width 0.1524)
				(type default)
			)
			(layer "F.SilkS")
		)
		(fp_line
			(start 0.7874 -0.4064)
			(end 0.7874 0.4064)
			(stroke
				(width 0.1524)
				(type default)
			)
			(layer "F.SilkS")
		)
		(fp_line
			(start 0.7874 0.4064)
			(end -0.7874 0.4064)
			(stroke
				(width 0.1524)
				(type default)
			)
			(layer "F.SilkS")
		)
		(fp_poly
			(pts
				(xy -0.5334 0.254) (xy -0.635 0.254) (xy -0.635 0.2286) (xy -0.635 -0.254) (xy -0.5334 -0.254) (xy -0.5334 -0.2794)
				(xy 0.5334 -0.2794) (xy 0.5334 -0.254) (xy 0.635 -0.254) (xy 0.635 0.254) (xy 0.5334 0.254) (xy 0.5334 0.2794)
				(xy -0.508 0.2794) (xy -0.5334 0.2794)
			)
			(stroke
				(width 0)
				(type default)
			)
			(fill no)
			(layer "F.CrtYd")
		)
		(pad "1" smd rect
			(at 0.40005 0)
			(size 0.4572 0.508)
			(layers "F.Cu" "F.Mask" "F.Paste")
			(net "P3V3_NODE1")
		)
		(pad "2" smd rect
			(at -0.40005 0)
			(size 0.4572 0.508)
			(layers "F.Cu" "F.Mask" "F.Paste")
			(net "GND")
		)
	)
	(footprint ""
		(layer "F.Cu")
		(at 121.77522 -185.209942 -90)
		(property "Reference" "R866"
			(at -4.768088 -0.152908 90)
			(unlocked yes)
			(layer "F.SilkS")
			(effects
				(font
					(size 0.7874 0.5842)
					(thickness 0.1524)
				)
				(justify left)
			)
		)
		(property "Value" ""
			(at 0 0 270)
			(layer "F.Fab")
			(effects
				(font
					(size 1.27 1.27)
				)
			)
		)
		(duplicate_pad_numbers_are_jumpers no)
		(fp_line
			(start -0.7874 0.4064)
			(end -0.7874 -0.4064)
			(stroke
				(width 0.1524)
				(type default)
			)
			(layer "F.SilkS")
		)
		(fp_line
			(start 0.7874 0.4064)
			(end -0.7874 0.4064)
			(stroke
				(width 0.1524)
				(type default)
			)
			(layer "F.SilkS")
		)
		(fp_line
			(start -0.7874 -0.4064)
			(end 0.7874 -0.4064)
			(stroke
				(width 0.1524)
				(type default)
			)
			(layer "F.SilkS")
		)
		(fp_line
			(start 0.7874 -0.4064)
			(end 0.7874 0.4064)
			(stroke
				(width 0.1524)
				(type default)
			)
			(layer "F.SilkS")
		)
		(fp_poly
			(pts
				(xy -0.508 0.2794) (xy -0.508 0.2286) (xy -0.635 0.2286) (xy -0.635 -0.254) (xy -0.5334 -0.254)
				(xy -0.5334 -0.2794) (xy 0.5334 -0.2794) (xy 0.5334 -0.254) (xy 0.635 -0.254) (xy 0.635 0.254) (xy 0.5334 0.254)
				(xy 0.5334 0.2794)
			)
			(stroke
				(width 0)
				(type default)
			)
			(fill no)
			(layer "F.CrtYd")
		)
		(pad "1" smd rect
			(at 0.40005 0 270)
			(size 0.4572 0.508)
			(layers "F.Cu" "F.Mask" "F.Paste")
			(net "T8_NODE3_EN")
		)
		(pad "2" smd rect
			(at -0.40005 0 270)
			(size 0.4572 0.508)
			(layers "F.Cu" "F.Mask" "F.Paste")
			(net "T8_NODE3_EN_R")
		)
	)
	(footprint ""
		(layer "F.Cu")
		(at 132.03936 -109.869224 90)
		(property "Reference" "R9"
			(at 0.912114 0.22098 90)
			(unlocked yes)
			(layer "F.SilkS")
			(effects
				(font
					(size 0.7874 0.5842)
					(thickness 0.1524)
				)
				(justify left)
			)
		)
		(property "Value" ""
			(at 0 0 90)
			(layer "F.Fab")
			(effects
				(font
					(size 1.27 1.27)
				)
			)
		)
		(duplicate_pad_numbers_are_jumpers no)
		(fp_line
			(start 0.7874 -0.4064)
			(end 0.7874 0.4064)
			(stroke
				(width 0.1524)
				(type default)
			)
			(layer "F.SilkS")
		)
		(fp_line
			(start -0.7874 -0.4064)
			(end 0.7874 -0.4064)
			(stroke
				(width 0.1524)
				(type default)
			)
			(layer "F.SilkS")
		)
		(fp_line
			(start 0.7874 0.4064)
			(end -0.7874 0.4064)
			(stroke
				(width 0.1524)
				(type default)
			)
			(layer "F.SilkS")
		)
		(fp_line
			(start -0.7874 0.4064)
			(end -0.7874 -0.4064)
			(stroke
				(width 0.1524)
				(type default)
			)
			(layer "F.SilkS")
		)
		(fp_poly
			(pts
				(xy -0.508 0.2794) (xy -0.508 0.2286) (xy -0.635 0.2286) (xy -0.635 -0.254) (xy -0.5334 -0.254)
				(xy -0.5334 -0.2794) (xy 0.5334 -0.2794) (xy 0.5334 -0.254) (xy 0.635 -0.254) (xy 0.635 0.254) (xy 0.5334 0.254)
				(xy 0.5334 0.2794)
			)
			(stroke
				(width 0)
				(type default)
			)
			(fill no)
			(layer "F.CrtYd")
		)
		(pad "1" smd rect
			(at 0.40005 0 90)
			(size 0.4572 0.508)
			(layers "F.Cu" "F.Mask" "F.Paste")
			(net "CLK_25M_SATA_NODE1_R")
		)
		(pad "2" smd rect
			(at -0.40005 0 90)
			(size 0.4572 0.508)
			(layers "F.Cu" "F.Mask" "F.Paste")
			(net "CLK_25M_SATA_NODE1")
		)
	)
	(footprint ""
		(layer "F.Cu")
		(at 180.1876 -188.4172 -90)
		(property "Reference" "R1294"
			(at -1.1176 0.02413 90)
			(unlocked yes)
			(layer "F.SilkS")
			(effects
				(font
					(size 0.7874 0.5842)
					(thickness 0.1524)
				)
				(justify left)
			)
		)
		(property "Value" ""
			(at 0 0 270)
			(layer "F.Fab")
			(effects
				(font
					(size 1.27 1.27)
				)
			)
		)
		(duplicate_pad_numbers_are_jumpers no)
		(fp_line
			(start -0.7874 0.4064)
			(end -0.7874 -0.4064)
			(stroke
				(width 0.1524)
				(type default)
			)
			(layer "F.SilkS")
		)
		(fp_line
			(start 0.7874 0.4064)
			(end -0.7874 0.4064)
			(stroke
				(width 0.1524)
				(type default)
			)
			(layer "F.SilkS")
		)
		(fp_line
			(start -0.7874 -0.4064)
			(end 0.7874 -0.4064)
			(stroke
				(width 0.1524)
				(type default)
			)
			(layer "F.SilkS")
		)
		(fp_line
			(start 0.7874 -0.4064)
			(end 0.7874 0.4064)
			(stroke
				(width 0.1524)
				(type default)
			)
			(layer "F.SilkS")
		)
		(fp_poly
			(pts
				(xy -0.508 0.2794) (xy -0.508 0.2286) (xy -0.635 0.2286) (xy -0.635 -0.254) (xy -0.5334 -0.254)
				(xy -0.5334 -0.2794) (xy 0.5334 -0.2794) (xy 0.5334 -0.254) (xy 0.635 -0.254) (xy 0.635 0.254) (xy 0.5334 0.254)
				(xy 0.5334 0.2794)
			)
			(stroke
				(width 0)
				(type default)
			)
			(fill no)
			(layer "F.CrtYd")
		)
		(pad "1" smd rect
			(at 0.40005 0 270)
			(size 0.4572 0.508)
			(layers "F.Cu" "F.Mask" "F.Paste")
			(net "POWER_SW1_PWR_CTR_12V")
		)
		(pad "2" smd rect
			(at -0.40005 0 270)
			(size 0.4572 0.508)
			(layers "F.Cu" "F.Mask" "F.Paste")
			(net "POWER_SW1_PWR_CTR_12V_R")
		)
	)
	(footprint ""
		(layer "F.Cu")
		(at 17.874996 -62.977776 90)
		(property "Reference" "Q17"
			(at 0.419862 3.758946 90)
			(unlocked yes)
			(layer "F.SilkS")
			(effects
				(font
					(size 0.7874 0.5842)
					(thickness 0.1524)
				)
			)
		)
		(property "Value" ""
			(at 0 0 90)
			(layer "F.Fab")
			(effects
				(font
					(size 1.27 1.27)
				)
			)
		)
		(duplicate_pad_numbers_are_jumpers no)
		(fp_line
			(start 1.651 -1.905)
			(end 1.651 1.905)
			(stroke
				(width 0.1524)
				(type default)
			)
			(layer "F.SilkS")
		)
		(fp_line
			(start -1.651 -1.905)
			(end 1.651 -1.905)
			(stroke
				(width 0.1524)
				(type default)
			)
			(layer "F.SilkS")
		)
		(fp_line
			(start 1.651 1.905)
			(end -1.651 1.905)
			(stroke
				(width 0.1524)
				(type default)
			)
			(layer "F.SilkS")
		)
		(fp_line
			(start -1.651 1.905)
			(end -1.651 -1.905)
			(stroke
				(width 0.1524)
				(type default)
			)
			(layer "F.SilkS")
		)
		(fp_poly
			(pts
				(xy -1.524 0.7112) (xy -1.524 1.7526) (xy -0.508 1.7526) (xy -0.508 0.6985) (xy 0.508 0.6985) (xy 0.508 1.7526)
				(xy 1.524 1.7526) (xy 1.524 0.6985) (xy 1.524 -0.6985) (xy 0.508 -0.6985) (xy 0.508 -1.7526) (xy -0.508 -1.7526)
				(xy -0.508 -0.6985) (xy -1.524 -0.6985) (xy -1.524 0.6985)
			)
			(stroke
				(width 0)
				(type default)
			)
			(fill no)
			(layer "F.CrtYd")
		)
		(fp_text user "S"
			(at 2.184146 -1.873504 0)
			(unlocked yes)
			(layer "F.SilkS")
			(effects
				(font
					(size 0.635 0.4064)
					(thickness 0.1524)
				)
			)
		)
		(fp_text user "D"
			(at -1.168908 -1.606296 0)
			(unlocked yes)
			(layer "F.SilkS")
			(effects
				(font
					(size 0.635 0.4064)
					(thickness 0.1524)
				)
			)
		)
		(fp_text user "G"
			(at -1.901444 2.389378 0)
			(unlocked yes)
			(layer "F.SilkS")
			(effects
				(font
					(size 0.635 0.4064)
					(thickness 0.1524)
				)
			)
		)
		(pad "D" smd rect
			(at 0 -1.1176 90)
			(size 1.016 1.27)
			(layers "F.Cu" "F.Mask" "F.Paste")
			(net "I2C_VIDREAR_5V_SCL")
		)
		(pad "G" smd rect
			(at -1.016 1.1176 90)
			(size 1.016 1.27)
			(layers "F.Cu" "F.Mask" "F.Paste")
			(net "N21581283")
		)
		(pad "S" smd rect
			(at 1.016 1.1176 90)
			(size 1.016 1.27)
			(layers "F.Cu" "F.Mask" "F.Paste")
			(net "SMB_BMC_NODE1_DDC_CLK")
		)
	)
	(footprint ""
		(layer "F.Cu")
		(at 18.231612 -54.254654 90)
		(property "Reference" "R659"
			(at -3.358896 13.863574 90)
			(unlocked yes)
			(layer "F.SilkS")
			(effects
				(font
					(size 0.7874 0.5842)
					(thickness 0.1524)
				)
				(justify left)
			)
		)
		(property "Value" ""
			(at 0 0 90)
			(layer "F.Fab")
			(effects
				(font
					(size 1.27 1.27)
				)
			)
		)
		(duplicate_pad_numbers_are_jumpers no)
		(fp_line
			(start 0.7874 -0.4064)
			(end 0.7874 0.4064)
			(stroke
				(width 0.1524)
				(type default)
			)
			(layer "F.SilkS")
		)
		(fp_line
			(start -0.7874 -0.4064)
			(end 0.7874 -0.4064)
			(stroke
				(width 0.1524)
				(type default)
			)
			(layer "F.SilkS")
		)
		(fp_line
			(start 0.7874 0.4064)
			(end -0.7874 0.4064)
			(stroke
				(width 0.1524)
				(type default)
			)
			(layer "F.SilkS")
		)
		(fp_line
			(start -0.7874 0.4064)
			(end -0.7874 -0.4064)
			(stroke
				(width 0.1524)
				(type default)
			)
			(layer "F.SilkS")
		)
		(fp_poly
			(pts
				(xy -0.508 0.2794) (xy -0.508 0.2286) (xy -0.635 0.2286) (xy -0.635 -0.254) (xy -0.5334 -0.254)
				(xy -0.5334 -0.2794) (xy 0.5334 -0.2794) (xy 0.5334 -0.254) (xy 0.635 -0.254) (xy 0.635 0.254) (xy 0.5334 0.254)
				(xy 0.5334 0.2794)
			)
			(stroke
				(width 0)
				(type default)
			)
			(fill no)
			(layer "F.CrtYd")
		)
		(pad "1" smd rect
			(at 0.40005 0 90)
			(size 0.4572 0.508)
			(layers "F.Cu" "F.Mask" "F.Paste")
			(net "CRT_B_L")
		)
		(pad "2" smd rect
			(at -0.40005 0 90)
			(size 0.4572 0.508)
			(layers "F.Cu" "F.Mask" "F.Paste")
			(net "CRT_B")
		)
	)
	(footprint ""
		(layer "F.Cu")
		(at 16.686784 -43.934634 -90)
		(property "Reference" "L41"
			(at 8.057134 1.275588 90)
			(unlocked yes)
			(layer "F.SilkS")
			(effects
				(font
					(size 0.7874 0.5842)
					(thickness 0.1524)
				)
			)
		)
		(property "Value" ""
			(at 0 0 270)
			(layer "F.Fab")
			(effects
				(font
					(size 1.27 1.27)
				)
			)
		)
		(duplicate_pad_numbers_are_jumpers no)
		(fp_line
			(start 1.2954 0.635)
			(end -1.2954 0.635)
			(stroke
				(width 0.1524)
				(type default)
			)
			(layer "F.SilkS")
		)
		(fp_line
			(start -0.127 -0.5842)
			(end -0.127 0.5842)
			(stroke
				(width 0.1524)
				(type default)
			)
			(layer "F.SilkS")
		)
		(fp_line
			(start 0.127 -0.5842)
			(end 0.127 0.5842)
			(stroke
				(width 0.1524)
				(type default)
			)
			(layer "F.SilkS")
		)
		(fp_line
			(start -1.2954 -0.635)
			(end -1.2954 0.635)
			(stroke
				(width 0.1524)
				(type default)
			)
			(layer "F.SilkS")
		)
		(fp_line
			(start -1.2954 -0.635)
			(end 1.2954 -0.635)
			(stroke
				(width 0.1524)
				(type default)
			)
			(layer "F.SilkS")
		)
		(fp_line
			(start 1.2954 -0.635)
			(end 1.2954 0.635)
			(stroke
				(width 0.1524)
				(type default)
			)
			(layer "F.SilkS")
		)
		(fp_poly
			(pts
				(xy -0.9144 0.508) (xy -0.9144 0.3556) (xy -1.143 0.3556) (xy -1.143 -0.3556) (xy -0.9144 -0.3556)
				(xy -0.9144 -0.508) (xy 0.9144 -0.508) (xy 0.9144 -0.3556) (xy 1.143 -0.3556) (xy 1.143 0.3556)
				(xy 0.9144 0.3556) (xy 0.9144 0.508)
			)
			(stroke
				(width 0)
				(type default)
			)
			(fill no)
			(layer "F.CrtYd")
		)
		(pad "1" smd rect
			(at 0.7366 0)
			(size 0.7112 0.8128)
			(layers "F.Cu" "F.Mask" "F.Paste")
			(net "BMC_NODE1_GFX_RED")
		)
		(pad "2" smd rect
			(at -0.7366 0)
			(size 0.7112 0.8128)
			(layers "F.Cu" "F.Mask" "F.Paste")
			(net "CRT_R_L")
		)
	)
	(footprint ""
		(layer "F.Cu")
		(at 19.938746 -98.963734 180)
		(property "Reference" "R186"
			(at 5.192776 0.467106 0)
			(unlocked yes)
			(layer "F.SilkS")
			(effects
				(font
					(size 0.7874 0.5842)
					(thickness 0.1524)
				)
				(justify left)
			)
		)
		(property "Value" ""
			(at 0 0 180)
			(layer "F.Fab")
			(effects
				(font
					(size 1.27 1.27)
				)
			)
		)
		(duplicate_pad_numbers_are_jumpers no)
		(fp_line
			(start 0.7874 0.4064)
			(end -0.7874 0.4064)
			(stroke
				(width 0.1524)
				(type default)
			)
			(layer "F.SilkS")
		)
		(fp_line
			(start 0.7874 -0.4064)
			(end 0.7874 0.4064)
			(stroke
				(width 0.1524)
				(type default)
			)
			(layer "F.SilkS")
		)
		(fp_line
			(start -0.7874 0.4064)
			(end -0.7874 -0.4064)
			(stroke
				(width 0.1524)
				(type default)
			)
			(layer "F.SilkS")
		)
		(fp_line
			(start -0.7874 -0.4064)
			(end 0.7874 -0.4064)
			(stroke
				(width 0.1524)
				(type default)
			)
			(layer "F.SilkS")
		)
		(fp_poly
			(pts
				(xy -0.508 0.2794) (xy -0.508 0.2286) (xy -0.635 0.2286) (xy -0.635 -0.254) (xy -0.5334 -0.254)
				(xy -0.5334 -0.2794) (xy 0.5334 -0.2794) (xy 0.5334 -0.254) (xy 0.635 -0.254) (xy 0.635 0.254) (xy 0.5334 0.254)
				(xy 0.5334 0.2794)
			)
			(stroke
				(width 0)
				(type default)
			)
			(fill no)
			(layer "F.CrtYd")
		)
		(pad "1" smd rect
			(at 0.40005 0 180)
			(size 0.4572 0.508)
			(layers "F.Cu" "F.Mask" "F.Paste")
			(net "P3V3_NODE1")
		)
		(pad "2" smd rect
			(at -0.40005 0 180)
			(size 0.4572 0.508)
			(layers "F.Cu" "F.Mask" "F.Paste")
			(net "FRU_SYS_A1")
		)
	)
	(footprint ""
		(layer "F.Cu")
		(at 136.450324 -157.537658)
		(property "Reference" "R671"
			(at -64.6176 108.436918 0)
			(unlocked yes)
			(layer "F.SilkS")
			(effects
				(font
					(size 0.7874 0.5842)
					(thickness 0.1524)
				)
				(justify left)
			)
		)
		(property "Value" ""
			(at 0 0 0)
			(layer "F.Fab")
			(effects
				(font
					(size 1.27 1.27)
				)
			)
		)
		(duplicate_pad_numbers_are_jumpers no)
		(fp_line
			(start -0.7874 -0.4064)
			(end 0.7874 -0.4064)
			(stroke
				(width 0.1524)
				(type default)
			)
			(layer "F.SilkS")
		)
		(fp_line
			(start -0.7874 0.4064)
			(end -0.7874 -0.4064)
			(stroke
				(width 0.1524)
				(type default)
			)
			(layer "F.SilkS")
		)
		(fp_line
			(start 0.7874 -0.4064)
			(end 0.7874 0.4064)
			(stroke
				(width 0.1524)
				(type default)
			)
			(layer "F.SilkS")
		)
		(fp_line
			(start 0.7874 0.4064)
			(end -0.7874 0.4064)
			(stroke
				(width 0.1524)
				(type default)
			)
			(layer "F.SilkS")
		)
		(fp_poly
			(pts
				(xy -0.508 0.2794) (xy -0.508 0.2286) (xy -0.635 0.2286) (xy -0.635 -0.254) (xy -0.5334 -0.254)
				(xy -0.5334 -0.2794) (xy 0.5334 -0.2794) (xy 0.5334 -0.254) (xy 0.635 -0.254) (xy 0.635 0.254) (xy 0.5334 0.254)
				(xy 0.5334 0.2794)
			)
			(stroke
				(width 0)
				(type default)
			)
			(fill no)
			(layer "F.CrtYd")
		)
		(pad "1" smd rect
			(at 0.40005 0)
			(size 0.4572 0.508)
			(layers "F.Cu" "F.Mask" "F.Paste")
			(net "P3V3_NODE1")
		)
		(pad "2" smd rect
			(at -0.40005 0)
			(size 0.4572 0.508)
			(layers "F.Cu" "F.Mask" "F.Paste")
			(net "I2C_PSU3_SDA_MOS")
		)
	)
	(footprint ""
		(layer "F.Cu")
		(at 58.314336 -164.534596 -90)
		(property "Reference" "C846"
			(at -1.509776 0.121412 90)
			(unlocked yes)
			(layer "F.SilkS")
			(effects
				(font
					(size 0.7874 0.5842)
					(thickness 0.1524)
				)
				(justify left)
			)
		)
		(property "Value" ""
			(at 0 0 270)
			(layer "F.Fab")
			(effects
				(font
					(size 1.27 1.27)
				)
			)
		)
		(duplicate_pad_numbers_are_jumpers no)
		(fp_line
			(start -0.7874 0.4064)
			(end -0.7874 -0.4064)
			(stroke
				(width 0.1524)
				(type default)
			)
			(layer "F.SilkS")
		)
		(fp_line
			(start 0.7874 0.4064)
			(end -0.7874 0.4064)
			(stroke
				(width 0.1524)
				(type default)
			)
			(layer "F.SilkS")
		)
		(fp_line
			(start 0 0.381)
			(end 0 -0.381)
			(stroke
				(width 0.1524)
				(type default)
			)
			(layer "F.SilkS")
		)
		(fp_line
			(start -0.7874 -0.4064)
			(end 0.7874 -0.4064)
			(stroke
				(width 0.1524)
				(type default)
			)
			(layer "F.SilkS")
		)
		(fp_line
			(start 0.7874 -0.4064)
			(end 0.7874 0.4064)
			(stroke
				(width 0.1524)
				(type default)
			)
			(layer "F.SilkS")
		)
		(fp_poly
			(pts
				(xy -0.5334 0.254) (xy -0.635 0.254) (xy -0.635 0.2286) (xy -0.635 -0.254) (xy -0.5334 -0.254) (xy -0.5334 -0.2794)
				(xy 0.5334 -0.2794) (xy 0.5334 -0.254) (xy 0.635 -0.254) (xy 0.635 0.254) (xy 0.5334 0.254) (xy 0.5334 0.2794)
				(xy -0.508 0.2794) (xy -0.5334 0.2794)
			)
			(stroke
				(width 0)
				(type default)
			)
			(fill no)
			(layer "F.CrtYd")
		)
		(pad "1" smd rect
			(at 0.40005 0 270)
			(size 0.4572 0.508)
			(layers "F.Cu" "F.Mask" "F.Paste")
			(net "FM_CPLD_NODE1_P5V_EN")
		)
		(pad "2" smd rect
			(at -0.40005 0 270)
			(size 0.4572 0.508)
			(layers "F.Cu" "F.Mask" "F.Paste")
			(net "GND")
		)
	)
	(footprint ""
		(layer "F.Cu")
		(at 155.05176 -185.205624 -90)
		(property "Reference" "R897"
			(at -4.768088 -0.259588 90)
			(unlocked yes)
			(layer "F.SilkS")
			(effects
				(font
					(size 0.7874 0.5842)
					(thickness 0.1524)
				)
				(justify left)
			)
		)
		(property "Value" ""
			(at 0 0 270)
			(layer "F.Fab")
			(effects
				(font
					(size 1.27 1.27)
				)
			)
		)
		(duplicate_pad_numbers_are_jumpers no)
		(fp_line
			(start -0.7874 0.4064)
			(end -0.7874 -0.4064)
			(stroke
				(width 0.1524)
				(type default)
			)
			(layer "F.SilkS")
		)
		(fp_line
			(start 0.7874 0.4064)
			(end -0.7874 0.4064)
			(stroke
				(width 0.1524)
				(type default)
			)
			(layer "F.SilkS")
		)
		(fp_line
			(start -0.7874 -0.4064)
			(end 0.7874 -0.4064)
			(stroke
				(width 0.1524)
				(type default)
			)
			(layer "F.SilkS")
		)
		(fp_line
			(start 0.7874 -0.4064)
			(end 0.7874 0.4064)
			(stroke
				(width 0.1524)
				(type default)
			)
			(layer "F.SilkS")
		)
		(fp_poly
			(pts
				(xy -0.508 0.2794) (xy -0.508 0.2286) (xy -0.635 0.2286) (xy -0.635 -0.254) (xy -0.5334 -0.254)
				(xy -0.5334 -0.2794) (xy 0.5334 -0.2794) (xy 0.5334 -0.254) (xy 0.635 -0.254) (xy 0.635 0.254) (xy 0.5334 0.254)
				(xy 0.5334 0.2794)
			)
			(stroke
				(width 0)
				(type default)
			)
			(fill no)
			(layer "F.CrtYd")
		)
		(pad "1" smd rect
			(at 0.40005 0 270)
			(size 0.4572 0.508)
			(layers "F.Cu" "F.Mask" "F.Paste")
			(net "T12_NODE1_EN")
		)
		(pad "2" smd rect
			(at -0.40005 0 270)
			(size 0.4572 0.508)
			(layers "F.Cu" "F.Mask" "F.Paste")
			(net "T12_NODE1_EN_R")
		)
	)
	(footprint ""
		(layer "F.Cu")
		(at 109.095286 -125.189742 90)
		(property "Reference" "U124"
			(at -0.399542 4.7244 90)
			(unlocked yes)
			(layer "F.SilkS")
			(effects
				(font
					(size 0.7874 0.5842)
					(thickness 0.1524)
				)
				(justify left)
			)
		)
		(property "Value" ""
			(at 0 0 90)
			(layer "F.Fab")
			(effects
				(font
					(size 1.27 1.27)
				)
			)
		)
		(duplicate_pad_numbers_are_jumpers no)
		(fp_line
			(start 2.649982 -3.10007)
			(end 2.649982 3.10007)
			(stroke
				(width 0.1524)
				(type default)
			)
			(layer "F.SilkS")
		)
		(fp_line
			(start 2.413 -3.10007)
			(end 2.649982 -3.10007)
			(stroke
				(width 0.1524)
				(type default)
			)
			(layer "F.SilkS")
		)
		(fp_line
			(start 1.143 -3.10007)
			(end 1.397 -3.10007)
			(stroke
				(width 0.1524)
				(type default)
			)
			(layer "F.SilkS")
		)
		(fp_line
			(start -0.127 -3.10007)
			(end 0.127 -3.10007)
			(stroke
				(width 0.1524)
				(type default)
			)
			(layer "F.SilkS")
		)
		(fp_line
			(start -1.397 -3.10007)
			(end -1.143 -3.10007)
			(stroke
				(width 0.1524)
				(type default)
			)
			(layer "F.SilkS")
		)
		(fp_line
			(start -2.649982 -3.10007)
			(end -2.413 -3.10007)
			(stroke
				(width 0.1524)
				(type default)
			)
			(layer "F.SilkS")
		)
		(fp_line
			(start 2.649982 3.10007)
			(end 2.413 3.10007)
			(stroke
				(width 0.1524)
				(type default)
			)
			(layer "F.SilkS")
		)
		(fp_line
			(start 1.143 3.10007)
			(end 1.397 3.10007)
			(stroke
				(width 0.1524)
				(type default)
			)
			(layer "F.SilkS")
		)
		(fp_line
			(start -0.127 3.10007)
			(end 0.127 3.10007)
			(stroke
				(width 0.1524)
				(type default)
			)
			(layer "F.SilkS")
		)
		(fp_line
			(start -1.397 3.10007)
			(end -1.143 3.10007)
			(stroke
				(width 0.1524)
				(type default)
			)
			(layer "F.SilkS")
		)
		(fp_line
			(start -2.413 3.10007)
			(end -2.649982 3.10007)
			(stroke
				(width 0.1524)
				(type default)
			)
			(layer "F.SilkS")
		)
		(fp_line
			(start -2.649982 3.10007)
			(end -2.649982 -3.10007)
			(stroke
				(width 0.1524)
				(type default)
			)
			(layer "F.SilkS")
		)
		(fp_poly
			(pts
				(xy -2.693416 3.52044) (xy -3.201416 4.53644) (xy -2.185416 4.53644)
			)
			(stroke
				(width 0)
				(type default)
			)
			(fill yes)
			(layer "F.SilkS")
		)
		(fp_poly
			(pts
				(xy -2.649982 3.10007) (xy -2.3368 3.10007) (xy -2.3368 3.5814) (xy 2.3368 3.5814) (xy 2.3368 3.10007)
				(xy 2.649982 3.10007) (xy 2.649982 -3.10007) (xy 2.3368 -3.10007) (xy 2.3368 -3.5814) (xy -2.3368 -3.5814)
				(xy -2.3368 -3.10007) (xy -2.649982 -3.10007)
			)
			(stroke
				(width 0)
				(type default)
			)
			(fill no)
			(layer "F.CrtYd")
		)
		(fp_line
			(start 2.649982 -3.10007)
			(end 2.649982 3.10007)
			(stroke
				(width 0.1)
				(type default)
			)
			(layer "F.Fab")
		)
		(fp_line
			(start -2.649982 -3.10007)
			(end 2.649982 -3.10007)
			(stroke
				(width 0.1)
				(type default)
			)
			(layer "F.Fab")
		)
		(fp_line
			(start 2.649982 3.10007)
			(end -2.649982 3.10007)
			(stroke
				(width 0.1)
				(type default)
			)
			(layer "F.Fab")
		)
		(fp_line
			(start -2.649982 3.10007)
			(end -2.649982 -3.10007)
			(stroke
				(width 0.1)
				(type default)
			)
			(layer "F.Fab")
		)
		(pad "1" smd rect
			(at -1.905 3.0099 90)
			(size 0.762 1.0414)
			(layers "F.Cu" "F.Mask" "F.Paste")
			(net "VR_PVCCP_NODE1_UGATE1")
		)
		(pad "2" smd rect
			(at -0.635 3.0099 90)
			(size 0.762 1.0414)
			(layers "F.Cu" "F.Mask" "F.Paste")
			(net "SW_VR_PVCCP_NODE1_VIN_FLT")
		)
		(pad "3" smd rect
			(at 0.635 3.0099 90)
			(size 0.762 1.0414)
			(layers "F.Cu" "F.Mask" "F.Paste")
			(net "SW_VR_PVCCP_NODE1_VIN_FLT")
		)
		(pad "4" smd rect
			(at 1.905 3.0099 90)
			(size 0.762 1.0414)
			(layers "F.Cu" "F.Mask" "F.Paste")
			(net "SW_VR_PVCCP_NODE1_VIN_FLT")
		)
		(pad "5" smd rect
			(at 1.905 -3.0099 90)
			(size 0.762 1.0414)
			(layers "F.Cu" "F.Mask" "F.Paste")
			(net "GND")
		)
		(pad "6" smd rect
			(at 0.635 -3.0099 90)
			(size 0.762 1.0414)
			(layers "F.Cu" "F.Mask" "F.Paste")
			(net "GND")
		)
		(pad "7" smd rect
			(at -0.635 -3.0099 90)
			(size 0.762 1.0414)
			(layers "F.Cu" "F.Mask" "F.Paste")
			(net "GND")
		)
		(pad "8" smd rect
			(at -1.905 -3.0099 90)
			(size 0.762 1.0414)
			(layers "F.Cu" "F.Mask" "F.Paste")
			(net "VR_PVCCP_NODE1_LGATE1")
		)
		(pad "D1_EP" smd rect
			(at 0 1.700022 180)
			(size 0.8128 4.2164)
			(layers "F.Cu" "F.Mask" "F.Paste")
			(net "SW_VR_PVCCP_NODE1_VIN_FLT")
		)
		(pad "S1/D2_EP" smd rect
			(at 0 -0.649986)
			(size 2.921 4.2164)
			(layers "F.Cu" "F.Mask" "F.Paste")
			(net "VR_PVCCP_NODE1_PHASE1")
		)
		(zone
			(layer "F.Cu")
			(hatch none 0.5)
			(connect_pads
				(clearance 0)
			)
			(min_thickness 0.25)
			(keepout
				(tracks allowed)
				(vias not_allowed)
				(pads allowed)
				(copperpour not_allowed)
				(footprints allowed)
			)
			(placement
				(enabled no)
				(sheetname "")
			)
			(fill
				(thermal_gap 0.5)
				(thermal_bridge_width 0.5)
				(island_removal_mode 0)
			)
			(polygon
				(pts
					(xy 110.822486 -122.700542) (xy 110.822486 -123.005342) (xy 111.279686 -123.005342) (xy 111.279686 -127.374142)
					(xy 110.314486 -127.374142) (xy 110.314486 -123.005342) (xy 110.797086 -123.005342) (xy 110.797086 -122.548142)
					(xy 108.409486 -122.548142) (xy 108.409486 -123.005342) (xy 109.984286 -123.005342) (xy 109.984286 -127.374142)
					(xy 106.910886 -127.374142) (xy 106.910886 -123.005342) (xy 108.384086 -123.005342) (xy 108.384086 -122.548142)
					(xy 106.682286 -122.548142) (xy 106.682286 -127.831342) (xy 111.508286 -127.831342) (xy 111.508286 -122.548142)
					(xy 110.822486 -122.548142)
				)
			)
		)
	)
	(footprint ""
		(layer "F.Cu")
		(at 87.887048 -128.998726 -90)
		(property "Reference" "R1256"
			(at 2.760218 -2.689098 90)
			(unlocked yes)
			(layer "F.SilkS")
			(effects
				(font
					(size 0.7874 0.5842)
					(thickness 0.1524)
				)
				(justify left)
			)
		)
		(property "Value" ""
			(at 0 0 270)
			(layer "F.Fab")
			(effects
				(font
					(size 1.27 1.27)
				)
			)
		)
		(duplicate_pad_numbers_are_jumpers no)
		(fp_line
			(start -0.7874 0.4064)
			(end -0.7874 -0.4064)
			(stroke
				(width 0.1524)
				(type default)
			)
			(layer "F.SilkS")
		)
		(fp_line
			(start 0.7874 0.4064)
			(end -0.7874 0.4064)
			(stroke
				(width 0.1524)
				(type default)
			)
			(layer "F.SilkS")
		)
		(fp_line
			(start -0.7874 -0.4064)
			(end 0.7874 -0.4064)
			(stroke
				(width 0.1524)
				(type default)
			)
			(layer "F.SilkS")
		)
		(fp_line
			(start 0.7874 -0.4064)
			(end 0.7874 0.4064)
			(stroke
				(width 0.1524)
				(type default)
			)
			(layer "F.SilkS")
		)
		(fp_poly
			(pts
				(xy -0.508 0.2794) (xy -0.508 0.2286) (xy -0.635 0.2286) (xy -0.635 -0.254) (xy -0.5334 -0.254)
				(xy -0.5334 -0.2794) (xy 0.5334 -0.2794) (xy 0.5334 -0.254) (xy 0.635 -0.254) (xy 0.635 0.254) (xy 0.5334 0.254)
				(xy 0.5334 0.2794)
			)
			(stroke
				(width 0)
				(type default)
			)
			(fill no)
			(layer "F.CrtYd")
		)
		(pad "1" smd rect
			(at 0.40005 0 270)
			(size 0.4572 0.508)
			(layers "F.Cu" "F.Mask" "F.Paste")
			(net "PORT80_LOUT4")
		)
		(pad "2" smd rect
			(at -0.40005 0 270)
			(size 0.4572 0.508)
			(layers "F.Cu" "F.Mask" "F.Paste")
			(net "N53313513")
		)
	)
	(footprint ""
		(layer "F.Cu")
		(at 94.451932 -175.322992)
		(property "Reference" "R739"
			(at 86.67369 74.174096 0)
			(unlocked yes)
			(layer "F.SilkS")
			(effects
				(font
					(size 0.7874 0.5842)
					(thickness 0.1524)
				)
				(justify left)
			)
		)
		(property "Value" ""
			(at 0 0 0)
			(layer "F.Fab")
			(effects
				(font
					(size 1.27 1.27)
				)
			)
		)
		(duplicate_pad_numbers_are_jumpers no)
		(fp_line
			(start -0.7874 -0.4064)
			(end 0.7874 -0.4064)
			(stroke
				(width 0.1524)
				(type default)
			)
			(layer "F.SilkS")
		)
		(fp_line
			(start -0.7874 0.4064)
			(end -0.7874 -0.4064)
			(stroke
				(width 0.1524)
				(type default)
			)
			(layer "F.SilkS")
		)
		(fp_line
			(start 0.7874 -0.4064)
			(end 0.7874 0.4064)
			(stroke
				(width 0.1524)
				(type default)
			)
			(layer "F.SilkS")
		)
		(fp_line
			(start 0.7874 0.4064)
			(end -0.7874 0.4064)
			(stroke
				(width 0.1524)
				(type default)
			)
			(layer "F.SilkS")
		)
		(fp_poly
			(pts
				(xy -0.508 0.2794) (xy -0.508 0.2286) (xy -0.635 0.2286) (xy -0.635 -0.254) (xy -0.5334 -0.254)
				(xy -0.5334 -0.2794) (xy 0.5334 -0.2794) (xy 0.5334 -0.254) (xy 0.635 -0.254) (xy 0.635 0.254) (xy 0.5334 0.254)
				(xy 0.5334 0.2794)
			)
			(stroke
				(width 0)
				(type default)
			)
			(fill no)
			(layer "F.CrtYd")
		)
		(pad "1" smd rect
			(at 0.40005 0)
			(size 0.4572 0.508)
			(layers "F.Cu" "F.Mask" "F.Paste")
			(net "N21698906")
		)
		(pad "2" smd rect
			(at -0.40005 0)
			(size 0.4572 0.508)
			(layers "F.Cu" "F.Mask" "F.Paste")
			(net "P3V3_NODE1")
		)
	)
	(footprint ""
		(layer "F.Cu")
		(at 105.947718 -151.7142)
		(property "Reference" "PR15"
			(at -2.05486 4.593082 0)
			(unlocked yes)
			(layer "F.SilkS")
			(effects
				(font
					(size 0.635 0.4064)
					(thickness 0.1524)
				)
				(justify left)
			)
		)
		(property "Value" ""
			(at 0 0 0)
			(layer "F.Fab")
			(effects
				(font
					(size 1.27 1.27)
				)
			)
		)
		(duplicate_pad_numbers_are_jumpers no)
		(fp_line
			(start -0.7874 -0.4064)
			(end 0.7874 -0.4064)
			(stroke
				(width 0.1524)
				(type default)
			)
			(layer "F.SilkS")
		)
		(fp_line
			(start -0.7874 0.4064)
			(end -0.7874 -0.4064)
			(stroke
				(width 0.1524)
				(type default)
			)
			(layer "F.SilkS")
		)
		(fp_line
			(start 0.7874 -0.4064)
			(end 0.7874 0.4064)
			(stroke
				(width 0.1524)
				(type default)
			)
			(layer "F.SilkS")
		)
		(fp_line
			(start 0.7874 0.4064)
			(end -0.7874 0.4064)
			(stroke
				(width 0.1524)
				(type default)
			)
			(layer "F.SilkS")
		)
		(fp_poly
			(pts
				(xy -0.508 0.2794) (xy -0.508 0.2286) (xy -0.635 0.2286) (xy -0.635 -0.254) (xy -0.5334 -0.254)
				(xy -0.5334 -0.2794) (xy 0.5334 -0.2794) (xy 0.5334 -0.254) (xy 0.635 -0.254) (xy 0.635 0.254) (xy 0.5334 0.254)
				(xy 0.5334 0.2794)
			)
			(stroke
				(width 0)
				(type default)
			)
			(fill no)
			(layer "F.CrtYd")
		)
		(pad "1" smd rect
			(at 0.40005 0)
			(size 0.4572 0.508)
			(layers "F.Cu" "F.Mask" "F.Paste")
			(net "P1V8_STB_NODE1_FB")
		)
		(pad "2" smd rect
			(at -0.40005 0)
			(size 0.4572 0.508)
			(layers "F.Cu" "F.Mask" "F.Paste")
			(net "P1V8_STB_NODE1")
		)
	)
	(footprint ""
		(layer "F.Cu")
		(at 155.444952 -103.99395 -90)
		(property "Reference" "R520"
			(at 0.801878 2.11963 90)
			(unlocked yes)
			(layer "F.SilkS")
			(effects
				(font
					(size 0.7874 0.5842)
					(thickness 0.1524)
				)
				(justify left)
			)
		)
		(property "Value" ""
			(at 0 0 270)
			(layer "F.Fab")
			(effects
				(font
					(size 1.27 1.27)
				)
			)
		)
		(duplicate_pad_numbers_are_jumpers no)
		(fp_line
			(start -0.7874 0.4064)
			(end -0.7874 -0.4064)
			(stroke
				(width 0.1524)
				(type default)
			)
			(layer "F.SilkS")
		)
		(fp_line
			(start 0.7874 0.4064)
			(end -0.7874 0.4064)
			(stroke
				(width 0.1524)
				(type default)
			)
			(layer "F.SilkS")
		)
		(fp_line
			(start -0.7874 -0.4064)
			(end 0.7874 -0.4064)
			(stroke
				(width 0.1524)
				(type default)
			)
			(layer "F.SilkS")
		)
		(fp_line
			(start 0.7874 -0.4064)
			(end 0.7874 0.4064)
			(stroke
				(width 0.1524)
				(type default)
			)
			(layer "F.SilkS")
		)
		(fp_poly
			(pts
				(xy -0.508 0.2794) (xy -0.508 0.2286) (xy -0.635 0.2286) (xy -0.635 -0.254) (xy -0.5334 -0.254)
				(xy -0.5334 -0.2794) (xy 0.5334 -0.2794) (xy 0.5334 -0.254) (xy 0.635 -0.254) (xy 0.635 0.254) (xy 0.5334 0.254)
				(xy 0.5334 0.2794)
			)
			(stroke
				(width 0)
				(type default)
			)
			(fill no)
			(layer "F.CrtYd")
		)
		(pad "1" smd rect
			(at 0.40005 0 270)
			(size 0.4572 0.508)
			(layers "F.Cu" "F.Mask" "F.Paste")
			(net "IRQ_LVC3_CPU_NODE1_WAKE_L")
		)
		(pad "2" smd rect
			(at -0.40005 0 270)
			(size 0.4572 0.508)
			(layers "F.Cu" "F.Mask" "F.Paste")
			(net "USB_WAKE_N")
		)
	)
	(footprint ""
		(layer "F.Cu")
		(at 184.3786 -181.8132)
		(property "Reference" "R1320"
			(at 9.2964 17.09547 0)
			(unlocked yes)
			(layer "F.SilkS")
			(effects
				(font
					(size 0.7874 0.5842)
					(thickness 0.1524)
				)
				(justify left)
			)
		)
		(property "Value" ""
			(at 0 0 0)
			(layer "F.Fab")
			(effects
				(font
					(size 1.27 1.27)
				)
			)
		)
		(duplicate_pad_numbers_are_jumpers no)
		(fp_line
			(start -0.7874 -0.4064)
			(end 0.7874 -0.4064)
			(stroke
				(width 0.1524)
				(type default)
			)
			(layer "F.SilkS")
		)
		(fp_line
			(start -0.7874 0.4064)
			(end -0.7874 -0.4064)
			(stroke
				(width 0.1524)
				(type default)
			)
			(layer "F.SilkS")
		)
		(fp_line
			(start 0.7874 -0.4064)
			(end 0.7874 0.4064)
			(stroke
				(width 0.1524)
				(type default)
			)
			(layer "F.SilkS")
		)
		(fp_line
			(start 0.7874 0.4064)
			(end -0.7874 0.4064)
			(stroke
				(width 0.1524)
				(type default)
			)
			(layer "F.SilkS")
		)
		(fp_poly
			(pts
				(xy -0.508 0.2794) (xy -0.508 0.2286) (xy -0.635 0.2286) (xy -0.635 -0.254) (xy -0.5334 -0.254)
				(xy -0.5334 -0.2794) (xy 0.5334 -0.2794) (xy 0.5334 -0.254) (xy 0.635 -0.254) (xy 0.635 0.254) (xy 0.5334 0.254)
				(xy 0.5334 0.2794)
			)
			(stroke
				(width 0)
				(type default)
			)
			(fill no)
			(layer "F.CrtYd")
		)
		(pad "1" smd rect
			(at 0.40005 0)
			(size 0.4572 0.508)
			(layers "F.Cu" "F.Mask" "F.Paste")
			(net "POWER_SW3_PWR_CTR_12V")
		)
		(pad "2" smd rect
			(at -0.40005 0)
			(size 0.4572 0.508)
			(layers "F.Cu" "F.Mask" "F.Paste")
			(net "POWER_SW3_PWR_CTR_12V_R")
		)
	)
	(footprint ""
		(layer "F.Cu")
		(at 51.03114 -163.89985 90)
		(property "Reference" "R538"
			(at -131.03606 -3.526028 90)
			(unlocked yes)
			(layer "F.SilkS")
			(effects
				(font
					(size 0.7874 0.5842)
					(thickness 0.1524)
				)
				(justify left)
			)
		)
		(property "Value" ""
			(at 0 0 90)
			(layer "F.Fab")
			(effects
				(font
					(size 1.27 1.27)
				)
			)
		)
		(duplicate_pad_numbers_are_jumpers no)
		(fp_line
			(start 0.7874 -0.4064)
			(end 0.7874 0.4064)
			(stroke
				(width 0.1524)
				(type default)
			)
			(layer "F.SilkS")
		)
		(fp_line
			(start -0.7874 -0.4064)
			(end 0.7874 -0.4064)
			(stroke
				(width 0.1524)
				(type default)
			)
			(layer "F.SilkS")
		)
		(fp_line
			(start 0.7874 0.4064)
			(end -0.7874 0.4064)
			(stroke
				(width 0.1524)
				(type default)
			)
			(layer "F.SilkS")
		)
		(fp_line
			(start -0.7874 0.4064)
			(end -0.7874 -0.4064)
			(stroke
				(width 0.1524)
				(type default)
			)
			(layer "F.SilkS")
		)
		(fp_poly
			(pts
				(xy -0.508 0.2794) (xy -0.508 0.2286) (xy -0.635 0.2286) (xy -0.635 -0.254) (xy -0.5334 -0.254)
				(xy -0.5334 -0.2794) (xy 0.5334 -0.2794) (xy 0.5334 -0.254) (xy 0.635 -0.254) (xy 0.635 0.254) (xy 0.5334 0.254)
				(xy 0.5334 0.2794)
			)
			(stroke
				(width 0)
				(type default)
			)
			(fill no)
			(layer "F.CrtYd")
		)
		(pad "1" smd rect
			(at 0.40005 0 90)
			(size 0.4572 0.508)
			(layers "F.Cu" "F.Mask" "F.Paste")
			(net "P3V3_NODE1")
		)
		(pad "2" smd rect
			(at -0.40005 0 90)
			(size 0.4572 0.508)
			(layers "F.Cu" "F.Mask" "F.Paste")
			(net "SMB_LAN1_ALT_N")
		)
	)
	(footprint ""
		(layer "F.Cu")
		(at 144.678146 -154.610816 -90)
		(property "Reference" "U13"
			(at 3.071622 0.10668 0)
			(unlocked yes)
			(layer "F.SilkS")
			(effects
				(font
					(size 0.7874 0.5842)
					(thickness 0.1524)
				)
				(justify left)
			)
		)
		(property "Value" ""
			(at 0 0 270)
			(layer "F.Fab")
			(effects
				(font
					(size 1.27 1.27)
				)
			)
		)
		(duplicate_pad_numbers_are_jumpers no)
		(fp_line
			(start -2.5146 1.4224)
			(end -2.5146 0.4572)
			(stroke
				(width 0.1524)
				(type default)
			)
			(layer "F.SilkS")
		)
		(fp_line
			(start 2.5146 1.4224)
			(end -2.5146 1.4224)
			(stroke
				(width 0.1524)
				(type default)
			)
			(layer "F.SilkS")
		)
		(fp_line
			(start -2.5146 0.4572)
			(end -2.0574 0)
			(stroke
				(width 0.1524)
				(type default)
			)
			(layer "F.SilkS")
		)
		(fp_line
			(start -2.0574 0)
			(end -2.5146 -0.4572)
			(stroke
				(width 0.1524)
				(type default)
			)
			(layer "F.SilkS")
		)
		(fp_line
			(start -2.5146 -0.4572)
			(end -2.5146 -1.4224)
			(stroke
				(width 0.1524)
				(type default)
			)
			(layer "F.SilkS")
		)
		(fp_line
			(start -2.5146 -1.4224)
			(end 2.5146 -1.4224)
			(stroke
				(width 0.1524)
				(type default)
			)
			(layer "F.SilkS")
		)
		(fp_line
			(start 2.5146 -1.4224)
			(end 2.5146 1.4224)
			(stroke
				(width 0.1524)
				(type default)
			)
			(layer "F.SilkS")
		)
		(fp_circle
			(center -1.905 0.889)
			(end -1.905 0.635)
			(stroke
				(width 0.1524)
				(type default)
			)
			(fill no)
			(layer "F.SilkS")
		)
		(fp_poly
			(pts
				(xy -2.1844 3.5052) (xy -2.1844 2.0066) (xy -2.5146 2.0066) (xy -2.5146 -2.0066) (xy -2.1844 -2.0066)
				(xy -2.1844 -3.5052) (xy 2.1844 -3.5052) (xy 2.1844 -2.0066) (xy 2.5146 -2.0066) (xy 2.5146 2.0066)
				(xy 2.1844 2.0066) (xy 2.1844 3.5052)
			)
			(stroke
				(width 0)
				(type default)
			)
			(fill no)
			(layer "F.CrtYd")
		)
		(pad "1" smd rect
			(at -1.905 2.6416 270)
			(size 0.5588 1.7272)
			(layers "F.Cu" "F.Mask" "F.Paste")
			(net "N49382752")
		)
		(pad "2" smd rect
			(at -0.635 2.6416 270)
			(size 0.5588 1.7272)
			(layers "F.Cu" "F.Mask" "F.Paste")
			(net "N49382752")
		)
		(pad "3" smd rect
			(at 0.635 2.6416 270)
			(size 0.5588 1.7272)
			(layers "F.Cu" "F.Mask" "F.Paste")
			(net "N49382752")
		)
		(pad "4" smd rect
			(at 1.905 2.6416 270)
			(size 0.5588 1.7272)
			(layers "F.Cu" "F.Mask" "F.Paste")
			(net "GND")
		)
		(pad "5" smd rect
			(at 1.905 -2.6416 270)
			(size 0.5588 1.7272)
			(layers "F.Cu" "F.Mask" "F.Paste")
			(net "PCIE_SW_EEPROM_DAT")
		)
		(pad "6" smd rect
			(at 0.635 -2.6416 270)
			(size 0.5588 1.7272)
			(layers "F.Cu" "F.Mask" "F.Paste")
			(net "PCIE_SW_EEPROM_CLK")
		)
		(pad "7" smd rect
			(at -0.635 -2.6416 270)
			(size 0.5588 1.7272)
			(layers "F.Cu" "F.Mask" "F.Paste")
			(net "PCIE_SW_WP_N")
		)
		(pad "8" smd rect
			(at -1.905 -2.6416 270)
			(size 0.5588 1.7272)
			(layers "F.Cu" "F.Mask" "F.Paste")
			(net "P3V3_NODE1")
		)
	)
	(footprint ""
		(layer "F.Cu")
		(at 100.626672 -159.571182 180)
		(property "Reference" "R1232"
			(at -86.995 -70.789292 0)
			(unlocked yes)
			(layer "F.SilkS")
			(effects
				(font
					(size 0.7874 0.5842)
					(thickness 0.1524)
				)
				(justify left)
			)
		)
		(property "Value" ""
			(at 0 0 180)
			(layer "F.Fab")
			(effects
				(font
					(size 1.27 1.27)
				)
			)
		)
		(duplicate_pad_numbers_are_jumpers no)
		(fp_line
			(start 0.7874 0.4064)
			(end -0.7874 0.4064)
			(stroke
				(width 0.1524)
				(type default)
			)
			(layer "F.SilkS")
		)
		(fp_line
			(start 0.7874 -0.4064)
			(end 0.7874 0.4064)
			(stroke
				(width 0.1524)
				(type default)
			)
			(layer "F.SilkS")
		)
		(fp_line
			(start -0.7874 0.4064)
			(end -0.7874 -0.4064)
			(stroke
				(width 0.1524)
				(type default)
			)
			(layer "F.SilkS")
		)
		(fp_line
			(start -0.7874 -0.4064)
			(end 0.7874 -0.4064)
			(stroke
				(width 0.1524)
				(type default)
			)
			(layer "F.SilkS")
		)
		(fp_poly
			(pts
				(xy -0.508 0.2794) (xy -0.508 0.2286) (xy -0.635 0.2286) (xy -0.635 -0.254) (xy -0.5334 -0.254)
				(xy -0.5334 -0.2794) (xy 0.5334 -0.2794) (xy 0.5334 -0.254) (xy 0.635 -0.254) (xy 0.635 0.254) (xy 0.5334 0.254)
				(xy 0.5334 0.2794)
			)
			(stroke
				(width 0)
				(type default)
			)
			(fill no)
			(layer "F.CrtYd")
		)
		(pad "1" smd rect
			(at 0.40005 0 180)
			(size 0.4572 0.508)
			(layers "F.Cu" "F.Mask" "F.Paste")
			(net "GND")
		)
		(pad "2" smd rect
			(at -0.40005 0 180)
			(size 0.4572 0.508)
			(layers "F.Cu" "F.Mask" "F.Paste")
			(net "FM_CPLD_NODE1_P1V8_STB_EN")
		)
	)
	(footprint ""
		(layer "F.Cu")
		(at 36.88334 -14.24559 90)
		(property "Reference" "PC85"
			(at -0.985012 -3.4925 90)
			(unlocked yes)
			(layer "F.SilkS")
			(effects
				(font
					(size 0.7874 0.5842)
					(thickness 0.1524)
				)
				(justify left)
			)
		)
		(property "Value" ""
			(at 0 0 90)
			(layer "F.Fab")
			(effects
				(font
					(size 1.27 1.27)
				)
			)
		)
		(duplicate_pad_numbers_are_jumpers no)
		(fp_line
			(start 0.7874 -0.4064)
			(end 0.7874 0.4064)
			(stroke
				(width 0.1524)
				(type default)
			)
			(layer "F.SilkS")
		)
		(fp_line
			(start -0.7874 -0.4064)
			(end 0.7874 -0.4064)
			(stroke
				(width 0.1524)
				(type default)
			)
			(layer "F.SilkS")
		)
		(fp_line
			(start 0 0.381)
			(end 0 -0.381)
			(stroke
				(width 0.1524)
				(type default)
			)
			(layer "F.SilkS")
		)
		(fp_line
			(start 0.7874 0.4064)
			(end -0.7874 0.4064)
			(stroke
				(width 0.1524)
				(type default)
			)
			(layer "F.SilkS")
		)
		(fp_line
			(start -0.7874 0.4064)
			(end -0.7874 -0.4064)
			(stroke
				(width 0.1524)
				(type default)
			)
			(layer "F.SilkS")
		)
		(fp_poly
			(pts
				(xy -0.5334 0.254) (xy -0.635 0.254) (xy -0.635 0.2286) (xy -0.635 -0.254) (xy -0.5334 -0.254) (xy -0.5334 -0.2794)
				(xy 0.5334 -0.2794) (xy 0.5334 -0.254) (xy 0.635 -0.254) (xy 0.635 0.254) (xy 0.5334 0.254) (xy 0.5334 0.2794)
				(xy -0.508 0.2794) (xy -0.5334 0.2794)
			)
			(stroke
				(width 0)
				(type default)
			)
			(fill no)
			(layer "F.CrtYd")
		)
		(pad "1" smd rect
			(at 0.40005 0 90)
			(size 0.4572 0.508)
			(layers "F.Cu" "F.Mask" "F.Paste")
			(net "GND")
		)
		(pad "2" smd rect
			(at -0.40005 0 90)
			(size 0.4572 0.508)
			(layers "F.Cu" "F.Mask" "F.Paste")
			(net "PV_VDDR_NODE1_SLEW")
		)
	)
	(footprint ""
		(layer "F.Cu")
		(at 66.491358 -9.506966 180)
		(property "Reference" "PR20"
			(at 1.450086 4.40055 0)
			(unlocked yes)
			(layer "F.SilkS")
			(effects
				(font
					(size 0.7874 0.5842)
					(thickness 0.1524)
				)
				(justify left)
			)
		)
		(property "Value" ""
			(at 0 0 180)
			(layer "F.Fab")
			(effects
				(font
					(size 1.27 1.27)
				)
			)
		)
		(duplicate_pad_numbers_are_jumpers no)
		(fp_line
			(start 0.7874 0.4064)
			(end -0.7874 0.4064)
			(stroke
				(width 0.1524)
				(type default)
			)
			(layer "F.SilkS")
		)
		(fp_line
			(start 0.7874 -0.4064)
			(end 0.7874 0.4064)
			(stroke
				(width 0.1524)
				(type default)
			)
			(layer "F.SilkS")
		)
		(fp_line
			(start -0.7874 0.4064)
			(end -0.7874 -0.4064)
			(stroke
				(width 0.1524)
				(type default)
			)
			(layer "F.SilkS")
		)
		(fp_line
			(start -0.7874 -0.4064)
			(end 0.7874 -0.4064)
			(stroke
				(width 0.1524)
				(type default)
			)
			(layer "F.SilkS")
		)
		(fp_poly
			(pts
				(xy -0.508 0.2794) (xy -0.508 0.2286) (xy -0.635 0.2286) (xy -0.635 -0.254) (xy -0.5334 -0.254)
				(xy -0.5334 -0.2794) (xy 0.5334 -0.2794) (xy 0.5334 -0.254) (xy 0.635 -0.254) (xy 0.635 0.254) (xy 0.5334 0.254)
				(xy 0.5334 0.2794)
			)
			(stroke
				(width 0)
				(type default)
			)
			(fill no)
			(layer "F.CrtYd")
		)
		(pad "1" smd rect
			(at 0.40005 0 180)
			(size 0.4572 0.508)
			(layers "F.Cu" "F.Mask" "F.Paste")
			(net "P3V3_NODE1_FB")
		)
		(pad "2" smd rect
			(at -0.40005 0 180)
			(size 0.4572 0.508)
			(layers "F.Cu" "F.Mask" "F.Paste")
			(net "P3V3_NODE1")
		)
	)
	(footprint ""
		(layer "F.Cu")
		(at 139.676886 -51.476656 90)
		(property "Reference" "R1020"
			(at 16.324326 30.427168 90)
			(unlocked yes)
			(layer "F.SilkS")
			(effects
				(font
					(size 0.7874 0.5842)
					(thickness 0.1524)
				)
				(justify left)
			)
		)
		(property "Value" ""
			(at 0 0 90)
			(layer "F.Fab")
			(effects
				(font
					(size 1.27 1.27)
				)
			)
		)
		(duplicate_pad_numbers_are_jumpers no)
		(fp_line
			(start 0.7874 -0.4064)
			(end 0.7874 0.4064)
			(stroke
				(width 0.1524)
				(type default)
			)
			(layer "F.SilkS")
		)
		(fp_line
			(start -0.7874 -0.4064)
			(end 0.7874 -0.4064)
			(stroke
				(width 0.1524)
				(type default)
			)
			(layer "F.SilkS")
		)
		(fp_line
			(start 0.7874 0.4064)
			(end -0.7874 0.4064)
			(stroke
				(width 0.1524)
				(type default)
			)
			(layer "F.SilkS")
		)
		(fp_line
			(start -0.7874 0.4064)
			(end -0.7874 -0.4064)
			(stroke
				(width 0.1524)
				(type default)
			)
			(layer "F.SilkS")
		)
		(fp_poly
			(pts
				(xy -0.508 0.2794) (xy -0.508 0.2286) (xy -0.635 0.2286) (xy -0.635 -0.254) (xy -0.5334 -0.254)
				(xy -0.5334 -0.2794) (xy 0.5334 -0.2794) (xy 0.5334 -0.254) (xy 0.635 -0.254) (xy 0.635 0.254) (xy 0.5334 0.254)
				(xy 0.5334 0.2794)
			)
			(stroke
				(width 0)
				(type default)
			)
			(fill no)
			(layer "F.CrtYd")
		)
		(pad "1" smd rect
			(at 0.40005 0 90)
			(size 0.4572 0.508)
			(layers "F.Cu" "F.Mask" "F.Paste")
			(net "P5V_NODE1")
		)
		(pad "2" smd rect
			(at -0.40005 0 90)
			(size 0.4572 0.508)
			(layers "F.Cu" "F.Mask" "F.Paste")
			(net "UART_TX_P2")
		)
	)
	(footprint ""
		(layer "F.Cu")
		(at 79.077566 -158.46298)
		(property "Reference" "PJ1"
			(at 3.839464 1.161796 90)
			(unlocked yes)
			(layer "F.SilkS")
			(effects
				(font
					(size 0.7874 0.5842)
					(thickness 0.1524)
				)
				(justify left)
			)
		)
		(property "Value" ""
			(at 0 0 0)
			(layer "F.Fab")
			(effects
				(font
					(size 1.27 1.27)
				)
			)
		)
		(duplicate_pad_numbers_are_jumpers no)
		(fp_poly
			(pts
				(xy 0.2794 0.907796) (xy 0.254 0.907796) (xy 0.254 1.0414) (xy -0.254 1.0414) (xy -0.254 1.034796)
				(xy -0.254 0.933196) (xy -0.2794 0.933196) (xy -0.2794 -0.133604) (xy -0.254 -0.133604) (xy -0.254 -0.235204)
				(xy 0.254 -0.235204) (xy 0.254 -0.133604) (xy 0.2794 -0.133604)
			)
			(stroke
				(width 0)
				(type default)
			)
			(fill no)
			(layer "F.CrtYd")
		)
		(pad "1" smd custom
			(at 0 -0.000254)
			(size 0.127 0.127)
			(layers "F.Cu" "F.Mask" "F.Paste")
			(net "P5V_STB_NODE1_EN")
			(options
				(clearance outline)
				(anchor circle)
			)
			(primitives
				(gr_poly
					(pts
						(xy -0.127 0.508) (xy -0.127 -0.0508) (xy -0.254 -0.0508) (xy -0.254 -0.508) (xy 0.254 -0.508)
						(xy 0.254 -0.0508) (xy 0.127 -0.0508) (xy 0.127 0.508)
					)
					(width 0)
					(fill yes)
				)
			)
		)
		(pad "2" smd rect
			(at 0 0.799846 90)
			(size 0.4572 0.508)
			(layers "F.Cu" "F.Mask" "F.Paste")
			(net "P5V_STB_NODE1_EN_P")
		)
		(zone
			(layer "F.Cu")
			(hatch none 0.5)
			(connect_pads
				(clearance 0)
			)
			(min_thickness 0.25)
			(keepout
				(tracks allowed)
				(vias not_allowed)
				(pads allowed)
				(copperpour not_allowed)
				(footprints allowed)
			)
			(placement
				(enabled no)
				(sheetname "")
			)
			(fill
				(thermal_gap 0.5)
				(thermal_bridge_width 0.5)
				(island_removal_mode 0)
			)
			(polygon
				(pts
					(xy 78.772766 -157.377384) (xy 79.382366 -157.377384) (xy 79.382366 -158.748984) (xy 78.772766 -158.748984)
				)
			)
		)
	)
	(footprint ""
		(layer "F.Cu")
		(at 144.738852 -147.19935)
		(property "Reference" "R306"
			(at -0.526288 18.534888 0)
			(unlocked yes)
			(layer "F.SilkS")
			(effects
				(font
					(size 0.7874 0.5842)
					(thickness 0.1524)
				)
				(justify left)
			)
		)
		(property "Value" ""
			(at 0 0 0)
			(layer "F.Fab")
			(effects
				(font
					(size 1.27 1.27)
				)
			)
		)
		(duplicate_pad_numbers_are_jumpers no)
		(fp_line
			(start -0.7874 -0.4064)
			(end 0.7874 -0.4064)
			(stroke
				(width 0.1524)
				(type default)
			)
			(layer "F.SilkS")
		)
		(fp_line
			(start -0.7874 0.4064)
			(end -0.7874 -0.4064)
			(stroke
				(width 0.1524)
				(type default)
			)
			(layer "F.SilkS")
		)
		(fp_line
			(start 0.7874 -0.4064)
			(end 0.7874 0.4064)
			(stroke
				(width 0.1524)
				(type default)
			)
			(layer "F.SilkS")
		)
		(fp_line
			(start 0.7874 0.4064)
			(end -0.7874 0.4064)
			(stroke
				(width 0.1524)
				(type default)
			)
			(layer "F.SilkS")
		)
		(fp_poly
			(pts
				(xy -0.508 0.2794) (xy -0.508 0.2286) (xy -0.635 0.2286) (xy -0.635 -0.254) (xy -0.5334 -0.254)
				(xy -0.5334 -0.2794) (xy 0.5334 -0.2794) (xy 0.5334 -0.254) (xy 0.635 -0.254) (xy 0.635 0.254) (xy 0.5334 0.254)
				(xy 0.5334 0.2794)
			)
			(stroke
				(width 0)
				(type default)
			)
			(fill no)
			(layer "F.CrtYd")
		)
		(pad "1" smd rect
			(at 0.40005 0)
			(size 0.4572 0.508)
			(layers "F.Cu" "F.Mask" "F.Paste")
			(net "GND")
		)
		(pad "2" smd rect
			(at -0.40005 0)
			(size 0.4572 0.508)
			(layers "F.Cu" "F.Mask" "F.Paste")
			(net "PCIE_SW_GPIO6")
		)
	)
	(footprint ""
		(layer "F.Cu")
		(at 106.069638 -140.815822 180)
		(property "Reference" "PR77"
			(at 1.345946 3.26009 0)
			(unlocked yes)
			(layer "F.SilkS")
			(effects
				(font
					(size 0.635 0.4064)
					(thickness 0.1524)
				)
				(justify left)
			)
		)
		(property "Value" ""
			(at 0 0 180)
			(layer "F.Fab")
			(effects
				(font
					(size 1.27 1.27)
				)
			)
		)
		(duplicate_pad_numbers_are_jumpers no)
		(fp_line
			(start 0.7874 0.4064)
			(end -0.7874 0.4064)
			(stroke
				(width 0.1524)
				(type default)
			)
			(layer "F.SilkS")
		)
		(fp_line
			(start 0.7874 -0.4064)
			(end 0.7874 0.4064)
			(stroke
				(width 0.1524)
				(type default)
			)
			(layer "F.SilkS")
		)
		(fp_line
			(start -0.7874 0.4064)
			(end -0.7874 -0.4064)
			(stroke
				(width 0.1524)
				(type default)
			)
			(layer "F.SilkS")
		)
		(fp_line
			(start -0.7874 -0.4064)
			(end 0.7874 -0.4064)
			(stroke
				(width 0.1524)
				(type default)
			)
			(layer "F.SilkS")
		)
		(fp_poly
			(pts
				(xy -0.508 0.2794) (xy -0.508 0.2286) (xy -0.635 0.2286) (xy -0.635 -0.254) (xy -0.5334 -0.254)
				(xy -0.5334 -0.2794) (xy 0.5334 -0.2794) (xy 0.5334 -0.254) (xy 0.635 -0.254) (xy 0.635 0.254) (xy 0.5334 0.254)
				(xy 0.5334 0.2794)
			)
			(stroke
				(width 0)
				(type default)
			)
			(fill no)
			(layer "F.CrtYd")
		)
		(pad "1" smd rect
			(at 0.40005 0 180)
			(size 0.4572 0.508)
			(layers "F.Cu" "F.Mask" "F.Paste")
			(net "AGND_PVCCP_NODE1")
		)
		(pad "2" smd rect
			(at -0.40005 0 180)
			(size 0.4572 0.508)
			(layers "F.Cu" "F.Mask" "F.Paste")
			(net "VR_PVCCP_NODE1_OCSET")
		)
	)
	(footprint ""
		(layer "F.Cu")
		(at 79.963518 -90.011504 180)
		(property "Reference" "R166"
			(at 1.195578 -18.994374 0)
			(unlocked yes)
			(layer "F.SilkS")
			(effects
				(font
					(size 0.7874 0.5842)
					(thickness 0.1524)
				)
				(justify left)
			)
		)
		(property "Value" ""
			(at 0 0 180)
			(layer "F.Fab")
			(effects
				(font
					(size 1.27 1.27)
				)
			)
		)
		(duplicate_pad_numbers_are_jumpers no)
		(fp_line
			(start 0.7874 0.4064)
			(end -0.7874 0.4064)
			(stroke
				(width 0.1524)
				(type default)
			)
			(layer "F.SilkS")
		)
		(fp_line
			(start 0.7874 -0.4064)
			(end 0.7874 0.4064)
			(stroke
				(width 0.1524)
				(type default)
			)
			(layer "F.SilkS")
		)
		(fp_line
			(start -0.7874 0.4064)
			(end -0.7874 -0.4064)
			(stroke
				(width 0.1524)
				(type default)
			)
			(layer "F.SilkS")
		)
		(fp_line
			(start -0.7874 -0.4064)
			(end 0.7874 -0.4064)
			(stroke
				(width 0.1524)
				(type default)
			)
			(layer "F.SilkS")
		)
		(fp_poly
			(pts
				(xy -0.508 0.2794) (xy -0.508 0.2286) (xy -0.635 0.2286) (xy -0.635 -0.254) (xy -0.5334 -0.254)
				(xy -0.5334 -0.2794) (xy 0.5334 -0.2794) (xy 0.5334 -0.254) (xy 0.635 -0.254) (xy 0.635 0.254) (xy 0.5334 0.254)
				(xy 0.5334 0.2794)
			)
			(stroke
				(width 0)
				(type default)
			)
			(fill no)
			(layer "F.CrtYd")
		)
		(pad "1" smd rect
			(at 0.40005 0 180)
			(size 0.4572 0.508)
			(layers "F.Cu" "F.Mask" "F.Paste")
			(net "VR_CPU_NODE1_INTVRMEN")
		)
		(pad "2" smd rect
			(at -0.40005 0 180)
			(size 0.4572 0.508)
			(layers "F.Cu" "F.Mask" "F.Paste")
			(net "GND")
		)
	)
	(footprint ""
		(layer "F.Cu")
		(at 171.151042 -138.367008)
		(property "Reference" "R1054"
			(at -2.942082 -9.390888 0)
			(unlocked yes)
			(layer "F.SilkS")
			(effects
				(font
					(size 0.7874 0.5842)
					(thickness 0.1524)
				)
				(justify left)
			)
		)
		(property "Value" ""
			(at 0 0 0)
			(layer "F.Fab")
			(effects
				(font
					(size 1.27 1.27)
				)
			)
		)
		(duplicate_pad_numbers_are_jumpers no)
		(fp_line
			(start -0.7874 -0.4064)
			(end 0.7874 -0.4064)
			(stroke
				(width 0.1524)
				(type default)
			)
			(layer "F.SilkS")
		)
		(fp_line
			(start -0.7874 0.4064)
			(end -0.7874 -0.4064)
			(stroke
				(width 0.1524)
				(type default)
			)
			(layer "F.SilkS")
		)
		(fp_line
			(start 0.7874 -0.4064)
			(end 0.7874 0.4064)
			(stroke
				(width 0.1524)
				(type default)
			)
			(layer "F.SilkS")
		)
		(fp_line
			(start 0.7874 0.4064)
			(end -0.7874 0.4064)
			(stroke
				(width 0.1524)
				(type default)
			)
			(layer "F.SilkS")
		)
		(fp_poly
			(pts
				(xy -0.508 0.2794) (xy -0.508 0.2286) (xy -0.635 0.2286) (xy -0.635 -0.254) (xy -0.5334 -0.254)
				(xy -0.5334 -0.2794) (xy 0.5334 -0.2794) (xy 0.5334 -0.254) (xy 0.635 -0.254) (xy 0.635 0.254) (xy 0.5334 0.254)
				(xy 0.5334 0.2794)
			)
			(stroke
				(width 0)
				(type default)
			)
			(fill no)
			(layer "F.CrtYd")
		)
		(pad "1" smd rect
			(at 0.40005 0)
			(size 0.4572 0.508)
			(layers "F.Cu" "F.Mask" "F.Paste")
			(net "PWR_BTN_NODE1_C_L")
		)
		(pad "2" smd rect
			(at -0.40005 0)
			(size 0.4572 0.508)
			(layers "F.Cu" "F.Mask" "F.Paste")
			(net "PWR_BTN_NODE1_L")
		)
	)
	(footprint ""
		(layer "F.Cu")
		(at 136.25576 -110.783624 -90)
		(property "Reference" "R23"
			(at 5.84835 -0.374142 90)
			(unlocked yes)
			(layer "F.SilkS")
			(effects
				(font
					(size 0.7874 0.5842)
					(thickness 0.1524)
				)
				(justify left)
			)
		)
		(property "Value" ""
			(at 0 0 270)
			(layer "F.Fab")
			(effects
				(font
					(size 1.27 1.27)
				)
			)
		)
		(duplicate_pad_numbers_are_jumpers no)
		(fp_line
			(start -0.7874 0.4064)
			(end -0.7874 -0.4064)
			(stroke
				(width 0.1524)
				(type default)
			)
			(layer "F.SilkS")
		)
		(fp_line
			(start 0.7874 0.4064)
			(end -0.7874 0.4064)
			(stroke
				(width 0.1524)
				(type default)
			)
			(layer "F.SilkS")
		)
		(fp_line
			(start -0.7874 -0.4064)
			(end 0.7874 -0.4064)
			(stroke
				(width 0.1524)
				(type default)
			)
			(layer "F.SilkS")
		)
		(fp_line
			(start 0.7874 -0.4064)
			(end 0.7874 0.4064)
			(stroke
				(width 0.1524)
				(type default)
			)
			(layer "F.SilkS")
		)
		(fp_poly
			(pts
				(xy -0.508 0.2794) (xy -0.508 0.2286) (xy -0.635 0.2286) (xy -0.635 -0.254) (xy -0.5334 -0.254)
				(xy -0.5334 -0.2794) (xy 0.5334 -0.2794) (xy 0.5334 -0.254) (xy 0.635 -0.254) (xy 0.635 0.254) (xy 0.5334 0.254)
				(xy 0.5334 0.2794)
			)
			(stroke
				(width 0)
				(type default)
			)
			(fill no)
			(layer "F.CrtYd")
		)
		(pad "1" smd rect
			(at 0.40005 0 270)
			(size 0.4572 0.508)
			(layers "F.Cu" "F.Mask" "F.Paste")
			(net "GND")
		)
		(pad "2" smd rect
			(at -0.40005 0 270)
			(size 0.4572 0.508)
			(layers "F.Cu" "F.Mask" "F.Paste")
			(net "CLKREQA_NODE1_N")
		)
	)
	(footprint ""
		(layer "F.Cu")
		(at 24.14524 -41.591992 180)
		(property "Reference" "D8"
			(at 0.09017 -2.29743 0)
			(unlocked yes)
			(layer "F.SilkS")
			(effects
				(font
					(size 0.7874 0.5842)
					(thickness 0.1524)
				)
			)
		)
		(property "Value" ""
			(at 0 0 180)
			(layer "F.Fab")
			(effects
				(font
					(size 1.27 1.27)
				)
			)
		)
		(duplicate_pad_numbers_are_jumpers no)
		(fp_line
			(start 1.519936 1.6002)
			(end -1.519936 1.6002)
			(stroke
				(width 0.1524)
				(type default)
			)
			(layer "F.SilkS")
		)
		(fp_line
			(start 1.519936 -1.6002)
			(end 1.519936 1.6002)
			(stroke
				(width 0.1524)
				(type default)
			)
			(layer "F.SilkS")
		)
		(fp_line
			(start -1.519936 1.6002)
			(end -1.519936 -1.5748)
			(stroke
				(width 0.1524)
				(type default)
			)
			(layer "F.SilkS")
		)
		(fp_line
			(start -1.519936 -1.6002)
			(end 1.519936 -1.6002)
			(stroke
				(width 0.1524)
				(type default)
			)
			(layer "F.SilkS")
		)
		(fp_poly
			(pts
				(xy -1.519936 0.700024) (xy -1.3716 0.700024) (xy -1.3716 1.4732) (xy -0.5334 1.4732) (xy -0.5334 0.700024)
				(xy 0.5334 0.700024) (xy 0.5334 1.4732) (xy 1.3716 1.4732) (xy 1.3716 0.700024) (xy 1.519936 0.700024)
				(xy 1.519936 -0.700024) (xy 0.4064 -0.700024) (xy 0.4064 -1.4732) (xy -0.4064 -1.4732) (xy -0.4064 -0.700024)
				(xy -1.519936 -0.700024)
			)
			(stroke
				(width 0)
				(type default)
			)
			(fill no)
			(layer "F.CrtYd")
		)
		(fp_line
			(start 1.519936 0.700024)
			(end -1.519936 0.700024)
			(stroke
				(width 0.1)
				(type default)
			)
			(layer "F.Fab")
		)
		(fp_line
			(start 1.519936 -0.700024)
			(end 1.519936 0.700024)
			(stroke
				(width 0.1)
				(type default)
			)
			(layer "F.Fab")
		)
		(fp_line
			(start -1.519936 0.700024)
			(end -1.519936 -0.700024)
			(stroke
				(width 0.1)
				(type default)
			)
			(layer "F.Fab")
		)
		(fp_line
			(start -1.519936 -0.700024)
			(end 1.519936 -0.700024)
			(stroke
				(width 0.1)
				(type default)
			)
			(layer "F.Fab")
		)
		(fp_text user "3"
			(at -0.915416 -2.25552 0)
			(unlocked yes)
			(layer "F.SilkS")
			(effects
				(font
					(size 0.635 0.4064)
					(thickness 0.1524)
				)
			)
		)
		(fp_text user "1"
			(at -1.72085 1.051814 0)
			(unlocked yes)
			(layer "F.SilkS")
			(effects
				(font
					(size 0.635 0.4064)
					(thickness 0.1524)
				)
			)
		)
		(fp_text user "2"
			(at -3.20167 1.05791 0)
			(unlocked yes)
			(layer "F.SilkS")
			(effects
				(font
					(size 0.635 0.4064)
					(thickness 0.1524)
				)
			)
		)
		(pad "1" smd rect
			(at -0.94996 0.999998 180)
			(size 0.8128 0.9144)
			(layers "F.Cu" "F.Mask" "F.Paste")
			(net "SMB_BMC_NODE1_DDC_DAT")
		)
		(pad "2" smd rect
			(at 0.94996 0.999998 180)
			(size 0.8128 0.9144)
			(layers "F.Cu" "F.Mask" "F.Paste")
			(net "Net_1680")
		)
		(pad "3" smd rect
			(at 0 -0.999998 180)
			(size 0.8128 0.9144)
			(layers "F.Cu" "F.Mask" "F.Paste")
			(net "I2C_VIDREAR_5V_SDA")
		)
	)
	(footprint ""
		(layer "F.Cu")
		(at 143.36776 -188.126624 -90)
		(property "Reference" "R999"
			(at -5.519674 0.767588 90)
			(unlocked yes)
			(layer "F.SilkS")
			(effects
				(font
					(size 0.7874 0.5842)
					(thickness 0.1524)
				)
				(justify left)
			)
		)
		(property "Value" ""
			(at 0 0 270)
			(layer "F.Fab")
			(effects
				(font
					(size 1.27 1.27)
				)
			)
		)
		(duplicate_pad_numbers_are_jumpers no)
		(fp_line
			(start -0.7874 0.4064)
			(end -0.7874 -0.4064)
			(stroke
				(width 0.1524)
				(type default)
			)
			(layer "F.SilkS")
		)
		(fp_line
			(start 0.7874 0.4064)
			(end -0.7874 0.4064)
			(stroke
				(width 0.1524)
				(type default)
			)
			(layer "F.SilkS")
		)
		(fp_line
			(start -0.7874 -0.4064)
			(end 0.7874 -0.4064)
			(stroke
				(width 0.1524)
				(type default)
			)
			(layer "F.SilkS")
		)
		(fp_line
			(start 0.7874 -0.4064)
			(end 0.7874 0.4064)
			(stroke
				(width 0.1524)
				(type default)
			)
			(layer "F.SilkS")
		)
		(fp_poly
			(pts
				(xy -0.508 0.2794) (xy -0.508 0.2286) (xy -0.635 0.2286) (xy -0.635 -0.254) (xy -0.5334 -0.254)
				(xy -0.5334 -0.2794) (xy 0.5334 -0.2794) (xy 0.5334 -0.254) (xy 0.635 -0.254) (xy 0.635 0.254) (xy 0.5334 0.254)
				(xy 0.5334 0.2794)
			)
			(stroke
				(width 0)
				(type default)
			)
			(fill no)
			(layer "F.CrtYd")
		)
		(pad "1" smd rect
			(at 0.40005 0 270)
			(size 0.4572 0.508)
			(layers "F.Cu" "F.Mask" "F.Paste")
			(net "UART_T12_NODE4_RXD")
		)
		(pad "2" smd rect
			(at -0.40005 0 270)
			(size 0.4572 0.508)
			(layers "F.Cu" "F.Mask" "F.Paste")
			(net "UART_T12_NODE4_RXD_R")
		)
	)
	(footprint ""
		(layer "F.Cu")
		(at 116.630196 -28.97886 -90)
		(property "Reference" "C854"
			(at -2.034286 -0.75565 90)
			(unlocked yes)
			(layer "F.SilkS")
			(effects
				(font
					(size 0.7874 0.5842)
					(thickness 0.1524)
				)
				(justify left)
			)
		)
		(property "Value" ""
			(at 0 0 270)
			(layer "F.Fab")
			(effects
				(font
					(size 1.27 1.27)
				)
			)
		)
		(duplicate_pad_numbers_are_jumpers no)
		(fp_line
			(start -1.905 0.8636)
			(end -1.905 -0.8636)
			(stroke
				(width 0.1524)
				(type default)
			)
			(layer "F.SilkS")
		)
		(fp_line
			(start 1.905 0.8636)
			(end -1.905 0.8636)
			(stroke
				(width 0.1524)
				(type default)
			)
			(layer "F.SilkS")
		)
		(fp_line
			(start 0 0.8382)
			(end 0 -0.8382)
			(stroke
				(width 0.1524)
				(type default)
			)
			(layer "F.SilkS")
		)
		(fp_line
			(start -1.905 -0.8636)
			(end 1.905 -0.8636)
			(stroke
				(width 0.1524)
				(type default)
			)
			(layer "F.SilkS")
		)
		(fp_line
			(start 1.905 -0.8636)
			(end 1.905 0.8636)
			(stroke
				(width 0.1524)
				(type default)
			)
			(layer "F.SilkS")
		)
		(fp_rect
			(start -1.524 0.7366)
			(end 1.524 -0.7366)
			(stroke
				(width 0)
				(type default)
			)
			(fill no)
			(layer "F.CrtYd")
		)
		(pad "1" smd rect
			(at 0.94996 0 270)
			(size 1.1176 1.3716)
			(layers "F.Cu" "F.Mask" "F.Paste")
			(net "PV_VDDR_NODE1")
		)
		(pad "2" smd rect
			(at -0.94996 0 270)
			(size 1.1176 1.3716)
			(layers "F.Cu" "F.Mask" "F.Paste")
			(net "GND")
		)
	)
	(footprint ""
		(layer "F.Cu")
		(at 52.223162 -148.562822 180)
		(property "Reference" "R543"
			(at 2.1336 -5.273548 0)
			(unlocked yes)
			(layer "F.SilkS")
			(effects
				(font
					(size 0.7874 0.5842)
					(thickness 0.1524)
				)
				(justify left)
			)
		)
		(property "Value" ""
			(at 0 0 180)
			(layer "F.Fab")
			(effects
				(font
					(size 1.27 1.27)
				)
			)
		)
		(duplicate_pad_numbers_are_jumpers no)
		(fp_line
			(start 0.7874 0.4064)
			(end -0.7874 0.4064)
			(stroke
				(width 0.1524)
				(type default)
			)
			(layer "F.SilkS")
		)
		(fp_line
			(start 0.7874 -0.4064)
			(end 0.7874 0.4064)
			(stroke
				(width 0.1524)
				(type default)
			)
			(layer "F.SilkS")
		)
		(fp_line
			(start -0.7874 0.4064)
			(end -0.7874 -0.4064)
			(stroke
				(width 0.1524)
				(type default)
			)
			(layer "F.SilkS")
		)
		(fp_line
			(start -0.7874 -0.4064)
			(end 0.7874 -0.4064)
			(stroke
				(width 0.1524)
				(type default)
			)
			(layer "F.SilkS")
		)
		(fp_poly
			(pts
				(xy -0.508 0.2794) (xy -0.508 0.2286) (xy -0.635 0.2286) (xy -0.635 -0.254) (xy -0.5334 -0.254)
				(xy -0.5334 -0.2794) (xy 0.5334 -0.2794) (xy 0.5334 -0.254) (xy 0.635 -0.254) (xy 0.635 0.254) (xy 0.5334 0.254)
				(xy 0.5334 0.2794)
			)
			(stroke
				(width 0)
				(type default)
			)
			(fill no)
			(layer "F.CrtYd")
		)
		(pad "1" smd rect
			(at 0.40005 0 180)
			(size 0.4572 0.508)
			(layers "F.Cu" "F.Mask" "F.Paste")
			(net "SPI_LAN1_NVM_CS_N")
		)
		(pad "2" smd rect
			(at -0.40005 0 180)
			(size 0.4572 0.508)
			(layers "F.Cu" "F.Mask" "F.Paste")
			(net "LAN1_NVM_CS_N_R")
		)
	)
	(footprint ""
		(layer "F.Cu")
		(at 42.11828 -110.955836)
		(property "Reference" "PR8"
			(at -1.338326 -4.656328 0)
			(unlocked yes)
			(layer "F.SilkS")
			(effects
				(font
					(size 0.7874 0.5842)
					(thickness 0.1524)
				)
				(justify left)
			)
		)
		(property "Value" ""
			(at 0 0 0)
			(layer "F.Fab")
			(effects
				(font
					(size 1.27 1.27)
				)
			)
		)
		(duplicate_pad_numbers_are_jumpers no)
		(fp_line
			(start -0.7874 -0.4064)
			(end 0.7874 -0.4064)
			(stroke
				(width 0.1524)
				(type default)
			)
			(layer "F.SilkS")
		)
		(fp_line
			(start -0.7874 0.4064)
			(end -0.7874 -0.4064)
			(stroke
				(width 0.1524)
				(type default)
			)
			(layer "F.SilkS")
		)
		(fp_line
			(start 0.7874 -0.4064)
			(end 0.7874 0.4064)
			(stroke
				(width 0.1524)
				(type default)
			)
			(layer "F.SilkS")
		)
		(fp_line
			(start 0.7874 0.4064)
			(end -0.7874 0.4064)
			(stroke
				(width 0.1524)
				(type default)
			)
			(layer "F.SilkS")
		)
		(fp_poly
			(pts
				(xy -0.508 0.2794) (xy -0.508 0.2286) (xy -0.635 0.2286) (xy -0.635 -0.254) (xy -0.5334 -0.254)
				(xy -0.5334 -0.2794) (xy 0.5334 -0.2794) (xy 0.5334 -0.254) (xy 0.635 -0.254) (xy 0.635 0.254) (xy 0.5334 0.254)
				(xy 0.5334 0.2794)
			)
			(stroke
				(width 0)
				(type default)
			)
			(fill no)
			(layer "F.CrtYd")
		)
		(pad "1" smd rect
			(at 0.40005 0)
			(size 0.4572 0.508)
			(layers "F.Cu" "F.Mask" "F.Paste")
			(net "P3V3_STB_NODE1_FB")
		)
		(pad "2" smd rect
			(at -0.40005 0)
			(size 0.4572 0.508)
			(layers "F.Cu" "F.Mask" "F.Paste")
			(net "GND")
		)
	)
	(footprint ""
		(layer "F.Cu")
		(at 19.375628 -148.263102)
		(property "Reference" "C416"
			(at -3.673348 0.213614 0)
			(unlocked yes)
			(layer "F.SilkS")
			(effects
				(font
					(size 0.7874 0.5842)
					(thickness 0.1524)
				)
			)
		)
		(property "Value" ""
			(at 0 0 0)
			(layer "F.Fab")
			(effects
				(font
					(size 1.27 1.27)
				)
			)
		)
		(duplicate_pad_numbers_are_jumpers no)
		(fp_line
			(start -1.2954 -0.5842)
			(end 1.2954 -0.5842)
			(stroke
				(width 0.1524)
				(type default)
			)
			(layer "F.SilkS")
		)
		(fp_line
			(start -1.2954 0.5842)
			(end -1.2954 -0.5842)
			(stroke
				(width 0.1524)
				(type default)
			)
			(layer "F.SilkS")
		)
		(fp_line
			(start 0 -0.5842)
			(end 0 0.5842)
			(stroke
				(width 0.1524)
				(type default)
			)
			(layer "F.SilkS")
		)
		(fp_line
			(start 1.2954 -0.5842)
			(end 1.2954 0.5842)
			(stroke
				(width 0.1524)
				(type default)
			)
			(layer "F.SilkS")
		)
		(fp_line
			(start 1.2954 0.5842)
			(end -1.2954 0.5842)
			(stroke
				(width 0.1524)
				(type default)
			)
			(layer "F.SilkS")
		)
		(fp_poly
			(pts
				(xy 0.8636 -0.4572) (xy 0.8636 -0.3556) (xy 1.143 -0.3556) (xy 1.143 0.3556) (xy 0.8636 0.3556)
				(xy 0.8636 0.4572) (xy -0.8636 0.4572) (xy -0.8636 0.3556) (xy -1.143 0.3556) (xy -1.143 -0.3556)
				(xy -0.8636 -0.3556) (xy -0.8636 -0.4572)
			)
			(stroke
				(width 0)
				(type default)
			)
			(fill no)
			(layer "F.CrtYd")
		)
		(fp_line
			(start -0.884936 -0.504952)
			(end 0.884936 -0.504952)
			(stroke
				(width 0.1)
				(type default)
			)
			(layer "F.Fab")
		)
		(fp_line
			(start -0.884936 0.504952)
			(end -0.884936 -0.504952)
			(stroke
				(width 0.1)
				(type default)
			)
			(layer "F.Fab")
		)
		(fp_line
			(start 0.884936 -0.504952)
			(end 0.884936 0.504952)
			(stroke
				(width 0.1)
				(type default)
			)
			(layer "F.Fab")
		)
		(fp_line
			(start 0.884936 0.504952)
			(end -0.884936 0.504952)
			(stroke
				(width 0.1)
				(type default)
			)
			(layer "F.Fab")
		)
		(pad "1" smd rect
			(at 0.7366 0 90)
			(size 0.7112 0.8128)
			(layers "F.Cu" "F.Mask" "F.Paste")
			(net "P3V3_NODE1")
		)
		(pad "2" smd rect
			(at -0.7366 0 90)
			(size 0.7112 0.8128)
			(layers "F.Cu" "F.Mask" "F.Paste")
			(net "GND")
		)
	)
	(footprint ""
		(layer "F.Cu")
		(at 54.033166 -96.709992 90)
		(property "Reference" "R83"
			(at -54.98719 28.429712 90)
			(unlocked yes)
			(layer "F.SilkS")
			(effects
				(font
					(size 0.7874 0.5842)
					(thickness 0.1524)
				)
				(justify left)
			)
		)
		(property "Value" ""
			(at 0 0 90)
			(layer "F.Fab")
			(effects
				(font
					(size 1.27 1.27)
				)
			)
		)
		(duplicate_pad_numbers_are_jumpers no)
		(fp_line
			(start 0.7874 -0.4064)
			(end 0.7874 0.4064)
			(stroke
				(width 0.1524)
				(type default)
			)
			(layer "F.SilkS")
		)
		(fp_line
			(start -0.7874 -0.4064)
			(end 0.7874 -0.4064)
			(stroke
				(width 0.1524)
				(type default)
			)
			(layer "F.SilkS")
		)
		(fp_line
			(start 0.7874 0.4064)
			(end -0.7874 0.4064)
			(stroke
				(width 0.1524)
				(type default)
			)
			(layer "F.SilkS")
		)
		(fp_line
			(start -0.7874 0.4064)
			(end -0.7874 -0.4064)
			(stroke
				(width 0.1524)
				(type default)
			)
			(layer "F.SilkS")
		)
		(fp_poly
			(pts
				(xy -0.508 0.2794) (xy -0.508 0.2286) (xy -0.635 0.2286) (xy -0.635 -0.254) (xy -0.5334 -0.254)
				(xy -0.5334 -0.2794) (xy 0.5334 -0.2794) (xy 0.5334 -0.254) (xy 0.635 -0.254) (xy 0.635 0.254) (xy 0.5334 0.254)
				(xy 0.5334 0.2794)
			)
			(stroke
				(width 0)
				(type default)
			)
			(fill no)
			(layer "F.CrtYd")
		)
		(pad "1" smd rect
			(at 0.40005 0 90)
			(size 0.4572 0.508)
			(layers "F.Cu" "F.Mask" "F.Paste")
			(net "GND")
		)
		(pad "2" smd rect
			(at -0.40005 0 90)
			(size 0.4572 0.508)
			(layers "F.Cu" "F.Mask" "F.Paste")
			(net "PD_CPU_NODE1_DFX_GPIO_GRP0_2")
		)
	)
	(footprint ""
		(layer "F.Cu")
		(at 142.954248 -159.787336 -90)
		(property "Reference" "R1057"
			(at 110.310168 66.533522 90)
			(unlocked yes)
			(layer "F.SilkS")
			(effects
				(font
					(size 0.7874 0.5842)
					(thickness 0.1524)
				)
				(justify left)
			)
		)
		(property "Value" ""
			(at 0 0 270)
			(layer "F.Fab")
			(effects
				(font
					(size 1.27 1.27)
				)
			)
		)
		(duplicate_pad_numbers_are_jumpers no)
		(fp_line
			(start -0.7874 0.4064)
			(end -0.7874 -0.4064)
			(stroke
				(width 0.1524)
				(type default)
			)
			(layer "F.SilkS")
		)
		(fp_line
			(start 0.7874 0.4064)
			(end -0.7874 0.4064)
			(stroke
				(width 0.1524)
				(type default)
			)
			(layer "F.SilkS")
		)
		(fp_line
			(start -0.7874 -0.4064)
			(end 0.7874 -0.4064)
			(stroke
				(width 0.1524)
				(type default)
			)
			(layer "F.SilkS")
		)
		(fp_line
			(start 0.7874 -0.4064)
			(end 0.7874 0.4064)
			(stroke
				(width 0.1524)
				(type default)
			)
			(layer "F.SilkS")
		)
		(fp_poly
			(pts
				(xy -0.508 0.2794) (xy -0.508 0.2286) (xy -0.635 0.2286) (xy -0.635 -0.254) (xy -0.5334 -0.254)
				(xy -0.5334 -0.2794) (xy 0.5334 -0.2794) (xy 0.5334 -0.254) (xy 0.635 -0.254) (xy 0.635 0.254) (xy 0.5334 0.254)
				(xy 0.5334 0.2794)
			)
			(stroke
				(width 0)
				(type default)
			)
			(fill no)
			(layer "F.CrtYd")
		)
		(pad "1" smd rect
			(at 0.40005 0 270)
			(size 0.4572 0.508)
			(layers "F.Cu" "F.Mask" "F.Paste")
			(net "P3V3_NODE1")
		)
		(pad "2" smd rect
			(at -0.40005 0 270)
			(size 0.4572 0.508)
			(layers "F.Cu" "F.Mask" "F.Paste")
			(net "N31521709")
		)
	)
	(footprint ""
		(layer "F.Cu")
		(at 65.383664 -176.26203 180)
		(property "Reference" "R1014"
			(at 14.220952 -132.954014 0)
			(unlocked yes)
			(layer "F.SilkS")
			(effects
				(font
					(size 0.7874 0.5842)
					(thickness 0.1524)
				)
				(justify left)
			)
		)
		(property "Value" ""
			(at 0 0 180)
			(layer "F.Fab")
			(effects
				(font
					(size 1.27 1.27)
				)
			)
		)
		(duplicate_pad_numbers_are_jumpers no)
		(fp_line
			(start 0.7874 0.4064)
			(end -0.7874 0.4064)
			(stroke
				(width 0.1524)
				(type default)
			)
			(layer "F.SilkS")
		)
		(fp_line
			(start 0.7874 -0.4064)
			(end 0.7874 0.4064)
			(stroke
				(width 0.1524)
				(type default)
			)
			(layer "F.SilkS")
		)
		(fp_line
			(start -0.7874 0.4064)
			(end -0.7874 -0.4064)
			(stroke
				(width 0.1524)
				(type default)
			)
			(layer "F.SilkS")
		)
		(fp_line
			(start -0.7874 -0.4064)
			(end 0.7874 -0.4064)
			(stroke
				(width 0.1524)
				(type default)
			)
			(layer "F.SilkS")
		)
		(fp_poly
			(pts
				(xy -0.508 0.2794) (xy -0.508 0.2286) (xy -0.635 0.2286) (xy -0.635 -0.254) (xy -0.5334 -0.254)
				(xy -0.5334 -0.2794) (xy 0.5334 -0.2794) (xy 0.5334 -0.254) (xy 0.635 -0.254) (xy 0.635 0.254) (xy 0.5334 0.254)
				(xy 0.5334 0.2794)
			)
			(stroke
				(width 0)
				(type default)
			)
			(fill no)
			(layer "F.CrtYd")
		)
		(pad "1" smd rect
			(at 0.40005 0 180)
			(size 0.4572 0.508)
			(layers "F.Cu" "F.Mask" "F.Paste")
			(net "GND")
		)
		(pad "2" smd rect
			(at -0.40005 0 180)
			(size 0.4572 0.508)
			(layers "F.Cu" "F.Mask" "F.Paste")
			(net "PSU_DC_OK_N")
		)
	)
	(footprint ""
		(layer "F.Cu")
		(at 166.715694 -122.66422 180)
		(property "Reference" "R1042"
			(at 2.798064 -9.851644 0)
			(unlocked yes)
			(layer "F.SilkS")
			(effects
				(font
					(size 0.7874 0.5842)
					(thickness 0.1524)
				)
				(justify left)
			)
		)
		(property "Value" ""
			(at 0 0 180)
			(layer "F.Fab")
			(effects
				(font
					(size 1.27 1.27)
				)
			)
		)
		(duplicate_pad_numbers_are_jumpers no)
		(fp_line
			(start 0.7874 0.4064)
			(end -0.7874 0.4064)
			(stroke
				(width 0.1524)
				(type default)
			)
			(layer "F.SilkS")
		)
		(fp_line
			(start 0.7874 -0.4064)
			(end 0.7874 0.4064)
			(stroke
				(width 0.1524)
				(type default)
			)
			(layer "F.SilkS")
		)
		(fp_line
			(start -0.7874 0.4064)
			(end -0.7874 -0.4064)
			(stroke
				(width 0.1524)
				(type default)
			)
			(layer "F.SilkS")
		)
		(fp_line
			(start -0.7874 -0.4064)
			(end 0.7874 -0.4064)
			(stroke
				(width 0.1524)
				(type default)
			)
			(layer "F.SilkS")
		)
		(fp_poly
			(pts
				(xy -0.508 0.2794) (xy -0.508 0.2286) (xy -0.635 0.2286) (xy -0.635 -0.254) (xy -0.5334 -0.254)
				(xy -0.5334 -0.2794) (xy 0.5334 -0.2794) (xy 0.5334 -0.254) (xy 0.635 -0.254) (xy 0.635 0.254) (xy 0.5334 0.254)
				(xy 0.5334 0.2794)
			)
			(stroke
				(width 0)
				(type default)
			)
			(fill no)
			(layer "F.CrtYd")
		)
		(pad "1" smd rect
			(at 0.40005 0 180)
			(size 0.4572 0.508)
			(layers "F.Cu" "F.Mask" "F.Paste")
			(net "FM_NODE1_DDR3_DRAM_POK_R_L")
		)
		(pad "2" smd rect
			(at -0.40005 0 180)
			(size 0.4572 0.508)
			(layers "F.Cu" "F.Mask" "F.Paste")
			(net "FM_NODE1_DDR3_DRAM_POK_L")
		)
	)
	(footprint ""
		(layer "F.Cu")
		(at 152.755854 -136.171432)
		(property "Reference" "R1062"
			(at -5.190236 1.951482 0)
			(unlocked yes)
			(layer "F.SilkS")
			(effects
				(font
					(size 0.7874 0.5842)
					(thickness 0.1524)
				)
				(justify left)
			)
		)
		(property "Value" ""
			(at 0 0 0)
			(layer "F.Fab")
			(effects
				(font
					(size 1.27 1.27)
				)
			)
		)
		(duplicate_pad_numbers_are_jumpers no)
		(fp_line
			(start -0.7874 -0.4064)
			(end 0.7874 -0.4064)
			(stroke
				(width 0.1524)
				(type default)
			)
			(layer "F.SilkS")
		)
		(fp_line
			(start -0.7874 0.4064)
			(end -0.7874 -0.4064)
			(stroke
				(width 0.1524)
				(type default)
			)
			(layer "F.SilkS")
		)
		(fp_line
			(start 0.7874 -0.4064)
			(end 0.7874 0.4064)
			(stroke
				(width 0.1524)
				(type default)
			)
			(layer "F.SilkS")
		)
		(fp_line
			(start 0.7874 0.4064)
			(end -0.7874 0.4064)
			(stroke
				(width 0.1524)
				(type default)
			)
			(layer "F.SilkS")
		)
		(fp_poly
			(pts
				(xy -0.508 0.2794) (xy -0.508 0.2286) (xy -0.635 0.2286) (xy -0.635 -0.254) (xy -0.5334 -0.254)
				(xy -0.5334 -0.2794) (xy 0.5334 -0.2794) (xy 0.5334 -0.254) (xy 0.635 -0.254) (xy 0.635 0.254) (xy 0.5334 0.254)
				(xy 0.5334 0.2794)
			)
			(stroke
				(width 0)
				(type default)
			)
			(fill no)
			(layer "F.CrtYd")
		)
		(pad "1" smd rect
			(at 0.40005 0)
			(size 0.4572 0.508)
			(layers "F.Cu" "F.Mask" "F.Paste")
			(net "RST_BTN_L")
		)
		(pad "2" smd rect
			(at -0.40005 0)
			(size 0.4572 0.508)
			(layers "F.Cu" "F.Mask" "F.Paste")
			(net "P3V3_STB_NODE1")
		)
	)
	(footprint ""
		(layer "F.Cu")
		(at 82.038444 -118.645686 -90)
		(property "Reference" "TP175"
			(at 0 0 270)
			(layer "F.SilkS")
			(hide yes)
			(effects
				(font
					(size 1.27 1.27)
				)
			)
		)
		(property "Value" ""
			(at 0 0 270)
			(layer "F.Fab")
			(effects
				(font
					(size 1.27 1.27)
				)
			)
		)
		(duplicate_pad_numbers_are_jumpers no)
		(fp_poly
			(pts
				(arc
					(start 0 0.3302)
					(mid 0 -0.3302)
					(end 0 0.3302)
				)
			)
			(stroke
				(width 0)
				(type default)
			)
			(fill no)
			(layer "B.CrtYd")
		)
		(pad "1" thru_hole circle
			(at 0 0 270)
			(size 0.508 0.508)
			(drill 0.254)
			(layers "*.Cu" "*.Mask")
			(remove_unused_layers no)
			(net "N53313175")
			(clearance 0.127)
			(thermal_gap 0.127)
			(padstack
				(mode front_inner_back)
				(layer "Inner"
					(shape circle)
					(size 0.508 0.508)
					(clearance 0.127)
				)
				(layer "B.Cu"
					(shape circle)
					(size 0.6604 0.6604)
					(clearance 0.0508)
				)
			)
		)
	)
	(footprint ""
		(layer "F.Cu")
		(at 163.152328 -82.549492 180)
		(property "Reference" "PC28"
			(at -3.539744 0.125222 0)
			(unlocked yes)
			(layer "F.SilkS")
			(effects
				(font
					(size 0.7874 0.5842)
					(thickness 0.1524)
				)
				(justify left)
			)
		)
		(property "Value" ""
			(at 0 0 180)
			(layer "F.Fab")
			(effects
				(font
					(size 1.27 1.27)
				)
			)
		)
		(duplicate_pad_numbers_are_jumpers no)
		(fp_line
			(start 1.905 0.8636)
			(end -1.905 0.8636)
			(stroke
				(width 0.1524)
				(type default)
			)
			(layer "F.SilkS")
		)
		(fp_line
			(start 1.905 -0.8636)
			(end 1.905 0.8636)
			(stroke
				(width 0.1524)
				(type default)
			)
			(layer "F.SilkS")
		)
		(fp_line
			(start 0 0.8382)
			(end 0 -0.8382)
			(stroke
				(width 0.1524)
				(type default)
			)
			(layer "F.SilkS")
		)
		(fp_line
			(start -1.905 0.8636)
			(end -1.905 -0.8636)
			(stroke
				(width 0.1524)
				(type default)
			)
			(layer "F.SilkS")
		)
		(fp_line
			(start -1.905 -0.8636)
			(end 1.905 -0.8636)
			(stroke
				(width 0.1524)
				(type default)
			)
			(layer "F.SilkS")
		)
		(fp_rect
			(start -1.524 0.7366)
			(end 1.524 -0.7366)
			(stroke
				(width 0)
				(type default)
			)
			(fill no)
			(layer "F.CrtYd")
		)
		(pad "1" smd rect
			(at 0.94996 0 180)
			(size 1.1176 1.3716)
			(layers "F.Cu" "F.Mask" "F.Paste")
			(net "P1V0_NODE1")
		)
		(pad "2" smd rect
			(at -0.94996 0 180)
			(size 1.1176 1.3716)
			(layers "F.Cu" "F.Mask" "F.Paste")
			(net "GND")
		)
	)
	(footprint ""
		(layer "F.Cu")
		(at 117.68836 -164.631624 -90)
		(property "Reference" "U61"
			(at 48.179736 -32.1818 0)
			(unlocked yes)
			(layer "F.SilkS")
			(effects
				(font
					(size 0.7874 0.5842)
					(thickness 0.1524)
				)
				(justify left)
			)
		)
		(property "Value" ""
			(at 0 0 270)
			(layer "F.Fab")
			(effects
				(font
					(size 1.27 1.27)
				)
			)
		)
		(duplicate_pad_numbers_are_jumpers no)
		(fp_line
			(start -2.5654 2.0066)
			(end -2.5654 0.5842)
			(stroke
				(width 0.1524)
				(type default)
			)
			(layer "F.SilkS")
		)
		(fp_line
			(start 2.5654 2.0066)
			(end -2.5654 2.0066)
			(stroke
				(width 0.1524)
				(type default)
			)
			(layer "F.SilkS")
		)
		(fp_line
			(start -2.5654 0.5842)
			(end -1.9812 0)
			(stroke
				(width 0.1524)
				(type default)
			)
			(layer "F.SilkS")
		)
		(fp_line
			(start -1.9812 0)
			(end -2.5654 -0.5842)
			(stroke
				(width 0.1524)
				(type default)
			)
			(layer "F.SilkS")
		)
		(fp_line
			(start -2.5654 -0.5842)
			(end -2.5654 -2.0066)
			(stroke
				(width 0.1524)
				(type default)
			)
			(layer "F.SilkS")
		)
		(fp_line
			(start -2.5654 -2.0066)
			(end 2.5654 -2.0066)
			(stroke
				(width 0.1524)
				(type default)
			)
			(layer "F.SilkS")
		)
		(fp_line
			(start 2.5654 -2.0066)
			(end 2.5654 2.0066)
			(stroke
				(width 0.1524)
				(type default)
			)
			(layer "F.SilkS")
		)
		(fp_circle
			(center -2.032 1.524)
			(end -2.032 1.27)
			(stroke
				(width 0.1524)
				(type default)
			)
			(fill no)
			(layer "F.SilkS")
		)
		(fp_rect
			(start -2.5654 3.6703)
			(end 2.5654 -3.6703)
			(stroke
				(width 0)
				(type default)
			)
			(fill no)
			(layer "F.CrtYd")
		)
		(pad "1" smd rect
			(at -2.275078 2.921 270)
			(size 0.3556 1.4986)
			(layers "F.Cu" "F.Mask" "F.Paste")
			(net "PSU1_HUB_EN")
		)
		(pad "2" smd rect
			(at -1.625092 2.921 270)
			(size 0.3556 1.4986)
			(layers "F.Cu" "F.Mask" "F.Paste")
			(net "PSU2_HUB_EN")
		)
		(pad "3" smd rect
			(at -0.975106 2.921 270)
			(size 0.3556 1.4986)
			(layers "F.Cu" "F.Mask" "F.Paste")
			(net "UART3_RESET_N")
		)
		(pad "4" smd rect
			(at -0.32512 2.921 270)
			(size 0.3556 1.4986)
			(layers "F.Cu" "F.Mask" "F.Paste")
			(net "GND")
		)
		(pad "5" smd rect
			(at 0.32512 2.921 270)
			(size 0.3556 1.4986)
			(layers "F.Cu" "F.Mask" "F.Paste")
			(net "PSU3_HUB_EN")
		)
		(pad "6" smd rect
			(at 0.975106 2.921 270)
			(size 0.3556 1.4986)
			(layers "F.Cu" "F.Mask" "F.Paste")
			(net "PCA9535_INT_N")
		)
		(pad "7" smd rect
			(at 1.625092 2.921 270)
			(size 0.3556 1.4986)
			(layers "F.Cu" "F.Mask" "F.Paste")
			(net "I2C_COM3_SDA_RC")
		)
		(pad "8" smd rect
			(at 2.275078 2.921 270)
			(size 0.3556 1.4986)
			(layers "F.Cu" "F.Mask" "F.Paste")
			(net "I2C_COM3_SCL")
		)
		(pad "9" smd rect
			(at 2.275078 -2.921 270)
			(size 0.3556 1.4986)
			(layers "F.Cu" "F.Mask" "F.Paste")
			(net "UART_CMC_TX_P")
		)
		(pad "10" smd rect
			(at 1.625092 -2.921 270)
			(size 0.3556 1.4986)
			(layers "F.Cu" "F.Mask" "F.Paste")
			(net "UART_CMC_RX_P")
		)
		(pad "11" smd rect
			(at 0.975106 -2.921 270)
			(size 0.3556 1.4986)
			(layers "F.Cu" "F.Mask" "F.Paste")
			(net "CMC_CPU_RST_N")
		)
		(pad "12" smd rect
			(at 0.32512 -2.921 270)
			(size 0.3556 1.4986)
			(layers "F.Cu" "F.Mask" "F.Paste")
			(net "P3V3_NODE1")
		)
		(pad "13" smd rect
			(at -0.32512 -2.921 270)
			(size 0.3556 1.4986)
			(layers "F.Cu" "F.Mask" "F.Paste")
			(net "COM3_WAKEUP")
		)
		(pad "14" smd rect
			(at -0.975106 -2.921 270)
			(size 0.3556 1.4986)
			(layers "F.Cu" "F.Mask" "F.Paste")
			(net "CPLD_WDT1_R")
		)
		(pad "15" smd rect
			(at -1.625092 -2.921 270)
			(size 0.3556 1.4986)
			(layers "F.Cu" "F.Mask" "F.Paste")
			(net "FAN_MAX_CTRL")
		)
		(pad "16" smd rect
			(at -2.275078 -2.921 270)
			(size 0.3556 1.4986)
			(layers "F.Cu" "F.Mask" "F.Paste")
			(net "CMC_CPLD_RSV1")
		)
	)
	(footprint ""
		(layer "F.Cu")
		(at 151.113998 -155.33243 180)
		(property "Reference" "C435"
			(at -0.918972 1.004824 0)
			(unlocked yes)
			(layer "F.SilkS")
			(effects
				(font
					(size 0.7874 0.5842)
					(thickness 0.1524)
				)
				(justify left)
			)
		)
		(property "Value" ""
			(at 0 0 180)
			(layer "F.Fab")
			(effects
				(font
					(size 1.27 1.27)
				)
			)
		)
		(duplicate_pad_numbers_are_jumpers no)
		(fp_line
			(start 0.7874 0.4064)
			(end -0.7874 0.4064)
			(stroke
				(width 0.1524)
				(type default)
			)
			(layer "F.SilkS")
		)
		(fp_line
			(start 0.7874 -0.4064)
			(end 0.7874 0.4064)
			(stroke
				(width 0.1524)
				(type default)
			)
			(layer "F.SilkS")
		)
		(fp_line
			(start 0 0.381)
			(end 0 -0.381)
			(stroke
				(width 0.1524)
				(type default)
			)
			(layer "F.SilkS")
		)
		(fp_line
			(start -0.7874 0.4064)
			(end -0.7874 -0.4064)
			(stroke
				(width 0.1524)
				(type default)
			)
			(layer "F.SilkS")
		)
		(fp_line
			(start -0.7874 -0.4064)
			(end 0.7874 -0.4064)
			(stroke
				(width 0.1524)
				(type default)
			)
			(layer "F.SilkS")
		)
		(fp_poly
			(pts
				(xy -0.5334 0.254) (xy -0.635 0.254) (xy -0.635 0.2286) (xy -0.635 -0.254) (xy -0.5334 -0.254) (xy -0.5334 -0.2794)
				(xy 0.5334 -0.2794) (xy 0.5334 -0.254) (xy 0.635 -0.254) (xy 0.635 0.254) (xy 0.5334 0.254) (xy 0.5334 0.2794)
				(xy -0.508 0.2794) (xy -0.5334 0.2794)
			)
			(stroke
				(width 0)
				(type default)
			)
			(fill no)
			(layer "F.CrtYd")
		)
		(pad "1" smd rect
			(at 0.40005 0 180)
			(size 0.4572 0.508)
			(layers "F.Cu" "F.Mask" "F.Paste")
			(net "P2E_CPU_NIC2_NODE1_RX_DP")
		)
		(pad "2" smd rect
			(at -0.40005 0 180)
			(size 0.4572 0.508)
			(layers "F.Cu" "F.Mask" "F.Paste")
			(net "PCIE_LAN2_RX_C_DP")
		)
	)
	(footprint ""
		(layer "F.Cu")
		(at 11.704828 -151.71039)
		(property "Reference" "C552"
			(at 2.89179 2.504186 90)
			(unlocked yes)
			(layer "F.SilkS")
			(effects
				(font
					(size 0.7874 0.5842)
					(thickness 0.1524)
				)
				(justify left)
			)
		)
		(property "Value" ""
			(at 0 0 0)
			(layer "F.Fab")
			(effects
				(font
					(size 1.27 1.27)
				)
			)
		)
		(duplicate_pad_numbers_are_jumpers no)
		(fp_line
			(start -0.7874 -0.4064)
			(end 0.7874 -0.4064)
			(stroke
				(width 0.1524)
				(type default)
			)
			(layer "F.SilkS")
		)
		(fp_line
			(start -0.7874 0.4064)
			(end -0.7874 -0.4064)
			(stroke
				(width 0.1524)
				(type default)
			)
			(layer "F.SilkS")
		)
		(fp_line
			(start 0 0.381)
			(end 0 -0.381)
			(stroke
				(width 0.1524)
				(type default)
			)
			(layer "F.SilkS")
		)
		(fp_line
			(start 0.7874 -0.4064)
			(end 0.7874 0.4064)
			(stroke
				(width 0.1524)
				(type default)
			)
			(layer "F.SilkS")
		)
		(fp_line
			(start 0.7874 0.4064)
			(end -0.7874 0.4064)
			(stroke
				(width 0.1524)
				(type default)
			)
			(layer "F.SilkS")
		)
		(fp_poly
			(pts
				(xy -0.5334 0.254) (xy -0.635 0.254) (xy -0.635 0.2286) (xy -0.635 -0.254) (xy -0.5334 -0.254) (xy -0.5334 -0.2794)
				(xy 0.5334 -0.2794) (xy 0.5334 -0.254) (xy 0.635 -0.254) (xy 0.635 0.254) (xy 0.5334 0.254) (xy 0.5334 0.2794)
				(xy -0.508 0.2794) (xy -0.5334 0.2794)
			)
			(stroke
				(width 0)
				(type default)
			)
			(fill no)
			(layer "F.CrtYd")
		)
		(pad "1" smd rect
			(at 0.40005 0)
			(size 0.4572 0.508)
			(layers "F.Cu" "F.Mask" "F.Paste")
			(net "N54310596")
		)
		(pad "2" smd rect
			(at -0.40005 0)
			(size 0.4572 0.508)
			(layers "F.Cu" "F.Mask" "F.Paste")
			(net "N54310598")
		)
	)
	(footprint ""
		(layer "F.Cu")
		(at 120.63222 -185.209942 -90)
		(property "Reference" "R869"
			(at -4.768088 -0.152908 90)
			(unlocked yes)
			(layer "F.SilkS")
			(effects
				(font
					(size 0.7874 0.5842)
					(thickness 0.1524)
				)
				(justify left)
			)
		)
		(property "Value" ""
			(at 0 0 270)
			(layer "F.Fab")
			(effects
				(font
					(size 1.27 1.27)
				)
			)
		)
		(duplicate_pad_numbers_are_jumpers no)
		(fp_line
			(start -0.7874 0.4064)
			(end -0.7874 -0.4064)
			(stroke
				(width 0.1524)
				(type default)
			)
			(layer "F.SilkS")
		)
		(fp_line
			(start 0.7874 0.4064)
			(end -0.7874 0.4064)
			(stroke
				(width 0.1524)
				(type default)
			)
			(layer "F.SilkS")
		)
		(fp_line
			(start -0.7874 -0.4064)
			(end 0.7874 -0.4064)
			(stroke
				(width 0.1524)
				(type default)
			)
			(layer "F.SilkS")
		)
		(fp_line
			(start 0.7874 -0.4064)
			(end 0.7874 0.4064)
			(stroke
				(width 0.1524)
				(type default)
			)
			(layer "F.SilkS")
		)
		(fp_poly
			(pts
				(xy -0.508 0.2794) (xy -0.508 0.2286) (xy -0.635 0.2286) (xy -0.635 -0.254) (xy -0.5334 -0.254)
				(xy -0.5334 -0.2794) (xy 0.5334 -0.2794) (xy 0.5334 -0.254) (xy 0.635 -0.254) (xy 0.635 0.254) (xy 0.5334 0.254)
				(xy 0.5334 0.2794)
			)
			(stroke
				(width 0)
				(type default)
			)
			(fill no)
			(layer "F.CrtYd")
		)
		(pad "1" smd rect
			(at 0.40005 0 270)
			(size 0.4572 0.508)
			(layers "F.Cu" "F.Mask" "F.Paste")
			(net "T8_NODE4_EN")
		)
		(pad "2" smd rect
			(at -0.40005 0 270)
			(size 0.4572 0.508)
			(layers "F.Cu" "F.Mask" "F.Paste")
			(net "T8_NODE4_EN_R")
		)
	)
	(footprint ""
		(layer "F.Cu")
		(at 149.411944 -43.664124)
		(property "Reference" "R1009"
			(at -2.3368 -2.962148 0)
			(unlocked yes)
			(layer "F.SilkS")
			(effects
				(font
					(size 0.7874 0.5842)
					(thickness 0.1524)
				)
				(justify left)
			)
		)
		(property "Value" ""
			(at 0 0 0)
			(layer "F.Fab")
			(effects
				(font
					(size 1.27 1.27)
				)
			)
		)
		(duplicate_pad_numbers_are_jumpers no)
		(fp_line
			(start -0.7874 -0.4064)
			(end 0.7874 -0.4064)
			(stroke
				(width 0.1524)
				(type default)
			)
			(layer "F.SilkS")
		)
		(fp_line
			(start -0.7874 0.4064)
			(end -0.7874 -0.4064)
			(stroke
				(width 0.1524)
				(type default)
			)
			(layer "F.SilkS")
		)
		(fp_line
			(start 0.7874 -0.4064)
			(end 0.7874 0.4064)
			(stroke
				(width 0.1524)
				(type default)
			)
			(layer "F.SilkS")
		)
		(fp_line
			(start 0.7874 0.4064)
			(end -0.7874 0.4064)
			(stroke
				(width 0.1524)
				(type default)
			)
			(layer "F.SilkS")
		)
		(fp_poly
			(pts
				(xy -0.508 0.2794) (xy -0.508 0.2286) (xy -0.635 0.2286) (xy -0.635 -0.254) (xy -0.5334 -0.254)
				(xy -0.5334 -0.2794) (xy 0.5334 -0.2794) (xy 0.5334 -0.254) (xy 0.635 -0.254) (xy 0.635 0.254) (xy 0.5334 0.254)
				(xy 0.5334 0.2794)
			)
			(stroke
				(width 0)
				(type default)
			)
			(fill no)
			(layer "F.CrtYd")
		)
		(pad "1" smd rect
			(at 0.40005 0)
			(size 0.4572 0.508)
			(layers "F.Cu" "F.Mask" "F.Paste")
			(net "P5V_NODE1")
		)
		(pad "2" smd rect
			(at -0.40005 0)
			(size 0.4572 0.508)
			(layers "F.Cu" "F.Mask" "F.Paste")
			(net "UART_TX_P1")
		)
	)
	(footprint ""
		(layer "F.Cu")
		(at 37.18052 -6.550914 -90)
		(property "Reference" "PR31"
			(at 1.42494 9.388602 90)
			(unlocked yes)
			(layer "F.SilkS")
			(effects
				(font
					(size 0.7874 0.5842)
					(thickness 0.1524)
				)
				(justify left)
			)
		)
		(property "Value" ""
			(at 0 0 270)
			(layer "F.Fab")
			(effects
				(font
					(size 1.27 1.27)
				)
			)
		)
		(duplicate_pad_numbers_are_jumpers no)
		(fp_line
			(start -0.7874 0.4064)
			(end -0.7874 -0.4064)
			(stroke
				(width 0.1524)
				(type default)
			)
			(layer "F.SilkS")
		)
		(fp_line
			(start 0.7874 0.4064)
			(end -0.7874 0.4064)
			(stroke
				(width 0.1524)
				(type default)
			)
			(layer "F.SilkS")
		)
		(fp_line
			(start -0.7874 -0.4064)
			(end 0.7874 -0.4064)
			(stroke
				(width 0.1524)
				(type default)
			)
			(layer "F.SilkS")
		)
		(fp_line
			(start 0.7874 -0.4064)
			(end 0.7874 0.4064)
			(stroke
				(width 0.1524)
				(type default)
			)
			(layer "F.SilkS")
		)
		(fp_poly
			(pts
				(xy -0.508 0.2794) (xy -0.508 0.2286) (xy -0.635 0.2286) (xy -0.635 -0.254) (xy -0.5334 -0.254)
				(xy -0.5334 -0.2794) (xy 0.5334 -0.2794) (xy 0.5334 -0.254) (xy 0.635 -0.254) (xy 0.635 0.254) (xy 0.5334 0.254)
				(xy 0.5334 0.2794)
			)
			(stroke
				(width 0)
				(type default)
			)
			(fill no)
			(layer "F.CrtYd")
		)
		(pad "1" smd rect
			(at 0.40005 0 270)
			(size 0.4572 0.508)
			(layers "F.Cu" "F.Mask" "F.Paste")
			(net "P3V3_STB_NODE1")
		)
		(pad "2" smd rect
			(at -0.40005 0 270)
			(size 0.4572 0.508)
			(layers "F.Cu" "F.Mask" "F.Paste")
			(net "PWRGD_NODE1_PVDDR_STB_PG")
		)
	)
	(footprint ""
		(layer "F.Cu")
		(at 63.177166 -96.709992 90)
		(property "Reference" "R104"
			(at -54.98719 28.497276 90)
			(unlocked yes)
			(layer "F.SilkS")
			(effects
				(font
					(size 0.7874 0.5842)
					(thickness 0.1524)
				)
				(justify left)
			)
		)
		(property "Value" ""
			(at 0 0 90)
			(layer "F.Fab")
			(effects
				(font
					(size 1.27 1.27)
				)
			)
		)
		(duplicate_pad_numbers_are_jumpers no)
		(fp_line
			(start 0.7874 -0.4064)
			(end 0.7874 0.4064)
			(stroke
				(width 0.1524)
				(type default)
			)
			(layer "F.SilkS")
		)
		(fp_line
			(start -0.7874 -0.4064)
			(end 0.7874 -0.4064)
			(stroke
				(width 0.1524)
				(type default)
			)
			(layer "F.SilkS")
		)
		(fp_line
			(start 0.7874 0.4064)
			(end -0.7874 0.4064)
			(stroke
				(width 0.1524)
				(type default)
			)
			(layer "F.SilkS")
		)
		(fp_line
			(start -0.7874 0.4064)
			(end -0.7874 -0.4064)
			(stroke
				(width 0.1524)
				(type default)
			)
			(layer "F.SilkS")
		)
		(fp_poly
			(pts
				(xy -0.508 0.2794) (xy -0.508 0.2286) (xy -0.635 0.2286) (xy -0.635 -0.254) (xy -0.5334 -0.254)
				(xy -0.5334 -0.2794) (xy 0.5334 -0.2794) (xy 0.5334 -0.254) (xy 0.635 -0.254) (xy 0.635 0.254) (xy 0.5334 0.254)
				(xy 0.5334 0.2794)
			)
			(stroke
				(width 0)
				(type default)
			)
			(fill no)
			(layer "F.CrtYd")
		)
		(pad "1" smd rect
			(at 0.40005 0 90)
			(size 0.4572 0.508)
			(layers "F.Cu" "F.Mask" "F.Paste")
			(net "GND")
		)
		(pad "2" smd rect
			(at -0.40005 0 90)
			(size 0.4572 0.508)
			(layers "F.Cu" "F.Mask" "F.Paste")
			(net "A_CPU_NODE1_NTB_CROSSLK_MODE")
		)
	)
	(footprint ""
		(layer "F.Cu")
		(at 137.65276 -188.126624 90)
		(property "Reference" "C645"
			(at 5.519674 -0.070612 90)
			(unlocked yes)
			(layer "F.SilkS")
			(effects
				(font
					(size 0.7874 0.5842)
					(thickness 0.1524)
				)
				(justify left)
			)
		)
		(property "Value" ""
			(at 0 0 90)
			(layer "F.Fab")
			(effects
				(font
					(size 1.27 1.27)
				)
			)
		)
		(duplicate_pad_numbers_are_jumpers no)
		(fp_line
			(start 0.7874 -0.4064)
			(end 0.7874 0.4064)
			(stroke
				(width 0.1524)
				(type default)
			)
			(layer "F.SilkS")
		)
		(fp_line
			(start -0.7874 -0.4064)
			(end 0.7874 -0.4064)
			(stroke
				(width 0.1524)
				(type default)
			)
			(layer "F.SilkS")
		)
		(fp_line
			(start 0 0.381)
			(end 0 -0.381)
			(stroke
				(width 0.1524)
				(type default)
			)
			(layer "F.SilkS")
		)
		(fp_line
			(start 0.7874 0.4064)
			(end -0.7874 0.4064)
			(stroke
				(width 0.1524)
				(type default)
			)
			(layer "F.SilkS")
		)
		(fp_line
			(start -0.7874 0.4064)
			(end -0.7874 -0.4064)
			(stroke
				(width 0.1524)
				(type default)
			)
			(layer "F.SilkS")
		)
		(fp_poly
			(pts
				(xy -0.5334 0.254) (xy -0.635 0.254) (xy -0.635 0.2286) (xy -0.635 -0.254) (xy -0.5334 -0.254) (xy -0.5334 -0.2794)
				(xy 0.5334 -0.2794) (xy 0.5334 -0.254) (xy 0.635 -0.254) (xy 0.635 0.254) (xy 0.5334 0.254) (xy 0.5334 0.2794)
				(xy -0.508 0.2794) (xy -0.5334 0.2794)
			)
			(stroke
				(width 0)
				(type default)
			)
			(fill no)
			(layer "F.CrtYd")
		)
		(pad "1" smd rect
			(at 0.40005 0 90)
			(size 0.4572 0.508)
			(layers "F.Cu" "F.Mask" "F.Paste")
			(net "T10_NODE4_EN_R")
		)
		(pad "2" smd rect
			(at -0.40005 0 90)
			(size 0.4572 0.508)
			(layers "F.Cu" "F.Mask" "F.Paste")
			(net "GND")
		)
	)
	(footprint ""
		(layer "F.Cu")
		(at 95.113094 -139.085066 180)
		(property "Reference" "R1085"
			(at 1.865122 4.096766 0)
			(unlocked yes)
			(layer "F.SilkS")
			(effects
				(font
					(size 0.7874 0.5842)
					(thickness 0.1524)
				)
				(justify left)
			)
		)
		(property "Value" ""
			(at 0 0 180)
			(layer "F.Fab")
			(effects
				(font
					(size 1.27 1.27)
				)
			)
		)
		(duplicate_pad_numbers_are_jumpers no)
		(fp_line
			(start 0.7874 0.4064)
			(end -0.7874 0.4064)
			(stroke
				(width 0.1524)
				(type default)
			)
			(layer "F.SilkS")
		)
		(fp_line
			(start 0.7874 -0.4064)
			(end 0.7874 0.4064)
			(stroke
				(width 0.1524)
				(type default)
			)
			(layer "F.SilkS")
		)
		(fp_line
			(start -0.7874 0.4064)
			(end -0.7874 -0.4064)
			(stroke
				(width 0.1524)
				(type default)
			)
			(layer "F.SilkS")
		)
		(fp_line
			(start -0.7874 -0.4064)
			(end 0.7874 -0.4064)
			(stroke
				(width 0.1524)
				(type default)
			)
			(layer "F.SilkS")
		)
		(fp_poly
			(pts
				(xy -0.508 0.2794) (xy -0.508 0.2286) (xy -0.635 0.2286) (xy -0.635 -0.254) (xy -0.5334 -0.254)
				(xy -0.5334 -0.2794) (xy 0.5334 -0.2794) (xy 0.5334 -0.254) (xy 0.635 -0.254) (xy 0.635 0.254) (xy 0.5334 0.254)
				(xy 0.5334 0.2794)
			)
			(stroke
				(width 0)
				(type default)
			)
			(fill no)
			(layer "F.CrtYd")
		)
		(pad "1" smd rect
			(at 0.40005 0 180)
			(size 0.4572 0.508)
			(layers "F.Cu" "F.Mask" "F.Paste")
			(net "P1V05_SUS_NODE1_ADJ")
		)
		(pad "2" smd rect
			(at -0.40005 0 180)
			(size 0.4572 0.508)
			(layers "F.Cu" "F.Mask" "F.Paste")
			(net "P1V05_SUS_NODE1_ADJ_S")
		)
	)
	(footprint ""
		(layer "F.Cu")
		(at 31.655512 -185.390536 -90)
		(property "Reference" "C780"
			(at -4.83616 4.312412 90)
			(unlocked yes)
			(layer "F.SilkS")
			(effects
				(font
					(size 0.7874 0.5842)
					(thickness 0.1524)
				)
			)
		)
		(property "Value" ""
			(at 0 0 270)
			(layer "F.Fab")
			(effects
				(font
					(size 1.27 1.27)
				)
			)
		)
		(duplicate_pad_numbers_are_jumpers no)
		(fp_line
			(start -1.2954 0.5842)
			(end -1.2954 -0.5842)
			(stroke
				(width 0.1524)
				(type default)
			)
			(layer "F.SilkS")
		)
		(fp_line
			(start 1.2954 0.5842)
			(end -1.2954 0.5842)
			(stroke
				(width 0.1524)
				(type default)
			)
			(layer "F.SilkS")
		)
		(fp_line
			(start -1.2954 -0.5842)
			(end 1.2954 -0.5842)
			(stroke
				(width 0.1524)
				(type default)
			)
			(layer "F.SilkS")
		)
		(fp_line
			(start 0 -0.5842)
			(end 0 0.5842)
			(stroke
				(width 0.1524)
				(type default)
			)
			(layer "F.SilkS")
		)
		(fp_line
			(start 1.2954 -0.5842)
			(end 1.2954 0.5842)
			(stroke
				(width 0.1524)
				(type default)
			)
			(layer "F.SilkS")
		)
		(fp_poly
			(pts
				(xy 0.8636 -0.4572) (xy 0.8636 -0.3556) (xy 1.143 -0.3556) (xy 1.143 0.3556) (xy 0.8636 0.3556)
				(xy 0.8636 0.4572) (xy -0.8636 0.4572) (xy -0.8636 0.3556) (xy -1.143 0.3556) (xy -1.143 -0.3556)
				(xy -0.8636 -0.3556) (xy -0.8636 -0.4572)
			)
			(stroke
				(width 0)
				(type default)
			)
			(fill no)
			(layer "F.CrtYd")
		)
		(fp_line
			(start -0.884936 0.504952)
			(end -0.884936 -0.504952)
			(stroke
				(width 0.1)
				(type default)
			)
			(layer "F.Fab")
		)
		(fp_line
			(start 0.884936 0.504952)
			(end -0.884936 0.504952)
			(stroke
				(width 0.1)
				(type default)
			)
			(layer "F.Fab")
		)
		(fp_line
			(start -0.884936 -0.504952)
			(end 0.884936 -0.504952)
			(stroke
				(width 0.1)
				(type default)
			)
			(layer "F.Fab")
		)
		(fp_line
			(start 0.884936 -0.504952)
			(end 0.884936 0.504952)
			(stroke
				(width 0.1)
				(type default)
			)
			(layer "F.Fab")
		)
		(pad "1" smd rect
			(at 0.7366 0)
			(size 0.7112 0.8128)
			(layers "F.Cu" "F.Mask" "F.Paste")
			(net "VR_HSC_NODE1_TIMER")
		)
		(pad "2" smd rect
			(at -0.7366 0)
			(size 0.7112 0.8128)
			(layers "F.Cu" "F.Mask" "F.Paste")
			(net "AGND_HSC_NODE1")
		)
	)
	(footprint ""
		(layer "F.Cu")
		(at 72.500998 -13.02766 180)
		(property "Reference" "PC45"
			(at -2.854198 -1.762506 0)
			(unlocked yes)
			(layer "F.SilkS")
			(effects
				(font
					(size 0.7874 0.5842)
					(thickness 0.1524)
				)
				(justify left)
			)
		)
		(property "Value" ""
			(at 0 0 180)
			(layer "F.Fab")
			(effects
				(font
					(size 1.27 1.27)
				)
			)
		)
		(duplicate_pad_numbers_are_jumpers no)
		(fp_line
			(start 2.2098 0.9398)
			(end -2.2098 0.9398)
			(stroke
				(width 0.1524)
				(type default)
			)
			(layer "F.SilkS")
		)
		(fp_line
			(start 2.2098 -0.9398)
			(end 2.2098 0.9398)
			(stroke
				(width 0.1524)
				(type default)
			)
			(layer "F.SilkS")
		)
		(fp_line
			(start 0 -0.9398)
			(end 0 0.9398)
			(stroke
				(width 0.1524)
				(type default)
			)
			(layer "F.SilkS")
		)
		(fp_line
			(start -2.2098 0.9398)
			(end -2.2098 -0.9398)
			(stroke
				(width 0.1524)
				(type default)
			)
			(layer "F.SilkS")
		)
		(fp_line
			(start -2.2098 -0.9398)
			(end 2.2098 -0.9398)
			(stroke
				(width 0.1524)
				(type default)
			)
			(layer "F.SilkS")
		)
		(fp_poly
			(pts
				(xy -1.6764 0.889) (xy -1.6764 0.7874) (xy -2.0574 0.7874) (xy -2.0574 -0.7874) (xy -1.6764 -0.7874)
				(xy -1.6764 -0.9398) (xy 1.6764 -0.9398) (xy 1.6764 -0.7874) (xy 2.0574 -0.7874) (xy 2.0574 0.7874)
				(xy 1.6764 0.7874) (xy 1.6764 0.9398) (xy -1.6764 0.9398)
			)
			(stroke
				(width 0)
				(type default)
			)
			(fill no)
			(layer "F.CrtYd")
		)
		(fp_line
			(start 1.700022 0.899922)
			(end -1.700022 0.899922)
			(stroke
				(width 0.1)
				(type default)
			)
			(layer "F.Fab")
		)
		(fp_line
			(start 1.700022 -0.899922)
			(end 1.700022 0.899922)
			(stroke
				(width 0.1)
				(type default)
			)
			(layer "F.Fab")
		)
		(fp_line
			(start -1.700022 0.899922)
			(end -1.700022 -0.899922)
			(stroke
				(width 0.1)
				(type default)
			)
			(layer "F.Fab")
		)
		(fp_line
			(start -1.700022 -0.899922)
			(end 1.700022 -0.899922)
			(stroke
				(width 0.1)
				(type default)
			)
			(layer "F.Fab")
		)
		(pad "1" smd rect
			(at 1.4732 0 180)
			(size 1.1684 1.5748)
			(layers "F.Cu" "F.Mask" "F.Paste")
			(net "P12V_AUX")
		)
		(pad "2" smd rect
			(at -1.4732 0 180)
			(size 1.1684 1.5748)
			(layers "F.Cu" "F.Mask" "F.Paste")
			(net "GND")
		)
	)
	(footprint ""
		(layer "F.Cu")
		(at 103.329994 -115.01882 180)
		(property "Reference" "PC117"
			(at 5.918454 -0.029972 0)
			(unlocked yes)
			(layer "F.SilkS")
			(effects
				(font
					(size 0.7874 0.5842)
					(thickness 0.1524)
				)
				(justify left)
			)
		)
		(property "Value" ""
			(at 0 0 180)
			(layer "F.Fab")
			(effects
				(font
					(size 1.27 1.27)
				)
			)
		)
		(duplicate_pad_numbers_are_jumpers no)
		(fp_line
			(start 1.905 0.8636)
			(end -1.905 0.8636)
			(stroke
				(width 0.1524)
				(type default)
			)
			(layer "F.SilkS")
		)
		(fp_line
			(start 1.905 -0.8636)
			(end 1.905 0.8636)
			(stroke
				(width 0.1524)
				(type default)
			)
			(layer "F.SilkS")
		)
		(fp_line
			(start 0 0.8382)
			(end 0 -0.8382)
			(stroke
				(width 0.1524)
				(type default)
			)
			(layer "F.SilkS")
		)
		(fp_line
			(start -1.905 0.8636)
			(end -1.905 -0.8636)
			(stroke
				(width 0.1524)
				(type default)
			)
			(layer "F.SilkS")
		)
		(fp_line
			(start -1.905 -0.8636)
			(end 1.905 -0.8636)
			(stroke
				(width 0.1524)
				(type default)
			)
			(layer "F.SilkS")
		)
		(fp_rect
			(start -1.524 0.7366)
			(end 1.524 -0.7366)
			(stroke
				(width 0)
				(type default)
			)
			(fill no)
			(layer "F.CrtYd")
		)
		(pad "1" smd rect
			(at 0.94996 0 180)
			(size 1.1176 1.3716)
			(layers "F.Cu" "F.Mask" "F.Paste")
			(net "GND")
		)
		(pad "2" smd rect
			(at -0.94996 0 180)
			(size 1.1176 1.3716)
			(layers "F.Cu" "F.Mask" "F.Paste")
			(net "PV_VCCP_NODE1")
		)
	)
	(footprint ""
		(layer "F.Cu")
		(at 126.22276 -185.205624 -90)
		(property "Reference" "R974"
			(at -4.675632 0.173228 90)
			(unlocked yes)
			(layer "F.SilkS")
			(effects
				(font
					(size 0.7874 0.5842)
					(thickness 0.1524)
				)
				(justify left)
			)
		)
		(property "Value" ""
			(at 0 0 270)
			(layer "F.Fab")
			(effects
				(font
					(size 1.27 1.27)
				)
			)
		)
		(duplicate_pad_numbers_are_jumpers no)
		(fp_line
			(start -0.7874 0.4064)
			(end -0.7874 -0.4064)
			(stroke
				(width 0.1524)
				(type default)
			)
			(layer "F.SilkS")
		)
		(fp_line
			(start 0.7874 0.4064)
			(end -0.7874 0.4064)
			(stroke
				(width 0.1524)
				(type default)
			)
			(layer "F.SilkS")
		)
		(fp_line
			(start -0.7874 -0.4064)
			(end 0.7874 -0.4064)
			(stroke
				(width 0.1524)
				(type default)
			)
			(layer "F.SilkS")
		)
		(fp_line
			(start 0.7874 -0.4064)
			(end 0.7874 0.4064)
			(stroke
				(width 0.1524)
				(type default)
			)
			(layer "F.SilkS")
		)
		(fp_poly
			(pts
				(xy -0.508 0.2794) (xy -0.508 0.2286) (xy -0.635 0.2286) (xy -0.635 -0.254) (xy -0.5334 -0.254)
				(xy -0.5334 -0.2794) (xy 0.5334 -0.2794) (xy 0.5334 -0.254) (xy 0.635 -0.254) (xy 0.635 0.254) (xy 0.5334 0.254)
				(xy 0.5334 0.2794)
			)
			(stroke
				(width 0)
				(type default)
			)
			(fill no)
			(layer "F.CrtYd")
		)
		(pad "1" smd rect
			(at 0.40005 0 270)
			(size 0.4572 0.508)
			(layers "F.Cu" "F.Mask" "F.Paste")
			(net "UART_T9_NODE4_RXD")
		)
		(pad "2" smd rect
			(at -0.40005 0 270)
			(size 0.4572 0.508)
			(layers "F.Cu" "F.Mask" "F.Paste")
			(net "UART_T9_NODE4_RXD_R")
		)
	)
	(footprint ""
		(layer "F.Cu")
		(at 103.1621 -129.745994 180)
		(property "Reference" "PJ16"
			(at 6.798818 -4.947158 90)
			(unlocked yes)
			(layer "F.SilkS")
			(effects
				(font
					(size 0.7874 0.5842)
					(thickness 0.1524)
				)
				(justify left)
			)
		)
		(property "Value" ""
			(at 0 0 180)
			(layer "F.Fab")
			(effects
				(font
					(size 1.27 1.27)
				)
			)
		)
		(duplicate_pad_numbers_are_jumpers no)
		(fp_poly
			(pts
				(xy 0.2794 0.907796) (xy 0.254 0.907796) (xy 0.254 1.0414) (xy -0.254 1.0414) (xy -0.254 1.034796)
				(xy -0.254 0.933196) (xy -0.2794 0.933196) (xy -0.2794 -0.133604) (xy -0.254 -0.133604) (xy -0.254 -0.235204)
				(xy 0.254 -0.235204) (xy 0.254 -0.133604) (xy 0.2794 -0.133604)
			)
			(stroke
				(width 0)
				(type default)
			)
			(fill no)
			(layer "F.CrtYd")
		)
		(pad "1" smd custom
			(at 0 -0.000254 180)
			(size 0.127 0.127)
			(layers "F.Cu" "F.Mask" "F.Paste")
			(net "FM_CPLD_NODE1_PVCCP_EN")
			(options
				(clearance outline)
				(anchor circle)
			)
			(primitives
				(gr_poly
					(pts
						(xy -0.127 0.508) (xy -0.127 -0.0508) (xy -0.254 -0.0508) (xy -0.254 -0.508) (xy 0.254 -0.508)
						(xy 0.254 -0.0508) (xy 0.127 -0.0508) (xy 0.127 0.508)
					)
					(width 0)
					(fill yes)
				)
			)
		)
		(pad "2" smd rect
			(at 0 0.799846 270)
			(size 0.4572 0.508)
			(layers "F.Cu" "F.Mask" "F.Paste")
			(net "VR_PVCCP_NODE1_EN")
		)
		(zone
			(layer "F.Cu")
			(hatch none 0.5)
			(connect_pads
				(clearance 0)
			)
			(min_thickness 0.25)
			(keepout
				(tracks allowed)
				(vias not_allowed)
				(pads allowed)
				(copperpour not_allowed)
				(footprints allowed)
			)
			(placement
				(enabled no)
				(sheetname "")
			)
			(fill
				(thermal_gap 0.5)
				(thermal_bridge_width 0.5)
				(island_removal_mode 0)
			)
			(polygon
				(pts
					(xy 103.4669 -130.83159) (xy 102.8573 -130.83159) (xy 102.8573 -129.45999) (xy 103.4669 -129.45999)
				)
			)
		)
	)
	(footprint ""
		(layer "F.Cu")
		(at 70.097396 -6.446266)
		(property "Reference" "PU5"
			(at 2.031746 3.663188 90)
			(unlocked yes)
			(layer "F.SilkS")
			(effects
				(font
					(size 0.7874 0.5842)
					(thickness 0.1524)
				)
				(justify left)
			)
		)
		(property "Value" ""
			(at 0 0 0)
			(layer "F.Fab")
			(effects
				(font
					(size 1.27 1.27)
				)
			)
		)
		(duplicate_pad_numbers_are_jumpers no)
		(fp_line
			(start -1.575054 -1.575054)
			(end -1.575054 -1.0414)
			(stroke
				(width 0.1524)
				(type default)
			)
			(layer "F.SilkS")
		)
		(fp_line
			(start -1.575054 1.0922)
			(end -1.575054 1.575054)
			(stroke
				(width 0.1524)
				(type default)
			)
			(layer "F.SilkS")
		)
		(fp_line
			(start -1.575054 1.575054)
			(end -1.0922 1.575054)
			(stroke
				(width 0.1524)
				(type default)
			)
			(layer "F.SilkS")
		)
		(fp_line
			(start -1.0668 -1.575054)
			(end -1.575054 -1.575054)
			(stroke
				(width 0.1524)
				(type default)
			)
			(layer "F.SilkS")
		)
		(fp_line
			(start -0.750062 2.043938)
			(end -0.750062 2.348738)
			(stroke
				(width 0.1524)
				(type default)
			)
			(layer "F.SilkS")
		)
		(fp_line
			(start -0.255778 -2.350262)
			(end -0.255778 -2.045462)
			(stroke
				(width 0.1524)
				(type default)
			)
			(layer "F.SilkS")
		)
		(fp_line
			(start 1.0414 1.575054)
			(end 1.575054 1.575054)
			(stroke
				(width 0.1524)
				(type default)
			)
			(layer "F.SilkS")
		)
		(fp_line
			(start 1.575054 -1.575054)
			(end 1.0414 -1.575054)
			(stroke
				(width 0.1524)
				(type default)
			)
			(layer "F.SilkS")
		)
		(fp_line
			(start 1.575054 -1.0668)
			(end 1.575054 -1.575054)
			(stroke
				(width 0.1524)
				(type default)
			)
			(layer "F.SilkS")
		)
		(fp_line
			(start 1.575054 1.575054)
			(end 1.575054 1.143)
			(stroke
				(width 0.1524)
				(type default)
			)
			(layer "F.SilkS")
		)
		(fp_line
			(start 2.055622 0.25019)
			(end 2.563622 0.25019)
			(stroke
				(width 0.1524)
				(type default)
			)
			(layer "F.SilkS")
		)
		(fp_poly
			(pts
				(xy -1.687576 -1.074166) (xy -2.22504 -2.14884) (xy -2.76225 -1.611376)
			)
			(stroke
				(width 0)
				(type default)
			)
			(fill yes)
			(layer "F.SilkS")
		)
		(fp_poly
			(pts
				(xy -1.575054 1.575054) (xy -0.9398 1.575054) (xy -0.9398 1.9558) (xy 0.9398 1.9558) (xy 0.9398 1.575054)
				(xy 1.575054 1.575054) (xy 1.575054 0.9398) (xy 1.9558 0.9398) (xy 1.9558 -0.9398) (xy 1.575054 -0.9398)
				(xy 1.575054 -1.575054) (xy 0.9398 -1.575054) (xy 0.9398 -1.9558) (xy -0.9398 -1.9558) (xy -0.9398 -1.575054)
				(xy -1.575054 -1.575054) (xy -1.575054 -0.9398) (xy -1.9558 -0.9398) (xy -1.9558 0.9398) (xy -1.575054 0.9398)
			)
			(stroke
				(width 0)
				(type default)
			)
			(fill no)
			(layer "F.CrtYd")
		)
		(fp_line
			(start -1.575054 -1.575054)
			(end 1.575054 -1.575054)
			(stroke
				(width 0.1)
				(type default)
			)
			(layer "F.Fab")
		)
		(fp_line
			(start -1.575054 1.575054)
			(end -1.575054 -1.575054)
			(stroke
				(width 0.1)
				(type default)
			)
			(layer "F.Fab")
		)
		(fp_line
			(start -0.750062 2.043938)
			(end -0.750062 2.348738)
			(stroke
				(width 0.1)
				(type default)
			)
			(layer "F.Fab")
		)
		(fp_line
			(start -0.255778 -2.350262)
			(end -0.255778 -2.045462)
			(stroke
				(width 0.1)
				(type default)
			)
			(layer "F.Fab")
		)
		(fp_line
			(start 1.575054 -1.575054)
			(end 1.575054 1.575054)
			(stroke
				(width 0.1)
				(type default)
			)
			(layer "F.Fab")
		)
		(fp_line
			(start 1.575054 1.575054)
			(end -1.575054 1.575054)
			(stroke
				(width 0.1)
				(type default)
			)
			(layer "F.Fab")
		)
		(fp_line
			(start 2.055622 0.25019)
			(end 2.563622 0.25019)
			(stroke
				(width 0.1)
				(type default)
			)
			(layer "F.Fab")
		)
		(fp_poly
			(pts
				(xy -2.100072 -0.750062) (xy -3.240024 -1.130046) (xy -3.240024 -0.370078)
			)
			(stroke
				(width 0)
				(type default)
			)
			(fill yes)
			(layer "F.Fab")
		)
		(fp_text user "16"
			(at -2.035048 -1.936496 0)
			(unlocked yes)
			(layer "F.SilkS")
			(effects
				(font
					(size 0.635 0.4064)
					(thickness 0.1524)
				)
				(justify left)
			)
		)
		(fp_text user "5"
			(at -1.464056 2.126234 0)
			(unlocked yes)
			(layer "F.SilkS")
			(effects
				(font
					(size 0.635 0.4064)
					(thickness 0.1524)
				)
				(justify left)
			)
		)
		(fp_text user "12"
			(at 1.406652 -1.996948 0)
			(unlocked yes)
			(layer "F.SilkS")
			(effects
				(font
					(size 0.635 0.4064)
					(thickness 0.1524)
				)
				(justify left)
			)
		)
		(fp_text user "9"
			(at 1.902206 0.8128 0)
			(unlocked yes)
			(layer "F.SilkS")
			(effects
				(font
					(size 0.635 0.4064)
					(thickness 0.1524)
				)
				(justify left)
			)
		)
		(fp_text user "16"
			(at -2.457958 -2.225675 0)
			(unlocked yes)
			(layer "F.Fab")
			(effects
				(font
					(size 0.78994 0.579882)
					(thickness 0.000001)
				)
				(justify left)
			)
		)
		(fp_text user "5"
			(at -1.737868 2.295525 0)
			(unlocked yes)
			(layer "F.Fab")
			(effects
				(font
					(size 0.78994 0.579882)
					(thickness 0.000001)
				)
				(justify left)
			)
		)
		(fp_text user "12"
			(at 1.708912 -1.514475 0)
			(unlocked yes)
			(layer "F.Fab")
			(effects
				(font
					(size 0.78994 0.579882)
					(thickness 0.000001)
				)
				(justify left)
			)
		)
		(fp_text user "9"
			(at 1.767586 1.584325 0)
			(unlocked yes)
			(layer "F.Fab")
			(effects
				(font
					(size 0.78994 0.579882)
					(thickness 0.000001)
				)
				(justify left)
			)
		)
		(pad "1" smd rect
			(at -1.474978 -0.750062 90)
			(size 0.254 0.8382)
			(layers "F.Cu" "F.Mask" "F.Paste")
			(net "P3V3_NODE1_FB")
		)
		(pad "2" smd rect
			(at -1.474978 -0.249936 90)
			(size 0.254 0.8382)
			(layers "F.Cu" "F.Mask" "F.Paste")
			(net "P3V3_NODE1_VREG5")
		)
		(pad "3" smd rect
			(at -1.474978 0.249936 90)
			(size 0.254 0.8382)
			(layers "F.Cu" "F.Mask" "F.Paste")
			(net "P3V3_NODE1_SS")
		)
		(pad "4" smd rect
			(at -1.474978 0.750062 90)
			(size 0.254 0.8382)
			(layers "F.Cu" "F.Mask" "F.Paste")
			(net "GND")
		)
		(pad "5" smd rect
			(at -0.750062 1.474978)
			(size 0.254 0.8382)
			(layers "F.Cu" "F.Mask" "F.Paste")
			(net "PWRGD_NODE1_P3V3_PG")
		)
		(pad "6" smd rect
			(at -0.249936 1.474978)
			(size 0.254 0.8382)
			(layers "F.Cu" "F.Mask" "F.Paste")
			(net "FM_CPLD_NODE1_P3V3_S_EN")
		)
		(pad "7" smd rect
			(at 0.249936 1.474978)
			(size 0.254 0.8382)
			(layers "F.Cu" "F.Mask" "F.Paste")
			(net "GND")
		)
		(pad "8" smd rect
			(at 0.750062 1.474978)
			(size 0.254 0.8382)
			(layers "F.Cu" "F.Mask" "F.Paste")
			(net "GND")
		)
		(pad "9" smd rect
			(at 1.474978 0.750062 90)
			(size 0.254 0.8382)
			(layers "F.Cu" "F.Mask" "F.Paste")
			(net "SW_P3V3_NODE1_PH")
		)
		(pad "10" smd rect
			(at 1.474978 0.249936 90)
			(size 0.254 0.8382)
			(layers "F.Cu" "F.Mask" "F.Paste")
			(net "SW_P3V3_NODE1_PH")
		)
		(pad "11" smd rect
			(at 1.474978 -0.249936 90)
			(size 0.254 0.8382)
			(layers "F.Cu" "F.Mask" "F.Paste")
			(net "SW_P3V3_NODE1_PH")
		)
		(pad "12" smd rect
			(at 1.474978 -0.750062 90)
			(size 0.254 0.8382)
			(layers "F.Cu" "F.Mask" "F.Paste")
			(net "SW_P3V3_NODE1_BT")
		)
		(pad "13" smd rect
			(at 0.750062 -1.474978)
			(size 0.254 0.8382)
			(layers "F.Cu" "F.Mask" "F.Paste")
			(net "P12V_AUX")
		)
		(pad "14" smd rect
			(at 0.249936 -1.474978)
			(size 0.254 0.8382)
			(layers "F.Cu" "F.Mask" "F.Paste")
			(net "P12V_AUX")
		)
		(pad "15" smd rect
			(at -0.249936 -1.474978)
			(size 0.254 0.8382)
			(layers "F.Cu" "F.Mask" "F.Paste")
			(net "P5V_STB_NODE1")
		)
		(pad "16" smd rect
			(at -0.750062 -1.474978)
			(size 0.254 0.8382)
			(layers "F.Cu" "F.Mask" "F.Paste")
			(net "P3V3_NODE1")
		)
		(pad "TH" smd rect
			(at 0 0 90)
			(size 1.7018 1.7018)
			(layers "F.Cu" "F.Mask" "F.Paste")
			(net "GND")
		)
		(zone
			(layer "F.Cu")
			(hatch none 0.5)
			(connect_pads
				(clearance 0)
			)
			(min_thickness 0.25)
			(keepout
				(tracks allowed)
				(vias not_allowed)
				(pads allowed)
				(copperpour not_allowed)
				(footprints allowed)
			)
			(placement
				(enabled no)
				(sheetname "")
			)
			(fill
				(thermal_gap 0.5)
				(thermal_bridge_width 0.5)
				(island_removal_mode 0)
			)
			(polygon
				(pts
					(xy 69.106796 -7.436866) (xy 71.087996 -7.436866) (xy 71.087996 -5.455666) (xy 69.106796 -5.455666)
					(xy 69.106796 -5.531866) (xy 71.011796 -5.531866) (xy 71.011796 -7.360666) (xy 69.182996 -7.360666)
					(xy 69.182996 -5.557266) (xy 69.106796 -5.557266)
				)
			)
		)
	)
	(footprint ""
		(layer "F.Cu")
		(at 38.004242 -174.634906)
		(property "Reference" "C771"
			(at -2.461768 1.909318 0)
			(unlocked yes)
			(layer "F.SilkS")
			(effects
				(font
					(size 0.7874 0.5842)
					(thickness 0.1524)
				)
				(justify left)
			)
		)
		(property "Value" ""
			(at 0 0 0)
			(layer "F.Fab")
			(effects
				(font
					(size 1.27 1.27)
				)
			)
		)
		(duplicate_pad_numbers_are_jumpers no)
		(fp_line
			(start -2.2098 -0.9398)
			(end 2.2098 -0.9398)
			(stroke
				(width 0.1524)
				(type default)
			)
			(layer "F.SilkS")
		)
		(fp_line
			(start -2.2098 0.9398)
			(end -2.2098 -0.9398)
			(stroke
				(width 0.1524)
				(type default)
			)
			(layer "F.SilkS")
		)
		(fp_line
			(start 0 -0.9398)
			(end 0 0.9398)
			(stroke
				(width 0.1524)
				(type default)
			)
			(layer "F.SilkS")
		)
		(fp_line
			(start 2.2098 -0.9398)
			(end 2.2098 0.9398)
			(stroke
				(width 0.1524)
				(type default)
			)
			(layer "F.SilkS")
		)
		(fp_line
			(start 2.2098 0.9398)
			(end -2.2098 0.9398)
			(stroke
				(width 0.1524)
				(type default)
			)
			(layer "F.SilkS")
		)
		(fp_poly
			(pts
				(xy -1.6764 0.889) (xy -1.6764 0.7874) (xy -2.0574 0.7874) (xy -2.0574 -0.7874) (xy -1.6764 -0.7874)
				(xy -1.6764 -0.9398) (xy 1.6764 -0.9398) (xy 1.6764 -0.7874) (xy 2.0574 -0.7874) (xy 2.0574 0.7874)
				(xy 1.6764 0.7874) (xy 1.6764 0.9398) (xy -1.6764 0.9398)
			)
			(stroke
				(width 0)
				(type default)
			)
			(fill no)
			(layer "F.CrtYd")
		)
		(fp_line
			(start -1.700022 -0.899922)
			(end 1.700022 -0.899922)
			(stroke
				(width 0.1)
				(type default)
			)
			(layer "F.Fab")
		)
		(fp_line
			(start -1.700022 0.899922)
			(end -1.700022 -0.899922)
			(stroke
				(width 0.1)
				(type default)
			)
			(layer "F.Fab")
		)
		(fp_line
			(start 1.700022 -0.899922)
			(end 1.700022 0.899922)
			(stroke
				(width 0.1)
				(type default)
			)
			(layer "F.Fab")
		)
		(fp_line
			(start 1.700022 0.899922)
			(end -1.700022 0.899922)
			(stroke
				(width 0.1)
				(type default)
			)
			(layer "F.Fab")
		)
		(pad "1" smd rect
			(at 1.4732 0)
			(size 1.1684 1.5748)
			(layers "F.Cu" "F.Mask" "F.Paste")
			(net "P12V_AUX")
		)
		(pad "2" smd rect
			(at -1.4732 0)
			(size 1.1684 1.5748)
			(layers "F.Cu" "F.Mask" "F.Paste")
			(net "GND")
		)
	)
	(footprint ""
		(layer "F.Cu")
		(at 129.45618 -185.180732 -90)
		(property "Reference" "R971"
			(at -4.535678 -0.381 90)
			(unlocked yes)
			(layer "F.SilkS")
			(effects
				(font
					(size 0.7874 0.5842)
					(thickness 0.1524)
				)
				(justify left)
			)
		)
		(property "Value" ""
			(at 0 0 270)
			(layer "F.Fab")
			(effects
				(font
					(size 1.27 1.27)
				)
			)
		)
		(duplicate_pad_numbers_are_jumpers no)
		(fp_line
			(start -0.7874 0.4064)
			(end -0.7874 -0.4064)
			(stroke
				(width 0.1524)
				(type default)
			)
			(layer "F.SilkS")
		)
		(fp_line
			(start 0.7874 0.4064)
			(end -0.7874 0.4064)
			(stroke
				(width 0.1524)
				(type default)
			)
			(layer "F.SilkS")
		)
		(fp_line
			(start -0.7874 -0.4064)
			(end 0.7874 -0.4064)
			(stroke
				(width 0.1524)
				(type default)
			)
			(layer "F.SilkS")
		)
		(fp_line
			(start 0.7874 -0.4064)
			(end 0.7874 0.4064)
			(stroke
				(width 0.1524)
				(type default)
			)
			(layer "F.SilkS")
		)
		(fp_poly
			(pts
				(xy -0.508 0.2794) (xy -0.508 0.2286) (xy -0.635 0.2286) (xy -0.635 -0.254) (xy -0.5334 -0.254)
				(xy -0.5334 -0.2794) (xy 0.5334 -0.2794) (xy 0.5334 -0.254) (xy 0.635 -0.254) (xy 0.635 0.254) (xy 0.5334 0.254)
				(xy 0.5334 0.2794)
			)
			(stroke
				(width 0)
				(type default)
			)
			(fill no)
			(layer "F.CrtYd")
		)
		(pad "1" smd rect
			(at 0.40005 0 270)
			(size 0.4572 0.508)
			(layers "F.Cu" "F.Mask" "F.Paste")
			(net "UART_T9_NODE3_TXD")
		)
		(pad "2" smd rect
			(at -0.40005 0 270)
			(size 0.4572 0.508)
			(layers "F.Cu" "F.Mask" "F.Paste")
			(net "UART_T9_NODE3_TXD_R")
		)
	)
	(footprint ""
		(layer "F.Cu")
		(at 94.25432 -122.323606 -90)
		(property "Reference" "TP172"
			(at 0 0 270)
			(layer "F.SilkS")
			(hide yes)
			(effects
				(font
					(size 1.27 1.27)
				)
			)
		)
		(property "Value" ""
			(at 0 0 270)
			(layer "F.Fab")
			(effects
				(font
					(size 1.27 1.27)
				)
			)
		)
		(duplicate_pad_numbers_are_jumpers no)
		(fp_poly
			(pts
				(arc
					(start 0 0.3302)
					(mid 0 -0.3302)
					(end 0 0.3302)
				)
			)
			(stroke
				(width 0)
				(type default)
			)
			(fill no)
			(layer "B.CrtYd")
		)
		(pad "1" thru_hole circle
			(at 0 0 270)
			(size 0.508 0.508)
			(drill 0.254)
			(layers "*.Cu" "*.Mask")
			(remove_unused_layers no)
			(net "N53313389")
			(clearance 0.127)
			(thermal_gap 0.127)
			(padstack
				(mode front_inner_back)
				(layer "Inner"
					(shape circle)
					(size 0.508 0.508)
					(clearance 0.127)
				)
				(layer "B.Cu"
					(shape circle)
					(size 0.6604 0.6604)
					(clearance 0.0508)
				)
			)
		)
	)
	(footprint ""
		(layer "F.Cu")
		(at 60.81776 -188.126624 90)
		(property "Reference" "C703"
			(at 4.548886 0.234442 90)
			(unlocked yes)
			(layer "F.SilkS")
			(effects
				(font
					(size 0.7874 0.5842)
					(thickness 0.1524)
				)
				(justify left)
			)
		)
		(property "Value" ""
			(at 0 0 90)
			(layer "F.Fab")
			(effects
				(font
					(size 1.27 1.27)
				)
			)
		)
		(duplicate_pad_numbers_are_jumpers no)
		(fp_line
			(start 0.7874 -0.4064)
			(end 0.7874 0.4064)
			(stroke
				(width 0.1524)
				(type default)
			)
			(layer "F.SilkS")
		)
		(fp_line
			(start -0.7874 -0.4064)
			(end 0.7874 -0.4064)
			(stroke
				(width 0.1524)
				(type default)
			)
			(layer "F.SilkS")
		)
		(fp_line
			(start 0 0.381)
			(end 0 -0.381)
			(stroke
				(width 0.1524)
				(type default)
			)
			(layer "F.SilkS")
		)
		(fp_line
			(start 0.7874 0.4064)
			(end -0.7874 0.4064)
			(stroke
				(width 0.1524)
				(type default)
			)
			(layer "F.SilkS")
		)
		(fp_line
			(start -0.7874 0.4064)
			(end -0.7874 -0.4064)
			(stroke
				(width 0.1524)
				(type default)
			)
			(layer "F.SilkS")
		)
		(fp_poly
			(pts
				(xy -0.5334 0.254) (xy -0.635 0.254) (xy -0.635 0.2286) (xy -0.635 -0.254) (xy -0.5334 -0.254) (xy -0.5334 -0.2794)
				(xy 0.5334 -0.2794) (xy 0.5334 -0.254) (xy 0.635 -0.254) (xy 0.635 0.254) (xy 0.5334 0.254) (xy 0.5334 0.2794)
				(xy -0.508 0.2794) (xy -0.5334 0.2794)
			)
			(stroke
				(width 0)
				(type default)
			)
			(fill no)
			(layer "F.CrtYd")
		)
		(pad "1" smd rect
			(at 0.40005 0 90)
			(size 0.4572 0.508)
			(layers "F.Cu" "F.Mask" "F.Paste")
			(net "UART_T2_NODE2_TXD_R")
		)
		(pad "2" smd rect
			(at -0.40005 0 90)
			(size 0.4572 0.508)
			(layers "F.Cu" "F.Mask" "F.Paste")
			(net "GND")
		)
	)
	(footprint ""
		(layer "F.Cu")
		(at 142.83436 -121.451624 -90)
		(property "Reference" "R2"
			(at -2.680716 0.023114 90)
			(unlocked yes)
			(layer "F.SilkS")
			(effects
				(font
					(size 0.7874 0.5842)
					(thickness 0.1524)
				)
			)
		)
		(property "Value" ""
			(at 0 0 270)
			(layer "F.Fab")
			(effects
				(font
					(size 1.27 1.27)
				)
			)
		)
		(duplicate_pad_numbers_are_jumpers no)
		(fp_line
			(start -1.2954 0.5842)
			(end -1.2954 -0.5842)
			(stroke
				(width 0.1524)
				(type default)
			)
			(layer "F.SilkS")
		)
		(fp_line
			(start 1.2954 0.5842)
			(end -1.2954 0.5842)
			(stroke
				(width 0.1524)
				(type default)
			)
			(layer "F.SilkS")
		)
		(fp_line
			(start -1.2954 -0.5842)
			(end 1.2954 -0.5842)
			(stroke
				(width 0.1524)
				(type default)
			)
			(layer "F.SilkS")
		)
		(fp_line
			(start 1.2954 -0.5842)
			(end 1.2954 0.5842)
			(stroke
				(width 0.1524)
				(type default)
			)
			(layer "F.SilkS")
		)
		(fp_poly
			(pts
				(xy 1.143 -0.3556) (xy 1.143 0.3556) (xy 0.8636 0.3556) (xy 0.8636 0.4572) (xy -0.8636 0.4572) (xy -0.8636 0.4318)
				(xy -0.8636 0.3556) (xy -1.143 0.3556) (xy -1.143 -0.3556) (xy -0.8636 -0.3556) (xy -0.8636 -0.4572)
				(xy 0.8636 -0.4572) (xy 0.8636 -0.3556)
			)
			(stroke
				(width 0)
				(type default)
			)
			(fill no)
			(layer "F.CrtYd")
		)
		(pad "1" smd rect
			(at 0.7366 0)
			(size 0.7112 0.8128)
			(layers "F.Cu" "F.Mask" "F.Paste")
			(net "P1V5_NODE1")
		)
		(pad "2" smd rect
			(at -0.7366 0)
			(size 0.7112 0.8128)
			(layers "F.Cu" "F.Mask" "F.Paste")
			(net "P1V5_CLK_NODE1_R")
		)
	)
	(footprint ""
		(layer "F.Cu")
		(at 109.979968 -149.245066)
		(property "Reference" "R1004"
			(at 2.195068 0.337566 0)
			(unlocked yes)
			(layer "F.SilkS")
			(effects
				(font
					(size 0.635 0.4064)
					(thickness 0.1524)
				)
				(justify left)
			)
		)
		(property "Value" ""
			(at 0 0 0)
			(layer "F.Fab")
			(effects
				(font
					(size 1.27 1.27)
				)
			)
		)
		(duplicate_pad_numbers_are_jumpers no)
		(fp_line
			(start -0.7874 -0.4064)
			(end 0.7874 -0.4064)
			(stroke
				(width 0.1524)
				(type default)
			)
			(layer "F.SilkS")
		)
		(fp_line
			(start -0.7874 0.4064)
			(end -0.7874 -0.4064)
			(stroke
				(width 0.1524)
				(type default)
			)
			(layer "F.SilkS")
		)
		(fp_line
			(start 0.7874 -0.4064)
			(end 0.7874 0.4064)
			(stroke
				(width 0.1524)
				(type default)
			)
			(layer "F.SilkS")
		)
		(fp_line
			(start 0.7874 0.4064)
			(end -0.7874 0.4064)
			(stroke
				(width 0.1524)
				(type default)
			)
			(layer "F.SilkS")
		)
		(fp_poly
			(pts
				(xy -0.508 0.2794) (xy -0.508 0.2286) (xy -0.635 0.2286) (xy -0.635 -0.254) (xy -0.5334 -0.254)
				(xy -0.5334 -0.2794) (xy 0.5334 -0.2794) (xy 0.5334 -0.254) (xy 0.635 -0.254) (xy 0.635 0.254) (xy 0.5334 0.254)
				(xy 0.5334 0.2794)
			)
			(stroke
				(width 0)
				(type default)
			)
			(fill no)
			(layer "F.CrtYd")
		)
		(pad "1" smd rect
			(at 0.40005 0)
			(size 0.4572 0.508)
			(layers "F.Cu" "F.Mask" "F.Paste")
			(net "GND")
		)
		(pad "2" smd rect
			(at -0.40005 0)
			(size 0.4572 0.508)
			(layers "F.Cu" "F.Mask" "F.Paste")
			(net "POWER_SW2_PWR_CTR_12V")
		)
	)
	(footprint ""
		(layer "F.Cu")
		(at 84.171282 -4.70662 180)
		(property "Reference" "PC49"
			(at -2.299462 -2.666746 0)
			(unlocked yes)
			(layer "F.SilkS")
			(effects
				(font
					(size 0.7874 0.5842)
					(thickness 0.1524)
				)
				(justify left)
			)
		)
		(property "Value" ""
			(at 0 0 180)
			(layer "F.Fab")
			(effects
				(font
					(size 1.27 1.27)
				)
			)
		)
		(duplicate_pad_numbers_are_jumpers no)
		(fp_line
			(start 1.905 0.8636)
			(end -1.905 0.8636)
			(stroke
				(width 0.1524)
				(type default)
			)
			(layer "F.SilkS")
		)
		(fp_line
			(start 1.905 -0.8636)
			(end 1.905 0.8636)
			(stroke
				(width 0.1524)
				(type default)
			)
			(layer "F.SilkS")
		)
		(fp_line
			(start 0 0.8382)
			(end 0 -0.8382)
			(stroke
				(width 0.1524)
				(type default)
			)
			(layer "F.SilkS")
		)
		(fp_line
			(start -1.905 0.8636)
			(end -1.905 -0.8636)
			(stroke
				(width 0.1524)
				(type default)
			)
			(layer "F.SilkS")
		)
		(fp_line
			(start -1.905 -0.8636)
			(end 1.905 -0.8636)
			(stroke
				(width 0.1524)
				(type default)
			)
			(layer "F.SilkS")
		)
		(fp_rect
			(start -1.524 0.7366)
			(end 1.524 -0.7366)
			(stroke
				(width 0)
				(type default)
			)
			(fill no)
			(layer "F.CrtYd")
		)
		(pad "1" smd rect
			(at 0.94996 0 180)
			(size 1.1176 1.3716)
			(layers "F.Cu" "F.Mask" "F.Paste")
			(net "P3V3_NODE1")
		)
		(pad "2" smd rect
			(at -0.94996 0 180)
			(size 1.1176 1.3716)
			(layers "F.Cu" "F.Mask" "F.Paste")
			(net "GND")
		)
	)
	(footprint ""
		(layer "F.Cu")
		(at 161.019998 -153.09723 -90)
		(property "Reference" "U37"
			(at 2.170176 -6.839204 90)
			(unlocked yes)
			(layer "F.SilkS")
			(effects
				(font
					(size 0.7874 0.5842)
					(thickness 0.1524)
				)
				(justify left)
			)
		)
		(property "Value" ""
			(at 0 0 270)
			(layer "F.Fab")
			(effects
				(font
					(size 1.27 1.27)
				)
			)
		)
		(duplicate_pad_numbers_are_jumpers no)
		(fp_line
			(start 0.249936 5.207)
			(end 0.249936 5.715)
			(stroke
				(width 0.1524)
				(type default)
			)
			(layer "F.SilkS")
		)
		(fp_line
			(start 2.750058 5.207)
			(end 2.750058 6.223)
			(stroke
				(width 0.1524)
				(type default)
			)
			(layer "F.SilkS")
		)
		(fp_line
			(start -4.474718 4.500118)
			(end -4.500118 4.474718)
			(stroke
				(width 0.1524)
				(type default)
			)
			(layer "F.SilkS")
		)
		(fp_line
			(start -4.0132 4.500118)
			(end -4.474718 4.500118)
			(stroke
				(width 0.1524)
				(type default)
			)
			(layer "F.SilkS")
		)
		(fp_line
			(start 4.500118 4.500118)
			(end 4.0132 4.500118)
			(stroke
				(width 0.1524)
				(type default)
			)
			(layer "F.SilkS")
		)
		(fp_line
			(start -4.500118 4.474718)
			(end -4.500118 4.0132)
			(stroke
				(width 0.1524)
				(type default)
			)
			(layer "F.SilkS")
		)
		(fp_line
			(start 4.500118 4.0386)
			(end 4.500118 4.500118)
			(stroke
				(width 0.1524)
				(type default)
			)
			(layer "F.SilkS")
		)
		(fp_line
			(start -5.207 3.24993)
			(end -5.715 3.24993)
			(stroke
				(width 0.1524)
				(type default)
			)
			(layer "F.SilkS")
		)
		(fp_line
			(start 5.207 2.750058)
			(end 5.715 2.750058)
			(stroke
				(width 0.1524)
				(type default)
			)
			(layer "F.SilkS")
		)
		(fp_line
			(start -5.207 0.750062)
			(end -6.223 0.750062)
			(stroke
				(width 0.1524)
				(type default)
			)
			(layer "F.SilkS")
		)
		(fp_line
			(start 5.207 0.249936)
			(end 6.223 0.249936)
			(stroke
				(width 0.1524)
				(type default)
			)
			(layer "F.SilkS")
		)
		(fp_line
			(start -5.207 -1.75006)
			(end -5.715 -1.75006)
			(stroke
				(width 0.1524)
				(type default)
			)
			(layer "F.SilkS")
		)
		(fp_line
			(start 5.207 -1.75006)
			(end 5.715 -1.75006)
			(stroke
				(width 0.1524)
				(type default)
			)
			(layer "F.SilkS")
		)
		(fp_line
			(start -4.487418 -4.004818)
			(end -4.004818 -4.487418)
			(stroke
				(width 0.1524)
				(type default)
			)
			(layer "F.SilkS")
		)
		(fp_line
			(start 4.0386 -4.500118)
			(end 4.500118 -4.500118)
			(stroke
				(width 0.1524)
				(type default)
			)
			(layer "F.SilkS")
		)
		(fp_line
			(start 4.500118 -4.500118)
			(end 4.500118 -4.0132)
			(stroke
				(width 0.1524)
				(type default)
			)
			(layer "F.SilkS")
		)
		(fp_line
			(start 0.750062 -5.207)
			(end 0.750062 -5.715)
			(stroke
				(width 0.1524)
				(type default)
			)
			(layer "F.SilkS")
		)
		(fp_line
			(start -1.75006 -5.2832)
			(end -1.75006 -6.2992)
			(stroke
				(width 0.1524)
				(type default)
			)
			(layer "F.SilkS")
		)
		(fp_line
			(start 3.24993 -5.2832)
			(end 3.24993 -6.2992)
			(stroke
				(width 0.1524)
				(type default)
			)
			(layer "F.SilkS")
		)
		(fp_poly
			(pts
				(xy -4.766564 -4.09067) (xy -5.448046 -5.564378) (xy -6.256274 -4.75615)
			)
			(stroke
				(width 0)
				(type default)
			)
			(fill yes)
			(layer "F.SilkS")
		)
		(fp_poly
			(pts
				(xy -4.500118 4.500118) (xy -3.8862 4.500118) (xy -3.8862 5.0292) (xy -3.8608 5.0292) (xy 3.8608 5.0292)
				(xy 3.8862 5.0292) (xy 3.8862 4.500118) (xy 4.500118 4.500118) (xy 4.500118 3.8862) (xy 5.0292 3.8862)
				(xy 5.0292 3.8608) (xy 5.0292 -3.8608) (xy 5.0292 -3.8862) (xy 4.500118 -3.8862) (xy 4.500118 -4.500118)
				(xy 3.8862 -4.500118) (xy 3.8862 -5.0292) (xy 3.8608 -5.0292) (xy -3.8608 -5.0292) (xy -3.8862 -5.0292)
				(xy -3.8862 -4.500118) (xy -4.500118 -4.500118) (xy -4.500118 -3.8862) (xy -5.0292 -3.8862) (xy -5.0292 -3.8608)
				(xy -5.0292 3.8608) (xy -5.0292 3.8862) (xy -4.500118 3.8862)
			)
			(stroke
				(width 0)
				(type default)
			)
			(fill no)
			(layer "F.CrtYd")
		)
		(fp_line
			(start -4.500118 4.500118)
			(end -4.500118 -4.500118)
			(stroke
				(width 0.1)
				(type default)
			)
			(layer "F.Fab")
		)
		(fp_line
			(start 4.500118 4.500118)
			(end -4.500118 4.500118)
			(stroke
				(width 0.1)
				(type default)
			)
			(layer "F.Fab")
		)
		(fp_line
			(start -4.500118 -4.500118)
			(end 4.500118 -4.500118)
			(stroke
				(width 0.1)
				(type default)
			)
			(layer "F.Fab")
		)
		(fp_line
			(start 4.500118 -4.500118)
			(end 4.500118 4.500118)
			(stroke
				(width 0.1)
				(type default)
			)
			(layer "F.Fab")
		)
		(fp_text user "17"
			(at -4.675124 5.771642 0)
			(unlocked yes)
			(layer "F.SilkS")
			(effects
				(font
					(size 0.635 0.4064)
					(thickness 0.1524)
				)
				(justify left)
			)
		)
		(fp_text user "32"
			(at 5.316982 5.525516 0)
			(unlocked yes)
			(layer "F.SilkS")
			(effects
				(font
					(size 0.635 0.4064)
					(thickness 0.1524)
				)
				(justify left)
			)
		)
		(fp_text user "16"
			(at -6.279388 4.348734 0)
			(unlocked yes)
			(layer "F.SilkS")
			(effects
				(font
					(size 0.635 0.4064)
					(thickness 0.1524)
				)
				(justify left)
			)
		)
		(fp_text user "33"
			(at 5.662422 3.985768 0)
			(unlocked yes)
			(layer "F.SilkS")
			(effects
				(font
					(size 0.635 0.4064)
					(thickness 0.1524)
				)
				(justify left)
			)
		)
		(fp_text user "48"
			(at 5.367782 -4.100576 0)
			(unlocked yes)
			(layer "F.SilkS")
			(effects
				(font
					(size 0.635 0.4064)
					(thickness 0.1524)
				)
				(justify left)
			)
		)
		(fp_text user "49"
			(at 4.03733 -5.404612 0)
			(unlocked yes)
			(layer "F.SilkS")
			(effects
				(font
					(size 0.635 0.4064)
					(thickness 0.1524)
				)
				(justify left)
			)
		)
		(pad "1" smd rect
			(at -4.549902 -3.750056 180)
			(size 0.254 0.9144)
			(layers "F.Cu" "F.Mask" "F.Paste")
			(net "P3V3_NODE1")
		)
		(pad "2" smd rect
			(at -4.549902 -3.24993 180)
			(size 0.254 0.9144)
			(layers "F.Cu" "F.Mask" "F.Paste")
			(net "LAN2_NC_SI_CLK_IN")
		)
		(pad "3" smd rect
			(at -4.549902 -2.750058 180)
			(size 0.254 0.9144)
			(layers "F.Cu" "F.Mask" "F.Paste")
			(net "LAN2_NC_SI_CRS_DV")
		)
		(pad "4" smd rect
			(at -4.549902 -2.249932 180)
			(size 0.254 0.9144)
			(layers "F.Cu" "F.Mask" "F.Paste")
			(net "P1V05_LAN2")
		)
		(pad "5" smd rect
			(at -4.549902 -1.75006 180)
			(size 0.254 0.9144)
			(layers "F.Cu" "F.Mask" "F.Paste")
			(net "LAN2_NC_SI_RXD1")
		)
		(pad "6" smd rect
			(at -4.549902 -1.249934 180)
			(size 0.254 0.9144)
			(layers "F.Cu" "F.Mask" "F.Paste")
			(net "LAN2_NC_SI_RXD0")
		)
		(pad "7" smd rect
			(at -4.549902 -0.750062 180)
			(size 0.254 0.9144)
			(layers "F.Cu" "F.Mask" "F.Paste")
			(net "LAN2_NC_SI_TX_EN")
		)
		(pad "8" smd rect
			(at -4.549902 -0.249936 180)
			(size 0.254 0.9144)
			(layers "F.Cu" "F.Mask" "F.Paste")
			(net "LAN2_NC_SI_TDX1")
		)
		(pad "9" smd rect
			(at -4.549902 0.249936 180)
			(size 0.254 0.9144)
			(layers "F.Cu" "F.Mask" "F.Paste")
			(net "LAN2_NC_SI_TDX0")
		)
		(pad "10" smd rect
			(at -4.549902 0.750062 180)
			(size 0.254 0.9144)
			(layers "F.Cu" "F.Mask" "F.Paste")
			(net "P3V3_NODE1")
		)
		(pad "11" smd rect
			(at -4.549902 1.249934 180)
			(size 0.254 0.9144)
			(layers "F.Cu" "F.Mask" "F.Paste")
			(net "P1V05_LAN2")
		)
		(pad "12" smd rect
			(at -4.549902 1.75006 180)
			(size 0.254 0.9144)
			(layers "F.Cu" "F.Mask" "F.Paste")
			(net "SPI_LAN2_NVM_SI")
		)
		(pad "13" smd rect
			(at -4.549902 2.249932 180)
			(size 0.254 0.9144)
			(layers "F.Cu" "F.Mask" "F.Paste")
			(net "SPI_LAN2_NVM_SK")
		)
		(pad "14" smd rect
			(at -4.549902 2.750058 180)
			(size 0.254 0.9144)
			(layers "F.Cu" "F.Mask" "F.Paste")
			(net "SPI_LAN2_NVM_SO")
		)
		(pad "15" smd rect
			(at -4.549902 3.24993 180)
			(size 0.254 0.9144)
			(layers "F.Cu" "F.Mask" "F.Paste")
			(net "SPI_LAN2_NVM_CS_N")
		)
		(pad "16" smd rect
			(at -4.549902 3.750056 180)
			(size 0.254 0.9144)
			(layers "F.Cu" "F.Mask" "F.Paste")
			(net "IRQ_LVC3_CPU_NODE1_WAKE_L")
		)
		(pad "17" smd rect
			(at -3.750056 4.549902 270)
			(size 0.254 0.9144)
			(layers "F.Cu" "F.Mask" "F.Paste")
			(net "PLT_RST_LAN2_N")
		)
		(pad "18" smd rect
			(at -3.24993 4.549902 270)
			(size 0.254 0.9144)
			(layers "F.Cu" "F.Mask" "F.Paste")
			(net "P1V05_LAN2")
		)
		(pad "19" smd rect
			(at -2.750058 4.549902 270)
			(size 0.254 0.9144)
			(layers "F.Cu" "F.Mask" "F.Paste")
			(net "P1V9_LAN2")
		)
		(pad "20" smd rect
			(at -2.249932 4.549902 270)
			(size 0.254 0.9144)
			(layers "F.Cu" "F.Mask" "F.Paste")
			(net "PCIE_LAN2_RX_C_DN")
		)
		(pad "21" smd rect
			(at -1.75006 4.549902 270)
			(size 0.254 0.9144)
			(layers "F.Cu" "F.Mask" "F.Paste")
			(net "PCIE_LAN2_RX_C_DP")
		)
		(pad "22" smd rect
			(at -1.249934 4.549902 270)
			(size 0.254 0.9144)
			(layers "F.Cu" "F.Mask" "F.Paste")
			(net "P1V9_LAN2")
		)
		(pad "23" smd rect
			(at -0.750062 4.549902 270)
			(size 0.254 0.9144)
			(layers "F.Cu" "F.Mask" "F.Paste")
			(net "P2E_CPU_NIC2_NODE1_TX_DN")
		)
		(pad "24" smd rect
			(at -0.249936 4.549902 270)
			(size 0.254 0.9144)
			(layers "F.Cu" "F.Mask" "F.Paste")
			(net "P2E_CPU_NIC2_NODE1_TX_DP")
		)
		(pad "25" smd rect
			(at 0.249936 4.549902 270)
			(size 0.254 0.9144)
			(layers "F.Cu" "F.Mask" "F.Paste")
			(net "CLK_100M_NIC2_NODE1_DN")
		)
		(pad "26" smd rect
			(at 0.750062 4.549902 270)
			(size 0.254 0.9144)
			(layers "F.Cu" "F.Mask" "F.Paste")
			(net "CLK_100M_NIC2_NODE1_DP")
		)
		(pad "27" smd rect
			(at 1.249934 4.549902 270)
			(size 0.254 0.9144)
			(layers "F.Cu" "F.Mask" "F.Paste")
			(net "P1V05_LAN2")
		)
		(pad "28" smd rect
			(at 1.75006 4.549902 270)
			(size 0.254 0.9144)
			(layers "F.Cu" "F.Mask" "F.Paste")
			(net "LAN2_DISABLE_N")
		)
		(pad "29" smd rect
			(at 2.249932 4.549902 270)
			(size 0.254 0.9144)
			(layers "F.Cu" "F.Mask" "F.Paste")
			(net "LAN2_TEST_EN")
		)
		(pad "30" smd rect
			(at 2.750058 4.549902 270)
			(size 0.254 0.9144)
			(layers "F.Cu" "F.Mask" "F.Paste")
			(net "LAN2_LED_ACT_N")
		)
		(pad "31" smd rect
			(at 3.24993 4.549902 270)
			(size 0.254 0.9144)
			(layers "F.Cu" "F.Mask" "F.Paste")
			(net "LAN2_LED_LINK_100_N")
		)
		(pad "32" smd rect
			(at 3.750056 4.549902 270)
			(size 0.254 0.9144)
			(layers "F.Cu" "F.Mask" "F.Paste")
			(net "P3V3_NODE1")
		)
		(pad "33" smd rect
			(at 4.549902 3.750056)
			(size 0.254 0.9144)
			(layers "F.Cu" "F.Mask" "F.Paste")
			(net "LAN2_LED_LINK_1000_N")
		)
		(pad "34" smd rect
			(at 4.549902 3.24993)
			(size 0.254 0.9144)
			(layers "F.Cu" "F.Mask" "F.Paste")
			(net "SMB_LAN2_CLK")
		)
		(pad "35" smd rect
			(at 4.549902 2.750058)
			(size 0.254 0.9144)
			(layers "F.Cu" "F.Mask" "F.Paste")
			(net "SMB_LAN2_ALT_N")
		)
		(pad "36" smd rect
			(at 4.549902 2.249932)
			(size 0.254 0.9144)
			(layers "F.Cu" "F.Mask" "F.Paste")
			(net "SMB_LAN2_DAT")
		)
		(pad "37" smd rect
			(at 4.549902 1.75006)
			(size 0.254 0.9144)
			(layers "F.Cu" "F.Mask" "F.Paste")
			(net "P1V05_LAN2")
		)
		(pad "38" smd rect
			(at 4.549902 1.249934)
			(size 0.254 0.9144)
			(layers "F.Cu" "F.Mask" "F.Paste")
			(net "PU_LAN2_TMS")
		)
		(pad "39" smd rect
			(at 4.549902 0.750062)
			(size 0.254 0.9144)
			(layers "F.Cu" "F.Mask" "F.Paste")
			(net "LAN2_AUX_PWR")
		)
		(pad "40" smd rect
			(at 4.549902 0.249936)
			(size 0.254 0.9144)
			(layers "F.Cu" "F.Mask" "F.Paste")
			(net "PU_LAN2_TDI")
		)
		(pad "41" smd rect
			(at 4.549902 -0.249936)
			(size 0.254 0.9144)
			(layers "F.Cu" "F.Mask" "F.Paste")
			(net "P1V05_LAN2")
		)
		(pad "42" smd rect
			(at 4.549902 -0.750062)
			(size 0.254 0.9144)
			(layers "F.Cu" "F.Mask" "F.Paste")
			(net "LAN2_XTAL_OUT")
		)
		(pad "43" smd rect
			(at 4.549902 -1.249934)
			(size 0.254 0.9144)
			(layers "F.Cu" "F.Mask" "F.Paste")
			(net "LAN2_XTAL_IN")
		)
		(pad "44" smd rect
			(at 4.549902 -1.75006)
			(size 0.254 0.9144)
			(layers "F.Cu" "F.Mask" "F.Paste")
			(net "P1V9_LAN2")
		)
		(pad "45" smd rect
			(at 4.549902 -2.249932)
			(size 0.254 0.9144)
			(layers "F.Cu" "F.Mask" "F.Paste")
			(net "N21357353")
		)
		(pad "46" smd rect
			(at 4.549902 -2.750058)
			(size 0.254 0.9144)
			(layers "F.Cu" "F.Mask" "F.Paste")
			(net "N21357373")
		)
		(pad "47" smd rect
			(at 4.549902 -3.24993)
			(size 0.254 0.9144)
			(layers "F.Cu" "F.Mask" "F.Paste")
			(net "P1V9_LAN2")
		)
		(pad "48" smd rect
			(at 4.549902 -3.750056)
			(size 0.254 0.9144)
			(layers "F.Cu" "F.Mask" "F.Paste")
			(net "LAN2_RST")
		)
		(pad "49" smd rect
			(at 3.750056 -4.549902 270)
			(size 0.254 0.9144)
			(layers "F.Cu" "F.Mask" "F.Paste")
			(net "LAN2_MDI3_DN")
		)
		(pad "50" smd rect
			(at 3.24993 -4.549902 270)
			(size 0.254 0.9144)
			(layers "F.Cu" "F.Mask" "F.Paste")
			(net "LAN2_MDI3_DP")
		)
		(pad "51" smd rect
			(at 2.750058 -4.549902 270)
			(size 0.254 0.9144)
			(layers "F.Cu" "F.Mask" "F.Paste")
			(net "P1V9_LAN2")
		)
		(pad "52" smd rect
			(at 2.249932 -4.549902 270)
			(size 0.254 0.9144)
			(layers "F.Cu" "F.Mask" "F.Paste")
			(net "LAN2_MDI2_DN")
		)
		(pad "53" smd rect
			(at 1.75006 -4.549902 270)
			(size 0.254 0.9144)
			(layers "F.Cu" "F.Mask" "F.Paste")
			(net "LAN2_MDI2_DP")
		)
		(pad "54" smd rect
			(at 1.249934 -4.549902 270)
			(size 0.254 0.9144)
			(layers "F.Cu" "F.Mask" "F.Paste")
			(net "LAN2_MDI1_DN")
		)
		(pad "55" smd rect
			(at 0.750062 -4.549902 270)
			(size 0.254 0.9144)
			(layers "F.Cu" "F.Mask" "F.Paste")
			(net "LAN2_MDI1_DP")
		)
		(pad "56" smd rect
			(at 0.249936 -4.549902 270)
			(size 0.254 0.9144)
			(layers "F.Cu" "F.Mask" "F.Paste")
			(net "P1V9_LAN2")
		)
		(pad "57" smd rect
			(at -0.249936 -4.549902 270)
			(size 0.254 0.9144)
			(layers "F.Cu" "F.Mask" "F.Paste")
			(net "LAN2_MDI0_DN")
		)
		(pad "58" smd rect
			(at -0.750062 -4.549902 270)
			(size 0.254 0.9144)
			(layers "F.Cu" "F.Mask" "F.Paste")
			(net "LAN2_MDI0_DP")
		)
		(pad "59" smd rect
			(at -1.249934 -4.549902 270)
			(size 0.254 0.9144)
			(layers "F.Cu" "F.Mask" "F.Paste")
			(net "LAN2_DIS_REG10")
		)
		(pad "60" smd rect
			(at -1.75006 -4.549902 270)
			(size 0.254 0.9144)
			(layers "F.Cu" "F.Mask" "F.Paste")
			(net "P1V05_LAN2")
		)
		(pad "61" smd rect
			(at -2.249932 -4.549902 270)
			(size 0.254 0.9144)
			(layers "F.Cu" "F.Mask" "F.Paste")
			(net "P1V9_LAN2")
		)
		(pad "62" smd rect
			(at -2.750058 -4.549902 270)
			(size 0.254 0.9144)
			(layers "F.Cu" "F.Mask" "F.Paste")
			(net "Net_1820")
		)
		(pad "63" smd rect
			(at -3.24993 -4.549902 270)
			(size 0.254 0.9144)
			(layers "F.Cu" "F.Mask" "F.Paste")
			(net "P1V9_LAN2")
		)
		(pad "64" smd rect
			(at -3.750056 -4.549902 270)
			(size 0.254 0.9144)
			(layers "F.Cu" "F.Mask" "F.Paste")
			(net "LAN2_CTRL_P1V9")
		)
		(pad "TH" smd rect
			(at 0 0 270)
			(size 5.4102 5.4102)
			(layers "F.Cu" "F.Mask" "F.Paste")
			(net "GND")
		)
		(zone
			(layer "F.Cu")
			(hatch none 0.5)
			(connect_pads
				(clearance 0)
			)
			(min_thickness 0.25)
			(keepout
				(tracks not_allowed)
				(vias allowed)
				(pads allowed)
				(copperpour not_allowed)
				(footprints allowed)
			)
			(placement
				(enabled no)
				(sheetname "")
			)
			(fill
				(thermal_gap 0.5)
				(thermal_bridge_width 0.5)
				(island_removal_mode 0)
			)
			(polygon
				(pts
					(xy 165.033198 -157.11043) (xy 165.033198 -149.08403) (xy 157.006798 -149.08403) (xy 157.006798 -157.11043)
					(xy 163.788598 -157.11043) (xy 163.788598 -155.89123) (xy 158.225998 -155.89123) (xy 158.225998 -150.30323)
					(xy 163.813998 -150.30323) (xy 163.813998 -157.11043) (xy 164.220398 -157.11043)
				)
			)
		)
		(zone
			(layers "F.Cu" "B.Cu" "In1.Cu" "In2.Cu" "In3.Cu" "In4.Cu" "In5.Cu" "In6.Cu"
				"In7.Cu" "In8.Cu"
			)
			(hatch none 0.5)
			(connect_pads
				(clearance 0)
			)
			(min_thickness 0.25)
			(keepout
				(tracks allowed)
				(vias not_allowed)
				(pads allowed)
				(copperpour not_allowed)
				(footprints allowed)
			)
			(placement
				(enabled no)
				(sheetname "")
			)
			(fill
				(thermal_gap 0.5)
				(thermal_bridge_width 0.5)
				(island_removal_mode 0)
			)
			(polygon
				(pts
					(xy 165.033198 -157.11043) (xy 165.033198 -149.08403) (xy 157.006798 -149.08403) (xy 157.006798 -157.11043)
					(xy 163.788598 -157.11043) (xy 163.788598 -155.89123) (xy 158.225998 -155.89123) (xy 158.225998 -150.30323)
					(xy 163.813998 -150.30323) (xy 163.813998 -157.11043)
				)
			)
		)
	)
	(footprint ""
		(layer "F.Cu")
		(at -6.825488 -59.063382 90)
		(property "Reference" "J4"
			(at 1.44272 -6.64083 90)
			(unlocked yes)
			(layer "F.SilkS")
			(effects
				(font
					(size 0.7874 0.5842)
					(thickness 0.1524)
				)
				(justify left)
			)
		)
		(property "Value" ""
			(at 0 0 90)
			(layer "F.Fab")
			(effects
				(font
					(size 1.27 1.27)
				)
			)
		)
		(duplicate_pad_numbers_are_jumpers no)
		(fp_circle
			(center 4.064 -4.572)
			(end 4.064 -3.937)
			(stroke
				(width 0.05)
				(type default)
			)
			(fill no)
			(layer "Edge.Cuts")
		)
		(fp_circle
			(center 0 -4.572)
			(end 0 -3.937)
			(stroke
				(width 0.05)
				(type default)
			)
			(fill no)
			(layer "Edge.Cuts")
		)
		(fp_circle
			(center 4.064 0)
			(end 4.064 0.635)
			(stroke
				(width 0.05)
				(type default)
			)
			(fill no)
			(layer "Edge.Cuts")
		)
		(fp_circle
			(center 0 0)
			(end 0 0.635)
			(stroke
				(width 0.05)
				(type default)
			)
			(fill no)
			(layer "Edge.Cuts")
		)
		(fp_rect
			(start -1.27 1.27)
			(end 5.334 -5.842)
			(stroke
				(width 0)
				(type default)
			)
			(fill no)
			(layer "F.CrtYd")
		)
		(pad "" np_thru_hole circle
			(at 0 -4.572 90)
			(size 0.254 0.254)
			(drill 1.27)
			(layers "*.Cu" "*.Mask")
			(clearance 0.889)
			(thermal_gap 0.889)
		)
		(pad "" np_thru_hole circle
			(at 0 0 90)
			(size 0.254 0.254)
			(drill 1.27)
			(layers "*.Cu" "*.Mask")
			(clearance 0.889)
			(thermal_gap 0.889)
		)
		(pad "" np_thru_hole circle
			(at 4.064 -4.572 90)
			(size 0.254 0.254)
			(drill 1.27)
			(layers "*.Cu" "*.Mask")
			(clearance 0.889)
			(thermal_gap 0.889)
		)
		(pad "" np_thru_hole circle
			(at 4.064 0 90)
			(size 0.254 0.254)
			(drill 1.27)
			(layers "*.Cu" "*.Mask")
			(clearance 0.889)
			(thermal_gap 0.889)
		)
		(pad "1" thru_hole custom
			(at 1.397 -2.286 180)
			(size 0.266741 0.266741)
			(drill 0.254)
			(layers "*.Cu" "*.Mask")
			(remove_unused_layers no)
			(net "GND")
			(options
				(clearance outline)
				(anchor circle)
			)
			(primitives
				(gr_poly
					(pts
						(xy -0.979932 0.5334)
						(arc
							(start -0.979932 -0.078994)
							(mid -0.925932 -0.48038)
							(end -0.527812 -0.4064)
						)
						(arc
							(start -0.234188 -0.4064)
							(mid 0 -0.53341)
							(end 0.234188 -0.4064)
						)
						(arc
							(start 0.527812 -0.4064)
							(mid 0.925878 -0.480305)
							(end 0.979932 -0.078994)
						)
						(xy 0.979932 0.5334) (xy 0.548132 0.5334) (xy 0.548132 0.1016) (xy -0.548132 0.1016) (xy -0.548132 0.5334)
					)
					(width 0)
					(fill yes)
				)
			)
			(padstack
				(mode front_inner_back)
				(layer "Inner"
					(shape custom)
					(size 0.139735 0.139735)
					(options
						(anchor circle)
					)
					(primitives
						(gr_poly
							(pts
								(arc
									(start 0.26035 0.1016)
									(mid 0 0.279472)
									(end -0.26035 0.1016)
								)
								(arc
									(start -0.50165 0.1016)
									(mid -1.041472 0)
									(end -0.50165 -0.1016)
								)
								(arc
									(start -0.26035 -0.1016)
									(mid 0 -0.279472)
									(end 0.26035 -0.1016)
								)
								(arc
									(start 0.50165 -0.1016)
									(mid 1.041472 0)
									(end 0.50165 0.1016)
								)
							)
							(width 0)
							(fill yes)
						)
					)
				)
				(layer "B.Cu"
					(shape custom)
					(size 0.139735 0.139735)
					(options
						(anchor circle)
					)
					(primitives
						(gr_poly
							(pts
								(arc
									(start 0.26035 0.1016)
									(mid 0 0.279472)
									(end -0.26035 0.1016)
								)
								(arc
									(start -0.50165 0.1016)
									(mid -1.041472 0)
									(end -0.50165 -0.1016)
								)
								(arc
									(start -0.26035 -0.1016)
									(mid 0 -0.279472)
									(end 0.26035 -0.1016)
								)
								(arc
									(start 0.50165 -0.1016)
									(mid 1.041472 0)
									(end 0.50165 0.1016)
								)
							)
							(width 0)
							(fill yes)
						)
					)
				)
			)
		)
		(pad "2" smd rect
			(at 2.032 -2.060956 90)
			(size 0.3048 0.2032)
			(layers "F.Cu" "F.Mask" "F.Paste")
			(net "TOP_85OHM")
		)
		(pad "3" smd rect
			(at 2.032 -2.511044 90)
			(size 0.3048 0.2032)
			(layers "F.Cu" "F.Mask" "F.Paste")
			(net "TOP_85OHM")
		)
		(zone
			(layers "F.Cu" "B.Cu" "In1.Cu" "In2.Cu" "In3.Cu" "In4.Cu" "In5.Cu" "In6.Cu"
				"In7.Cu" "In8.Cu"
			)
			(hatch none 0.5)
			(connect_pads
				(clearance 0)
			)
			(min_thickness 0.25)
			(keepout
				(tracks not_allowed)
				(vias allowed)
				(pads allowed)
				(copperpour not_allowed)
				(footprints allowed)
			)
			(placement
				(enabled no)
				(sheetname "")
			)
			(fill
				(thermal_gap 0.5)
				(thermal_bridge_width 0.5)
				(island_removal_mode 0)
			)
			(polygon
				(pts
					(arc
						(start -11.397488 -64.016382)
						(mid -11.397488 -62.238382)
						(end -11.397488 -64.016382)
					)
				)
			)
		)
		(zone
			(layers "F.Cu" "B.Cu" "In1.Cu" "In2.Cu" "In3.Cu" "In4.Cu" "In5.Cu" "In6.Cu"
				"In7.Cu" "In8.Cu"
			)
			(hatch none 0.5)
			(connect_pads
				(clearance 0)
			)
			(min_thickness 0.25)
			(keepout
				(tracks not_allowed)
				(vias allowed)
				(pads allowed)
				(copperpour not_allowed)
				(footprints allowed)
			)
			(placement
				(enabled no)
				(sheetname "")
			)
			(fill
				(thermal_gap 0.5)
				(thermal_bridge_width 0.5)
				(island_removal_mode 0)
			)
			(polygon
				(pts
					(arc
						(start -11.397488 -59.952382)
						(mid -11.397488 -58.174382)
						(end -11.397488 -59.952382)
					)
				)
			)
		)
		(zone
			(layers "F.Cu" "B.Cu" "In1.Cu" "In2.Cu" "In3.Cu" "In4.Cu" "In5.Cu" "In6.Cu"
				"In7.Cu" "In8.Cu"
			)
			(hatch none 0.5)
			(connect_pads
				(clearance 0)
			)
			(min_thickness 0.25)
			(keepout
				(tracks not_allowed)
				(vias allowed)
				(pads allowed)
				(copperpour not_allowed)
				(footprints allowed)
			)
			(placement
				(enabled no)
				(sheetname "")
			)
			(fill
				(thermal_gap 0.5)
				(thermal_bridge_width 0.5)
				(island_removal_mode 0)
			)
			(polygon
				(pts
					(arc
						(start -6.825488 -64.016382)
						(mid -6.825488 -62.238382)
						(end -6.825488 -64.016382)
					)
				)
			)
		)
		(zone
			(layers "F.Cu" "B.Cu" "In1.Cu" "In2.Cu" "In3.Cu" "In4.Cu" "In5.Cu" "In6.Cu"
				"In7.Cu" "In8.Cu"
			)
			(hatch none 0.5)
			(connect_pads
				(clearance 0)
			)
			(min_thickness 0.25)
			(keepout
				(tracks not_allowed)
				(vias allowed)
				(pads allowed)
				(copperpour not_allowed)
				(footprints allowed)
			)
			(placement
				(enabled no)
				(sheetname "")
			)
			(fill
				(thermal_gap 0.5)
				(thermal_bridge_width 0.5)
				(island_removal_mode 0)
			)
			(polygon
				(pts
					(arc
						(start -6.825488 -59.952382)
						(mid -6.825488 -58.174382)
						(end -6.825488 -59.952382)
					)
				)
			)
		)
	)
	(footprint ""
		(layer "F.Cu")
		(at 68.81876 -185.205624 -90)
		(property "Reference" "R871"
			(at -4.006088 0.814324 90)
			(unlocked yes)
			(layer "F.SilkS")
			(effects
				(font
					(size 0.7874 0.5842)
					(thickness 0.1524)
				)
				(justify left)
			)
		)
		(property "Value" ""
			(at 0 0 270)
			(layer "F.Fab")
			(effects
				(font
					(size 1.27 1.27)
				)
			)
		)
		(duplicate_pad_numbers_are_jumpers no)
		(fp_line
			(start -0.7874 0.4064)
			(end -0.7874 -0.4064)
			(stroke
				(width 0.1524)
				(type default)
			)
			(layer "F.SilkS")
		)
		(fp_line
			(start 0.7874 0.4064)
			(end -0.7874 0.4064)
			(stroke
				(width 0.1524)
				(type default)
			)
			(layer "F.SilkS")
		)
		(fp_line
			(start -0.7874 -0.4064)
			(end 0.7874 -0.4064)
			(stroke
				(width 0.1524)
				(type default)
			)
			(layer "F.SilkS")
		)
		(fp_line
			(start 0.7874 -0.4064)
			(end 0.7874 0.4064)
			(stroke
				(width 0.1524)
				(type default)
			)
			(layer "F.SilkS")
		)
		(fp_poly
			(pts
				(xy -0.508 0.2794) (xy -0.508 0.2286) (xy -0.635 0.2286) (xy -0.635 -0.254) (xy -0.5334 -0.254)
				(xy -0.5334 -0.2794) (xy 0.5334 -0.2794) (xy 0.5334 -0.254) (xy 0.635 -0.254) (xy 0.635 0.254) (xy 0.5334 0.254)
				(xy 0.5334 0.2794)
			)
			(stroke
				(width 0)
				(type default)
			)
			(fill no)
			(layer "F.CrtYd")
		)
		(pad "1" smd rect
			(at 0.40005 0 270)
			(size 0.4572 0.508)
			(layers "F.Cu" "F.Mask" "F.Paste")
			(net "T2_NODE1_EN")
		)
		(pad "2" smd rect
			(at -0.40005 0 270)
			(size 0.4572 0.508)
			(layers "F.Cu" "F.Mask" "F.Paste")
			(net "T2_NODE1_EN_R")
		)
	)
	(footprint ""
		(layer "F.Cu")
		(at 144.916652 -141.20495)
		(property "Reference" "R232"
			(at -0.990346 17.763744 0)
			(unlocked yes)
			(layer "F.SilkS")
			(effects
				(font
					(size 0.7874 0.5842)
					(thickness 0.1524)
				)
				(justify left)
			)
		)
		(property "Value" ""
			(at 0 0 0)
			(layer "F.Fab")
			(effects
				(font
					(size 1.27 1.27)
				)
			)
		)
		(duplicate_pad_numbers_are_jumpers no)
		(fp_line
			(start -0.7874 -0.4064)
			(end 0.7874 -0.4064)
			(stroke
				(width 0.1524)
				(type default)
			)
			(layer "F.SilkS")
		)
		(fp_line
			(start -0.7874 0.4064)
			(end -0.7874 -0.4064)
			(stroke
				(width 0.1524)
				(type default)
			)
			(layer "F.SilkS")
		)
		(fp_line
			(start 0.7874 -0.4064)
			(end 0.7874 0.4064)
			(stroke
				(width 0.1524)
				(type default)
			)
			(layer "F.SilkS")
		)
		(fp_line
			(start 0.7874 0.4064)
			(end -0.7874 0.4064)
			(stroke
				(width 0.1524)
				(type default)
			)
			(layer "F.SilkS")
		)
		(fp_poly
			(pts
				(xy -0.508 0.2794) (xy -0.508 0.2286) (xy -0.635 0.2286) (xy -0.635 -0.254) (xy -0.5334 -0.254)
				(xy -0.5334 -0.2794) (xy 0.5334 -0.2794) (xy 0.5334 -0.254) (xy 0.635 -0.254) (xy 0.635 0.254) (xy 0.5334 0.254)
				(xy 0.5334 0.2794)
			)
			(stroke
				(width 0)
				(type default)
			)
			(fill no)
			(layer "F.CrtYd")
		)
		(pad "1" smd rect
			(at 0.40005 0)
			(size 0.4572 0.508)
			(layers "F.Cu" "F.Mask" "F.Paste")
			(net "SMB_CPU_NODE1_BMC_CLK")
		)
		(pad "2" smd rect
			(at -0.40005 0)
			(size 0.4572 0.508)
			(layers "F.Cu" "F.Mask" "F.Paste")
			(net "PCIE_SW_I2C_SCL")
		)
	)
	(footprint ""
		(layer "F.Cu")
		(at 113.64976 -179.363624 -90)
		(property "Reference" "D24"
			(at -3.131312 -8.24611 90)
			(unlocked yes)
			(layer "F.SilkS")
			(effects
				(font
					(size 0.635 0.4064)
					(thickness 0.1524)
				)
				(justify left)
			)
		)
		(property "Value" ""
			(at 0 0 270)
			(layer "F.Fab")
			(effects
				(font
					(size 1.27 1.27)
				)
			)
		)
		(duplicate_pad_numbers_are_jumpers no)
		(fp_line
			(start -1.3208 0.5588)
			(end -1.3208 -0.5588)
			(stroke
				(width 0.1524)
				(type default)
			)
			(layer "F.SilkS")
		)
		(fp_line
			(start 1.3208 0.5588)
			(end -1.3208 0.5588)
			(stroke
				(width 0.1524)
				(type default)
			)
			(layer "F.SilkS")
		)
		(fp_line
			(start 1.6256 0.5588)
			(end 1.6256 -0.5588)
			(stroke
				(width 0.1524)
				(type default)
			)
			(layer "F.SilkS")
		)
		(fp_line
			(start 1.778 0.5588)
			(end 1.3208 0.5588)
			(stroke
				(width 0.1524)
				(type default)
			)
			(layer "F.SilkS")
		)
		(fp_line
			(start -1.3208 -0.5588)
			(end 1.3208 -0.5588)
			(stroke
				(width 0.1524)
				(type default)
			)
			(layer "F.SilkS")
		)
		(fp_line
			(start 1.3208 -0.5588)
			(end 1.3208 0.5588)
			(stroke
				(width 0.1524)
				(type default)
			)
			(layer "F.SilkS")
		)
		(fp_line
			(start 1.4732 -0.5588)
			(end 1.4732 0.5588)
			(stroke
				(width 0.1524)
				(type default)
			)
			(layer "F.SilkS")
		)
		(fp_line
			(start 1.778 -0.5588)
			(end 1.778 0.5588)
			(stroke
				(width 0.1524)
				(type default)
			)
			(layer "F.SilkS")
		)
		(fp_line
			(start 1.778 -0.5588)
			(end 1.3208 -0.5588)
			(stroke
				(width 0.1524)
				(type default)
			)
			(layer "F.SilkS")
		)
		(fp_rect
			(start -1.1684 0.508)
			(end 1.1684 -0.508)
			(stroke
				(width 0)
				(type default)
			)
			(fill no)
			(layer "F.CrtYd")
		)
		(pad "A" smd rect
			(at -0.750062 0 270)
			(size 0.8128 0.8128)
			(layers "F.Cu" "F.Mask" "F.Paste")
			(net "UART_SW_S5_N")
		)
		(pad "C" smd rect
			(at 0.750062 0 270)
			(size 0.8128 0.8128)
			(layers "F.Cu" "F.Mask" "F.Paste")
			(net "N31348569")
		)
	)
	(footprint ""
		(layer "F.Cu")
		(at 18.25752 -50.345086 -90)
		(property "Reference" "C500"
			(at 1.057148 -13.781532 90)
			(unlocked yes)
			(layer "F.SilkS")
			(effects
				(font
					(size 0.7874 0.5842)
					(thickness 0.1524)
				)
			)
		)
		(property "Value" ""
			(at 0 0 270)
			(layer "F.Fab")
			(effects
				(font
					(size 1.27 1.27)
				)
			)
		)
		(duplicate_pad_numbers_are_jumpers no)
		(fp_line
			(start -1.2954 0.5842)
			(end -1.2954 -0.5842)
			(stroke
				(width 0.1524)
				(type default)
			)
			(layer "F.SilkS")
		)
		(fp_line
			(start 1.2954 0.5842)
			(end -1.2954 0.5842)
			(stroke
				(width 0.1524)
				(type default)
			)
			(layer "F.SilkS")
		)
		(fp_line
			(start -1.2954 -0.5842)
			(end 1.2954 -0.5842)
			(stroke
				(width 0.1524)
				(type default)
			)
			(layer "F.SilkS")
		)
		(fp_line
			(start 0 -0.5842)
			(end 0 0.5842)
			(stroke
				(width 0.1524)
				(type default)
			)
			(layer "F.SilkS")
		)
		(fp_line
			(start 1.2954 -0.5842)
			(end 1.2954 0.5842)
			(stroke
				(width 0.1524)
				(type default)
			)
			(layer "F.SilkS")
		)
		(fp_poly
			(pts
				(xy 0.8636 -0.4572) (xy 0.8636 -0.3556) (xy 1.143 -0.3556) (xy 1.143 0.3556) (xy 0.8636 0.3556)
				(xy 0.8636 0.4572) (xy -0.8636 0.4572) (xy -0.8636 0.3556) (xy -1.143 0.3556) (xy -1.143 -0.3556)
				(xy -0.8636 -0.3556) (xy -0.8636 -0.4572)
			)
			(stroke
				(width 0)
				(type default)
			)
			(fill no)
			(layer "F.CrtYd")
		)
		(fp_line
			(start -0.884936 0.504952)
			(end -0.884936 -0.504952)
			(stroke
				(width 0.1)
				(type default)
			)
			(layer "F.Fab")
		)
		(fp_line
			(start 0.884936 0.504952)
			(end -0.884936 0.504952)
			(stroke
				(width 0.1)
				(type default)
			)
			(layer "F.Fab")
		)
		(fp_line
			(start -0.884936 -0.504952)
			(end 0.884936 -0.504952)
			(stroke
				(width 0.1)
				(type default)
			)
			(layer "F.Fab")
		)
		(fp_line
			(start 0.884936 -0.504952)
			(end 0.884936 0.504952)
			(stroke
				(width 0.1)
				(type default)
			)
			(layer "F.Fab")
		)
		(pad "1" smd rect
			(at 0.7366 0)
			(size 0.7112 0.8128)
			(layers "F.Cu" "F.Mask" "F.Paste")
			(net "BMC_NODE1_GFX_GREEN")
		)
		(pad "2" smd rect
			(at -0.7366 0)
			(size 0.7112 0.8128)
			(layers "F.Cu" "F.Mask" "F.Paste")
			(net "GND")
		)
	)
	(footprint ""
		(layer "F.Cu")
		(at 102.888034 -181.31409 180)
		(property "Reference" "C776"
			(at -85.014308 -77.836776 90)
			(unlocked yes)
			(layer "F.SilkS")
			(effects
				(font
					(size 0.7874 0.5842)
					(thickness 0.1524)
				)
				(justify left)
			)
		)
		(property "Value" ""
			(at 0 0 180)
			(layer "F.Fab")
			(effects
				(font
					(size 1.27 1.27)
				)
			)
		)
		(duplicate_pad_numbers_are_jumpers no)
		(fp_line
			(start 0.7874 0.4064)
			(end -0.7874 0.4064)
			(stroke
				(width 0.1524)
				(type default)
			)
			(layer "F.SilkS")
		)
		(fp_line
			(start 0.7874 -0.4064)
			(end 0.7874 0.4064)
			(stroke
				(width 0.1524)
				(type default)
			)
			(layer "F.SilkS")
		)
		(fp_line
			(start 0 0.381)
			(end 0 -0.381)
			(stroke
				(width 0.1524)
				(type default)
			)
			(layer "F.SilkS")
		)
		(fp_line
			(start -0.7874 0.4064)
			(end -0.7874 -0.4064)
			(stroke
				(width 0.1524)
				(type default)
			)
			(layer "F.SilkS")
		)
		(fp_line
			(start -0.7874 -0.4064)
			(end 0.7874 -0.4064)
			(stroke
				(width 0.1524)
				(type default)
			)
			(layer "F.SilkS")
		)
		(fp_poly
			(pts
				(xy -0.5334 0.254) (xy -0.635 0.254) (xy -0.635 0.2286) (xy -0.635 -0.254) (xy -0.5334 -0.254) (xy -0.5334 -0.2794)
				(xy 0.5334 -0.2794) (xy 0.5334 -0.254) (xy 0.635 -0.254) (xy 0.635 0.254) (xy 0.5334 0.254) (xy 0.5334 0.2794)
				(xy -0.508 0.2794) (xy -0.5334 0.2794)
			)
			(stroke
				(width 0)
				(type default)
			)
			(fill no)
			(layer "F.CrtYd")
		)
		(pad "1" smd rect
			(at 0.40005 0 180)
			(size 0.4572 0.508)
			(layers "F.Cu" "F.Mask" "F.Paste")
			(net "P3V3_NODE1")
		)
		(pad "2" smd rect
			(at -0.40005 0 180)
			(size 0.4572 0.508)
			(layers "F.Cu" "F.Mask" "F.Paste")
			(net "GND")
		)
	)
	(footprint ""
		(layer "F.Cu")
		(at 80.24876 -185.205624 -90)
		(property "Reference" "R901"
			(at -4.198112 1.795272 90)
			(unlocked yes)
			(layer "F.SilkS")
			(effects
				(font
					(size 0.7874 0.5842)
					(thickness 0.1524)
				)
				(justify left)
			)
		)
		(property "Value" ""
			(at 0 0 270)
			(layer "F.Fab")
			(effects
				(font
					(size 1.27 1.27)
				)
			)
		)
		(duplicate_pad_numbers_are_jumpers no)
		(fp_line
			(start -0.7874 0.4064)
			(end -0.7874 -0.4064)
			(stroke
				(width 0.1524)
				(type default)
			)
			(layer "F.SilkS")
		)
		(fp_line
			(start 0.7874 0.4064)
			(end -0.7874 0.4064)
			(stroke
				(width 0.1524)
				(type default)
			)
			(layer "F.SilkS")
		)
		(fp_line
			(start -0.7874 -0.4064)
			(end 0.7874 -0.4064)
			(stroke
				(width 0.1524)
				(type default)
			)
			(layer "F.SilkS")
		)
		(fp_line
			(start 0.7874 -0.4064)
			(end 0.7874 0.4064)
			(stroke
				(width 0.1524)
				(type default)
			)
			(layer "F.SilkS")
		)
		(fp_poly
			(pts
				(xy -0.508 0.2794) (xy -0.508 0.2286) (xy -0.635 0.2286) (xy -0.635 -0.254) (xy -0.5334 -0.254)
				(xy -0.5334 -0.2794) (xy 0.5334 -0.2794) (xy 0.5334 -0.254) (xy 0.635 -0.254) (xy 0.635 0.254) (xy 0.5334 0.254)
				(xy 0.5334 0.2794)
			)
			(stroke
				(width 0)
				(type default)
			)
			(fill no)
			(layer "F.CrtYd")
		)
		(pad "1" smd rect
			(at 0.40005 0 270)
			(size 0.4572 0.508)
			(layers "F.Cu" "F.Mask" "F.Paste")
			(net "T4_NODE3_EN")
		)
		(pad "2" smd rect
			(at -0.40005 0 270)
			(size 0.4572 0.508)
			(layers "F.Cu" "F.Mask" "F.Paste")
			(net "T4_NODE3_EN_R")
		)
	)
	(footprint ""
		(layer "F.Cu")
		(at 94.211394 -188.838586)
		(property "Reference" "R939"
			(at -1.182878 -7.467346 0)
			(unlocked yes)
			(layer "F.SilkS")
			(effects
				(font
					(size 0.7874 0.5842)
					(thickness 0.1524)
				)
				(justify left)
			)
		)
		(property "Value" ""
			(at 0 0 0)
			(layer "F.Fab")
			(effects
				(font
					(size 1.27 1.27)
				)
			)
		)
		(duplicate_pad_numbers_are_jumpers no)
		(fp_line
			(start -0.7874 -0.4064)
			(end 0.7874 -0.4064)
			(stroke
				(width 0.1524)
				(type default)
			)
			(layer "F.SilkS")
		)
		(fp_line
			(start -0.7874 0.4064)
			(end -0.7874 -0.4064)
			(stroke
				(width 0.1524)
				(type default)
			)
			(layer "F.SilkS")
		)
		(fp_line
			(start 0.7874 -0.4064)
			(end 0.7874 0.4064)
			(stroke
				(width 0.1524)
				(type default)
			)
			(layer "F.SilkS")
		)
		(fp_line
			(start 0.7874 0.4064)
			(end -0.7874 0.4064)
			(stroke
				(width 0.1524)
				(type default)
			)
			(layer "F.SilkS")
		)
		(fp_poly
			(pts
				(xy -0.508 0.2794) (xy -0.508 0.2286) (xy -0.635 0.2286) (xy -0.635 -0.254) (xy -0.5334 -0.254)
				(xy -0.5334 -0.2794) (xy 0.5334 -0.2794) (xy 0.5334 -0.254) (xy 0.635 -0.254) (xy 0.635 0.254) (xy 0.5334 0.254)
				(xy 0.5334 0.2794)
			)
			(stroke
				(width 0)
				(type default)
			)
			(fill no)
			(layer "F.CrtYd")
		)
		(pad "1" smd rect
			(at 0.40005 0)
			(size 0.4572 0.508)
			(layers "F.Cu" "F.Mask" "F.Paste")
			(net "UART_T6_NODE2_RXD")
		)
		(pad "2" smd rect
			(at -0.40005 0)
			(size 0.4572 0.508)
			(layers "F.Cu" "F.Mask" "F.Paste")
			(net "UART_T6_NODE2_RXD_R")
		)
	)
	(footprint ""
		(layer "F.Cu")
		(at 18.226532 -56.004206 -90)
		(property "Reference" "R642"
			(at 2.070608 -13.912088 90)
			(unlocked yes)
			(layer "F.SilkS")
			(effects
				(font
					(size 0.7874 0.5842)
					(thickness 0.1524)
				)
				(justify left)
			)
		)
		(property "Value" ""
			(at 0 0 270)
			(layer "F.Fab")
			(effects
				(font
					(size 1.27 1.27)
				)
			)
		)
		(duplicate_pad_numbers_are_jumpers no)
		(fp_line
			(start -0.7874 0.4064)
			(end -0.7874 -0.4064)
			(stroke
				(width 0.1524)
				(type default)
			)
			(layer "F.SilkS")
		)
		(fp_line
			(start 0.7874 0.4064)
			(end -0.7874 0.4064)
			(stroke
				(width 0.1524)
				(type default)
			)
			(layer "F.SilkS")
		)
		(fp_line
			(start -0.7874 -0.4064)
			(end 0.7874 -0.4064)
			(stroke
				(width 0.1524)
				(type default)
			)
			(layer "F.SilkS")
		)
		(fp_line
			(start 0.7874 -0.4064)
			(end 0.7874 0.4064)
			(stroke
				(width 0.1524)
				(type default)
			)
			(layer "F.SilkS")
		)
		(fp_poly
			(pts
				(xy -0.508 0.2794) (xy -0.508 0.2286) (xy -0.635 0.2286) (xy -0.635 -0.254) (xy -0.5334 -0.254)
				(xy -0.5334 -0.2794) (xy 0.5334 -0.2794) (xy 0.5334 -0.254) (xy 0.635 -0.254) (xy 0.635 0.254) (xy 0.5334 0.254)
				(xy 0.5334 0.2794)
			)
			(stroke
				(width 0)
				(type default)
			)
			(fill no)
			(layer "F.CrtYd")
		)
		(pad "1" smd rect
			(at 0.40005 0 270)
			(size 0.4572 0.508)
			(layers "F.Cu" "F.Mask" "F.Paste")
			(net "CRT_B_L")
		)
		(pad "2" smd rect
			(at -0.40005 0 270)
			(size 0.4572 0.508)
			(layers "F.Cu" "F.Mask" "F.Paste")
			(net "GND")
		)
	)
	(footprint ""
		(layer "F.Cu")
		(at 120.38076 -179.363624 -90)
		(property "Reference" "D16"
			(at -3.37693 -6.62305 90)
			(unlocked yes)
			(layer "F.SilkS")
			(effects
				(font
					(size 0.635 0.4064)
					(thickness 0.1524)
				)
				(justify left)
			)
		)
		(property "Value" ""
			(at 0 0 270)
			(layer "F.Fab")
			(effects
				(font
					(size 1.27 1.27)
				)
			)
		)
		(duplicate_pad_numbers_are_jumpers no)
		(fp_line
			(start -1.3208 0.5588)
			(end -1.3208 -0.5588)
			(stroke
				(width 0.1524)
				(type default)
			)
			(layer "F.SilkS")
		)
		(fp_line
			(start 1.3208 0.5588)
			(end -1.3208 0.5588)
			(stroke
				(width 0.1524)
				(type default)
			)
			(layer "F.SilkS")
		)
		(fp_line
			(start 1.6256 0.5588)
			(end 1.6256 -0.5588)
			(stroke
				(width 0.1524)
				(type default)
			)
			(layer "F.SilkS")
		)
		(fp_line
			(start 1.778 0.5588)
			(end 1.3208 0.5588)
			(stroke
				(width 0.1524)
				(type default)
			)
			(layer "F.SilkS")
		)
		(fp_line
			(start -1.3208 -0.5588)
			(end 1.3208 -0.5588)
			(stroke
				(width 0.1524)
				(type default)
			)
			(layer "F.SilkS")
		)
		(fp_line
			(start 1.3208 -0.5588)
			(end 1.3208 0.5588)
			(stroke
				(width 0.1524)
				(type default)
			)
			(layer "F.SilkS")
		)
		(fp_line
			(start 1.4732 -0.5588)
			(end 1.4732 0.5588)
			(stroke
				(width 0.1524)
				(type default)
			)
			(layer "F.SilkS")
		)
		(fp_line
			(start 1.778 -0.5588)
			(end 1.778 0.5588)
			(stroke
				(width 0.1524)
				(type default)
			)
			(layer "F.SilkS")
		)
		(fp_line
			(start 1.778 -0.5588)
			(end 1.3208 -0.5588)
			(stroke
				(width 0.1524)
				(type default)
			)
			(layer "F.SilkS")
		)
		(fp_rect
			(start -1.1684 0.508)
			(end 1.1684 -0.508)
			(stroke
				(width 0)
				(type default)
			)
			(fill no)
			(layer "F.CrtYd")
		)
		(pad "A" smd rect
			(at -0.750062 0 270)
			(size 0.8128 0.8128)
			(layers "F.Cu" "F.Mask" "F.Paste")
			(net "UART_SW_S1_N")
		)
		(pad "C" smd rect
			(at 0.750062 0 270)
			(size 0.8128 0.8128)
			(layers "F.Cu" "F.Mask" "F.Paste")
			(net "N31328108")
		)
	)
	(footprint ""
		(layer "F.Cu")
		(at 52.81676 -185.205624 90)
		(property "Reference" "R831"
			(at 4.006088 0.055372 90)
			(unlocked yes)
			(layer "F.SilkS")
			(effects
				(font
					(size 0.7874 0.5842)
					(thickness 0.1524)
				)
				(justify left)
			)
		)
		(property "Value" ""
			(at 0 0 90)
			(layer "F.Fab")
			(effects
				(font
					(size 1.27 1.27)
				)
			)
		)
		(duplicate_pad_numbers_are_jumpers no)
		(fp_line
			(start 0.7874 -0.4064)
			(end 0.7874 0.4064)
			(stroke
				(width 0.1524)
				(type default)
			)
			(layer "F.SilkS")
		)
		(fp_line
			(start -0.7874 -0.4064)
			(end 0.7874 -0.4064)
			(stroke
				(width 0.1524)
				(type default)
			)
			(layer "F.SilkS")
		)
		(fp_line
			(start 0.7874 0.4064)
			(end -0.7874 0.4064)
			(stroke
				(width 0.1524)
				(type default)
			)
			(layer "F.SilkS")
		)
		(fp_line
			(start -0.7874 0.4064)
			(end -0.7874 -0.4064)
			(stroke
				(width 0.1524)
				(type default)
			)
			(layer "F.SilkS")
		)
		(fp_poly
			(pts
				(xy -0.508 0.2794) (xy -0.508 0.2286) (xy -0.635 0.2286) (xy -0.635 -0.254) (xy -0.5334 -0.254)
				(xy -0.5334 -0.2794) (xy 0.5334 -0.2794) (xy 0.5334 -0.254) (xy 0.635 -0.254) (xy 0.635 0.254) (xy 0.5334 0.254)
				(xy 0.5334 0.2794)
			)
			(stroke
				(width 0)
				(type default)
			)
			(fill no)
			(layer "F.CrtYd")
		)
		(pad "1" smd rect
			(at 0.40005 0 90)
			(size 0.4572 0.508)
			(layers "F.Cu" "F.Mask" "F.Paste")
			(net "PSU1_AC_OK_R")
		)
		(pad "2" smd rect
			(at -0.40005 0 90)
			(size 0.4572 0.508)
			(layers "F.Cu" "F.Mask" "F.Paste")
			(net "PSU1_AC_OK")
		)
	)
	(footprint ""
		(layer "F.Cu")
		(at 82.340196 -108.09859 180)
		(property "Reference" "R1100"
			(at 5.41147 0.60198 0)
			(unlocked yes)
			(layer "F.SilkS")
			(effects
				(font
					(size 0.7874 0.5842)
					(thickness 0.1524)
				)
				(justify left)
			)
		)
		(property "Value" ""
			(at 0 0 180)
			(layer "F.Fab")
			(effects
				(font
					(size 1.27 1.27)
				)
			)
		)
		(duplicate_pad_numbers_are_jumpers no)
		(fp_line
			(start 0.7874 0.4064)
			(end -0.7874 0.4064)
			(stroke
				(width 0.1524)
				(type default)
			)
			(layer "F.SilkS")
		)
		(fp_line
			(start 0.7874 -0.4064)
			(end 0.7874 0.4064)
			(stroke
				(width 0.1524)
				(type default)
			)
			(layer "F.SilkS")
		)
		(fp_line
			(start -0.7874 0.4064)
			(end -0.7874 -0.4064)
			(stroke
				(width 0.1524)
				(type default)
			)
			(layer "F.SilkS")
		)
		(fp_line
			(start -0.7874 -0.4064)
			(end 0.7874 -0.4064)
			(stroke
				(width 0.1524)
				(type default)
			)
			(layer "F.SilkS")
		)
		(fp_poly
			(pts
				(xy -0.508 0.2794) (xy -0.508 0.2286) (xy -0.635 0.2286) (xy -0.635 -0.254) (xy -0.5334 -0.254)
				(xy -0.5334 -0.2794) (xy 0.5334 -0.2794) (xy 0.5334 -0.254) (xy 0.635 -0.254) (xy 0.635 0.254) (xy 0.5334 0.254)
				(xy 0.5334 0.2794)
			)
			(stroke
				(width 0)
				(type default)
			)
			(fill no)
			(layer "F.CrtYd")
		)
		(pad "1" smd rect
			(at 0.40005 0 180)
			(size 0.4572 0.508)
			(layers "F.Cu" "F.Mask" "F.Paste")
			(net "FM_CPLD_NODE1_P3V3_SUS_EN")
		)
		(pad "2" smd rect
			(at -0.40005 0 180)
			(size 0.4572 0.508)
			(layers "F.Cu" "F.Mask" "F.Paste")
			(net "P3V3_STB_NODE1")
		)
	)
	(footprint ""
		(layer "F.Cu")
		(at 27.385772 -103.221282 180)
		(property "Reference" "R1106"
			(at 0.39751 -4.406392 90)
			(unlocked yes)
			(layer "F.SilkS")
			(effects
				(font
					(size 0.7874 0.5842)
					(thickness 0.1524)
				)
				(justify left)
			)
		)
		(property "Value" ""
			(at 0 0 180)
			(layer "F.Fab")
			(effects
				(font
					(size 1.27 1.27)
				)
			)
		)
		(duplicate_pad_numbers_are_jumpers no)
		(fp_line
			(start 0.7874 0.4064)
			(end -0.7874 0.4064)
			(stroke
				(width 0.1524)
				(type default)
			)
			(layer "F.SilkS")
		)
		(fp_line
			(start 0.7874 -0.4064)
			(end 0.7874 0.4064)
			(stroke
				(width 0.1524)
				(type default)
			)
			(layer "F.SilkS")
		)
		(fp_line
			(start -0.7874 0.4064)
			(end -0.7874 -0.4064)
			(stroke
				(width 0.1524)
				(type default)
			)
			(layer "F.SilkS")
		)
		(fp_line
			(start -0.7874 -0.4064)
			(end 0.7874 -0.4064)
			(stroke
				(width 0.1524)
				(type default)
			)
			(layer "F.SilkS")
		)
		(fp_poly
			(pts
				(xy -0.508 0.2794) (xy -0.508 0.2286) (xy -0.635 0.2286) (xy -0.635 -0.254) (xy -0.5334 -0.254)
				(xy -0.5334 -0.2794) (xy 0.5334 -0.2794) (xy 0.5334 -0.254) (xy 0.635 -0.254) (xy 0.635 0.254) (xy 0.5334 0.254)
				(xy 0.5334 0.2794)
			)
			(stroke
				(width 0)
				(type default)
			)
			(fill no)
			(layer "F.CrtYd")
		)
		(pad "1" smd rect
			(at 0.40005 0 180)
			(size 0.4572 0.508)
			(layers "F.Cu" "F.Mask" "F.Paste")
			(net "GND")
		)
		(pad "2" smd rect
			(at -0.40005 0 180)
			(size 0.4572 0.508)
			(layers "F.Cu" "F.Mask" "F.Paste")
			(net "FM_CPLD_NODE1_P1V5_SUS_EN")
		)
	)
	(footprint ""
		(layer "F.Cu")
		(at 82.53476 -188.126624 90)
		(property "Reference" "C658"
			(at 4.548886 -1.831848 90)
			(unlocked yes)
			(layer "F.SilkS")
			(effects
				(font
					(size 0.7874 0.5842)
					(thickness 0.1524)
				)
				(justify left)
			)
		)
		(property "Value" ""
			(at 0 0 90)
			(layer "F.Fab")
			(effects
				(font
					(size 1.27 1.27)
				)
			)
		)
		(duplicate_pad_numbers_are_jumpers no)
		(fp_line
			(start 0.7874 -0.4064)
			(end 0.7874 0.4064)
			(stroke
				(width 0.1524)
				(type default)
			)
			(layer "F.SilkS")
		)
		(fp_line
			(start -0.7874 -0.4064)
			(end 0.7874 -0.4064)
			(stroke
				(width 0.1524)
				(type default)
			)
			(layer "F.SilkS")
		)
		(fp_line
			(start 0 0.381)
			(end 0 -0.381)
			(stroke
				(width 0.1524)
				(type default)
			)
			(layer "F.SilkS")
		)
		(fp_line
			(start 0.7874 0.4064)
			(end -0.7874 0.4064)
			(stroke
				(width 0.1524)
				(type default)
			)
			(layer "F.SilkS")
		)
		(fp_line
			(start -0.7874 0.4064)
			(end -0.7874 -0.4064)
			(stroke
				(width 0.1524)
				(type default)
			)
			(layer "F.SilkS")
		)
		(fp_poly
			(pts
				(xy -0.5334 0.254) (xy -0.635 0.254) (xy -0.635 0.2286) (xy -0.635 -0.254) (xy -0.5334 -0.254) (xy -0.5334 -0.2794)
				(xy 0.5334 -0.2794) (xy 0.5334 -0.254) (xy 0.635 -0.254) (xy 0.635 0.254) (xy 0.5334 0.254) (xy 0.5334 0.2794)
				(xy -0.508 0.2794) (xy -0.5334 0.2794)
			)
			(stroke
				(width 0)
				(type default)
			)
			(fill no)
			(layer "F.CrtYd")
		)
		(pad "1" smd rect
			(at 0.40005 0 90)
			(size 0.4572 0.508)
			(layers "F.Cu" "F.Mask" "F.Paste")
			(net "T4_NODE1_EN_R")
		)
		(pad "2" smd rect
			(at -0.40005 0 90)
			(size 0.4572 0.508)
			(layers "F.Cu" "F.Mask" "F.Paste")
			(net "GND")
		)
	)
	(footprint ""
		(layer "F.Cu")
		(at 116.31549 -156.330142 180)
		(property "Reference" "U110"
			(at 0.185166 3.018282 90)
			(unlocked yes)
			(layer "F.SilkS")
			(effects
				(font
					(size 0.635 0.4064)
					(thickness 0.1524)
				)
			)
		)
		(property "Value" ""
			(at 0 0 180)
			(layer "F.Fab")
			(effects
				(font
					(size 1.27 1.27)
				)
			)
		)
		(duplicate_pad_numbers_are_jumpers no)
		(fp_line
			(start 1.651 1.905)
			(end -1.651 1.905)
			(stroke
				(width 0.1524)
				(type default)
			)
			(layer "F.SilkS")
		)
		(fp_line
			(start 1.651 -1.905)
			(end 1.651 1.905)
			(stroke
				(width 0.1524)
				(type default)
			)
			(layer "F.SilkS")
		)
		(fp_line
			(start -1.651 1.905)
			(end -1.651 -1.905)
			(stroke
				(width 0.1524)
				(type default)
			)
			(layer "F.SilkS")
		)
		(fp_line
			(start -1.651 -1.905)
			(end 1.651 -1.905)
			(stroke
				(width 0.1524)
				(type default)
			)
			(layer "F.SilkS")
		)
		(fp_poly
			(pts
				(xy -1.524 0.7112) (xy -1.524 1.7526) (xy -0.508 1.7526) (xy -0.508 0.6985) (xy 0.508 0.6985) (xy 0.508 1.7526)
				(xy 1.524 1.7526) (xy 1.524 0.6985) (xy 1.524 -0.6985) (xy 0.508 -0.6985) (xy 0.508 -1.7526) (xy -0.508 -1.7526)
				(xy -0.508 -0.6985) (xy -1.524 -0.6985) (xy -1.524 0.6985)
			)
			(stroke
				(width 0)
				(type default)
			)
			(fill no)
			(layer "F.CrtYd")
		)
		(fp_text user "S"
			(at 1.02997 -0.100584 0)
			(unlocked yes)
			(layer "F.SilkS")
			(effects
				(font
					(size 0.635 0.4064)
					(thickness 0.1524)
				)
			)
		)
		(fp_text user "G"
			(at -0.92075 -0.076708 0)
			(unlocked yes)
			(layer "F.SilkS")
			(effects
				(font
					(size 0.635 0.4064)
					(thickness 0.1524)
				)
			)
		)
		(fp_text user "D"
			(at -1.11125 -1.374394 0)
			(unlocked yes)
			(layer "F.SilkS")
			(effects
				(font
					(size 0.635 0.4064)
					(thickness 0.1524)
				)
			)
		)
		(pad "D" smd rect
			(at 0 -1.1176 180)
			(size 1.016 1.27)
			(layers "F.Cu" "F.Mask" "F.Paste")
			(net "N52998261")
		)
		(pad "G" smd rect
			(at -1.016 1.1176 180)
			(size 1.016 1.27)
			(layers "F.Cu" "F.Mask" "F.Paste")
			(net "POWER_SW3_PWR_CTR_N")
		)
		(pad "S" smd rect
			(at 1.016 1.1176 180)
			(size 1.016 1.27)
			(layers "F.Cu" "F.Mask" "F.Paste")
			(net "GND")
		)
	)
	(footprint ""
		(layer "F.Cu")
		(at 107.652566 -142.394178 90)
		(property "Reference" "PR73"
			(at 1.927352 0.092964 90)
			(unlocked yes)
			(layer "F.SilkS")
			(effects
				(font
					(size 0.635 0.4064)
					(thickness 0.1524)
				)
				(justify left)
			)
		)
		(property "Value" ""
			(at 0 0 90)
			(layer "F.Fab")
			(effects
				(font
					(size 1.27 1.27)
				)
			)
		)
		(duplicate_pad_numbers_are_jumpers no)
		(fp_line
			(start 0.7874 -0.4064)
			(end 0.7874 0.4064)
			(stroke
				(width 0.1524)
				(type default)
			)
			(layer "F.SilkS")
		)
		(fp_line
			(start -0.7874 -0.4064)
			(end 0.7874 -0.4064)
			(stroke
				(width 0.1524)
				(type default)
			)
			(layer "F.SilkS")
		)
		(fp_line
			(start 0.7874 0.4064)
			(end -0.7874 0.4064)
			(stroke
				(width 0.1524)
				(type default)
			)
			(layer "F.SilkS")
		)
		(fp_line
			(start -0.7874 0.4064)
			(end -0.7874 -0.4064)
			(stroke
				(width 0.1524)
				(type default)
			)
			(layer "F.SilkS")
		)
		(fp_poly
			(pts
				(xy -0.508 0.2794) (xy -0.508 0.2286) (xy -0.635 0.2286) (xy -0.635 -0.254) (xy -0.5334 -0.254)
				(xy -0.5334 -0.2794) (xy 0.5334 -0.2794) (xy 0.5334 -0.254) (xy 0.635 -0.254) (xy 0.635 0.254) (xy 0.5334 0.254)
				(xy 0.5334 0.2794)
			)
			(stroke
				(width 0)
				(type default)
			)
			(fill no)
			(layer "F.CrtYd")
		)
		(pad "1" smd rect
			(at 0.40005 0 90)
			(size 0.4572 0.508)
			(layers "F.Cu" "F.Mask" "F.Paste")
			(net "VR_PVCCP_NODE1_TSEN_R")
		)
		(pad "2" smd rect
			(at -0.40005 0 90)
			(size 0.4572 0.508)
			(layers "F.Cu" "F.Mask" "F.Paste")
			(net "VR_PVCCP_NODE1_TSEN")
		)
	)
	(footprint ""
		(layer "F.Cu")
		(at 50.53076 -182.246524 90)
		(property "Reference" "C605"
			(at -133.313932 -3.637788 90)
			(unlocked yes)
			(layer "F.SilkS")
			(effects
				(font
					(size 0.7874 0.5842)
					(thickness 0.1524)
				)
				(justify left)
			)
		)
		(property "Value" ""
			(at 0 0 90)
			(layer "F.Fab")
			(effects
				(font
					(size 1.27 1.27)
				)
			)
		)
		(duplicate_pad_numbers_are_jumpers no)
		(fp_line
			(start 0.7874 -0.4064)
			(end 0.7874 0.4064)
			(stroke
				(width 0.1524)
				(type default)
			)
			(layer "F.SilkS")
		)
		(fp_line
			(start -0.7874 -0.4064)
			(end 0.7874 -0.4064)
			(stroke
				(width 0.1524)
				(type default)
			)
			(layer "F.SilkS")
		)
		(fp_line
			(start 0 0.381)
			(end 0 -0.381)
			(stroke
				(width 0.1524)
				(type default)
			)
			(layer "F.SilkS")
		)
		(fp_line
			(start 0.7874 0.4064)
			(end -0.7874 0.4064)
			(stroke
				(width 0.1524)
				(type default)
			)
			(layer "F.SilkS")
		)
		(fp_line
			(start -0.7874 0.4064)
			(end -0.7874 -0.4064)
			(stroke
				(width 0.1524)
				(type default)
			)
			(layer "F.SilkS")
		)
		(fp_poly
			(pts
				(xy -0.5334 0.254) (xy -0.635 0.254) (xy -0.635 0.2286) (xy -0.635 -0.254) (xy -0.5334 -0.254) (xy -0.5334 -0.2794)
				(xy 0.5334 -0.2794) (xy 0.5334 -0.254) (xy 0.635 -0.254) (xy 0.635 0.254) (xy 0.5334 0.254) (xy 0.5334 0.2794)
				(xy -0.508 0.2794) (xy -0.5334 0.2794)
			)
			(stroke
				(width 0)
				(type default)
			)
			(fill no)
			(layer "F.CrtYd")
		)
		(pad "1" smd rect
			(at 0.40005 0 90)
			(size 0.4572 0.508)
			(layers "F.Cu" "F.Mask" "F.Paste")
			(net "PSU3_AC_OK")
		)
		(pad "2" smd rect
			(at -0.40005 0 90)
			(size 0.4572 0.508)
			(layers "F.Cu" "F.Mask" "F.Paste")
			(net "GND")
		)
	)
	(footprint ""
		(layer "F.Cu")
		(at 8.73379 -167.373554 180)
		(property "Reference" "C548"
			(at 0.84074 1.497076 0)
			(unlocked yes)
			(layer "F.SilkS")
			(effects
				(font
					(size 0.7874 0.5842)
					(thickness 0.1524)
				)
				(justify left)
			)
		)
		(property "Value" ""
			(at 0 0 180)
			(layer "F.Fab")
			(effects
				(font
					(size 1.27 1.27)
				)
			)
		)
		(duplicate_pad_numbers_are_jumpers no)
		(fp_line
			(start 0.7874 0.4064)
			(end -0.7874 0.4064)
			(stroke
				(width 0.1524)
				(type default)
			)
			(layer "F.SilkS")
		)
		(fp_line
			(start 0.7874 -0.4064)
			(end 0.7874 0.4064)
			(stroke
				(width 0.1524)
				(type default)
			)
			(layer "F.SilkS")
		)
		(fp_line
			(start 0 0.381)
			(end 0 -0.381)
			(stroke
				(width 0.1524)
				(type default)
			)
			(layer "F.SilkS")
		)
		(fp_line
			(start -0.7874 0.4064)
			(end -0.7874 -0.4064)
			(stroke
				(width 0.1524)
				(type default)
			)
			(layer "F.SilkS")
		)
		(fp_line
			(start -0.7874 -0.4064)
			(end 0.7874 -0.4064)
			(stroke
				(width 0.1524)
				(type default)
			)
			(layer "F.SilkS")
		)
		(fp_poly
			(pts
				(xy -0.5334 0.254) (xy -0.635 0.254) (xy -0.635 0.2286) (xy -0.635 -0.254) (xy -0.5334 -0.254) (xy -0.5334 -0.2794)
				(xy 0.5334 -0.2794) (xy 0.5334 -0.254) (xy 0.635 -0.254) (xy 0.635 0.254) (xy 0.5334 0.254) (xy 0.5334 0.2794)
				(xy -0.508 0.2794) (xy -0.5334 0.2794)
			)
			(stroke
				(width 0)
				(type default)
			)
			(fill no)
			(layer "F.CrtYd")
		)
		(pad "1" smd rect
			(at 0.40005 0 180)
			(size 0.4572 0.508)
			(layers "F.Cu" "F.Mask" "F.Paste")
			(net "GND")
		)
		(pad "2" smd rect
			(at -0.40005 0 180)
			(size 0.4572 0.508)
			(layers "F.Cu" "F.Mask" "F.Paste")
			(net "N54258537")
		)
	)
	(footprint ""
		(layer "F.Cu")
		(at 14.035024 -160.409128 -90)
		(property "Reference" "C540"
			(at 0.076708 -1.743202 90)
			(unlocked yes)
			(layer "F.SilkS")
			(effects
				(font
					(size 0.7874 0.5842)
					(thickness 0.1524)
				)
				(justify left)
			)
		)
		(property "Value" ""
			(at 0 0 270)
			(layer "F.Fab")
			(effects
				(font
					(size 1.27 1.27)
				)
			)
		)
		(duplicate_pad_numbers_are_jumpers no)
		(fp_line
			(start -2.2098 0.9398)
			(end -2.2098 -0.9398)
			(stroke
				(width 0.1524)
				(type default)
			)
			(layer "F.SilkS")
		)
		(fp_line
			(start 2.2098 0.9398)
			(end -2.2098 0.9398)
			(stroke
				(width 0.1524)
				(type default)
			)
			(layer "F.SilkS")
		)
		(fp_line
			(start -2.2098 -0.9398)
			(end 2.2098 -0.9398)
			(stroke
				(width 0.1524)
				(type default)
			)
			(layer "F.SilkS")
		)
		(fp_line
			(start 0 -0.9398)
			(end 0 0.9398)
			(stroke
				(width 0.1524)
				(type default)
			)
			(layer "F.SilkS")
		)
		(fp_line
			(start 2.2098 -0.9398)
			(end 2.2098 0.9398)
			(stroke
				(width 0.1524)
				(type default)
			)
			(layer "F.SilkS")
		)
		(fp_poly
			(pts
				(xy -1.6764 0.889) (xy -1.6764 0.7874) (xy -2.0574 0.7874) (xy -2.0574 -0.7874) (xy -1.6764 -0.7874)
				(xy -1.6764 -0.889) (xy -1.6764 -0.9398) (xy 1.6764 -0.9398) (xy 1.6764 -0.889) (xy 1.6764 -0.7874)
				(xy 2.0574 -0.7874) (xy 2.0574 0.7874) (xy 1.6764 0.7874) (xy 1.6764 0.889) (xy 1.6764 0.9398) (xy -1.6764 0.9398)
			)
			(stroke
				(width 0)
				(type default)
			)
			(fill no)
			(layer "F.CrtYd")
		)
		(pad "1" smd rect
			(at 1.4732 0 270)
			(size 1.1684 1.5748)
			(layers "F.Cu" "F.Mask" "F.Paste")
			(net "N54065132")
		)
		(pad "2" smd rect
			(at -1.4732 0 270)
			(size 1.1684 1.5748)
			(layers "F.Cu" "F.Mask" "F.Paste")
			(net "GND")
		)
	)
	(footprint ""
		(layer "F.Cu")
		(at 90.812112 -171.48302 180)
		(property "Reference" "R936"
			(at -85.974428 -74.521568 0)
			(unlocked yes)
			(layer "F.SilkS")
			(effects
				(font
					(size 0.7874 0.5842)
					(thickness 0.1524)
				)
				(justify left)
			)
		)
		(property "Value" ""
			(at 0 0 180)
			(layer "F.Fab")
			(effects
				(font
					(size 1.27 1.27)
				)
			)
		)
		(duplicate_pad_numbers_are_jumpers no)
		(fp_line
			(start 0.7874 0.4064)
			(end -0.7874 0.4064)
			(stroke
				(width 0.1524)
				(type default)
			)
			(layer "F.SilkS")
		)
		(fp_line
			(start 0.7874 -0.4064)
			(end 0.7874 0.4064)
			(stroke
				(width 0.1524)
				(type default)
			)
			(layer "F.SilkS")
		)
		(fp_line
			(start -0.7874 0.4064)
			(end -0.7874 -0.4064)
			(stroke
				(width 0.1524)
				(type default)
			)
			(layer "F.SilkS")
		)
		(fp_line
			(start -0.7874 -0.4064)
			(end 0.7874 -0.4064)
			(stroke
				(width 0.1524)
				(type default)
			)
			(layer "F.SilkS")
		)
		(fp_poly
			(pts
				(xy -0.508 0.2794) (xy -0.508 0.2286) (xy -0.635 0.2286) (xy -0.635 -0.254) (xy -0.5334 -0.254)
				(xy -0.5334 -0.2794) (xy 0.5334 -0.2794) (xy 0.5334 -0.254) (xy 0.635 -0.254) (xy 0.635 0.254) (xy 0.5334 0.254)
				(xy 0.5334 0.2794)
			)
			(stroke
				(width 0)
				(type default)
			)
			(fill no)
			(layer "F.CrtYd")
		)
		(pad "1" smd rect
			(at 0.40005 0 180)
			(size 0.4572 0.508)
			(layers "F.Cu" "F.Mask" "F.Paste")
			(net "UART_T6_NODE1_TXD")
		)
		(pad "2" smd rect
			(at -0.40005 0 180)
			(size 0.4572 0.508)
			(layers "F.Cu" "F.Mask" "F.Paste")
			(net "UART_T6_NODE1_TXD_R")
		)
	)
	(footprint ""
		(layer "F.Cu")
		(at 143.105886 -54.529228 180)
		(property "Reference" "R1015"
			(at -1.100582 0.92202 0)
			(unlocked yes)
			(layer "F.SilkS")
			(effects
				(font
					(size 0.7874 0.5842)
					(thickness 0.1524)
				)
				(justify left)
			)
		)
		(property "Value" ""
			(at 0 0 180)
			(layer "F.Fab")
			(effects
				(font
					(size 1.27 1.27)
				)
			)
		)
		(duplicate_pad_numbers_are_jumpers no)
		(fp_line
			(start 0.7874 0.4064)
			(end -0.7874 0.4064)
			(stroke
				(width 0.1524)
				(type default)
			)
			(layer "F.SilkS")
		)
		(fp_line
			(start 0.7874 -0.4064)
			(end 0.7874 0.4064)
			(stroke
				(width 0.1524)
				(type default)
			)
			(layer "F.SilkS")
		)
		(fp_line
			(start -0.7874 0.4064)
			(end -0.7874 -0.4064)
			(stroke
				(width 0.1524)
				(type default)
			)
			(layer "F.SilkS")
		)
		(fp_line
			(start -0.7874 -0.4064)
			(end 0.7874 -0.4064)
			(stroke
				(width 0.1524)
				(type default)
			)
			(layer "F.SilkS")
		)
		(fp_poly
			(pts
				(xy -0.508 0.2794) (xy -0.508 0.2286) (xy -0.635 0.2286) (xy -0.635 -0.254) (xy -0.5334 -0.254)
				(xy -0.5334 -0.2794) (xy 0.5334 -0.2794) (xy 0.5334 -0.254) (xy 0.635 -0.254) (xy 0.635 0.254) (xy 0.5334 0.254)
				(xy 0.5334 0.2794)
			)
			(stroke
				(width 0)
				(type default)
			)
			(fill no)
			(layer "F.CrtYd")
		)
		(pad "1" smd rect
			(at 0.40005 0 180)
			(size 0.4572 0.508)
			(layers "F.Cu" "F.Mask" "F.Paste")
			(net "P5V_NODE1")
		)
		(pad "2" smd rect
			(at -0.40005 0 180)
			(size 0.4572 0.508)
			(layers "F.Cu" "F.Mask" "F.Paste")
			(net "UART_DTR_P2_N")
		)
	)
	(footprint ""
		(layer "F.Cu")
		(at 156.041852 -105.98023 -90)
		(property "Reference" "R273"
			(at -1.590802 -0.01143 90)
			(unlocked yes)
			(layer "F.SilkS")
			(effects
				(font
					(size 0.7874 0.5842)
					(thickness 0.1524)
				)
				(justify left)
			)
		)
		(property "Value" ""
			(at 0 0 270)
			(layer "F.Fab")
			(effects
				(font
					(size 1.27 1.27)
				)
			)
		)
		(duplicate_pad_numbers_are_jumpers no)
		(fp_line
			(start -0.7874 0.4064)
			(end -0.7874 -0.4064)
			(stroke
				(width 0.1524)
				(type default)
			)
			(layer "F.SilkS")
		)
		(fp_line
			(start 0.7874 0.4064)
			(end -0.7874 0.4064)
			(stroke
				(width 0.1524)
				(type default)
			)
			(layer "F.SilkS")
		)
		(fp_line
			(start -0.7874 -0.4064)
			(end 0.7874 -0.4064)
			(stroke
				(width 0.1524)
				(type default)
			)
			(layer "F.SilkS")
		)
		(fp_line
			(start 0.7874 -0.4064)
			(end 0.7874 0.4064)
			(stroke
				(width 0.1524)
				(type default)
			)
			(layer "F.SilkS")
		)
		(fp_poly
			(pts
				(xy -0.508 0.2794) (xy -0.508 0.2286) (xy -0.635 0.2286) (xy -0.635 -0.254) (xy -0.5334 -0.254)
				(xy -0.5334 -0.2794) (xy 0.5334 -0.2794) (xy 0.5334 -0.254) (xy 0.635 -0.254) (xy 0.635 0.254) (xy 0.5334 0.254)
				(xy 0.5334 0.2794)
			)
			(stroke
				(width 0)
				(type default)
			)
			(fill no)
			(layer "F.CrtYd")
		)
		(pad "1" smd rect
			(at 0.40005 0 270)
			(size 0.4572 0.508)
			(layers "F.Cu" "F.Mask" "F.Paste")
			(net "PE_SW_USB_PERST_L")
		)
		(pad "2" smd rect
			(at -0.40005 0 270)
			(size 0.4572 0.508)
			(layers "F.Cu" "F.Mask" "F.Paste")
			(net "N34379705")
		)
	)
	(footprint ""
		(layer "F.Cu")
		(at 119.238776 -160.40481 90)
		(property "Reference" "R668"
			(at -0.90297 -2.14503 90)
			(unlocked yes)
			(layer "F.SilkS")
			(effects
				(font
					(size 0.635 0.4064)
					(thickness 0.1524)
				)
				(justify left)
			)
		)
		(property "Value" ""
			(at 0 0 90)
			(layer "F.Fab")
			(effects
				(font
					(size 1.27 1.27)
				)
			)
		)
		(duplicate_pad_numbers_are_jumpers no)
		(fp_line
			(start 0.7874 -0.4064)
			(end 0.7874 0.4064)
			(stroke
				(width 0.1524)
				(type default)
			)
			(layer "F.SilkS")
		)
		(fp_line
			(start -0.7874 -0.4064)
			(end 0.7874 -0.4064)
			(stroke
				(width 0.1524)
				(type default)
			)
			(layer "F.SilkS")
		)
		(fp_line
			(start 0.7874 0.4064)
			(end -0.7874 0.4064)
			(stroke
				(width 0.1524)
				(type default)
			)
			(layer "F.SilkS")
		)
		(fp_line
			(start -0.7874 0.4064)
			(end -0.7874 -0.4064)
			(stroke
				(width 0.1524)
				(type default)
			)
			(layer "F.SilkS")
		)
		(fp_poly
			(pts
				(xy -0.508 0.2794) (xy -0.508 0.2286) (xy -0.635 0.2286) (xy -0.635 -0.254) (xy -0.5334 -0.254)
				(xy -0.5334 -0.2794) (xy 0.5334 -0.2794) (xy 0.5334 -0.254) (xy 0.635 -0.254) (xy 0.635 0.254) (xy 0.5334 0.254)
				(xy 0.5334 0.2794)
			)
			(stroke
				(width 0)
				(type default)
			)
			(fill no)
			(layer "F.CrtYd")
		)
		(pad "1" smd rect
			(at 0.40005 0 90)
			(size 0.4572 0.508)
			(layers "F.Cu" "F.Mask" "F.Paste")
			(net "P3V3_NODE1")
		)
		(pad "2" smd rect
			(at -0.40005 0 90)
			(size 0.4572 0.508)
			(layers "F.Cu" "F.Mask" "F.Paste")
			(net "I2C_PSU2_SDA_MOS")
		)
	)
	(footprint ""
		(layer "F.Cu")
		(at 183.71185 -43.04157 90)
		(property "Reference" "J14"
			(at -8.561832 7.690358 0)
			(unlocked yes)
			(layer "F.SilkS")
			(effects
				(font
					(size 0.7874 0.5842)
					(thickness 0.1524)
				)
				(justify left)
			)
		)
		(property "Value" ""
			(at 0 0 90)
			(layer "F.Fab")
			(effects
				(font
					(size 1.27 1.27)
				)
			)
		)
		(duplicate_pad_numbers_are_jumpers no)
		(fp_line
			(start 4.953 -3.9878)
			(end -4.953 -3.9878)
			(stroke
				(width 0.1524)
				(type default)
			)
			(layer "F.SilkS")
		)
		(fp_line
			(start -7.62 -1.3716)
			(end -7.62 1.1176)
			(stroke
				(width 0.1524)
				(type default)
			)
			(layer "F.SilkS")
		)
		(fp_line
			(start 7.62 1.1176)
			(end 7.62 -1.3716)
			(stroke
				(width 0.1524)
				(type default)
			)
			(layer "F.SilkS")
		)
		(fp_line
			(start -7.62 4.318)
			(end -7.62 14.3764)
			(stroke
				(width 0.1524)
				(type default)
			)
			(layer "F.SilkS")
		)
		(fp_line
			(start 7.62 14.3764)
			(end 7.62 4.318)
			(stroke
				(width 0.1524)
				(type default)
			)
			(layer "F.SilkS")
		)
		(fp_line
			(start -7.62 14.3764)
			(end 7.62 14.3764)
			(stroke
				(width 0.1524)
				(type default)
			)
			(layer "F.SilkS")
		)
		(fp_poly
			(pts
				(xy -8.5725 0) (xy -10.4775 -0.762) (xy -10.4775 0.762)
			)
			(stroke
				(width 0)
				(type default)
			)
			(fill yes)
			(layer "F.SilkS")
		)
		(fp_poly
			(pts
				(xy -4.2926 -3.4036) (xy 4.2926 -3.4036) (xy 4.2926 -1.8288) (xy -4.2926 -1.8288)
			)
			(stroke
				(width 0)
				(type default)
			)
			(fill no)
			(layer "B.CrtYd")
		)
		(fp_poly
			(pts
				(xy 4.2926 -0.7874) (xy -4.2926 -0.7874) (xy -4.2926 0.7874) (xy 4.2926 0.7874)
			)
			(stroke
				(width 0)
				(type default)
			)
			(fill no)
			(layer "B.CrtYd")
		)
		(fp_poly
			(pts
				(arc
					(start 6.5659 -4.8006)
					(mid 5.272743 -4.264957)
					(end 4.7371 -2.9718)
				)
				(arc
					(start 4.7371 -2.9464)
					(mid 5.265304 -1.671204)
					(end 6.5405 -1.143)
				)
				(arc
					(start 6.5913 -1.143)
					(mid 8.4201 -2.9718)
					(end 6.5913 -4.8006)
				)
			)
			(stroke
				(width 0)
				(type default)
			)
			(fill no)
			(layer "B.CrtYd")
		)
		(fp_poly
			(pts
				(arc
					(start -6.5786 -4.8006)
					(mid -7.871757 -4.264957)
					(end -8.4074 -2.9718)
				)
				(arc
					(start -8.4074 -2.9464)
					(mid -7.879196 -1.671204)
					(end -6.604 -1.143)
				)
				(arc
					(start -6.5532 -1.143)
					(mid -4.7244 -2.9718)
					(end -6.5532 -4.8006)
				)
			)
			(stroke
				(width 0)
				(type default)
			)
			(fill no)
			(layer "B.CrtYd")
		)
		(fp_poly
			(pts
				(arc
					(start 6.5659 0.889)
					(mid 5.272743 1.424643)
					(end 4.7371 2.7178)
				)
				(arc
					(start 4.7371 2.7432)
					(mid 5.265304 4.018396)
					(end 6.5405 4.5466)
				)
				(arc
					(start 6.5913 4.5466)
					(mid 8.4201 2.7178)
					(end 6.5913 0.889)
				)
			)
			(stroke
				(width 0)
				(type default)
			)
			(fill no)
			(layer "B.CrtYd")
		)
		(fp_poly
			(pts
				(arc
					(start -6.5913 0.889)
					(mid -7.884457 1.424643)
					(end -8.4201 2.7178)
				)
				(arc
					(start -8.4201 2.7432)
					(mid -7.891896 4.018396)
					(end -6.6167 4.5466)
				)
				(arc
					(start -6.5659 4.5466)
					(mid -4.7371 2.7178)
					(end -6.5659 0.889)
				)
			)
			(stroke
				(width 0)
				(type default)
			)
			(fill no)
			(layer "B.CrtYd")
		)
		(fp_rect
			(start -8.7376 14.4526)
			(end 8.7376 -4.9276)
			(stroke
				(width 0)
				(type default)
			)
			(fill no)
			(layer "F.CrtYd")
		)
		(fp_line
			(start 7.62 -3.9878)
			(end 7.62 14.3764)
			(stroke
				(width 0.1)
				(type default)
			)
			(layer "F.Fab")
		)
		(fp_line
			(start -7.62 -3.9878)
			(end 7.62 -3.9878)
			(stroke
				(width 0.1)
				(type default)
			)
			(layer "F.Fab")
		)
		(fp_line
			(start -7.62 4.318)
			(end -7.62 -3.9878)
			(stroke
				(width 0.1)
				(type default)
			)
			(layer "F.Fab")
		)
		(fp_line
			(start 7.62 14.3764)
			(end -7.62 14.3764)
			(stroke
				(width 0.1)
				(type default)
			)
			(layer "F.Fab")
		)
		(fp_line
			(start -7.62 14.3764)
			(end -7.62 4.318)
			(stroke
				(width 0.1)
				(type default)
			)
			(layer "F.Fab")
		)
		(fp_poly
			(pts
				(xy -8.5725 0) (xy -10.4775 -0.762) (xy -10.4775 0.762)
			)
			(stroke
				(width 0)
				(type default)
			)
			(fill yes)
			(layer "F.Fab")
		)
		(fp_text user "5"
			(at -3.44932 -4.927854 0)
			(unlocked yes)
			(layer "F.SilkS")
			(effects
				(font
					(size 0.7874 0.5842)
					(thickness 0.1524)
				)
				(justify left)
			)
		)
		(fp_text user "8"
			(at 3.736594 -4.872736 0)
			(unlocked yes)
			(layer "F.SilkS")
			(effects
				(font
					(size 0.7874 0.5842)
					(thickness 0.1524)
				)
				(justify left)
			)
		)
		(fp_text user "1"
			(at -8.516366 -1.058418 0)
			(unlocked yes)
			(layer "F.SilkS")
			(effects
				(font
					(size 0.7874 0.5842)
					(thickness 0.1524)
				)
				(justify left)
			)
		)
		(fp_text user "4"
			(at 8.269478 -0.192532 0)
			(unlocked yes)
			(layer "F.SilkS")
			(effects
				(font
					(size 0.7874 0.5842)
					(thickness 0.1524)
				)
				(justify left)
			)
		)
		(fp_text user "8"
			(at 3.588258 -3.830574 0)
			(unlocked yes)
			(layer "B.SilkS")
			(effects
				(font
					(size 0.7874 0.5842)
					(thickness 0.1524)
				)
				(justify left mirror)
			)
		)
		(fp_text user "5"
			(at -3.569208 -3.71348 0)
			(unlocked yes)
			(layer "B.SilkS")
			(effects
				(font
					(size 0.7874 0.5842)
					(thickness 0.1524)
				)
				(justify left mirror)
			)
		)
		(fp_text user "1"
			(at -3.569208 1.502664 0)
			(unlocked yes)
			(layer "B.SilkS")
			(effects
				(font
					(size 0.7874 0.5842)
					(thickness 0.1524)
				)
				(justify left mirror)
			)
		)
		(fp_text user "4"
			(at 3.541268 1.759966 0)
			(unlocked yes)
			(layer "B.SilkS")
			(effects
				(font
					(size 0.7874 0.5842)
					(thickness 0.1524)
				)
				(justify left mirror)
			)
		)
		(fp_text user "8"
			(at 3.9624 -5.5372 90)
			(unlocked yes)
			(layer "B.Fab")
			(effects
				(font
					(size 1.016 0.762)
					(thickness 0.000001)
				)
				(justify left mirror)
			)
		)
		(fp_text user "5"
			(at -3.0734 -5.5372 90)
			(unlocked yes)
			(layer "B.Fab")
			(effects
				(font
					(size 1.016 0.762)
					(thickness 0.000001)
				)
				(justify left mirror)
			)
		)
		(fp_text user "4"
			(at 5.334 -0.118618 90)
			(unlocked yes)
			(layer "B.Fab")
			(effects
				(font
					(size 1.016 0.762)
					(thickness 0.000001)
				)
				(justify left mirror)
			)
		)
		(fp_text user "1"
			(at -4.572 -0.118618 90)
			(unlocked yes)
			(layer "B.Fab")
			(effects
				(font
					(size 1.016 0.762)
					(thickness 0.000001)
				)
				(justify left mirror)
			)
		)
		(fp_text user "8"
			(at 3.175 -5.5372 90)
			(unlocked yes)
			(layer "F.Fab")
			(effects
				(font
					(size 1.016 0.762)
					(thickness 0.000001)
				)
				(justify left)
			)
		)
		(fp_text user "5"
			(at -3.81 -5.5372 90)
			(unlocked yes)
			(layer "F.Fab")
			(effects
				(font
					(size 1.016 0.762)
					(thickness 0.000001)
				)
				(justify left)
			)
		)
		(fp_text user "4"
			(at 8.001 -0.118618 90)
			(unlocked yes)
			(layer "F.Fab")
			(effects
				(font
					(size 1.016 0.762)
					(thickness 0.000001)
				)
				(justify left)
			)
		)
		(fp_text user "1"
			(at -8.763 -0.118618 90)
			(unlocked yes)
			(layer "F.Fab")
			(effects
				(font
					(size 1.016 0.762)
					(thickness 0.000001)
				)
				(justify left)
			)
		)
		(pad "1" thru_hole rect
			(at -3.5052 0 90)
			(size 1.4732 1.4732)
			(drill 1.016)
			(layers "*.Cu" "*.Mask")
			(remove_unused_layers no)
			(net "USBPWR_P0")
			(clearance 0.0254)
			(thermal_gap 0.0254)
			(padstack
				(mode front_inner_back)
				(layer "Inner"
					(shape circle)
					(size 1.4732 1.4732)
					(clearance 0.0254)
				)
				(layer "B.Cu"
					(shape rect)
					(size 1.4732 1.4732)
					(clearance 0.0254)
				)
			)
		)
		(pad "2" thru_hole circle
			(at -1.016 0 90)
			(size 1.4732 1.4732)
			(drill 1.016)
			(layers "*.Cu" "*.Mask")
			(remove_unused_layers no)
			(net "USB0_L_DN")
			(clearance 0.0254)
			(thermal_gap 0.0254)
		)
		(pad "3" thru_hole circle
			(at 1.016 0 90)
			(size 1.4732 1.4732)
			(drill 1.016)
			(layers "*.Cu" "*.Mask")
			(remove_unused_layers no)
			(net "USB0_L_DP")
			(clearance 0.0254)
			(thermal_gap 0.0254)
		)
		(pad "4" thru_hole circle
			(at 3.5052 0 90)
			(size 1.4732 1.4732)
			(drill 1.016)
			(layers "*.Cu" "*.Mask")
			(remove_unused_layers no)
			(net "GND")
			(clearance 0.0254)
			(thermal_gap 0.0254)
		)
		(pad "5" thru_hole circle
			(at -3.5052 -2.6162 90)
			(size 1.4732 1.4732)
			(drill 1.016)
			(layers "*.Cu" "*.Mask")
			(remove_unused_layers no)
			(net "USBPWR_P0")
			(clearance 0.0254)
			(thermal_gap 0.0254)
		)
		(pad "6" thru_hole circle
			(at -1.016 -2.6162 90)
			(size 1.4732 1.4732)
			(drill 1.016)
			(layers "*.Cu" "*.Mask")
			(remove_unused_layers no)
			(net "USB1_L_DN")
			(clearance 0.0254)
			(thermal_gap 0.0254)
		)
		(pad "7" thru_hole circle
			(at 1.016 -2.6162 90)
			(size 1.4732 1.4732)
			(drill 1.016)
			(layers "*.Cu" "*.Mask")
			(remove_unused_layers no)
			(net "USB1_L_DP")
			(clearance 0.0254)
			(thermal_gap 0.0254)
		)
		(pad "8" thru_hole circle
			(at 3.5052 -2.6162 90)
			(size 1.4732 1.4732)
			(drill 1.016)
			(layers "*.Cu" "*.Mask")
			(remove_unused_layers no)
			(net "GND")
			(clearance 0.0254)
			(thermal_gap 0.0254)
		)
		(pad "9" thru_hole circle
			(at -6.5786 2.7178 90)
			(size 3.556 3.556)
			(drill 2.286)
			(layers "*.Cu" "*.Mask")
			(remove_unused_layers no)
			(net "GND")
			(clearance -0.381)
		)
		(pad "10" thru_hole circle
			(at 6.5786 2.7178 90)
			(size 3.556 3.556)
			(drill 2.286)
			(layers "*.Cu" "*.Mask")
			(remove_unused_layers no)
			(net "GND")
			(clearance -0.381)
		)
		(pad "11" thru_hole circle
			(at -6.5786 -2.9718 90)
			(size 3.556 3.556)
			(drill 2.286)
			(layers "*.Cu" "*.Mask")
			(remove_unused_layers no)
			(net "GND")
			(clearance -0.381)
		)
		(pad "12" thru_hole circle
			(at 6.5786 -2.9718 90)
			(size 3.556 3.556)
			(drill 2.286)
			(layers "*.Cu" "*.Mask")
			(remove_unused_layers no)
			(net "GND")
			(clearance -0.381)
		)
	)
	(footprint ""
		(layer "F.Cu")
		(at 123.682252 -162.464242)
		(property "Reference" "R1248"
			(at 29.77388 46.490636 0)
			(unlocked yes)
			(layer "F.SilkS")
			(effects
				(font
					(size 0.7874 0.5842)
					(thickness 0.1524)
				)
				(justify left)
			)
		)
		(property "Value" ""
			(at 0 0 0)
			(layer "F.Fab")
			(effects
				(font
					(size 1.27 1.27)
				)
			)
		)
		(duplicate_pad_numbers_are_jumpers no)
		(fp_line
			(start -0.7874 -0.4064)
			(end 0.7874 -0.4064)
			(stroke
				(width 0.1524)
				(type default)
			)
			(layer "F.SilkS")
		)
		(fp_line
			(start -0.7874 0.4064)
			(end -0.7874 -0.4064)
			(stroke
				(width 0.1524)
				(type default)
			)
			(layer "F.SilkS")
		)
		(fp_line
			(start 0.7874 -0.4064)
			(end 0.7874 0.4064)
			(stroke
				(width 0.1524)
				(type default)
			)
			(layer "F.SilkS")
		)
		(fp_line
			(start 0.7874 0.4064)
			(end -0.7874 0.4064)
			(stroke
				(width 0.1524)
				(type default)
			)
			(layer "F.SilkS")
		)
		(fp_poly
			(pts
				(xy -0.508 0.2794) (xy -0.508 0.2286) (xy -0.635 0.2286) (xy -0.635 -0.254) (xy -0.5334 -0.254)
				(xy -0.5334 -0.2794) (xy 0.5334 -0.2794) (xy 0.5334 -0.254) (xy 0.635 -0.254) (xy 0.635 0.254) (xy 0.5334 0.254)
				(xy 0.5334 0.2794)
			)
			(stroke
				(width 0)
				(type default)
			)
			(fill no)
			(layer "F.CrtYd")
		)
		(pad "1" smd rect
			(at 0.40005 0)
			(size 0.4572 0.508)
			(layers "F.Cu" "F.Mask" "F.Paste")
			(net "P3V3_NODE1")
		)
		(pad "2" smd rect
			(at -0.40005 0)
			(size 0.4572 0.508)
			(layers "F.Cu" "F.Mask" "F.Paste")
			(net "UART_CMC_RX_P")
		)
	)
	(footprint ""
		(layer "F.Cu")
		(at 167.558212 -174.366428 90)
		(property "Reference" "R1303"
			(at 1.076706 0.131572 90)
			(unlocked yes)
			(layer "F.SilkS")
			(effects
				(font
					(size 0.7874 0.5842)
					(thickness 0.1524)
				)
				(justify left)
			)
		)
		(property "Value" ""
			(at 0 0 90)
			(layer "F.Fab")
			(effects
				(font
					(size 1.27 1.27)
				)
			)
		)
		(duplicate_pad_numbers_are_jumpers no)
		(fp_line
			(start 0.7874 -0.4064)
			(end 0.7874 0.4064)
			(stroke
				(width 0.1524)
				(type default)
			)
			(layer "F.SilkS")
		)
		(fp_line
			(start -0.7874 -0.4064)
			(end 0.7874 -0.4064)
			(stroke
				(width 0.1524)
				(type default)
			)
			(layer "F.SilkS")
		)
		(fp_line
			(start 0.7874 0.4064)
			(end -0.7874 0.4064)
			(stroke
				(width 0.1524)
				(type default)
			)
			(layer "F.SilkS")
		)
		(fp_line
			(start -0.7874 0.4064)
			(end -0.7874 -0.4064)
			(stroke
				(width 0.1524)
				(type default)
			)
			(layer "F.SilkS")
		)
		(fp_poly
			(pts
				(xy -0.508 0.2794) (xy -0.508 0.2286) (xy -0.635 0.2286) (xy -0.635 -0.254) (xy -0.5334 -0.254)
				(xy -0.5334 -0.2794) (xy 0.5334 -0.2794) (xy 0.5334 -0.254) (xy 0.635 -0.254) (xy 0.635 0.254) (xy 0.5334 0.254)
				(xy 0.5334 0.2794)
			)
			(stroke
				(width 0)
				(type default)
			)
			(fill no)
			(layer "F.CrtYd")
		)
		(pad "1" smd rect
			(at 0.40005 0 90)
			(size 0.4572 0.508)
			(layers "F.Cu" "F.Mask" "F.Paste")
			(net "GND")
		)
		(pad "2" smd rect
			(at -0.40005 0 90)
			(size 0.4572 0.508)
			(layers "F.Cu" "F.Mask" "F.Paste")
			(net "N54365542")
		)
	)
	(footprint ""
		(layer "F.Cu")
		(at 41.638982 -9.1186 -90)
		(property "Reference" "PC77"
			(at -0.18034 10.21969 90)
			(unlocked yes)
			(layer "F.SilkS")
			(effects
				(font
					(size 0.7874 0.5842)
					(thickness 0.1524)
				)
				(justify left)
			)
		)
		(property "Value" ""
			(at 0 0 270)
			(layer "F.Fab")
			(effects
				(font
					(size 1.27 1.27)
				)
			)
		)
		(duplicate_pad_numbers_are_jumpers no)
		(fp_line
			(start -0.7874 0.4064)
			(end -0.7874 -0.4064)
			(stroke
				(width 0.1524)
				(type default)
			)
			(layer "F.SilkS")
		)
		(fp_line
			(start 0.7874 0.4064)
			(end -0.7874 0.4064)
			(stroke
				(width 0.1524)
				(type default)
			)
			(layer "F.SilkS")
		)
		(fp_line
			(start 0 0.381)
			(end 0 -0.381)
			(stroke
				(width 0.1524)
				(type default)
			)
			(layer "F.SilkS")
		)
		(fp_line
			(start -0.7874 -0.4064)
			(end 0.7874 -0.4064)
			(stroke
				(width 0.1524)
				(type default)
			)
			(layer "F.SilkS")
		)
		(fp_line
			(start 0.7874 -0.4064)
			(end 0.7874 0.4064)
			(stroke
				(width 0.1524)
				(type default)
			)
			(layer "F.SilkS")
		)
		(fp_poly
			(pts
				(xy -0.5334 0.254) (xy -0.635 0.254) (xy -0.635 0.2286) (xy -0.635 -0.254) (xy -0.5334 -0.254) (xy -0.5334 -0.2794)
				(xy 0.5334 -0.2794) (xy 0.5334 -0.254) (xy 0.635 -0.254) (xy 0.635 0.254) (xy 0.5334 0.254) (xy 0.5334 0.2794)
				(xy -0.508 0.2794) (xy -0.5334 0.2794)
			)
			(stroke
				(width 0)
				(type default)
			)
			(fill no)
			(layer "F.CrtYd")
		)
		(pad "1" smd rect
			(at 0.40005 0 270)
			(size 0.4572 0.508)
			(layers "F.Cu" "F.Mask" "F.Paste")
			(net "SW_PV_VDDR_NODE1_BT")
		)
		(pad "2" smd rect
			(at -0.40005 0 270)
			(size 0.4572 0.508)
			(layers "F.Cu" "F.Mask" "F.Paste")
			(net "SW_PV_VDDR_NODE1_PH")
		)
	)
	(footprint ""
		(layer "F.Cu")
		(at 12.587986 -11.613896 90)
		(property "Reference" "R215"
			(at -0.984758 -4.622038 90)
			(unlocked yes)
			(layer "F.SilkS")
			(effects
				(font
					(size 0.7874 0.5842)
					(thickness 0.1524)
				)
				(justify left)
			)
		)
		(property "Value" ""
			(at 0 0 90)
			(layer "F.Fab")
			(effects
				(font
					(size 1.27 1.27)
				)
			)
		)
		(duplicate_pad_numbers_are_jumpers no)
		(fp_line
			(start 0.7874 -0.4064)
			(end 0.7874 0.4064)
			(stroke
				(width 0.1524)
				(type default)
			)
			(layer "F.SilkS")
		)
		(fp_line
			(start -0.7874 -0.4064)
			(end 0.7874 -0.4064)
			(stroke
				(width 0.1524)
				(type default)
			)
			(layer "F.SilkS")
		)
		(fp_line
			(start 0.7874 0.4064)
			(end -0.7874 0.4064)
			(stroke
				(width 0.1524)
				(type default)
			)
			(layer "F.SilkS")
		)
		(fp_line
			(start -0.7874 0.4064)
			(end -0.7874 -0.4064)
			(stroke
				(width 0.1524)
				(type default)
			)
			(layer "F.SilkS")
		)
		(fp_poly
			(pts
				(xy -0.508 0.2794) (xy -0.508 0.2286) (xy -0.635 0.2286) (xy -0.635 -0.254) (xy -0.5334 -0.254)
				(xy -0.5334 -0.2794) (xy 0.5334 -0.2794) (xy 0.5334 -0.254) (xy 0.635 -0.254) (xy 0.635 0.254) (xy 0.5334 0.254)
				(xy 0.5334 0.2794)
			)
			(stroke
				(width 0)
				(type default)
			)
			(fill no)
			(layer "F.CrtYd")
		)
		(pad "1" smd rect
			(at 0.40005 0 90)
			(size 0.4572 0.508)
			(layers "F.Cu" "F.Mask" "F.Paste")
			(net "PV_VDDR_NODE1")
		)
		(pad "2" smd rect
			(at -0.40005 0 90)
			(size 0.4572 0.508)
			(layers "F.Cu" "F.Mask" "F.Paste")
			(net "PV_VDDR_NODE1_VREF_R")
		)
	)
	(footprint ""
		(layer "F.Cu")
		(at 149.057868 -39.972996 90)
		(property "Reference" "R1008"
			(at -1.681226 10.212832 90)
			(unlocked yes)
			(layer "F.SilkS")
			(effects
				(font
					(size 0.7874 0.5842)
					(thickness 0.1524)
				)
				(justify left)
			)
		)
		(property "Value" ""
			(at 0 0 90)
			(layer "F.Fab")
			(effects
				(font
					(size 1.27 1.27)
				)
			)
		)
		(duplicate_pad_numbers_are_jumpers no)
		(fp_line
			(start 0.7874 -0.4064)
			(end 0.7874 0.4064)
			(stroke
				(width 0.1524)
				(type default)
			)
			(layer "F.SilkS")
		)
		(fp_line
			(start -0.7874 -0.4064)
			(end 0.7874 -0.4064)
			(stroke
				(width 0.1524)
				(type default)
			)
			(layer "F.SilkS")
		)
		(fp_line
			(start 0.7874 0.4064)
			(end -0.7874 0.4064)
			(stroke
				(width 0.1524)
				(type default)
			)
			(layer "F.SilkS")
		)
		(fp_line
			(start -0.7874 0.4064)
			(end -0.7874 -0.4064)
			(stroke
				(width 0.1524)
				(type default)
			)
			(layer "F.SilkS")
		)
		(fp_poly
			(pts
				(xy -0.508 0.2794) (xy -0.508 0.2286) (xy -0.635 0.2286) (xy -0.635 -0.254) (xy -0.5334 -0.254)
				(xy -0.5334 -0.2794) (xy 0.5334 -0.2794) (xy 0.5334 -0.254) (xy 0.635 -0.254) (xy 0.635 0.254) (xy 0.5334 0.254)
				(xy 0.5334 0.2794)
			)
			(stroke
				(width 0)
				(type default)
			)
			(fill no)
			(layer "F.CrtYd")
		)
		(pad "1" smd rect
			(at 0.40005 0 90)
			(size 0.4572 0.508)
			(layers "F.Cu" "F.Mask" "F.Paste")
			(net "GND")
		)
		(pad "2" smd rect
			(at -0.40005 0 90)
			(size 0.4572 0.508)
			(layers "F.Cu" "F.Mask" "F.Paste")
			(net "UART_DTR_P1_N")
		)
	)
	(footprint ""
		(layer "F.Cu")
		(at 35.243008 -187.636404)
		(property "Reference" "C770"
			(at -1.53162 -5.211064 0)
			(unlocked yes)
			(layer "F.SilkS")
			(effects
				(font
					(size 0.7874 0.5842)
					(thickness 0.1524)
				)
				(justify left)
			)
		)
		(property "Value" ""
			(at 0 0 0)
			(layer "F.Fab")
			(effects
				(font
					(size 1.27 1.27)
				)
			)
		)
		(duplicate_pad_numbers_are_jumpers no)
		(fp_line
			(start -0.7874 -0.4064)
			(end 0.7874 -0.4064)
			(stroke
				(width 0.1524)
				(type default)
			)
			(layer "F.SilkS")
		)
		(fp_line
			(start -0.7874 0.4064)
			(end -0.7874 -0.4064)
			(stroke
				(width 0.1524)
				(type default)
			)
			(layer "F.SilkS")
		)
		(fp_line
			(start 0 0.381)
			(end 0 -0.381)
			(stroke
				(width 0.1524)
				(type default)
			)
			(layer "F.SilkS")
		)
		(fp_line
			(start 0.7874 -0.4064)
			(end 0.7874 0.4064)
			(stroke
				(width 0.1524)
				(type default)
			)
			(layer "F.SilkS")
		)
		(fp_line
			(start 0.7874 0.4064)
			(end -0.7874 0.4064)
			(stroke
				(width 0.1524)
				(type default)
			)
			(layer "F.SilkS")
		)
		(fp_poly
			(pts
				(xy -0.5334 0.254) (xy -0.635 0.254) (xy -0.635 0.2286) (xy -0.635 -0.254) (xy -0.5334 -0.254) (xy -0.5334 -0.2794)
				(xy 0.5334 -0.2794) (xy 0.5334 -0.254) (xy 0.635 -0.254) (xy 0.635 0.254) (xy 0.5334 0.254) (xy 0.5334 0.2794)
				(xy -0.508 0.2794) (xy -0.5334 0.2794)
			)
			(stroke
				(width 0)
				(type default)
			)
			(fill no)
			(layer "F.CrtYd")
		)
		(pad "1" smd rect
			(at 0.40005 0)
			(size 0.4572 0.508)
			(layers "F.Cu" "F.Mask" "F.Paste")
			(net "P12V_PDB")
		)
		(pad "2" smd rect
			(at -0.40005 0)
			(size 0.4572 0.508)
			(layers "F.Cu" "F.Mask" "F.Paste")
			(net "GND")
		)
	)
	(footprint ""
		(layer "F.Cu")
		(at 88.22055 -152.199848)
		(property "Reference" "PC39"
			(at -1.455166 4.218686 0)
			(unlocked yes)
			(layer "F.SilkS")
			(effects
				(font
					(size 0.7874 0.5842)
					(thickness 0.1524)
				)
				(justify left)
			)
		)
		(property "Value" ""
			(at 0 0 0)
			(layer "F.Fab")
			(effects
				(font
					(size 1.27 1.27)
				)
			)
		)
		(duplicate_pad_numbers_are_jumpers no)
		(fp_line
			(start -0.7874 -0.4064)
			(end 0.7874 -0.4064)
			(stroke
				(width 0.1524)
				(type default)
			)
			(layer "F.SilkS")
		)
		(fp_line
			(start -0.7874 0.4064)
			(end -0.7874 -0.4064)
			(stroke
				(width 0.1524)
				(type default)
			)
			(layer "F.SilkS")
		)
		(fp_line
			(start 0 0.381)
			(end 0 -0.381)
			(stroke
				(width 0.1524)
				(type default)
			)
			(layer "F.SilkS")
		)
		(fp_line
			(start 0.7874 -0.4064)
			(end 0.7874 0.4064)
			(stroke
				(width 0.1524)
				(type default)
			)
			(layer "F.SilkS")
		)
		(fp_line
			(start 0.7874 0.4064)
			(end -0.7874 0.4064)
			(stroke
				(width 0.1524)
				(type default)
			)
			(layer "F.SilkS")
		)
		(fp_poly
			(pts
				(xy -0.5334 0.254) (xy -0.635 0.254) (xy -0.635 0.2286) (xy -0.635 -0.254) (xy -0.5334 -0.254) (xy -0.5334 -0.2794)
				(xy 0.5334 -0.2794) (xy 0.5334 -0.254) (xy 0.635 -0.254) (xy 0.635 0.254) (xy 0.5334 0.254) (xy 0.5334 0.2794)
				(xy -0.508 0.2794) (xy -0.5334 0.2794)
			)
			(stroke
				(width 0)
				(type default)
			)
			(fill no)
			(layer "F.CrtYd")
		)
		(pad "1" smd rect
			(at 0.40005 0)
			(size 0.4572 0.508)
			(layers "F.Cu" "F.Mask" "F.Paste")
			(net "P1V8_STB_NODE1")
		)
		(pad "2" smd rect
			(at -0.40005 0)
			(size 0.4572 0.508)
			(layers "F.Cu" "F.Mask" "F.Paste")
			(net "GND")
		)
	)
	(footprint ""
		(layer "F.Cu")
		(at 12.73556 -138.620246 90)
		(property "Reference" "C554"
			(at -4.252468 -4.938522 90)
			(unlocked yes)
			(layer "F.SilkS")
			(effects
				(font
					(size 0.7874 0.5842)
					(thickness 0.1524)
				)
				(justify left)
			)
		)
		(property "Value" ""
			(at 0 0 90)
			(layer "F.Fab")
			(effects
				(font
					(size 1.27 1.27)
				)
			)
		)
		(duplicate_pad_numbers_are_jumpers no)
		(fp_line
			(start 0.7874 -0.4064)
			(end 0.7874 0.4064)
			(stroke
				(width 0.1524)
				(type default)
			)
			(layer "F.SilkS")
		)
		(fp_line
			(start -0.7874 -0.4064)
			(end 0.7874 -0.4064)
			(stroke
				(width 0.1524)
				(type default)
			)
			(layer "F.SilkS")
		)
		(fp_line
			(start 0 0.381)
			(end 0 -0.381)
			(stroke
				(width 0.1524)
				(type default)
			)
			(layer "F.SilkS")
		)
		(fp_line
			(start 0.7874 0.4064)
			(end -0.7874 0.4064)
			(stroke
				(width 0.1524)
				(type default)
			)
			(layer "F.SilkS")
		)
		(fp_line
			(start -0.7874 0.4064)
			(end -0.7874 -0.4064)
			(stroke
				(width 0.1524)
				(type default)
			)
			(layer "F.SilkS")
		)
		(fp_poly
			(pts
				(xy -0.5334 0.254) (xy -0.635 0.254) (xy -0.635 0.2286) (xy -0.635 -0.254) (xy -0.5334 -0.254) (xy -0.5334 -0.2794)
				(xy 0.5334 -0.2794) (xy 0.5334 -0.254) (xy 0.635 -0.254) (xy 0.635 0.254) (xy 0.5334 0.254) (xy 0.5334 0.2794)
				(xy -0.508 0.2794) (xy -0.5334 0.2794)
			)
			(stroke
				(width 0)
				(type default)
			)
			(fill no)
			(layer "F.CrtYd")
		)
		(pad "1" smd rect
			(at 0.40005 0 90)
			(size 0.4572 0.508)
			(layers "F.Cu" "F.Mask" "F.Paste")
			(net "N54310590")
		)
		(pad "2" smd rect
			(at -0.40005 0 90)
			(size 0.4572 0.508)
			(layers "F.Cu" "F.Mask" "F.Paste")
			(net "N54310592")
		)
	)
	(footprint ""
		(layer "F.Cu")
		(at 118.08968 -147.746466 180)
		(property "Reference" "R1038"
			(at 4.530344 -1.160018 0)
			(unlocked yes)
			(layer "F.SilkS")
			(effects
				(font
					(size 0.635 0.4064)
					(thickness 0.1524)
				)
				(justify left)
			)
		)
		(property "Value" ""
			(at 0 0 180)
			(layer "F.Fab")
			(effects
				(font
					(size 1.27 1.27)
				)
			)
		)
		(duplicate_pad_numbers_are_jumpers no)
		(fp_line
			(start 0.7874 0.4064)
			(end -0.7874 0.4064)
			(stroke
				(width 0.1524)
				(type default)
			)
			(layer "F.SilkS")
		)
		(fp_line
			(start 0.7874 -0.4064)
			(end 0.7874 0.4064)
			(stroke
				(width 0.1524)
				(type default)
			)
			(layer "F.SilkS")
		)
		(fp_line
			(start -0.7874 0.4064)
			(end -0.7874 -0.4064)
			(stroke
				(width 0.1524)
				(type default)
			)
			(layer "F.SilkS")
		)
		(fp_line
			(start -0.7874 -0.4064)
			(end 0.7874 -0.4064)
			(stroke
				(width 0.1524)
				(type default)
			)
			(layer "F.SilkS")
		)
		(fp_poly
			(pts
				(xy -0.508 0.2794) (xy -0.508 0.2286) (xy -0.635 0.2286) (xy -0.635 -0.254) (xy -0.5334 -0.254)
				(xy -0.5334 -0.2794) (xy 0.5334 -0.2794) (xy 0.5334 -0.254) (xy 0.635 -0.254) (xy 0.635 0.254) (xy 0.5334 0.254)
				(xy 0.5334 0.2794)
			)
			(stroke
				(width 0)
				(type default)
			)
			(fill no)
			(layer "F.CrtYd")
		)
		(pad "1" smd rect
			(at 0.40005 0 180)
			(size 0.4572 0.508)
			(layers "F.Cu" "F.Mask" "F.Paste")
			(net "GND")
		)
		(pad "2" smd rect
			(at -0.40005 0 180)
			(size 0.4572 0.508)
			(layers "F.Cu" "F.Mask" "F.Paste")
			(net "POWER_SW3_PWR_CTR_12V")
		)
	)
	(footprint ""
		(layer "F.Cu")
		(at 3.51028 -152.801066 180)
		(property "Reference" "U144"
			(at 2.377948 -0.985266 90)
			(unlocked yes)
			(layer "F.SilkS")
			(effects
				(font
					(size 0.7874 0.5842)
					(thickness 0.1524)
				)
			)
		)
		(property "Value" ""
			(at 0 0 180)
			(layer "F.Fab")
			(effects
				(font
					(size 1.27 1.27)
				)
			)
		)
		(duplicate_pad_numbers_are_jumpers no)
		(fp_line
			(start 1.651 1.905)
			(end -1.651 1.905)
			(stroke
				(width 0.1524)
				(type default)
			)
			(layer "F.SilkS")
		)
		(fp_line
			(start 1.651 -1.905)
			(end 1.651 1.905)
			(stroke
				(width 0.1524)
				(type default)
			)
			(layer "F.SilkS")
		)
		(fp_line
			(start -1.651 1.905)
			(end -1.651 -1.905)
			(stroke
				(width 0.1524)
				(type default)
			)
			(layer "F.SilkS")
		)
		(fp_line
			(start -1.651 -1.905)
			(end 1.651 -1.905)
			(stroke
				(width 0.1524)
				(type default)
			)
			(layer "F.SilkS")
		)
		(fp_poly
			(pts
				(xy -1.524 0.7112) (xy -1.524 1.7526) (xy -0.508 1.7526) (xy -0.508 0.6985) (xy 0.508 0.6985) (xy 0.508 1.7526)
				(xy 1.524 1.7526) (xy 1.524 0.6985) (xy 1.524 -0.6985) (xy 0.508 -0.6985) (xy 0.508 -1.7526) (xy -0.508 -1.7526)
				(xy -0.508 -0.6985) (xy -1.524 -0.6985) (xy -1.524 0.6985)
			)
			(stroke
				(width 0)
				(type default)
			)
			(fill no)
			(layer "F.CrtYd")
		)
		(fp_text user "S"
			(at 2.02692 1.562354 0)
			(unlocked yes)
			(layer "F.SilkS")
			(effects
				(font
					(size 0.635 0.4064)
					(thickness 0.1524)
				)
			)
		)
		(fp_text user "D"
			(at -1.4224 -2.422398 0)
			(unlocked yes)
			(layer "F.SilkS")
			(effects
				(font
					(size 0.635 0.4064)
					(thickness 0.1524)
				)
			)
		)
		(fp_text user "G"
			(at -2.23012 1.753616 0)
			(unlocked yes)
			(layer "F.SilkS")
			(effects
				(font
					(size 0.635 0.4064)
					(thickness 0.1524)
				)
			)
		)
		(pad "D" smd rect
			(at 0 -1.1176 180)
			(size 1.016 1.27)
			(layers "F.Cu" "F.Mask" "F.Paste")
			(net "UART_RI_P5_N")
		)
		(pad "G" smd rect
			(at -1.016 1.1176 180)
			(size 1.016 1.27)
			(layers "F.Cu" "F.Mask" "F.Paste")
			(net "TACKOVER_EN")
		)
		(pad "S" smd rect
			(at 1.016 1.1176 180)
			(size 1.016 1.27)
			(layers "F.Cu" "F.Mask" "F.Paste")
			(net "UART_RI_P5_LS_N")
		)
	)
	(footprint ""
		(layer "F.Cu")
		(at 111.871252 -165.50513 180)
		(property "Reference" "R677"
			(at 1.917192 12.305538 0)
			(unlocked yes)
			(layer "F.SilkS")
			(effects
				(font
					(size 0.7874 0.5842)
					(thickness 0.1524)
				)
				(justify left)
			)
		)
		(property "Value" ""
			(at 0 0 180)
			(layer "F.Fab")
			(effects
				(font
					(size 1.27 1.27)
				)
			)
		)
		(duplicate_pad_numbers_are_jumpers no)
		(fp_line
			(start 0.7874 0.4064)
			(end -0.7874 0.4064)
			(stroke
				(width 0.1524)
				(type default)
			)
			(layer "F.SilkS")
		)
		(fp_line
			(start 0.7874 -0.4064)
			(end 0.7874 0.4064)
			(stroke
				(width 0.1524)
				(type default)
			)
			(layer "F.SilkS")
		)
		(fp_line
			(start -0.7874 0.4064)
			(end -0.7874 -0.4064)
			(stroke
				(width 0.1524)
				(type default)
			)
			(layer "F.SilkS")
		)
		(fp_line
			(start -0.7874 -0.4064)
			(end 0.7874 -0.4064)
			(stroke
				(width 0.1524)
				(type default)
			)
			(layer "F.SilkS")
		)
		(fp_poly
			(pts
				(xy -0.508 0.2794) (xy -0.508 0.2286) (xy -0.635 0.2286) (xy -0.635 -0.254) (xy -0.5334 -0.254)
				(xy -0.5334 -0.2794) (xy 0.5334 -0.2794) (xy 0.5334 -0.254) (xy 0.635 -0.254) (xy 0.635 0.254) (xy 0.5334 0.254)
				(xy 0.5334 0.2794)
			)
			(stroke
				(width 0)
				(type default)
			)
			(fill no)
			(layer "F.CrtYd")
		)
		(pad "1" smd rect
			(at 0.40005 0 180)
			(size 0.4572 0.508)
			(layers "F.Cu" "F.Mask" "F.Paste")
			(net "P3V3_NODE1")
		)
		(pad "2" smd rect
			(at -0.40005 0 180)
			(size 0.4572 0.508)
			(layers "F.Cu" "F.Mask" "F.Paste")
			(net "PCA9535_INT_N")
		)
	)
	(footprint ""
		(layer "F.Cu")
		(at 89.030048 -128.998726 -90)
		(property "Reference" "R1259"
			(at 2.83591 -2.600198 90)
			(unlocked yes)
			(layer "F.SilkS")
			(effects
				(font
					(size 0.7874 0.5842)
					(thickness 0.1524)
				)
				(justify left)
			)
		)
		(property "Value" ""
			(at 0 0 270)
			(layer "F.Fab")
			(effects
				(font
					(size 1.27 1.27)
				)
			)
		)
		(duplicate_pad_numbers_are_jumpers no)
		(fp_line
			(start -0.7874 0.4064)
			(end -0.7874 -0.4064)
			(stroke
				(width 0.1524)
				(type default)
			)
			(layer "F.SilkS")
		)
		(fp_line
			(start 0.7874 0.4064)
			(end -0.7874 0.4064)
			(stroke
				(width 0.1524)
				(type default)
			)
			(layer "F.SilkS")
		)
		(fp_line
			(start -0.7874 -0.4064)
			(end 0.7874 -0.4064)
			(stroke
				(width 0.1524)
				(type default)
			)
			(layer "F.SilkS")
		)
		(fp_line
			(start 0.7874 -0.4064)
			(end 0.7874 0.4064)
			(stroke
				(width 0.1524)
				(type default)
			)
			(layer "F.SilkS")
		)
		(fp_poly
			(pts
				(xy -0.508 0.2794) (xy -0.508 0.2286) (xy -0.635 0.2286) (xy -0.635 -0.254) (xy -0.5334 -0.254)
				(xy -0.5334 -0.2794) (xy 0.5334 -0.2794) (xy 0.5334 -0.254) (xy 0.635 -0.254) (xy 0.635 0.254) (xy 0.5334 0.254)
				(xy 0.5334 0.2794)
			)
			(stroke
				(width 0)
				(type default)
			)
			(fill no)
			(layer "F.CrtYd")
		)
		(pad "1" smd rect
			(at 0.40005 0 270)
			(size 0.4572 0.508)
			(layers "F.Cu" "F.Mask" "F.Paste")
			(net "PORT80_LOUT7")
		)
		(pad "2" smd rect
			(at -0.40005 0 270)
			(size 0.4572 0.508)
			(layers "F.Cu" "F.Mask" "F.Paste")
			(net "N53313596")
		)
	)
	(footprint ""
		(layer "F.Cu")
		(at 176.238916 -35.59556 -90)
		(property "Reference" "D9"
			(at 0.390398 3.56616 0)
			(unlocked yes)
			(layer "F.SilkS")
			(effects
				(font
					(size 0.7874 0.5842)
					(thickness 0.1524)
				)
				(justify left)
			)
		)
		(property "Value" ""
			(at 0 0 270)
			(layer "F.Fab")
			(effects
				(font
					(size 1.27 1.27)
				)
			)
		)
		(duplicate_pad_numbers_are_jumpers no)
		(fp_line
			(start -0.450088 0.430022)
			(end 0.450088 0.430022)
			(stroke
				(width 0.1524)
				(type default)
			)
			(layer "F.SilkS")
		)
		(fp_line
			(start 0.450088 0.430022)
			(end 0.450088 -1.35001)
			(stroke
				(width 0.1524)
				(type default)
			)
			(layer "F.SilkS")
		)
		(fp_line
			(start -0.0762 -0.3556)
			(end 0.1016 -0.3556)
			(stroke
				(width 0.050038)
				(type default)
			)
			(layer "F.SilkS")
		)
		(fp_line
			(start 0.1016 -0.3556)
			(end 0.0127 -0.4699)
			(stroke
				(width 0.050038)
				(type default)
			)
			(layer "F.SilkS")
		)
		(fp_line
			(start 0.0127 -0.4699)
			(end -0.0762 -0.3556)
			(stroke
				(width 0.050038)
				(type default)
			)
			(layer "F.SilkS")
		)
		(fp_line
			(start -0.149098 -0.487172)
			(end 0.185674 -0.487172)
			(stroke
				(width 0.050038)
				(type default)
			)
			(layer "F.SilkS")
		)
		(fp_line
			(start 0.4064 -1.27)
			(end -0.381 -1.27)
			(stroke
				(width 0.1524)
				(type default)
			)
			(layer "F.SilkS")
		)
		(fp_line
			(start -0.2794 -1.2954)
			(end 0.4064 -1.27)
			(stroke
				(width 0.1524)
				(type default)
			)
			(layer "F.SilkS")
		)
		(fp_line
			(start -0.450088 -1.370076)
			(end -0.450088 0.430022)
			(stroke
				(width 0.1524)
				(type default)
			)
			(layer "F.SilkS")
		)
		(fp_line
			(start 0.450088 -1.370076)
			(end -0.450088 -1.370076)
			(stroke
				(width 0.1524)
				(type default)
			)
			(layer "F.SilkS")
		)
		(fp_poly
			(pts
				(xy -0.350012 -0.501142) (xy -0.350012 -0.348742) (xy -0.3556 -0.348742) (xy -0.3556 0.337058) (xy 0.3556 0.337058)
				(xy 0.3556 -0.348742) (xy 0.350012 -0.348742) (xy 0.350012 -0.475742) (xy 0.3556 -0.475742) (xy 0.3556 -1.186942)
				(xy -0.3556 -1.186942) (xy -0.3556 -0.501142)
			)
			(stroke
				(width 0)
				(type default)
			)
			(fill no)
			(layer "F.CrtYd")
		)
		(fp_line
			(start -0.350012 0.124968)
			(end 0.350012 0.124968)
			(stroke
				(width 0.1)
				(type default)
			)
			(layer "F.Fab")
		)
		(fp_line
			(start 0.350012 0.124968)
			(end 0.350012 -0.975106)
			(stroke
				(width 0.1)
				(type default)
			)
			(layer "F.Fab")
		)
		(fp_line
			(start -0.350012 -0.975106)
			(end -0.350012 0.124968)
			(stroke
				(width 0.1)
				(type default)
			)
			(layer "F.Fab")
		)
		(fp_line
			(start 0.350012 -0.975106)
			(end -0.350012 -0.975106)
			(stroke
				(width 0.1)
				(type default)
			)
			(layer "F.Fab")
		)
		(fp_text user "+"
			(at 1.317498 -0.51943 180)
			(unlocked yes)
			(layer "F.SilkS")
			(effects
				(font
					(size 1.6002 1.1938)
					(thickness 0.1524)
				)
				(justify left)
			)
		)
		(fp_text user "-"
			(at 0.737362 -2.518664 180)
			(unlocked yes)
			(layer "F.SilkS")
			(effects
				(font
					(size 1.6002 1.1938)
					(thickness 0.1524)
				)
				(justify left)
			)
		)
		(pad "A" smd rect
			(at 0 0)
			(size 0.5588 0.6096)
			(layers "F.Cu" "F.Mask" "F.Paste")
			(net "GND")
		)
		(pad "C" smd rect
			(at 0 -0.849884 180)
			(size 0.5588 0.6096)
			(layers "F.Cu" "F.Mask" "F.Paste")
			(net "USBPWR_P0")
		)
	)
	(footprint ""
		(layer "F.Cu")
		(at 119.61876 -188.126624 90)
		(property "Reference" "C745"
			(at 4.82092 -0.110998 90)
			(unlocked yes)
			(layer "F.SilkS")
			(effects
				(font
					(size 0.7874 0.5842)
					(thickness 0.1524)
				)
				(justify left)
			)
		)
		(property "Value" ""
			(at 0 0 90)
			(layer "F.Fab")
			(effects
				(font
					(size 1.27 1.27)
				)
			)
		)
		(duplicate_pad_numbers_are_jumpers no)
		(fp_line
			(start 0.7874 -0.4064)
			(end 0.7874 0.4064)
			(stroke
				(width 0.1524)
				(type default)
			)
			(layer "F.SilkS")
		)
		(fp_line
			(start -0.7874 -0.4064)
			(end 0.7874 -0.4064)
			(stroke
				(width 0.1524)
				(type default)
			)
			(layer "F.SilkS")
		)
		(fp_line
			(start 0 0.381)
			(end 0 -0.381)
			(stroke
				(width 0.1524)
				(type default)
			)
			(layer "F.SilkS")
		)
		(fp_line
			(start 0.7874 0.4064)
			(end -0.7874 0.4064)
			(stroke
				(width 0.1524)
				(type default)
			)
			(layer "F.SilkS")
		)
		(fp_line
			(start -0.7874 0.4064)
			(end -0.7874 -0.4064)
			(stroke
				(width 0.1524)
				(type default)
			)
			(layer "F.SilkS")
		)
		(fp_poly
			(pts
				(xy -0.5334 0.254) (xy -0.635 0.254) (xy -0.635 0.2286) (xy -0.635 -0.254) (xy -0.5334 -0.254) (xy -0.5334 -0.2794)
				(xy 0.5334 -0.2794) (xy 0.5334 -0.254) (xy 0.635 -0.254) (xy 0.635 0.254) (xy 0.5334 0.254) (xy 0.5334 0.2794)
				(xy -0.508 0.2794) (xy -0.5334 0.2794)
			)
			(stroke
				(width 0)
				(type default)
			)
			(fill no)
			(layer "F.CrtYd")
		)
		(pad "1" smd rect
			(at 0.40005 0 90)
			(size 0.4572 0.508)
			(layers "F.Cu" "F.Mask" "F.Paste")
			(net "UART_T8_NODE1_TXD_R")
		)
		(pad "2" smd rect
			(at -0.40005 0 90)
			(size 0.4572 0.508)
			(layers "F.Cu" "F.Mask" "F.Paste")
			(net "GND")
		)
	)
	(footprint ""
		(layer "F.Cu")
		(at 144.916652 -145.21815)
		(property "Reference" "R277"
			(at -0.704088 18.560288 0)
			(unlocked yes)
			(layer "F.SilkS")
			(effects
				(font
					(size 0.7874 0.5842)
					(thickness 0.1524)
				)
				(justify left)
			)
		)
		(property "Value" ""
			(at 0 0 0)
			(layer "F.Fab")
			(effects
				(font
					(size 1.27 1.27)
				)
			)
		)
		(duplicate_pad_numbers_are_jumpers no)
		(fp_line
			(start -0.7874 -0.4064)
			(end 0.7874 -0.4064)
			(stroke
				(width 0.1524)
				(type default)
			)
			(layer "F.SilkS")
		)
		(fp_line
			(start -0.7874 0.4064)
			(end -0.7874 -0.4064)
			(stroke
				(width 0.1524)
				(type default)
			)
			(layer "F.SilkS")
		)
		(fp_line
			(start 0.7874 -0.4064)
			(end 0.7874 0.4064)
			(stroke
				(width 0.1524)
				(type default)
			)
			(layer "F.SilkS")
		)
		(fp_line
			(start 0.7874 0.4064)
			(end -0.7874 0.4064)
			(stroke
				(width 0.1524)
				(type default)
			)
			(layer "F.SilkS")
		)
		(fp_poly
			(pts
				(xy -0.508 0.2794) (xy -0.508 0.2286) (xy -0.635 0.2286) (xy -0.635 -0.254) (xy -0.5334 -0.254)
				(xy -0.5334 -0.2794) (xy 0.5334 -0.2794) (xy 0.5334 -0.254) (xy 0.635 -0.254) (xy 0.635 0.254) (xy 0.5334 0.254)
				(xy 0.5334 0.2794)
			)
			(stroke
				(width 0)
				(type default)
			)
			(fill no)
			(layer "F.CrtYd")
		)
		(pad "1" smd rect
			(at 0.40005 0)
			(size 0.4572 0.508)
			(layers "F.Cu" "F.Mask" "F.Paste")
			(net "GND")
		)
		(pad "2" smd rect
			(at -0.40005 0)
			(size 0.4572 0.508)
			(layers "F.Cu" "F.Mask" "F.Paste")
			(net "PCIE_SW_P0_CTCDIS")
		)
	)
	(footprint ""
		(layer "F.Cu")
		(at 121.50598 -27.62758 -90)
		(property "Reference" "D6"
			(at 0.964184 1.317752 90)
			(unlocked yes)
			(layer "F.SilkS")
			(effects
				(font
					(size 0.7874 0.5842)
					(thickness 0.1524)
				)
				(justify left)
			)
		)
		(property "Value" ""
			(at 0 0 270)
			(layer "F.Fab")
			(effects
				(font
					(size 1.27 1.27)
				)
			)
		)
		(duplicate_pad_numbers_are_jumpers no)
		(fp_line
			(start -1.651 0.6858)
			(end -1.651 -0.6858)
			(stroke
				(width 0.1524)
				(type default)
			)
			(layer "F.SilkS")
		)
		(fp_line
			(start 1.651 0.6858)
			(end -1.651 0.6858)
			(stroke
				(width 0.1524)
				(type default)
			)
			(layer "F.SilkS")
		)
		(fp_line
			(start 1.9558 0.6858)
			(end 1.9558 -0.6858)
			(stroke
				(width 0.1524)
				(type default)
			)
			(layer "F.SilkS")
		)
		(fp_line
			(start 2.1082 0.6858)
			(end 1.651 0.6858)
			(stroke
				(width 0.1524)
				(type default)
			)
			(layer "F.SilkS")
		)
		(fp_line
			(start -0.299974 0.500126)
			(end 0.199898 0)
			(stroke
				(width 0.1524)
				(type default)
			)
			(layer "F.SilkS")
		)
		(fp_line
			(start 0.199898 0)
			(end -0.299974 -0.500126)
			(stroke
				(width 0.1524)
				(type default)
			)
			(layer "F.SilkS")
		)
		(fp_line
			(start -0.299974 -0.500126)
			(end -0.299974 0.500126)
			(stroke
				(width 0.1524)
				(type default)
			)
			(layer "F.SilkS")
		)
		(fp_line
			(start 0.299974 -0.500126)
			(end 0.299974 0.500126)
			(stroke
				(width 0.1524)
				(type default)
			)
			(layer "F.SilkS")
		)
		(fp_line
			(start -1.651 -0.6858)
			(end 1.651 -0.6858)
			(stroke
				(width 0.1524)
				(type default)
			)
			(layer "F.SilkS")
		)
		(fp_line
			(start 1.651 -0.6858)
			(end 1.651 0.6858)
			(stroke
				(width 0.1524)
				(type default)
			)
			(layer "F.SilkS")
		)
		(fp_line
			(start 1.8034 -0.6858)
			(end 1.8034 0.6858)
			(stroke
				(width 0.1524)
				(type default)
			)
			(layer "F.SilkS")
		)
		(fp_line
			(start 2.1082 -0.6858)
			(end 2.1082 0.6858)
			(stroke
				(width 0.1524)
				(type default)
			)
			(layer "F.SilkS")
		)
		(fp_line
			(start 2.1082 -0.6858)
			(end 1.651 -0.6858)
			(stroke
				(width 0.1524)
				(type default)
			)
			(layer "F.SilkS")
		)
		(fp_rect
			(start -1.4986 0.6858)
			(end 1.4986 -0.6858)
			(stroke
				(width 0)
				(type default)
			)
			(fill no)
			(layer "F.CrtYd")
		)
		(pad "1" smd rect
			(at -1.0922 0 90)
			(size 0.8128 0.8636)
			(layers "F.Cu" "F.Mask" "F.Paste")
			(net "P3V3_RTC_NODE1")
		)
		(pad "2" smd rect
			(at 1.0922 0 270)
			(size 0.8128 0.8636)
			(layers "F.Cu" "F.Mask" "F.Paste")
			(net "SIO_VBAT")
		)
	)
	(footprint ""
		(layer "F.Cu")
		(at 54.515004 -205.199488 180)
		(property "Reference" "J35"
			(at -39.89832 -7.345934 0)
			(unlocked yes)
			(layer "F.SilkS")
			(effects
				(font
					(size 0.7874 0.5842)
					(thickness 0.1524)
				)
				(justify left)
			)
		)
		(property "Value" ""
			(at 0 0 180)
			(layer "F.Fab")
			(effects
				(font
					(size 1.27 1.27)
				)
			)
		)
		(duplicate_pad_numbers_are_jumpers no)
		(fp_line
			(start 42.15003 2.86512)
			(end 42.15003 -4.899914)
			(stroke
				(width 0.1524)
				(type default)
			)
			(layer "F.SilkS")
		)
		(fp_line
			(start 41.51503 3.50012)
			(end 42.15003 2.86512)
			(stroke
				(width 0.1524)
				(type default)
			)
			(layer "F.SilkS")
		)
		(fp_line
			(start -28.385008 3.50012)
			(end 41.51503 3.50012)
			(stroke
				(width 0.1524)
				(type default)
			)
			(layer "F.SilkS")
		)
		(fp_line
			(start -29.020008 2.86512)
			(end -28.385008 3.50012)
			(stroke
				(width 0.1524)
				(type default)
			)
			(layer "F.SilkS")
		)
		(fp_line
			(start -29.020008 -3.919982)
			(end -29.020008 2.86512)
			(stroke
				(width 0.1524)
				(type default)
			)
			(layer "F.SilkS")
		)
		(fp_line
			(start -30.979872 2.86512)
			(end -31.614872 3.50012)
			(stroke
				(width 0.1524)
				(type default)
			)
			(layer "F.SilkS")
		)
		(fp_line
			(start -30.979872 -3.919982)
			(end -30.979872 2.86512)
			(stroke
				(width 0.1524)
				(type default)
			)
			(layer "F.SilkS")
		)
		(fp_line
			(start -31.614872 3.50012)
			(end -41.51503 3.50012)
			(stroke
				(width 0.1524)
				(type default)
			)
			(layer "F.SilkS")
		)
		(fp_line
			(start -41.51503 3.50012)
			(end -42.15003 2.86512)
			(stroke
				(width 0.1524)
				(type default)
			)
			(layer "F.SilkS")
		)
		(fp_line
			(start -42.15003 2.86512)
			(end -42.15003 -4.899914)
			(stroke
				(width 0.1524)
				(type default)
			)
			(layer "F.SilkS")
		)
		(fp_line
			(start -42.15003 -6.500114)
			(end 42.15003 -6.500114)
			(stroke
				(width 0.1524)
				(type default)
			)
			(layer "F.SilkS")
		)
		(fp_arc
			(start -30.979872 -3.919982)
			(mid -29.99994 -4.899914)
			(end -29.020008 -3.919982)
			(stroke
				(width 0.1524)
				(type default)
			)
			(layer "F.SilkS")
		)
		(fp_line
			(start -42.15003 -6.500114)
			(end 42.15003 -6.500114)
			(stroke
				(width 0.1524)
				(type default)
			)
			(layer "B.SilkS")
		)
		(fp_rect
			(start -29.0322 3.5052)
			(end 42.164 -2.1082)
			(stroke
				(width 0)
				(type default)
			)
			(fill no)
			(layer "F.CrtYd")
		)
		(fp_rect
			(start -42.164 3.5052)
			(end -30.9626 -2.1082)
			(stroke
				(width 0)
				(type default)
			)
			(fill no)
			(layer "F.CrtYd")
		)
		(fp_text user "B82"
			(at 41.647364 -7.750302 0)
			(unlocked yes)
			(layer "F.SilkS")
			(effects
				(font
					(size 0.635 0.4064)
					(thickness 0.1524)
				)
				(justify left)
			)
		)
		(fp_text user "B12"
			(at -28.02255 -5.775198 0)
			(unlocked yes)
			(layer "F.SilkS")
			(effects
				(font
					(size 0.635 0.4064)
					(thickness 0.1524)
				)
				(justify left)
			)
		)
		(fp_text user "B11"
			(at -31.022544 -5.775198 0)
			(unlocked yes)
			(layer "F.SilkS")
			(effects
				(font
					(size 0.635 0.4064)
					(thickness 0.1524)
				)
				(justify left)
			)
		)
		(fp_text user "B1"
			(at -40.859456 -5.795264 0)
			(unlocked yes)
			(layer "F.SilkS")
			(effects
				(font
					(size 0.635 0.4064)
					(thickness 0.1524)
				)
				(justify left)
			)
		)
		(fp_text user "A82"
			(at 39.52494 -3.055366 0)
			(unlocked yes)
			(layer "B.SilkS")
			(effects
				(font
					(size 0.7874 0.5842)
					(thickness 0.1524)
				)
				(justify left mirror)
			)
		)
		(fp_text user "A12"
			(at -28.74772 -2.988056 0)
			(unlocked yes)
			(layer "B.SilkS")
			(effects
				(font
					(size 0.7874 0.5842)
					(thickness 0.1524)
				)
				(justify left mirror)
			)
		)
		(fp_text user "A11"
			(at -33.2359 -3.120136 0)
			(unlocked yes)
			(layer "B.SilkS")
			(effects
				(font
					(size 0.7874 0.5842)
					(thickness 0.1524)
				)
				(justify left mirror)
			)
		)
		(fp_text user "A1"
			(at -41.75252 -2.890266 0)
			(unlocked yes)
			(layer "B.SilkS")
			(effects
				(font
					(size 0.7874 0.5842)
					(thickness 0.1524)
				)
				(justify left mirror)
			)
		)
		(pad "A1" smd rect
			(at -41.500044 -0.499872 180)
			(size 0.762 3.2004)
			(layers "F.Cu" "F.Mask" "F.Paste")
			(net "GND")
		)
		(pad "A2" smd rect
			(at -40.500046 0 180)
			(size 0.762 4.2164)
			(layers "F.Cu" "F.Mask" "F.Paste")
			(net "T5_NODE3_EN_R")
		)
		(pad "A3" smd rect
			(at -39.500048 0 180)
			(size 0.762 4.2164)
			(layers "F.Cu" "F.Mask" "F.Paste")
			(net "T5_NODE4_EN_R")
		)
		(pad "A4" smd rect
			(at -38.50005 0 180)
			(size 0.762 4.2164)
			(layers "F.Cu" "F.Mask" "F.Paste")
			(net "GND")
		)
		(pad "A5" smd rect
			(at -37.500052 0 180)
			(size 0.762 4.2164)
			(layers "F.Cu" "F.Mask" "F.Paste")
			(net "UART_T5_NODE1_RXD_R")
		)
		(pad "A6" smd rect
			(at -36.500054 0 180)
			(size 0.762 4.2164)
			(layers "F.Cu" "F.Mask" "F.Paste")
			(net "UART_T5_NODE1_TXD_R")
		)
		(pad "A7" smd rect
			(at -35.500056 0 180)
			(size 0.762 4.2164)
			(layers "F.Cu" "F.Mask" "F.Paste")
			(net "GND")
		)
		(pad "A8" smd rect
			(at -34.500058 0 180)
			(size 0.762 4.2164)
			(layers "F.Cu" "F.Mask" "F.Paste")
			(net "UART_T5_NODE2_RXD_R")
		)
		(pad "A9" smd rect
			(at -33.50006 0 180)
			(size 0.762 4.2164)
			(layers "F.Cu" "F.Mask" "F.Paste")
			(net "UART_T5_NODE2_TXD_R")
		)
		(pad "A10" smd rect
			(at -32.500062 0 180)
			(size 0.762 4.2164)
			(layers "F.Cu" "F.Mask" "F.Paste")
			(net "UART_T5_NODE3_RXD_R")
		)
		(pad "A11" smd rect
			(at -31.500064 0 180)
			(size 0.762 4.2164)
			(layers "F.Cu" "F.Mask" "F.Paste")
			(net "UART_T5_NODE3_TXD_R")
		)
		(pad "A12" smd rect
			(at -28.50007 0 180)
			(size 0.762 4.2164)
			(layers "F.Cu" "F.Mask" "F.Paste")
			(net "UART_T5_NODE4_RXD_R")
		)
		(pad "A13" smd rect
			(at -27.500072 0 180)
			(size 0.762 4.2164)
			(layers "F.Cu" "F.Mask" "F.Paste")
			(net "UART_T5_NODE4_TXD_R")
		)
		(pad "A14" smd rect
			(at -26.500074 0 180)
			(size 0.762 4.2164)
			(layers "F.Cu" "F.Mask" "F.Paste")
			(net "GND")
		)
		(pad "A15" smd rect
			(at -25.500076 0 180)
			(size 0.762 4.2164)
			(layers "F.Cu" "F.Mask" "F.Paste")
			(net "T3_NODE1_EN_R")
		)
		(pad "A16" smd rect
			(at -24.500078 0 180)
			(size 0.762 4.2164)
			(layers "F.Cu" "F.Mask" "F.Paste")
			(net "T3_NODE2_EN_R")
		)
		(pad "A17" smd rect
			(at -23.50008 0 180)
			(size 0.762 4.2164)
			(layers "F.Cu" "F.Mask" "F.Paste")
			(net "T3_NODE3_EN_R")
		)
		(pad "A18" smd rect
			(at -22.500082 0 180)
			(size 0.762 4.2164)
			(layers "F.Cu" "F.Mask" "F.Paste")
			(net "T3_NODE4_EN_R")
		)
		(pad "A19" smd rect
			(at -21.500084 0 180)
			(size 0.762 4.2164)
			(layers "F.Cu" "F.Mask" "F.Paste")
			(net "GND")
		)
		(pad "A20" smd rect
			(at -20.500086 0 180)
			(size 0.762 4.2164)
			(layers "F.Cu" "F.Mask" "F.Paste")
			(net "UART_T3_NODE1_RXD_R")
		)
		(pad "A21" smd rect
			(at -19.500088 0 180)
			(size 0.762 4.2164)
			(layers "F.Cu" "F.Mask" "F.Paste")
			(net "UART_T3_NODE1_TXD_R")
		)
		(pad "A22" smd rect
			(at -18.50009 0 180)
			(size 0.762 4.2164)
			(layers "F.Cu" "F.Mask" "F.Paste")
			(net "UART_T3_NODE2_RXD_R")
		)
		(pad "A23" smd rect
			(at -17.500092 0 180)
			(size 0.762 4.2164)
			(layers "F.Cu" "F.Mask" "F.Paste")
			(net "UART_T3_NODE2_TXD_R")
		)
		(pad "A24" smd rect
			(at -16.500094 0 180)
			(size 0.762 4.2164)
			(layers "F.Cu" "F.Mask" "F.Paste")
			(net "GND")
		)
		(pad "A25" smd rect
			(at -15.500096 0 180)
			(size 0.762 4.2164)
			(layers "F.Cu" "F.Mask" "F.Paste")
			(net "UART_T3_NODE3_RXD_R")
		)
		(pad "A26" smd rect
			(at -14.500098 0 180)
			(size 0.762 4.2164)
			(layers "F.Cu" "F.Mask" "F.Paste")
			(net "UART_T3_NODE3_TXD_R")
		)
		(pad "A27" smd rect
			(at -13.5001 0 180)
			(size 0.762 4.2164)
			(layers "F.Cu" "F.Mask" "F.Paste")
			(net "UART_T3_NODE4_RXD_R")
		)
		(pad "A28" smd rect
			(at -12.500102 0 180)
			(size 0.762 4.2164)
			(layers "F.Cu" "F.Mask" "F.Paste")
			(net "UART_T3_NODE4_TXD_R")
		)
		(pad "A29" smd rect
			(at -11.500104 0 180)
			(size 0.762 4.2164)
			(layers "F.Cu" "F.Mask" "F.Paste")
			(net "GND")
		)
		(pad "A30" smd rect
			(at -10.500106 0 180)
			(size 0.762 4.2164)
			(layers "F.Cu" "F.Mask" "F.Paste")
			(net "T1_NODE1_EN_R")
		)
		(pad "A31" smd rect
			(at -9.500108 0 180)
			(size 0.762 4.2164)
			(layers "F.Cu" "F.Mask" "F.Paste")
			(net "T1_NODE2_EN_R")
		)
		(pad "A32" smd rect
			(at -8.50011 0 180)
			(size 0.762 4.2164)
			(layers "F.Cu" "F.Mask" "F.Paste")
			(net "T1_NODE3_EN_R")
		)
		(pad "A33" smd rect
			(at -7.500112 0 180)
			(size 0.762 4.2164)
			(layers "F.Cu" "F.Mask" "F.Paste")
			(net "T1_NODE4_EN_R")
		)
		(pad "A34" smd rect
			(at -6.500114 0 180)
			(size 0.762 4.2164)
			(layers "F.Cu" "F.Mask" "F.Paste")
			(net "GND")
		)
		(pad "A35" smd rect
			(at -5.500116 0 180)
			(size 0.762 4.2164)
			(layers "F.Cu" "F.Mask" "F.Paste")
			(net "UART_T1_NODE2_RXD_R")
		)
		(pad "A36" smd rect
			(at -4.500118 0 180)
			(size 0.762 4.2164)
			(layers "F.Cu" "F.Mask" "F.Paste")
			(net "UART_T1_NODE2_TXD_R")
		)
		(pad "A37" smd rect
			(at -3.50012 0 180)
			(size 0.762 4.2164)
			(layers "F.Cu" "F.Mask" "F.Paste")
			(net "UART_T1_NODE3_RXD_R")
		)
		(pad "A38" smd rect
			(at -2.500122 0 180)
			(size 0.762 4.2164)
			(layers "F.Cu" "F.Mask" "F.Paste")
			(net "UART_T1_NODE3_TXD_R")
		)
		(pad "A39" smd rect
			(at -1.500124 0 180)
			(size 0.762 4.2164)
			(layers "F.Cu" "F.Mask" "F.Paste")
			(net "GND")
		)
		(pad "A40" smd rect
			(at -0.499872 0 180)
			(size 0.762 4.2164)
			(layers "F.Cu" "F.Mask" "F.Paste")
			(net "UART_T1_NODE4_RXD_R")
		)
		(pad "A41" smd rect
			(at 0.499872 0 180)
			(size 0.762 4.2164)
			(layers "F.Cu" "F.Mask" "F.Paste")
			(net "UART_T1_NODE4_TXD_R")
		)
		(pad "A42" smd rect
			(at 1.500124 0 180)
			(size 0.762 4.2164)
			(layers "F.Cu" "F.Mask" "F.Paste")
			(net "UART_T1_NODE1_RXD_R")
		)
		(pad "A43" smd rect
			(at 2.500122 0 180)
			(size 0.762 4.2164)
			(layers "F.Cu" "F.Mask" "F.Paste")
			(net "UART_T1_NODE1_TXD_R")
		)
		(pad "A44" smd rect
			(at 3.50012 0 180)
			(size 0.762 4.2164)
			(layers "F.Cu" "F.Mask" "F.Paste")
			(net "GND")
		)
		(pad "A45" smd rect
			(at 4.500118 0 180)
			(size 0.762 4.2164)
			(layers "F.Cu" "F.Mask" "F.Paste")
			(net "PSU1_DC_OK_R")
		)
		(pad "A46" smd rect
			(at 5.500116 0 180)
			(size 0.762 4.2164)
			(layers "F.Cu" "F.Mask" "F.Paste")
			(net "PSU2_DC_OK_R")
		)
		(pad "A47" smd rect
			(at 6.500114 0 180)
			(size 0.762 4.2164)
			(layers "F.Cu" "F.Mask" "F.Paste")
			(net "PSU3_DC_OK_R")
		)
		(pad "A48" smd rect
			(at 7.500112 0 180)
			(size 0.762 4.2164)
			(layers "F.Cu" "F.Mask" "F.Paste")
			(net "PSU4_DC_OK_R")
		)
		(pad "A49" smd rect
			(at 8.50011 0 180)
			(size 0.762 4.2164)
			(layers "F.Cu" "F.Mask" "F.Paste")
			(net "PSU5_DC_OK_R")
		)
		(pad "A50" smd rect
			(at 9.500108 0 180)
			(size 0.762 4.2164)
			(layers "F.Cu" "F.Mask" "F.Paste")
			(net "PSU6_DC_OK_R")
		)
		(pad "A51" smd rect
			(at 10.500106 0 180)
			(size 0.762 4.2164)
			(layers "F.Cu" "F.Mask" "F.Paste")
			(net "GND")
		)
		(pad "A52" smd rect
			(at 11.500104 0 180)
			(size 0.762 4.2164)
			(layers "F.Cu" "F.Mask" "F.Paste")
			(net "UART_RTS_P6_L_N")
		)
		(pad "A53" smd rect
			(at 12.500102 0 180)
			(size 0.762 4.2164)
			(layers "F.Cu" "F.Mask" "F.Paste")
			(net "UART_DSR_P6_L_N")
		)
		(pad "A54" smd rect
			(at 13.5001 0 180)
			(size 0.762 4.2164)
			(layers "F.Cu" "F.Mask" "F.Paste")
			(net "UART_RX_P6_L")
		)
		(pad "A55" smd rect
			(at 14.500098 0 180)
			(size 0.762 4.2164)
			(layers "F.Cu" "F.Mask" "F.Paste")
			(net "UART_TX_P6_L")
		)
		(pad "A56" smd rect
			(at 15.500096 0 180)
			(size 0.762 4.2164)
			(layers "F.Cu" "F.Mask" "F.Paste")
			(net "UART_DTR_P6_L_N")
		)
		(pad "A57" smd rect
			(at 16.500094 0 180)
			(size 0.762 4.2164)
			(layers "F.Cu" "F.Mask" "F.Paste")
			(net "UART_CTS_P6_L_N")
		)
		(pad "A58" smd rect
			(at 17.500092 0 180)
			(size 0.762 4.2164)
			(layers "F.Cu" "F.Mask" "F.Paste")
			(net "UART_RI_P6_L_N_R")
		)
		(pad "A59" smd rect
			(at 18.50009 0 180)
			(size 0.762 4.2164)
			(layers "F.Cu" "F.Mask" "F.Paste")
			(net "GND")
		)
		(pad "A60" smd rect
			(at 19.500088 0 180)
			(size 0.762 4.2164)
			(layers "F.Cu" "F.Mask" "F.Paste")
			(net "UART_RTS_P2_L_N")
		)
		(pad "A61" smd rect
			(at 20.500086 0 180)
			(size 0.762 4.2164)
			(layers "F.Cu" "F.Mask" "F.Paste")
			(net "UART_DSR_P2_L_N")
		)
		(pad "A62" smd rect
			(at 21.500084 0 180)
			(size 0.762 4.2164)
			(layers "F.Cu" "F.Mask" "F.Paste")
			(net "UART_RX_P2_L")
		)
		(pad "A63" smd rect
			(at 22.500082 0 180)
			(size 0.762 4.2164)
			(layers "F.Cu" "F.Mask" "F.Paste")
			(net "UART_TX_P2_L")
		)
		(pad "A64" smd rect
			(at 23.50008 0 180)
			(size 0.762 4.2164)
			(layers "F.Cu" "F.Mask" "F.Paste")
			(net "UART_DTR_P2_L_N")
		)
		(pad "A65" smd rect
			(at 24.500078 0 180)
			(size 0.762 4.2164)
			(layers "F.Cu" "F.Mask" "F.Paste")
			(net "UART_CTS_P2_L_N")
		)
		(pad "A66" smd rect
			(at 25.500076 0 180)
			(size 0.762 4.2164)
			(layers "F.Cu" "F.Mask" "F.Paste")
			(net "GND")
		)
		(pad "A67" smd rect
			(at 26.500074 0 180)
			(size 0.762 4.2164)
			(layers "F.Cu" "F.Mask" "F.Paste")
			(net "Net_2330")
		)
		(pad "A68" smd rect
			(at 27.500072 0 180)
			(size 0.762 4.2164)
			(layers "F.Cu" "F.Mask" "F.Paste")
			(net "Net_2334")
		)
		(pad "A69" smd rect
			(at 28.50007 0 180)
			(size 0.762 4.2164)
			(layers "F.Cu" "F.Mask" "F.Paste")
			(net "Net_2333")
		)
		(pad "A70" smd rect
			(at 29.500068 0 180)
			(size 0.762 4.2164)
			(layers "F.Cu" "F.Mask" "F.Paste")
			(net "GND27")
		)
		(pad "A71" smd rect
			(at 30.500066 0 180)
			(size 0.762 4.2164)
			(layers "F.Cu" "F.Mask" "F.Paste")
			(net "GND")
		)
		(pad "A72" smd rect
			(at 31.500064 0 180)
			(size 0.762 4.2164)
			(layers "F.Cu" "F.Mask" "F.Paste")
			(net "LAN1_P1_P")
		)
		(pad "A73" smd rect
			(at 32.500062 0 180)
			(size 0.762 4.2164)
			(layers "F.Cu" "F.Mask" "F.Paste")
			(net "LAN1_P1_N")
		)
		(pad "A74" smd rect
			(at 33.50006 0 180)
			(size 0.762 4.2164)
			(layers "F.Cu" "F.Mask" "F.Paste")
			(net "GND")
		)
		(pad "A75" smd rect
			(at 34.500058 0 180)
			(size 0.762 4.2164)
			(layers "F.Cu" "F.Mask" "F.Paste")
			(net "LAN1_P2_P")
		)
		(pad "A76" smd rect
			(at 35.500056 0 180)
			(size 0.762 4.2164)
			(layers "F.Cu" "F.Mask" "F.Paste")
			(net "LAN1_P2_N")
		)
		(pad "A77" smd rect
			(at 36.500054 0 180)
			(size 0.762 4.2164)
			(layers "F.Cu" "F.Mask" "F.Paste")
			(net "GND")
		)
		(pad "A78" smd rect
			(at 37.500052 0 180)
			(size 0.762 4.2164)
			(layers "F.Cu" "F.Mask" "F.Paste")
			(net "P12V_PDB")
		)
		(pad "A79" smd rect
			(at 38.50005 0 180)
			(size 0.762 4.2164)
			(layers "F.Cu" "F.Mask" "F.Paste")
			(net "P12V_PDB")
		)
		(pad "A80" smd rect
			(at 39.500048 0 180)
			(size 0.762 4.2164)
			(layers "F.Cu" "F.Mask" "F.Paste")
			(net "P12V_PDB")
		)
		(pad "A81" smd rect
			(at 40.500046 0 180)
			(size 0.762 4.2164)
			(layers "F.Cu" "F.Mask" "F.Paste")
			(net "P12V_PDB")
		)
		(pad "A82" smd rect
			(at 41.500044 0 180)
			(size 0.762 4.2164)
			(layers "F.Cu" "F.Mask" "F.Paste")
			(net "P12V_PDB")
		)
		(pad "B1" smd rect
			(at -41.500044 0 180)
			(size 0.762 4.2164)
			(layers "F.Cu" "F.Mask" "F.Paste")
			(net "GND")
		)
		(pad "B2" smd rect
			(at -40.500046 0 180)
			(size 0.762 4.2164)
			(layers "F.Cu" "F.Mask" "F.Paste")
			(net "UART_T6_NODE2_RXD_R")
		)
		(pad "B3" smd rect
			(at -39.500048 0 180)
			(size 0.762 4.2164)
			(layers "F.Cu" "F.Mask" "F.Paste")
			(net "UART_T6_NODE2_TXD_R")
		)
		(pad "B4" smd rect
			(at -38.50005 0 180)
			(size 0.762 4.2164)
			(layers "F.Cu" "F.Mask" "F.Paste")
			(net "GND")
		)
		(pad "B5" smd rect
			(at -37.500052 0 180)
			(size 0.762 4.2164)
			(layers "F.Cu" "F.Mask" "F.Paste")
			(net "UART_T6_NODE3_RXD_R")
		)
		(pad "B6" smd rect
			(at -36.500054 0 180)
			(size 0.762 4.2164)
			(layers "F.Cu" "F.Mask" "F.Paste")
			(net "UART_T6_NODE3_TXD_R")
		)
		(pad "B7" smd rect
			(at -35.500056 0 180)
			(size 0.762 4.2164)
			(layers "F.Cu" "F.Mask" "F.Paste")
			(net "UART_T6_NODE4_RXD_R")
		)
		(pad "B8" smd rect
			(at -34.500058 0 180)
			(size 0.762 4.2164)
			(layers "F.Cu" "F.Mask" "F.Paste")
			(net "UART_T6_NODE4_TXD_R")
		)
		(pad "B9" smd rect
			(at -33.50006 0 180)
			(size 0.762 4.2164)
			(layers "F.Cu" "F.Mask" "F.Paste")
			(net "GND")
		)
		(pad "B10" smd rect
			(at -32.500062 0 180)
			(size 0.762 4.2164)
			(layers "F.Cu" "F.Mask" "F.Paste")
			(net "I2C_PSU2_R_SCL")
		)
		(pad "B11" smd rect
			(at -31.500064 0 180)
			(size 0.762 4.2164)
			(layers "F.Cu" "F.Mask" "F.Paste")
			(net "I2C_PSU2_R_SDA")
		)
		(pad "B12" smd rect
			(at -28.50007 0 180)
			(size 0.762 4.2164)
			(layers "F.Cu" "F.Mask" "F.Paste")
			(net "T4_NODE1_EN_R")
		)
		(pad "B13" smd rect
			(at -27.500072 0 180)
			(size 0.762 4.2164)
			(layers "F.Cu" "F.Mask" "F.Paste")
			(net "T4_NODE2_EN_R")
		)
		(pad "B14" smd rect
			(at -26.500074 0 180)
			(size 0.762 4.2164)
			(layers "F.Cu" "F.Mask" "F.Paste")
			(net "T4_NODE3_EN_R")
		)
		(pad "B15" smd rect
			(at -25.500076 0 180)
			(size 0.762 4.2164)
			(layers "F.Cu" "F.Mask" "F.Paste")
			(net "T4_NODE4_EN_R")
		)
		(pad "B16" smd rect
			(at -24.500078 0 180)
			(size 0.762 4.2164)
			(layers "F.Cu" "F.Mask" "F.Paste")
			(net "GND")
		)
		(pad "B17" smd rect
			(at -23.50008 -0.499872 180)
			(size 0.762 3.2004)
			(layers "F.Cu" "F.Mask" "F.Paste")
			(net "UART_T4_NODE1_RXD_R")
		)
		(pad "B18" smd rect
			(at -22.500082 0 180)
			(size 0.762 4.2164)
			(layers "F.Cu" "F.Mask" "F.Paste")
			(net "UART_T4_NODE1_TXD_R")
		)
		(pad "B19" smd rect
			(at -21.500084 0 180)
			(size 0.762 4.2164)
			(layers "F.Cu" "F.Mask" "F.Paste")
			(net "UART_T4_NODE2_RXD_R")
		)
		(pad "B20" smd rect
			(at -20.500086 0 180)
			(size 0.762 4.2164)
			(layers "F.Cu" "F.Mask" "F.Paste")
			(net "UART_T4_NODE2_TXD_R")
		)
		(pad "B21" smd rect
			(at -19.500088 0 180)
			(size 0.762 4.2164)
			(layers "F.Cu" "F.Mask" "F.Paste")
			(net "GND")
		)
		(pad "B22" smd rect
			(at -18.50009 0 180)
			(size 0.762 4.2164)
			(layers "F.Cu" "F.Mask" "F.Paste")
			(net "UART_T4_NODE3_RXD_R")
		)
		(pad "B23" smd rect
			(at -17.500092 0 180)
			(size 0.762 4.2164)
			(layers "F.Cu" "F.Mask" "F.Paste")
			(net "UART_T4_NODE3_TXD_R")
		)
		(pad "B24" smd rect
			(at -16.500094 0 180)
			(size 0.762 4.2164)
			(layers "F.Cu" "F.Mask" "F.Paste")
			(net "UART_T4_NODE4_RXD_R")
		)
		(pad "B25" smd rect
			(at -15.500096 0 180)
			(size 0.762 4.2164)
			(layers "F.Cu" "F.Mask" "F.Paste")
			(net "UART_T4_NODE4_TXD_R")
		)
		(pad "B26" smd rect
			(at -14.500098 0 180)
			(size 0.762 4.2164)
			(layers "F.Cu" "F.Mask" "F.Paste")
			(net "GND")
		)
		(pad "B27" smd rect
			(at -13.5001 0 180)
			(size 0.762 4.2164)
			(layers "F.Cu" "F.Mask" "F.Paste")
			(net "T2_NODE1_EN_R")
		)
		(pad "B28" smd rect
			(at -12.500102 0 180)
			(size 0.762 4.2164)
			(layers "F.Cu" "F.Mask" "F.Paste")
			(net "T2_NODE2_EN_R")
		)
		(pad "B29" smd rect
			(at -11.500104 0 180)
			(size 0.762 4.2164)
			(layers "F.Cu" "F.Mask" "F.Paste")
			(net "T2_NODE3_EN_R")
		)
		(pad "B30" smd rect
			(at -10.500106 0 180)
			(size 0.762 4.2164)
			(layers "F.Cu" "F.Mask" "F.Paste")
			(net "T2_NODE4_EN_R")
		)
		(pad "B31" smd rect
			(at -9.500108 -0.499872 180)
			(size 0.762 3.2004)
			(layers "F.Cu" "F.Mask" "F.Paste")
			(net "GND")
		)
		(pad "B32" smd rect
			(at -8.50011 0 180)
			(size 0.762 4.2164)
			(layers "F.Cu" "F.Mask" "F.Paste")
			(net "UART_T2_NODE1_RXD_R")
		)
		(pad "B33" smd rect
			(at -7.500112 0 180)
			(size 0.762 4.2164)
			(layers "F.Cu" "F.Mask" "F.Paste")
			(net "UART_T2_NODE1_TXD_R")
		)
		(pad "B34" smd rect
			(at -6.500114 0 180)
			(size 0.762 4.2164)
			(layers "F.Cu" "F.Mask" "F.Paste")
			(net "UART_T2_NODE2_RXD_R")
		)
		(pad "B35" smd rect
			(at -5.500116 0 180)
			(size 0.762 4.2164)
			(layers "F.Cu" "F.Mask" "F.Paste")
			(net "UART_T2_NODE2_TXD_R")
		)
		(pad "B36" smd rect
			(at -4.500118 0 180)
			(size 0.762 4.2164)
			(layers "F.Cu" "F.Mask" "F.Paste")
			(net "GND")
		)
		(pad "B37" smd rect
			(at -3.50012 0 180)
			(size 0.762 4.2164)
			(layers "F.Cu" "F.Mask" "F.Paste")
			(net "UART_T2_NODE3_RXD_R")
		)
		(pad "B38" smd rect
			(at -2.500122 0 180)
			(size 0.762 4.2164)
			(layers "F.Cu" "F.Mask" "F.Paste")
			(net "UART_T2_NODE3_TXD_R")
		)
		(pad "B39" smd rect
			(at -1.500124 0 180)
			(size 0.762 4.2164)
			(layers "F.Cu" "F.Mask" "F.Paste")
			(net "UART_T2_NODE4_RXD_R")
		)
		(pad "B40" smd rect
			(at -0.499872 0 180)
			(size 0.762 4.2164)
			(layers "F.Cu" "F.Mask" "F.Paste")
			(net "UART_T2_NODE4_TXD_R")
		)
		(pad "B41" smd rect
			(at 0.499872 0 180)
			(size 0.762 4.2164)
			(layers "F.Cu" "F.Mask" "F.Paste")
			(net "GND")
		)
		(pad "B42" smd rect
			(at 1.500124 0 180)
			(size 0.762 4.2164)
			(layers "F.Cu" "F.Mask" "F.Paste")
			(net "I2C_PSU1_R_SCL")
		)
		(pad "B43" smd rect
			(at 2.500122 0 180)
			(size 0.762 4.2164)
			(layers "F.Cu" "F.Mask" "F.Paste")
			(net "I2C_PSU1_R_SDA")
		)
		(pad "B44" smd rect
			(at 3.50012 0 180)
			(size 0.762 4.2164)
			(layers "F.Cu" "F.Mask" "F.Paste")
			(net "GND")
		)
		(pad "B45" smd rect
			(at 4.500118 0 180)
			(size 0.762 4.2164)
			(layers "F.Cu" "F.Mask" "F.Paste")
			(net "PSU1_AC_OK_R")
		)
		(pad "B46" smd rect
			(at 5.500116 0 180)
			(size 0.762 4.2164)
			(layers "F.Cu" "F.Mask" "F.Paste")
			(net "PSU2_AC_OK_R")
		)
		(pad "B47" smd rect
			(at 6.500114 0 180)
			(size 0.762 4.2164)
			(layers "F.Cu" "F.Mask" "F.Paste")
			(net "PSU3_AC_OK_R")
		)
		(pad "B48" smd rect
			(at 7.500112 -0.499872 180)
			(size 0.762 3.2004)
			(layers "F.Cu" "F.Mask" "F.Paste")
			(net "PSU4_AC_OK_R")
		)
		(pad "B49" smd rect
			(at 8.50011 0 180)
			(size 0.762 4.2164)
			(layers "F.Cu" "F.Mask" "F.Paste")
			(net "PSU5_AC_OK_R")
		)
		(pad "B50" smd rect
			(at 9.500108 0 180)
			(size 0.762 4.2164)
			(layers "F.Cu" "F.Mask" "F.Paste")
			(net "PSU6_AC_OK_R")
		)
		(pad "B51" smd rect
			(at 10.500106 0 180)
			(size 0.762 4.2164)
			(layers "F.Cu" "F.Mask" "F.Paste")
			(net "GND")
		)
		(pad "B52" smd rect
			(at 11.500104 0 180)
			(size 0.762 4.2164)
			(layers "F.Cu" "F.Mask" "F.Paste")
			(net "UART_RTS_P5_L_N")
		)
		(pad "B53" smd rect
			(at 12.500102 0 180)
			(size 0.762 4.2164)
			(layers "F.Cu" "F.Mask" "F.Paste")
			(net "UART_DSR_P5_L_N")
		)
		(pad "B54" smd rect
			(at 13.5001 0 180)
			(size 0.762 4.2164)
			(layers "F.Cu" "F.Mask" "F.Paste")
			(net "UART_RX_P5_L")
		)
		(pad "B55" smd rect
			(at 14.500098 0 180)
			(size 0.762 4.2164)
			(layers "F.Cu" "F.Mask" "F.Paste")
			(net "UART_TX_P5_L")
		)
		(pad "B56" smd rect
			(at 15.500096 0 180)
			(size 0.762 4.2164)
			(layers "F.Cu" "F.Mask" "F.Paste")
			(net "UART_DTR_P5_L_N")
		)
		(pad "B57" smd rect
			(at 16.500094 0 180)
			(size 0.762 4.2164)
			(layers "F.Cu" "F.Mask" "F.Paste")
			(net "UART_CTS_P5_L_N")
		)
		(pad "B58" smd rect
			(at 17.500092 0 180)
			(size 0.762 4.2164)
			(layers "F.Cu" "F.Mask" "F.Paste")
			(net "UART_RI_P5_L_N_R")
		)
		(pad "B59" smd rect
			(at 18.50009 0 180)
			(size 0.762 4.2164)
			(layers "F.Cu" "F.Mask" "F.Paste")
			(net "GND")
		)
		(pad "B60" smd rect
			(at 19.500088 0 180)
			(size 0.762 4.2164)
			(layers "F.Cu" "F.Mask" "F.Paste")
			(net "UART_RTS_P1_L_N")
		)
		(pad "B61" smd rect
			(at 20.500086 0 180)
			(size 0.762 4.2164)
			(layers "F.Cu" "F.Mask" "F.Paste")
			(net "UART_DSR_P1_L_N")
		)
		(pad "B62" smd rect
			(at 21.500084 0 180)
			(size 0.762 4.2164)
			(layers "F.Cu" "F.Mask" "F.Paste")
			(net "UART_RX_P1_L")
		)
		(pad "B63" smd rect
			(at 22.500082 0 180)
			(size 0.762 4.2164)
			(layers "F.Cu" "F.Mask" "F.Paste")
			(net "UART_TX_P1_L")
		)
		(pad "B64" smd rect
			(at 23.50008 0 180)
			(size 0.762 4.2164)
			(layers "F.Cu" "F.Mask" "F.Paste")
			(net "UART_DTR_P1_L_N")
		)
		(pad "B65" smd rect
			(at 24.500078 0 180)
			(size 0.762 4.2164)
			(layers "F.Cu" "F.Mask" "F.Paste")
			(net "UART_CTS_P1_L_N")
		)
		(pad "B66" smd rect
			(at 25.500076 0 180)
			(size 0.762 4.2164)
			(layers "F.Cu" "F.Mask" "F.Paste")
			(net "GND")
		)
		(pad "B67" smd rect
			(at 26.500074 0 180)
			(size 0.762 4.2164)
			(layers "F.Cu" "F.Mask" "F.Paste")
			(net "Net_2332")
		)
		(pad "B68" smd rect
			(at 27.500072 0 180)
			(size 0.762 4.2164)
			(layers "F.Cu" "F.Mask" "F.Paste")
			(net "GND61")
		)
		(pad "B69" smd rect
			(at 28.50007 0 180)
			(size 0.762 4.2164)
			(layers "F.Cu" "F.Mask" "F.Paste")
			(net "GND62")
		)
		(pad "B70" smd rect
			(at 29.500068 0 180)
			(size 0.762 4.2164)
			(layers "F.Cu" "F.Mask" "F.Paste")
			(net "Net_2331")
		)
		(pad "B71" smd rect
			(at 30.500066 0 180)
			(size 0.762 4.2164)
			(layers "F.Cu" "F.Mask" "F.Paste")
			(net "GND")
		)
		(pad "B72" smd rect
			(at 31.500064 0 180)
			(size 0.762 4.2164)
			(layers "F.Cu" "F.Mask" "F.Paste")
			(net "LAN1_P3_P")
		)
		(pad "B73" smd rect
			(at 32.500062 0 180)
			(size 0.762 4.2164)
			(layers "F.Cu" "F.Mask" "F.Paste")
			(net "LAN1_P3_N")
		)
		(pad "B74" smd rect
			(at 33.50006 0 180)
			(size 0.762 4.2164)
			(layers "F.Cu" "F.Mask" "F.Paste")
			(net "GND")
		)
		(pad "B75" smd rect
			(at 34.500058 0 180)
			(size 0.762 4.2164)
			(layers "F.Cu" "F.Mask" "F.Paste")
			(net "LAN1_P4_P")
		)
		(pad "B76" smd rect
			(at 35.500056 0 180)
			(size 0.762 4.2164)
			(layers "F.Cu" "F.Mask" "F.Paste")
			(net "LAN1_P4_N")
		)
		(pad "B77" smd rect
			(at 36.500054 0 180)
			(size 0.762 4.2164)
			(layers "F.Cu" "F.Mask" "F.Paste")
			(net "GND")
		)
		(pad "B78" smd rect
			(at 37.500052 0 180)
			(size 0.762 4.2164)
			(layers "F.Cu" "F.Mask" "F.Paste")
			(net "CM_PWR_CTL_IN")
		)
		(pad "B79" smd rect
			(at 38.50005 0 180)
			(size 0.762 4.2164)
			(layers "F.Cu" "F.Mask" "F.Paste")
			(net "P12V_PDB")
		)
		(pad "B80" smd rect
			(at 39.500048 0 180)
			(size 0.762 4.2164)
			(layers "F.Cu" "F.Mask" "F.Paste")
			(net "P12V_PDB")
		)
		(pad "B81" smd rect
			(at 40.500046 -0.499872 180)
			(size 0.762 3.2004)
			(layers "F.Cu" "F.Mask" "F.Paste")
			(net "MATE_R_N")
		)
		(pad "B82" smd rect
			(at 41.500044 0 180)
			(size 0.762 4.2164)
			(layers "F.Cu" "F.Mask" "F.Paste")
			(net "P12V_PDB")
		)
		(zone
			(layers "F.Cu" "B.Cu" "In1.Cu" "In2.Cu" "In3.Cu" "In4.Cu" "In5.Cu" "In6.Cu"
				"In7.Cu" "In8.Cu"
			)
			(hatch none 0.5)
			(connect_pads
				(clearance 0)
			)
			(min_thickness 0.25)
			(keepout
				(tracks allowed)
				(vias not_allowed)
				(pads allowed)
				(copperpour not_allowed)
				(footprints allowed)
			)
			(placement
				(enabled no)
				(sheetname "")
			)
			(fill
				(thermal_gap 0.5)
				(thermal_bridge_width 0.5)
				(island_removal_mode 0)
			)
			(polygon
				(pts
					(xy 83.471004 -207.358488) (xy 12.579604 -207.358488) (xy 12.579604 -201.770488) (xy 83.471004 -201.770488)
				)
			)
		)
		(zone
			(layers "F.Cu" "B.Cu" "In1.Cu" "In2.Cu" "In3.Cu" "In4.Cu" "In5.Cu" "In6.Cu"
				"In7.Cu" "In8.Cu"
			)
			(hatch none 0.5)
			(connect_pads
				(clearance 0)
			)
			(min_thickness 0.25)
			(keepout
				(tracks allowed)
				(vias not_allowed)
				(pads allowed)
				(copperpour not_allowed)
				(footprints allowed)
			)
			(placement
				(enabled no)
				(sheetname "")
			)
			(fill
				(thermal_gap 0.5)
				(thermal_bridge_width 0.5)
				(island_removal_mode 0)
			)
			(polygon
				(pts
					(xy 85.579204 -201.770488) (xy 96.450404 -201.770488) (xy 96.450404 -207.358488) (xy 85.579204 -207.358488)
				)
			)
		)
	)
	(footprint ""
		(layer "F.Cu")
		(at 111.871252 -166.52113)
		(property "Reference" "R673"
			(at -1.917192 -12.506198 0)
			(unlocked yes)
			(layer "F.SilkS")
			(effects
				(font
					(size 0.7874 0.5842)
					(thickness 0.1524)
				)
				(justify left)
			)
		)
		(property "Value" ""
			(at 0 0 0)
			(layer "F.Fab")
			(effects
				(font
					(size 1.27 1.27)
				)
			)
		)
		(duplicate_pad_numbers_are_jumpers no)
		(fp_line
			(start -0.7874 -0.4064)
			(end 0.7874 -0.4064)
			(stroke
				(width 0.1524)
				(type default)
			)
			(layer "F.SilkS")
		)
		(fp_line
			(start -0.7874 0.4064)
			(end -0.7874 -0.4064)
			(stroke
				(width 0.1524)
				(type default)
			)
			(layer "F.SilkS")
		)
		(fp_line
			(start 0.7874 -0.4064)
			(end 0.7874 0.4064)
			(stroke
				(width 0.1524)
				(type default)
			)
			(layer "F.SilkS")
		)
		(fp_line
			(start 0.7874 0.4064)
			(end -0.7874 0.4064)
			(stroke
				(width 0.1524)
				(type default)
			)
			(layer "F.SilkS")
		)
		(fp_poly
			(pts
				(xy -0.508 0.2794) (xy -0.508 0.2286) (xy -0.635 0.2286) (xy -0.635 -0.254) (xy -0.5334 -0.254)
				(xy -0.5334 -0.2794) (xy 0.5334 -0.2794) (xy 0.5334 -0.254) (xy 0.635 -0.254) (xy 0.635 0.254) (xy 0.5334 0.254)
				(xy 0.5334 0.2794)
			)
			(stroke
				(width 0)
				(type default)
			)
			(fill no)
			(layer "F.CrtYd")
		)
		(pad "1" smd rect
			(at 0.40005 0)
			(size 0.4572 0.508)
			(layers "F.Cu" "F.Mask" "F.Paste")
			(net "UART3_RESET_N")
		)
		(pad "2" smd rect
			(at -0.40005 0)
			(size 0.4572 0.508)
			(layers "F.Cu" "F.Mask" "F.Paste")
			(net "P3V3_NODE1")
		)
	)
	(footprint ""
		(layer "F.Cu")
		(at 10.65022 -46.794166 180)
		(property "Reference" "J9"
			(at -2.037842 0.385826 90)
			(unlocked yes)
			(layer "F.SilkS")
			(effects
				(font
					(size 0.7874 0.5842)
					(thickness 0.1524)
				)
				(justify left)
			)
		)
		(property "Value" ""
			(at 0 0 180)
			(layer "F.Fab")
			(effects
				(font
					(size 1.27 1.27)
				)
			)
		)
		(duplicate_pad_numbers_are_jumpers no)
		(fp_line
			(start 9.299956 19.50593)
			(end 9.299956 -11.494008)
			(stroke
				(width 0.1524)
				(type default)
			)
			(layer "F.SilkS")
		)
		(fp_line
			(start 9.299956 -11.494008)
			(end -1.299972 -11.494008)
			(stroke
				(width 0.1524)
				(type default)
			)
			(layer "F.SilkS")
		)
		(fp_line
			(start 3.10007 19.50593)
			(end 3.10007 -11.494008)
			(stroke
				(width 0.1524)
				(type default)
			)
			(layer "F.SilkS")
		)
		(fp_line
			(start 2.70002 19.50593)
			(end 2.70002 -11.494008)
			(stroke
				(width 0.1524)
				(type default)
			)
			(layer "F.SilkS")
		)
		(fp_line
			(start -1.299972 19.50593)
			(end 9.299956 19.50593)
			(stroke
				(width 0.1524)
				(type default)
			)
			(layer "F.SilkS")
		)
		(fp_line
			(start -1.299972 17.85112)
			(end -1.299972 19.50593)
			(stroke
				(width 0.1524)
				(type default)
			)
			(layer "F.SilkS")
		)
		(fp_line
			(start -1.299972 15.1511)
			(end -2.899918 15.1511)
			(stroke
				(width 0.1524)
				(type default)
			)
			(layer "F.SilkS")
		)
		(fp_line
			(start -1.299972 12.726416)
			(end -1.299972 15.1511)
			(stroke
				(width 0.1524)
				(type default)
			)
			(layer "F.SilkS")
		)
		(fp_line
			(start -1.299972 -3.24739)
			(end -1.299972 11.262106)
			(stroke
				(width 0.1524)
				(type default)
			)
			(layer "F.SilkS")
		)
		(fp_line
			(start -1.299972 -7.138924)
			(end -1.299972 -4.71678)
			(stroke
				(width 0.1524)
				(type default)
			)
			(layer "F.SilkS")
		)
		(fp_line
			(start -1.299972 -9.838944)
			(end -2.899918 -9.838944)
			(stroke
				(width 0.1524)
				(type default)
			)
			(layer "F.SilkS")
		)
		(fp_line
			(start -1.299972 -11.494008)
			(end -1.299972 -9.838944)
			(stroke
				(width 0.1524)
				(type default)
			)
			(layer "F.SilkS")
		)
		(fp_line
			(start -2.899918 17.85112)
			(end -1.299972 17.85112)
			(stroke
				(width 0.1524)
				(type default)
			)
			(layer "F.SilkS")
		)
		(fp_line
			(start -2.899918 15.1511)
			(end -2.899918 17.85112)
			(stroke
				(width 0.1524)
				(type default)
			)
			(layer "F.SilkS")
		)
		(fp_line
			(start -2.899918 -7.138924)
			(end -1.299972 -7.138924)
			(stroke
				(width 0.1524)
				(type default)
			)
			(layer "F.SilkS")
		)
		(fp_line
			(start -2.899918 -9.838944)
			(end -2.899918 -7.138924)
			(stroke
				(width 0.1524)
				(type default)
			)
			(layer "F.SilkS")
		)
		(fp_poly
			(pts
				(xy -3.096006 0.764286) (xy -3.096006 -0.759714) (xy -1.572006 0.002286)
			)
			(stroke
				(width 0)
				(type default)
			)
			(fill yes)
			(layer "F.SilkS")
		)
		(fp_poly
			(pts
				(xy 2.122424 -2.148332) (xy 2.122424 9.778238) (xy -0.6223 9.778238) (xy -0.6223 -2.148332)
			)
			(stroke
				(width 0)
				(type default)
			)
			(fill no)
			(layer "B.CrtYd")
		)
		(fp_poly
			(pts
				(arc
					(start 0.299974 14.73581)
					(mid -0.095157 14.899479)
					(end -0.258826 15.29461)
				)
				(arc
					(start -0.258826 17.70761)
					(mid -0.095157 18.102741)
					(end 0.299974 18.26641)
				)
				(arc
					(start 0.299974 18.26641)
					(mid 0.695105 18.102741)
					(end 0.858774 17.70761)
				)
				(arc
					(start 0.858774 15.29461)
					(mid 0.695105 14.899479)
					(end 0.299974 14.73581)
				)
			)
			(stroke
				(width 0)
				(type default)
			)
			(fill no)
			(layer "B.CrtYd")
		)
		(fp_poly
			(pts
				(arc
					(start 0.299974 -10.254234)
					(mid -0.095157 -10.090565)
					(end -0.258826 -9.695434)
				)
				(arc
					(start -0.258826 -7.282434)
					(mid -0.095157 -6.887303)
					(end 0.299974 -6.723634)
				)
				(arc
					(start 0.299974 -6.723634)
					(mid 0.695105 -6.887303)
					(end 0.858774 -7.282434)
				)
				(arc
					(start 0.858774 -9.695434)
					(mid 0.695105 -10.090565)
					(end 0.299974 -10.254234)
				)
			)
			(stroke
				(width 0)
				(type default)
			)
			(fill no)
			(layer "B.CrtYd")
		)
		(fp_poly
			(pts
				(arc
					(start 0.503428 11.995912)
					(mid -1.50368 11.995912)
					(end 0.503428 11.995912)
				)
			)
			(stroke
				(width 0)
				(type default)
			)
			(fill no)
			(layer "B.CrtYd")
		)
		(fp_poly
			(pts
				(arc
					(start 0.503428 -3.98399)
					(mid -1.50368 -3.98399)
					(end 0.503428 -3.98399)
				)
			)
			(stroke
				(width 0)
				(type default)
			)
			(fill no)
			(layer "B.CrtYd")
		)
		(fp_poly
			(pts
				(xy -2.899918 -9.838944) (xy -1.299972 -9.838944) (xy -1.299972 -11.494008) (xy 9.299956 -11.494008)
				(xy 9.299956 19.50593) (xy -1.299972 19.50593) (xy -1.299972 17.85112) (xy -2.899918 17.85112) (xy -2.899918 15.1511)
				(xy -1.299972 15.1511) (xy -1.299972 12.999212) (xy -1.503172 12.999212) (xy -1.503172 10.992612)
				(xy -1.299972 10.992612) (xy -1.299972 -2.98069) (xy -1.503172 -2.98069) (xy -1.503172 -4.98729)
				(xy -1.299972 -4.98729) (xy -1.299972 -7.138924) (xy -2.899918 -7.138924)
			)
			(stroke
				(width 0)
				(type default)
			)
			(fill no)
			(layer "F.CrtYd")
		)
		(fp_line
			(start 9.299956 19.50593)
			(end 9.299956 -11.494008)
			(stroke
				(width 0.1)
				(type default)
			)
			(layer "F.Fab")
		)
		(fp_line
			(start 9.299956 -11.494008)
			(end -1.299972 -11.494008)
			(stroke
				(width 0.1)
				(type default)
			)
			(layer "F.Fab")
		)
		(fp_line
			(start -1.299972 19.50593)
			(end 9.299956 19.50593)
			(stroke
				(width 0.1)
				(type default)
			)
			(layer "F.Fab")
		)
		(fp_line
			(start -1.299972 17.85112)
			(end -1.299972 19.50593)
			(stroke
				(width 0.1)
				(type default)
			)
			(layer "F.Fab")
		)
		(fp_line
			(start -1.299972 15.1511)
			(end -2.899918 15.1511)
			(stroke
				(width 0.1)
				(type default)
			)
			(layer "F.Fab")
		)
		(fp_line
			(start -1.299972 -7.138924)
			(end -1.299972 15.1511)
			(stroke
				(width 0.1)
				(type default)
			)
			(layer "F.Fab")
		)
		(fp_line
			(start -1.299972 -9.838944)
			(end -2.899918 -9.838944)
			(stroke
				(width 0.1)
				(type default)
			)
			(layer "F.Fab")
		)
		(fp_line
			(start -1.299972 -11.494008)
			(end -1.299972 -9.838944)
			(stroke
				(width 0.1)
				(type default)
			)
			(layer "F.Fab")
		)
		(fp_line
			(start -2.899918 17.85112)
			(end -1.299972 17.85112)
			(stroke
				(width 0.1)
				(type default)
			)
			(layer "F.Fab")
		)
		(fp_line
			(start -2.899918 15.1511)
			(end -2.899918 17.85112)
			(stroke
				(width 0.1)
				(type default)
			)
			(layer "F.Fab")
		)
		(fp_line
			(start -2.899918 -7.138924)
			(end -1.299972 -7.138924)
			(stroke
				(width 0.1)
				(type default)
			)
			(layer "F.Fab")
		)
		(fp_line
			(start -2.899918 -9.838944)
			(end -2.899918 -7.138924)
			(stroke
				(width 0.1)
				(type default)
			)
			(layer "F.Fab")
		)
		(fp_poly
			(pts
				(xy -3.096006 0.764286) (xy -3.096006 -0.759714) (xy -1.572006 0.002286)
			)
			(stroke
				(width 0)
				(type default)
			)
			(fill yes)
			(layer "F.Fab")
		)
		(fp_text user "11"
			(at 1.537462 -12.184126 0)
			(unlocked yes)
			(layer "F.SilkS")
			(effects
				(font
					(size 0.7874 0.5842)
					(thickness 0.1524)
				)
			)
		)
		(fp_text user "15"
			(at -0.766318 20.236942 0)
			(unlocked yes)
			(layer "F.SilkS")
			(effects
				(font
					(size 0.7874 0.5842)
					(thickness 0.1524)
				)
			)
		)
		(fp_text user "6"
			(at -1.76149 -1.074928 0)
			(unlocked yes)
			(layer "F.SilkS")
			(effects
				(font
					(size 0.7874 0.5842)
					(thickness 0.1524)
				)
			)
		)
		(fp_text user "5"
			(at -1.881378 10.684256 0)
			(unlocked yes)
			(layer "F.SilkS")
			(effects
				(font
					(size 0.7874 0.5842)
					(thickness 0.1524)
				)
			)
		)
		(fp_text user "11"
			(at 1.624838 -2.163318 0)
			(unlocked yes)
			(layer "B.SilkS")
			(effects
				(font
					(size 0.7874 0.5842)
					(thickness 0.1524)
				)
				(justify mirror)
			)
		)
		(fp_text user "15"
			(at 1.609598 9.572752 0)
			(unlocked yes)
			(layer "B.SilkS")
			(effects
				(font
					(size 0.7874 0.5842)
					(thickness 0.1524)
				)
				(justify mirror)
			)
		)
		(fp_text user "5"
			(at -1.04394 8.918702 0)
			(unlocked yes)
			(layer "B.SilkS")
			(effects
				(font
					(size 0.7874 0.5842)
					(thickness 0.1524)
				)
				(justify mirror)
			)
		)
		(fp_text user "6"
			(at -1.32588 -1.558544 0)
			(unlocked yes)
			(layer "B.SilkS")
			(effects
				(font
					(size 0.7874 0.5842)
					(thickness 0.1524)
				)
				(justify mirror)
			)
		)
		(fp_text user "15"
			(at 1.503426 9.986772 90)
			(unlocked yes)
			(layer "B.Fab")
			(effects
				(font
					(size 0.7874 0.5842)
					(thickness 0.000001)
				)
				(justify mirror)
			)
		)
		(fp_text user "11"
			(at 1.457452 -2.364486 90)
			(unlocked yes)
			(layer "B.Fab")
			(effects
				(font
					(size 0.7874 0.5842)
					(thickness 0.000001)
				)
				(justify mirror)
			)
		)
		(fp_text user "6"
			(at 0.021336 -2.64033 90)
			(unlocked yes)
			(layer "B.Fab")
			(effects
				(font
					(size 0.7874 0.5842)
					(thickness 0.000001)
				)
				(justify mirror)
			)
		)
		(fp_text user "5"
			(at -0.036068 10.411714 90)
			(unlocked yes)
			(layer "B.Fab")
			(effects
				(font
					(size 0.7874 0.5842)
					(thickness 0.000001)
				)
				(justify mirror)
			)
		)
		(fp_text user "15"
			(at 1.641348 20.534122 90)
			(unlocked yes)
			(layer "F.Fab")
			(effects
				(font
					(size 0.7874 0.5842)
					(thickness 0.000001)
				)
			)
		)
		(fp_text user "11"
			(at 1.53797 -12.45235 90)
			(unlocked yes)
			(layer "F.Fab")
			(effects
				(font
					(size 0.7874 0.5842)
					(thickness 0.000001)
				)
			)
		)
		(fp_text user "5"
			(at 0.124714 20.350226 90)
			(unlocked yes)
			(layer "F.Fab")
			(effects
				(font
					(size 0.7874 0.5842)
					(thickness 0.000001)
				)
			)
		)
		(fp_text user "6"
			(at 0.044196 -12.291568 90)
			(unlocked yes)
			(layer "F.Fab")
			(effects
				(font
					(size 0.7874 0.5842)
					(thickness 0.000001)
				)
			)
		)
		(pad "" np_thru_hole circle
			(at -0.499872 -3.98399 90)
			(size 1.4986 1.4986)
			(drill 1.4986)
			(layers "*.Cu" "*.Mask")
			(clearance 0.381)
			(thermal_gap 0.381)
		)
		(pad "" np_thru_hole circle
			(at -0.499872 11.995912 90)
			(size 1.4986 1.4986)
			(drill 1.4986)
			(layers "*.Cu" "*.Mask")
			(clearance 0.381)
			(thermal_gap 0.381)
		)
		(pad "1" thru_hole rect
			(at 0 0 90)
			(size 1.143 1.143)
			(drill 0.8382)
			(layers "*.Cu" "*.Mask")
			(remove_unused_layers no)
			(net "CRT_R")
			(clearance 0.1016)
			(thermal_gap 0.1016)
			(padstack
				(mode front_inner_back)
				(layer "Inner"
					(shape circle)
					(size 1.143 1.143)
					(clearance 0.1016)
				)
				(layer "B.Cu"
					(shape rect)
					(size 1.143 1.143)
					(clearance 0.1016)
				)
			)
		)
		(pad "2" thru_hole circle
			(at 1.500124 2.289048 90)
			(size 1.143 1.143)
			(drill 0.8382)
			(layers "*.Cu" "*.Mask")
			(remove_unused_layers no)
			(net "CRT_G")
			(clearance 0.1016)
			(thermal_gap 0.1016)
		)
		(pad "3" thru_hole circle
			(at 0 4.578096 90)
			(size 1.143 1.143)
			(drill 0.8382)
			(layers "*.Cu" "*.Mask")
			(remove_unused_layers no)
			(net "CRT_B")
			(clearance 0.1016)
			(thermal_gap 0.1016)
		)
		(pad "4" thru_hole circle
			(at 1.500124 6.86689 90)
			(size 1.143 1.143)
			(drill 0.8382)
			(layers "*.Cu" "*.Mask")
			(remove_unused_layers no)
			(net "Net_2246")
			(clearance 0.1016)
			(thermal_gap 0.1016)
		)
		(pad "5" thru_hole circle
			(at 0 9.155938 90)
			(size 1.143 1.143)
			(drill 0.8382)
			(layers "*.Cu" "*.Mask")
			(remove_unused_layers no)
			(net "GND")
			(clearance 0.1016)
			(thermal_gap 0.1016)
		)
		(pad "6" thru_hole circle
			(at 0 -1.526032 90)
			(size 1.143 1.143)
			(drill 0.8382)
			(layers "*.Cu" "*.Mask")
			(remove_unused_layers no)
			(net "GND")
			(clearance 0.1016)
			(thermal_gap 0.1016)
		)
		(pad "7" thru_hole circle
			(at 1.500124 0.763016 90)
			(size 1.143 1.143)
			(drill 0.8382)
			(layers "*.Cu" "*.Mask")
			(remove_unused_layers no)
			(net "GND")
			(clearance 0.1016)
			(thermal_gap 0.1016)
		)
		(pad "8" thru_hole circle
			(at 0 3.052064 90)
			(size 1.143 1.143)
			(drill 0.8382)
			(layers "*.Cu" "*.Mask")
			(remove_unused_layers no)
			(net "GND")
			(clearance 0.1016)
			(thermal_gap 0.1016)
		)
		(pad "9" thru_hole circle
			(at 1.500124 5.341112 90)
			(size 1.143 1.143)
			(drill 0.8382)
			(layers "*.Cu" "*.Mask")
			(remove_unused_layers no)
			(net "P5V_CRT")
			(clearance 0.1016)
			(thermal_gap 0.1016)
		)
		(pad "10" thru_hole circle
			(at 0 7.629906 90)
			(size 1.143 1.143)
			(drill 0.8382)
			(layers "*.Cu" "*.Mask")
			(remove_unused_layers no)
			(net "GND")
			(clearance 0.1016)
			(thermal_gap 0.1016)
		)
		(pad "11" thru_hole circle
			(at 1.500124 -0.763016 90)
			(size 1.143 1.143)
			(drill 0.8382)
			(layers "*.Cu" "*.Mask")
			(remove_unused_layers no)
			(net "Net_2247")
			(clearance 0.1016)
			(thermal_gap 0.1016)
		)
		(pad "12" thru_hole circle
			(at 0 1.526032 90)
			(size 1.143 1.143)
			(drill 0.8382)
			(layers "*.Cu" "*.Mask")
			(remove_unused_layers no)
			(net "CRT_DDCDATA")
			(clearance 0.1016)
			(thermal_gap 0.1016)
		)
		(pad "13" thru_hole circle
			(at 1.500124 3.81508 90)
			(size 1.143 1.143)
			(drill 0.8382)
			(layers "*.Cu" "*.Mask")
			(remove_unused_layers no)
			(net "CRT_HSYNC")
			(clearance 0.1016)
			(thermal_gap 0.1016)
		)
		(pad "14" thru_hole circle
			(at 0 6.103874 90)
			(size 1.143 1.143)
			(drill 0.8382)
			(layers "*.Cu" "*.Mask")
			(remove_unused_layers no)
			(net "CRT_VSYNC")
			(clearance 0.1016)
			(thermal_gap 0.1016)
		)
		(pad "15" thru_hole circle
			(at 1.500124 8.392922 90)
			(size 1.143 1.143)
			(drill 0.8382)
			(layers "*.Cu" "*.Mask")
			(remove_unused_layers no)
			(net "CRT_DDCCLK")
			(clearance 0.1016)
			(thermal_gap 0.1016)
		)
		(pad "G1" thru_hole oval
			(at 0.299974 -8.488934 180)
			(size 1.016 3.429)
			(drill oval 0.7112 3.1496)
			(layers "*.Cu" "*.Mask")
			(remove_unused_layers no)
			(net "GND")
			(clearance 0.2286)
			(thermal_gap 0.2286)
		)
		(pad "G2" thru_hole oval
			(at 0.299974 16.50111 180)
			(size 1.016 3.429)
			(drill oval 0.7112 3.1496)
			(layers "*.Cu" "*.Mask")
			(remove_unused_layers no)
			(net "GND")
			(clearance 0.2286)
			(thermal_gap 0.2286)
		)
		(zone
			(layers "F.Cu" "B.Cu" "In1.Cu" "In2.Cu" "In3.Cu" "In4.Cu" "In5.Cu" "In6.Cu"
				"In7.Cu" "In8.Cu"
			)
			(hatch none 0.5)
			(connect_pads
				(clearance 0)
			)
			(min_thickness 0.25)
			(keepout
				(tracks not_allowed)
				(vias allowed)
				(pads allowed)
				(copperpour not_allowed)
				(footprints allowed)
			)
			(placement
				(enabled no)
				(sheetname "")
			)
			(fill
				(thermal_gap 0.5)
				(thermal_bridge_width 0.5)
				(island_removal_mode 0)
			)
			(polygon
				(pts
					(arc
						(start 9.994392 -58.790078)
						(mid 12.3063 -58.790078)
						(end 9.994392 -58.790078)
					)
				)
			)
		)
		(zone
			(layers "F.Cu" "B.Cu" "In1.Cu" "In2.Cu" "In3.Cu" "In4.Cu" "In5.Cu" "In6.Cu"
				"In7.Cu" "In8.Cu"
			)
			(hatch none 0.5)
			(connect_pads
				(clearance 0)
			)
			(min_thickness 0.25)
			(keepout
				(tracks not_allowed)
				(vias allowed)
				(pads allowed)
				(copperpour not_allowed)
				(footprints allowed)
			)
			(placement
				(enabled no)
				(sheetname "")
			)
			(fill
				(thermal_gap 0.5)
				(thermal_bridge_width 0.5)
				(island_removal_mode 0)
			)
			(polygon
				(pts
					(arc
						(start 9.994392 -42.810176)
						(mid 12.3063 -42.810176)
						(end 9.994392 -42.810176)
					)
				)
			)
		)
	)
	(footprint ""
		(layer "F.Cu")
		(at 177.649632 -144.87652)
		(property "Reference" "C446"
			(at -5.210302 0.071628 0)
			(unlocked yes)
			(layer "F.SilkS")
			(effects
				(font
					(size 0.7874 0.5842)
					(thickness 0.1524)
				)
				(justify left)
			)
		)
		(property "Value" ""
			(at 0 0 0)
			(layer "F.Fab")
			(effects
				(font
					(size 1.27 1.27)
				)
			)
		)
		(duplicate_pad_numbers_are_jumpers no)
		(fp_line
			(start -1.905 -0.8636)
			(end 1.905 -0.8636)
			(stroke
				(width 0.1524)
				(type default)
			)
			(layer "F.SilkS")
		)
		(fp_line
			(start -1.905 0.8636)
			(end -1.905 -0.8636)
			(stroke
				(width 0.1524)
				(type default)
			)
			(layer "F.SilkS")
		)
		(fp_line
			(start 0 0.8382)
			(end 0 -0.8382)
			(stroke
				(width 0.1524)
				(type default)
			)
			(layer "F.SilkS")
		)
		(fp_line
			(start 1.905 -0.8636)
			(end 1.905 0.8636)
			(stroke
				(width 0.1524)
				(type default)
			)
			(layer "F.SilkS")
		)
		(fp_line
			(start 1.905 0.8636)
			(end -1.905 0.8636)
			(stroke
				(width 0.1524)
				(type default)
			)
			(layer "F.SilkS")
		)
		(fp_rect
			(start -1.524 0.7366)
			(end 1.524 -0.7366)
			(stroke
				(width 0)
				(type default)
			)
			(fill no)
			(layer "F.CrtYd")
		)
		(pad "1" smd rect
			(at 0.94996 0)
			(size 1.1176 1.3716)
			(layers "F.Cu" "F.Mask" "F.Paste")
			(net "P3V3_NODE1")
		)
		(pad "2" smd rect
			(at -0.94996 0)
			(size 1.1176 1.3716)
			(layers "F.Cu" "F.Mask" "F.Paste")
			(net "GND")
		)
	)
	(footprint ""
		(layer "F.Cu")
		(at 19.943826 -100.039678 180)
		(property "Reference" "R1154"
			(at 5.197856 0.42037 0)
			(unlocked yes)
			(layer "F.SilkS")
			(effects
				(font
					(size 0.7874 0.5842)
					(thickness 0.1524)
				)
				(justify left)
			)
		)
		(property "Value" ""
			(at 0 0 180)
			(layer "F.Fab")
			(effects
				(font
					(size 1.27 1.27)
				)
			)
		)
		(duplicate_pad_numbers_are_jumpers no)
		(fp_line
			(start 0.7874 0.4064)
			(end -0.7874 0.4064)
			(stroke
				(width 0.1524)
				(type default)
			)
			(layer "F.SilkS")
		)
		(fp_line
			(start 0.7874 -0.4064)
			(end 0.7874 0.4064)
			(stroke
				(width 0.1524)
				(type default)
			)
			(layer "F.SilkS")
		)
		(fp_line
			(start -0.7874 0.4064)
			(end -0.7874 -0.4064)
			(stroke
				(width 0.1524)
				(type default)
			)
			(layer "F.SilkS")
		)
		(fp_line
			(start -0.7874 -0.4064)
			(end 0.7874 -0.4064)
			(stroke
				(width 0.1524)
				(type default)
			)
			(layer "F.SilkS")
		)
		(fp_poly
			(pts
				(xy -0.508 0.2794) (xy -0.508 0.2286) (xy -0.635 0.2286) (xy -0.635 -0.254) (xy -0.5334 -0.254)
				(xy -0.5334 -0.2794) (xy 0.5334 -0.2794) (xy 0.5334 -0.254) (xy 0.635 -0.254) (xy 0.635 0.254) (xy 0.5334 0.254)
				(xy 0.5334 0.2794)
			)
			(stroke
				(width 0)
				(type default)
			)
			(fill no)
			(layer "F.CrtYd")
		)
		(pad "1" smd rect
			(at 0.40005 0 180)
			(size 0.4572 0.508)
			(layers "F.Cu" "F.Mask" "F.Paste")
			(net "GND")
		)
		(pad "2" smd rect
			(at -0.40005 0 180)
			(size 0.4572 0.508)
			(layers "F.Cu" "F.Mask" "F.Paste")
			(net "FRU_SYS_A2")
		)
	)
	(footprint ""
		(layer "F.Cu")
		(at 62.563502 -160.320736 -90)
		(property "Reference" "R1107"
			(at 4.581398 0.477774 90)
			(unlocked yes)
			(layer "F.SilkS")
			(effects
				(font
					(size 0.7874 0.5842)
					(thickness 0.1524)
				)
				(justify left)
			)
		)
		(property "Value" ""
			(at 0 0 270)
			(layer "F.Fab")
			(effects
				(font
					(size 1.27 1.27)
				)
			)
		)
		(duplicate_pad_numbers_are_jumpers no)
		(fp_line
			(start -0.7874 0.4064)
			(end -0.7874 -0.4064)
			(stroke
				(width 0.1524)
				(type default)
			)
			(layer "F.SilkS")
		)
		(fp_line
			(start 0.7874 0.4064)
			(end -0.7874 0.4064)
			(stroke
				(width 0.1524)
				(type default)
			)
			(layer "F.SilkS")
		)
		(fp_line
			(start -0.7874 -0.4064)
			(end 0.7874 -0.4064)
			(stroke
				(width 0.1524)
				(type default)
			)
			(layer "F.SilkS")
		)
		(fp_line
			(start 0.7874 -0.4064)
			(end 0.7874 0.4064)
			(stroke
				(width 0.1524)
				(type default)
			)
			(layer "F.SilkS")
		)
		(fp_poly
			(pts
				(xy -0.508 0.2794) (xy -0.508 0.2286) (xy -0.635 0.2286) (xy -0.635 -0.254) (xy -0.5334 -0.254)
				(xy -0.5334 -0.2794) (xy 0.5334 -0.2794) (xy 0.5334 -0.254) (xy 0.635 -0.254) (xy 0.635 0.254) (xy 0.5334 0.254)
				(xy 0.5334 0.2794)
			)
			(stroke
				(width 0)
				(type default)
			)
			(fill no)
			(layer "F.CrtYd")
		)
		(pad "1" smd rect
			(at 0.40005 0 270)
			(size 0.4572 0.508)
			(layers "F.Cu" "F.Mask" "F.Paste")
			(net "P12V_AUX")
		)
		(pad "2" smd rect
			(at -0.40005 0 270)
			(size 0.4572 0.508)
			(layers "F.Cu" "F.Mask" "F.Paste")
			(net "FM_CPLD_NODE1_P5V_EN_LV")
		)
	)
	(footprint ""
		(layer "F.Cu")
		(at 53.679598 -108.655866 90)
		(property "Reference" "PL2"
			(at 4.206748 -1.133094 0)
			(unlocked yes)
			(layer "F.SilkS")
			(effects
				(font
					(size 0.7874 0.5842)
					(thickness 0.1524)
				)
				(justify left)
			)
		)
		(property "Value" ""
			(at 0 0 90)
			(layer "F.Fab")
			(effects
				(font
					(size 1.27 1.27)
				)
			)
		)
		(duplicate_pad_numbers_are_jumpers no)
		(fp_line
			(start 3.350006 -4.1656)
			(end 3.350006 4.1656)
			(stroke
				(width 0.1524)
				(type default)
			)
			(layer "F.SilkS")
		)
		(fp_line
			(start -3.350006 -4.1656)
			(end 3.350006 -4.1656)
			(stroke
				(width 0.1524)
				(type default)
			)
			(layer "F.SilkS")
		)
		(fp_line
			(start 3.350006 4.1656)
			(end -3.350006 4.1656)
			(stroke
				(width 0.1524)
				(type default)
			)
			(layer "F.SilkS")
		)
		(fp_line
			(start -3.350006 4.1656)
			(end -3.350006 -4.1656)
			(stroke
				(width 0.1524)
				(type default)
			)
			(layer "F.SilkS")
		)
		(fp_poly
			(pts
				(xy -3.350006 -3.64998) (xy -1.7018 -3.64998) (xy -1.7018 -4.05257) (xy 1.7018 -4.05257) (xy 1.7018 -3.64998)
				(xy 3.350006 -3.64998) (xy 3.350006 3.64998) (xy 1.7018 3.64998) (xy 1.7018 4.05257) (xy -1.7018 4.05257)
				(xy -1.7018 3.64998) (xy -3.350006 3.64998)
			)
			(stroke
				(width 0)
				(type default)
			)
			(fill no)
			(layer "F.CrtYd")
		)
		(fp_line
			(start 3.350006 -3.64998)
			(end 3.350006 3.64998)
			(stroke
				(width 0.1)
				(type default)
			)
			(layer "F.Fab")
		)
		(fp_line
			(start -3.350006 -3.64998)
			(end 3.350006 -3.64998)
			(stroke
				(width 0.1)
				(type default)
			)
			(layer "F.Fab")
		)
		(fp_line
			(start 3.350006 3.64998)
			(end -3.350006 3.64998)
			(stroke
				(width 0.1)
				(type default)
			)
			(layer "F.Fab")
		)
		(fp_line
			(start -3.350006 3.64998)
			(end -3.350006 -3.64998)
			(stroke
				(width 0.1)
				(type default)
			)
			(layer "F.Fab")
		)
		(pad "1" smd rect
			(at 0 -2.92481)
			(size 2.15392 3.302)
			(layers "F.Cu" "F.Mask" "F.Paste")
			(net "SW_P3V3_STB_NODE1_PH")
		)
		(pad "2" smd rect
			(at 0 2.92481)
			(size 2.15392 3.302)
			(layers "F.Cu" "F.Mask" "F.Paste")
			(net "P3V3_STB_NODE1")
		)
	)
	(footprint ""
		(layer "F.Cu")
		(at 134.01167 -38.63975 -90)
		(property "Reference" "U43"
			(at -10.673334 -1.474216 0)
			(unlocked yes)
			(layer "F.SilkS")
			(effects
				(font
					(size 0.7874 0.5842)
					(thickness 0.1524)
				)
				(justify left)
			)
		)
		(property "Value" ""
			(at 0 0 270)
			(layer "F.Fab")
			(effects
				(font
					(size 1.27 1.27)
				)
			)
		)
		(duplicate_pad_numbers_are_jumpers no)
		(fp_line
			(start -5.7277 12.60983)
			(end -5.7277 14.13383)
			(stroke
				(width 0.1524)
				(type default)
			)
			(layer "F.SilkS")
		)
		(fp_line
			(start -3.2258 12.5984)
			(end -3.2258 13.3604)
			(stroke
				(width 0.1524)
				(type default)
			)
			(layer "F.SilkS")
		)
		(fp_line
			(start -0.7112 12.5984)
			(end -0.7112 14.1224)
			(stroke
				(width 0.1524)
				(type default)
			)
			(layer "F.SilkS")
		)
		(fp_line
			(start -7.050024 10.050018)
			(end -7.050024 -10.050018)
			(stroke
				(width 0.1524)
				(type default)
			)
			(layer "F.SilkS")
		)
		(fp_line
			(start 7.050024 10.050018)
			(end -7.050024 10.050018)
			(stroke
				(width 0.1524)
				(type default)
			)
			(layer "F.SilkS")
		)
		(fp_line
			(start 9.6012 9.29513)
			(end 10.3632 9.29513)
			(stroke
				(width 0.1524)
				(type default)
			)
			(layer "F.SilkS")
		)
		(fp_line
			(start -9.6012 7.7978)
			(end -10.3632 7.7978)
			(stroke
				(width 0.1524)
				(type default)
			)
			(layer "F.SilkS")
		)
		(fp_line
			(start 9.6012 6.8072)
			(end 11.1252 6.8072)
			(stroke
				(width 0.1524)
				(type default)
			)
			(layer "F.SilkS")
		)
		(fp_line
			(start -9.6012 5.2832)
			(end -11.1252 5.2832)
			(stroke
				(width 0.1524)
				(type default)
			)
			(layer "F.SilkS")
		)
		(fp_line
			(start 9.6012 4.318)
			(end 10.3632 4.318)
			(stroke
				(width 0.1524)
				(type default)
			)
			(layer "F.SilkS")
		)
		(fp_line
			(start -9.6012 2.794)
			(end -10.3632 2.794)
			(stroke
				(width 0.1524)
				(type default)
			)
			(layer "F.SilkS")
		)
		(fp_line
			(start 9.6012 1.8034)
			(end 11.1252 1.8034)
			(stroke
				(width 0.1524)
				(type default)
			)
			(layer "F.SilkS")
		)
		(fp_line
			(start -9.6012 0.2794)
			(end -11.1252 0.2794)
			(stroke
				(width 0.1524)
				(type default)
			)
			(layer "F.SilkS")
		)
		(fp_line
			(start 9.6012 -0.6858)
			(end 10.3632 -0.6858)
			(stroke
				(width 0.1524)
				(type default)
			)
			(layer "F.SilkS")
		)
		(fp_line
			(start -9.6012 -2.2098)
			(end -10.3632 -2.2098)
			(stroke
				(width 0.1524)
				(type default)
			)
			(layer "F.SilkS")
		)
		(fp_line
			(start 9.6012 -3.2004)
			(end 11.1252 -3.2004)
			(stroke
				(width 0.1524)
				(type default)
			)
			(layer "F.SilkS")
		)
		(fp_line
			(start -9.6266 -4.7244)
			(end -11.1506 -4.7244)
			(stroke
				(width 0.1524)
				(type default)
			)
			(layer "F.SilkS")
		)
		(fp_line
			(start 9.6266 -5.6896)
			(end 10.3886 -5.6896)
			(stroke
				(width 0.1524)
				(type default)
			)
			(layer "F.SilkS")
		)
		(fp_line
			(start -9.6266 -7.2136)
			(end -10.3886 -7.2136)
			(stroke
				(width 0.1524)
				(type default)
			)
			(layer "F.SilkS")
		)
		(fp_line
			(start 9.652 -8.255)
			(end 11.176 -8.255)
			(stroke
				(width 0.1524)
				(type default)
			)
			(layer "F.SilkS")
		)
		(fp_line
			(start -7.050024 -10.050018)
			(end 7.050024 -10.050018)
			(stroke
				(width 0.1524)
				(type default)
			)
			(layer "F.SilkS")
		)
		(fp_line
			(start 7.050024 -10.050018)
			(end 7.050024 10.050018)
			(stroke
				(width 0.1524)
				(type default)
			)
			(layer "F.SilkS")
		)
		(fp_line
			(start 0.254 -12.573)
			(end 0.254 -13.335)
			(stroke
				(width 0.1524)
				(type default)
			)
			(layer "F.SilkS")
		)
		(fp_line
			(start -4.7752 -12.5984)
			(end -4.7752 -13.3604)
			(stroke
				(width 0.1524)
				(type default)
			)
			(layer "F.SilkS")
		)
		(fp_line
			(start -2.286 -12.5984)
			(end -2.286 -14.1224)
			(stroke
				(width 0.1524)
				(type default)
			)
			(layer "F.SilkS")
		)
		(fp_line
			(start 2.6924 -12.5984)
			(end 2.6924 -14.1224)
			(stroke
				(width 0.1524)
				(type default)
			)
			(layer "F.SilkS")
		)
		(fp_line
			(start 5.1943 -12.61237)
			(end 5.1943 -13.37437)
			(stroke
				(width 0.1524)
				(type default)
			)
			(layer "F.SilkS")
		)
		(fp_poly
			(pts
				(xy -7.050024 10.050018) (xy -6.4008 10.050018) (xy -6.4008 12.4714) (xy 6.4008 12.4714) (xy 6.4008 10.050018)
				(xy 7.050024 10.050018) (xy 7.050024 9.398) (xy 9.4742 9.398) (xy 9.4742 -9.398) (xy 7.050024 -9.398)
				(xy 7.050024 -10.050018) (xy 6.4008 -10.050018) (xy 6.4008 -12.4714) (xy -6.4008 -12.4714) (xy -6.4008 -10.050018)
				(xy -7.050024 -10.050018) (xy -7.050024 -9.398) (xy -9.4742 -9.398) (xy -9.4742 9.398) (xy -7.050024 9.398)
			)
			(stroke
				(width 0)
				(type default)
			)
			(fill no)
			(layer "F.CrtYd")
		)
		(fp_text user "64"
			(at 6.97865 11.411204 0)
			(unlocked yes)
			(layer "F.SilkS")
			(effects
				(font
					(size 0.635 0.4064)
					(thickness 0.1524)
				)
				(justify left)
			)
		)
		(fp_text user "39"
			(at -6.93801 11.221212 0)
			(unlocked yes)
			(layer "F.SilkS")
			(effects
				(font
					(size 0.635 0.4064)
					(thickness 0.1524)
				)
				(justify left)
			)
		)
		(fp_text user "65"
			(at 8.664702 10.628122 0)
			(unlocked yes)
			(layer "F.SilkS")
			(effects
				(font
					(size 0.635 0.4064)
					(thickness 0.1524)
				)
				(justify left)
			)
		)
		(fp_text user "38"
			(at -8.89127 10.530332 0)
			(unlocked yes)
			(layer "F.SilkS")
			(effects
				(font
					(size 0.635 0.4064)
					(thickness 0.1524)
				)
				(justify left)
			)
		)
		(fp_text user "1"
			(at -8.836152 -9.563354 0)
			(unlocked yes)
			(layer "F.SilkS")
			(effects
				(font
					(size 0.635 0.4064)
					(thickness 0.1524)
				)
				(justify left)
			)
		)
		(fp_text user "102"
			(at 8.650478 -9.581896 0)
			(unlocked yes)
			(layer "F.SilkS")
			(effects
				(font
					(size 0.635 0.4064)
					(thickness 0.1524)
				)
				(justify left)
			)
		)
		(fp_text user "103"
			(at 7.010654 -10.576814 0)
			(unlocked yes)
			(layer "F.SilkS")
			(effects
				(font
					(size 0.635 0.4064)
					(thickness 0.1524)
				)
				(justify left)
			)
		)
		(fp_text user "128"
			(at -6.919722 -10.687304 0)
			(unlocked yes)
			(layer "F.SilkS")
			(effects
				(font
					(size 0.635 0.4064)
					(thickness 0.1524)
				)
				(justify left)
			)
		)
		(pad "1" smd rect
			(at -8.560054 -9.249918 180)
			(size 0.2794 1.8034)
			(layers "F.Cu" "F.Mask" "F.Paste")
			(net "UART_DTR_P2_N")
		)
		(pad "2" smd rect
			(at -8.560054 -8.750046 180)
			(size 0.2794 1.8034)
			(layers "F.Cu" "F.Mask" "F.Paste")
			(net "UART_RTS_P2_N")
		)
		(pad "3" smd rect
			(at -8.560054 -8.24992 180)
			(size 0.2794 1.8034)
			(layers "F.Cu" "F.Mask" "F.Paste")
			(net "UART_DSR_P2_N")
		)
		(pad "4" smd rect
			(at -8.560054 -7.750048 180)
			(size 0.2794 1.8034)
			(layers "F.Cu" "F.Mask" "F.Paste")
			(net "P5V_NODE1")
		)
		(pad "5" smd rect
			(at -8.560054 -7.249922 180)
			(size 0.2794 1.8034)
			(layers "F.Cu" "F.Mask" "F.Paste")
			(net "UART_TX_P2")
		)
		(pad "6" smd rect
			(at -8.560054 -6.75005 180)
			(size 0.2794 1.8034)
			(layers "F.Cu" "F.Mask" "F.Paste")
			(net "UART_RX_P2")
		)
		(pad "7" smd rect
			(at -8.560054 -6.249924 180)
			(size 0.2794 1.8034)
			(layers "F.Cu" "F.Mask" "F.Paste")
			(net "Net_1829")
		)
		(pad "8" smd rect
			(at -8.560054 -5.750052 180)
			(size 0.2794 1.8034)
			(layers "F.Cu" "F.Mask" "F.Paste")
			(net "Net_1827")
		)
		(pad "9" smd rect
			(at -8.560054 -5.249926 180)
			(size 0.2794 1.8034)
			(layers "F.Cu" "F.Mask" "F.Paste")
			(net "Net_1830")
		)
		(pad "10" smd rect
			(at -8.560054 -4.750054 180)
			(size 0.2794 1.8034)
			(layers "F.Cu" "F.Mask" "F.Paste")
			(net "Net_1828")
		)
		(pad "11" smd rect
			(at -8.560054 -4.249928 180)
			(size 0.2794 1.8034)
			(layers "F.Cu" "F.Mask" "F.Paste")
			(net "UART_DCD_P3_N")
		)
		(pad "12" smd rect
			(at -8.560054 -3.750056 180)
			(size 0.2794 1.8034)
			(layers "F.Cu" "F.Mask" "F.Paste")
			(net "UART_RI_P3_N")
		)
		(pad "13" smd rect
			(at -8.560054 -3.24993 180)
			(size 0.2794 1.8034)
			(layers "F.Cu" "F.Mask" "F.Paste")
			(net "UART_CTS_P3_N")
		)
		(pad "14" smd rect
			(at -8.560054 -2.750058 180)
			(size 0.2794 1.8034)
			(layers "F.Cu" "F.Mask" "F.Paste")
			(net "UART_DTR_P3_R_N")
		)
		(pad "15" smd rect
			(at -8.560054 -2.249932 180)
			(size 0.2794 1.8034)
			(layers "F.Cu" "F.Mask" "F.Paste")
			(net "GND")
		)
		(pad "16" smd rect
			(at -8.560054 -1.75006 180)
			(size 0.2794 1.8034)
			(layers "F.Cu" "F.Mask" "F.Paste")
			(net "UART_RTS_P3_R_N")
		)
		(pad "17" smd rect
			(at -8.560054 -1.249934 180)
			(size 0.2794 1.8034)
			(layers "F.Cu" "F.Mask" "F.Paste")
			(net "UART_DSR_P3_N")
		)
		(pad "18" smd rect
			(at -8.560054 -0.750062 180)
			(size 0.2794 1.8034)
			(layers "F.Cu" "F.Mask" "F.Paste")
			(net "UART_TX_P3_R")
		)
		(pad "19" smd rect
			(at -8.560054 -0.249936 180)
			(size 0.2794 1.8034)
			(layers "F.Cu" "F.Mask" "F.Paste")
			(net "UART_RX_P3")
		)
		(pad "20" smd rect
			(at -8.560054 0.249936 180)
			(size 0.2794 1.8034)
			(layers "F.Cu" "F.Mask" "F.Paste")
			(net "UART_DCD_P4_N")
		)
		(pad "21" smd rect
			(at -8.560054 0.750062 180)
			(size 0.2794 1.8034)
			(layers "F.Cu" "F.Mask" "F.Paste")
			(net "UART_RI_P4_R_N")
		)
		(pad "22" smd rect
			(at -8.560054 1.249934 180)
			(size 0.2794 1.8034)
			(layers "F.Cu" "F.Mask" "F.Paste")
			(net "UART_CTS_P4_N")
		)
		(pad "23" smd rect
			(at -8.560054 1.75006 180)
			(size 0.2794 1.8034)
			(layers "F.Cu" "F.Mask" "F.Paste")
			(net "UART_DTR_P4_R_N")
		)
		(pad "24" smd rect
			(at -8.560054 2.249932 180)
			(size 0.2794 1.8034)
			(layers "F.Cu" "F.Mask" "F.Paste")
			(net "Net_1835")
		)
		(pad "25" smd rect
			(at -8.560054 2.750058 180)
			(size 0.2794 1.8034)
			(layers "F.Cu" "F.Mask" "F.Paste")
			(net "Net_1834")
		)
		(pad "26" smd rect
			(at -8.560054 3.24993 180)
			(size 0.2794 1.8034)
			(layers "F.Cu" "F.Mask" "F.Paste")
			(net "UART_RTS_P4_R_N")
		)
		(pad "27" smd rect
			(at -8.560054 3.750056 180)
			(size 0.2794 1.8034)
			(layers "F.Cu" "F.Mask" "F.Paste")
			(net "UART_DSR_P4_N")
		)
		(pad "28" smd rect
			(at -8.560054 4.249928 180)
			(size 0.2794 1.8034)
			(layers "F.Cu" "F.Mask" "F.Paste")
			(net "UART_TX_P4_R")
		)
		(pad "29" smd rect
			(at -8.560054 4.750054 180)
			(size 0.2794 1.8034)
			(layers "F.Cu" "F.Mask" "F.Paste")
			(net "UART_DTR_P6_N")
		)
		(pad "30" smd rect
			(at -8.560054 5.249926 180)
			(size 0.2794 1.8034)
			(layers "F.Cu" "F.Mask" "F.Paste")
			(net "Net_1824")
		)
		(pad "31" smd rect
			(at -8.560054 5.750052 180)
			(size 0.2794 1.8034)
			(layers "F.Cu" "F.Mask" "F.Paste")
			(net "UART_RX_P4_BUF")
		)
		(pad "32" smd rect
			(at -8.560054 6.249924 180)
			(size 0.2794 1.8034)
			(layers "F.Cu" "F.Mask" "F.Paste")
			(net "UART_CTS_P5_N")
		)
		(pad "33" smd rect
			(at -8.560054 6.75005 180)
			(size 0.2794 1.8034)
			(layers "F.Cu" "F.Mask" "F.Paste")
			(net "UART_DTR_P5_N")
		)
		(pad "34" smd rect
			(at -8.560054 7.249922 180)
			(size 0.2794 1.8034)
			(layers "F.Cu" "F.Mask" "F.Paste")
			(net "UART_RTS_P5_N")
		)
		(pad "35" smd rect
			(at -8.560054 7.750048 180)
			(size 0.2794 1.8034)
			(layers "F.Cu" "F.Mask" "F.Paste")
			(net "P5V_NODE1")
		)
		(pad "36" smd rect
			(at -8.560054 8.24992 180)
			(size 0.2794 1.8034)
			(layers "F.Cu" "F.Mask" "F.Paste")
			(net "UART_DSR_P5_N")
		)
		(pad "37" smd rect
			(at -8.560054 8.750046 180)
			(size 0.2794 1.8034)
			(layers "F.Cu" "F.Mask" "F.Paste")
			(net "SIO_LRESET_N")
		)
		(pad "38" smd rect
			(at -8.560054 9.249918 180)
			(size 0.2794 1.8034)
			(layers "F.Cu" "F.Mask" "F.Paste")
			(net "SIO_PIN38")
		)
		(pad "39" smd rect
			(at -6.249924 11.560048 270)
			(size 0.2794 1.8034)
			(layers "F.Cu" "F.Mask" "F.Paste")
			(net "IRQ_CPU_NODE1_SERIAL_SIO")
		)
		(pad "40" smd rect
			(at -5.750052 11.560048 270)
			(size 0.2794 1.8034)
			(layers "F.Cu" "F.Mask" "F.Paste")
			(net "LPC_CPU_NODE1_FRAME_SIO_L")
		)
		(pad "41" smd rect
			(at -5.249926 11.560048 270)
			(size 0.2794 1.8034)
			(layers "F.Cu" "F.Mask" "F.Paste")
			(net "LPC_CPU_NODE1_LAD0_SIO")
		)
		(pad "42" smd rect
			(at -4.750054 11.560048 270)
			(size 0.2794 1.8034)
			(layers "F.Cu" "F.Mask" "F.Paste")
			(net "LPC_CPU_NODE1_LAD1_SIO")
		)
		(pad "43" smd rect
			(at -4.249928 11.560048 270)
			(size 0.2794 1.8034)
			(layers "F.Cu" "F.Mask" "F.Paste")
			(net "LPC_CPU_NODE1_LAD2_SIO")
		)
		(pad "44" smd rect
			(at -3.750056 11.560048 270)
			(size 0.2794 1.8034)
			(layers "F.Cu" "F.Mask" "F.Paste")
			(net "LPC_CPU_NODE1_LAD3_SIO")
		)
		(pad "45" smd rect
			(at -3.24993 11.560048 270)
			(size 0.2794 1.8034)
			(layers "F.Cu" "F.Mask" "F.Paste")
			(net "SIO_PIN45")
		)
		(pad "46" smd rect
			(at -2.750058 11.560048 270)
			(size 0.2794 1.8034)
			(layers "F.Cu" "F.Mask" "F.Paste")
			(net "Net_576")
		)
		(pad "47" smd rect
			(at -2.249932 11.560048 270)
			(size 0.2794 1.8034)
			(layers "F.Cu" "F.Mask" "F.Paste")
			(net "SIO_PCICLK33")
		)
		(pad "48" smd rect
			(at -1.75006 11.560048 270)
			(size 0.2794 1.8034)
			(layers "F.Cu" "F.Mask" "F.Paste")
			(net "UART_RX_P5")
		)
		(pad "49" smd rect
			(at -1.249934 11.560048 270)
			(size 0.2794 1.8034)
			(layers "F.Cu" "F.Mask" "F.Paste")
			(net "SIO_CLKIN")
		)
		(pad "50" smd rect
			(at -0.750062 11.560048 270)
			(size 0.2794 1.8034)
			(layers "F.Cu" "F.Mask" "F.Paste")
			(net "GND")
		)
		(pad "51" smd rect
			(at -0.249936 11.560048 270)
			(size 0.2794 1.8034)
			(layers "F.Cu" "F.Mask" "F.Paste")
			(net "SIO_PWROK2")
		)
		(pad "52" smd rect
			(at 0.249936 11.560048 270)
			(size 0.2794 1.8034)
			(layers "F.Cu" "F.Mask" "F.Paste")
			(net "SIO_JTAG_CPLD3_TCK_R")
		)
		(pad "53" smd rect
			(at 0.750062 11.560048 270)
			(size 0.2794 1.8034)
			(layers "F.Cu" "F.Mask" "F.Paste")
			(net "Net_1838")
		)
		(pad "54" smd rect
			(at 1.249934 11.560048 270)
			(size 0.2794 1.8034)
			(layers "F.Cu" "F.Mask" "F.Paste")
			(net "SIO_JTAG_CPLD3_TDO")
		)
		(pad "55" smd rect
			(at 1.75006 11.560048 270)
			(size 0.2794 1.8034)
			(layers "F.Cu" "F.Mask" "F.Paste")
			(net "Net_327")
		)
		(pad "56" smd rect
			(at 2.249932 11.560048 270)
			(size 0.2794 1.8034)
			(layers "F.Cu" "F.Mask" "F.Paste")
			(net "SIO_JTAG_CPLD3_TMS_R")
		)
		(pad "57" smd rect
			(at 2.750058 11.560048 270)
			(size 0.2794 1.8034)
			(layers "F.Cu" "F.Mask" "F.Paste")
			(net "SIO_JTAG_CPLD3_TDI_R")
		)
		(pad "58" smd rect
			(at 3.24993 11.560048 270)
			(size 0.2794 1.8034)
			(layers "F.Cu" "F.Mask" "F.Paste")
			(net "SIO_JTAG_CPLD1_TCK_R")
		)
		(pad "59" smd rect
			(at 3.750056 11.560048 270)
			(size 0.2794 1.8034)
			(layers "F.Cu" "F.Mask" "F.Paste")
			(net "SIO_JTAG_CPLD1_TDI_R")
		)
		(pad "60" smd rect
			(at 4.249928 11.560048 270)
			(size 0.2794 1.8034)
			(layers "F.Cu" "F.Mask" "F.Paste")
			(net "Net_57")
		)
		(pad "61" smd rect
			(at 4.750054 11.560048 270)
			(size 0.2794 1.8034)
			(layers "F.Cu" "F.Mask" "F.Paste")
			(net "SIO_JTAG_CPLD1_TMS_R")
		)
		(pad "62" smd rect
			(at 5.249926 11.560048 270)
			(size 0.2794 1.8034)
			(layers "F.Cu" "F.Mask" "F.Paste")
			(net "Net_1842")
		)
		(pad "63" smd rect
			(at 5.750052 11.560048 270)
			(size 0.2794 1.8034)
			(layers "F.Cu" "F.Mask" "F.Paste")
			(net "Net_1831")
		)
		(pad "64" smd rect
			(at 6.249924 11.560048 270)
			(size 0.2794 1.8034)
			(layers "F.Cu" "F.Mask" "F.Paste")
			(net "Net_1847")
		)
		(pad "65" smd rect
			(at 8.560054 9.249918 180)
			(size 0.2794 1.8034)
			(layers "F.Cu" "F.Mask" "F.Paste")
			(net "Net_1825")
		)
		(pad "66" smd rect
			(at 8.560054 8.750046 180)
			(size 0.2794 1.8034)
			(layers "F.Cu" "F.Mask" "F.Paste")
			(net "UART_TX_P5")
		)
		(pad "67" smd rect
			(at 8.560054 8.24992 180)
			(size 0.2794 1.8034)
			(layers "F.Cu" "F.Mask" "F.Paste")
			(net "SIO_VCCH")
		)
		(pad "68" smd rect
			(at 8.560054 7.750048 180)
			(size 0.2794 1.8034)
			(layers "F.Cu" "F.Mask" "F.Paste")
			(net "SIO_COPEN_N")
		)
		(pad "69" smd rect
			(at 8.560054 7.249922 180)
			(size 0.2794 1.8034)
			(layers "F.Cu" "F.Mask" "F.Paste")
			(net "SIO_VBAT")
		)
		(pad "70" smd rect
			(at 8.560054 6.75005 180)
			(size 0.2794 1.8034)
			(layers "F.Cu" "F.Mask" "F.Paste")
			(net "UART_RI_P5_N")
		)
		(pad "71" smd rect
			(at 8.560054 6.249924 180)
			(size 0.2794 1.8034)
			(layers "F.Cu" "F.Mask" "F.Paste")
			(net "SIO_GPIO47")
		)
		(pad "72" smd rect
			(at 8.560054 5.750052 180)
			(size 0.2794 1.8034)
			(layers "F.Cu" "F.Mask" "F.Paste")
			(net "SIO_PIN72")
		)
		(pad "73" smd rect
			(at 8.560054 5.249926 180)
			(size 0.2794 1.8034)
			(layers "F.Cu" "F.Mask" "F.Paste")
			(net "SIO_PIN73")
		)
		(pad "74" smd rect
			(at 8.560054 4.750054 180)
			(size 0.2794 1.8034)
			(layers "F.Cu" "F.Mask" "F.Paste")
			(net "GND")
		)
		(pad "75" smd rect
			(at 8.560054 4.249928 180)
			(size 0.2794 1.8034)
			(layers "F.Cu" "F.Mask" "F.Paste")
			(net "SIO_PIN75")
		)
		(pad "76" smd rect
			(at 8.560054 3.750056 180)
			(size 0.2794 1.8034)
			(layers "F.Cu" "F.Mask" "F.Paste")
			(net "SIO_PIN76")
		)
		(pad "77" smd rect
			(at 8.560054 3.24993 180)
			(size 0.2794 1.8034)
			(layers "F.Cu" "F.Mask" "F.Paste")
			(net "UART_TX_P6")
		)
		(pad "78" smd rect
			(at 8.560054 2.750058 180)
			(size 0.2794 1.8034)
			(layers "F.Cu" "F.Mask" "F.Paste")
			(net "SIO_PIN78")
		)
		(pad "79" smd rect
			(at 8.560054 2.249932 180)
			(size 0.2794 1.8034)
			(layers "F.Cu" "F.Mask" "F.Paste")
			(net "Net_326")
		)
		(pad "80" smd rect
			(at 8.560054 1.75006 180)
			(size 0.2794 1.8034)
			(layers "F.Cu" "F.Mask" "F.Paste")
			(net "SIO_PIN80")
		)
		(pad "81" smd rect
			(at 8.560054 1.249934 180)
			(size 0.2794 1.8034)
			(layers "F.Cu" "F.Mask" "F.Paste")
			(net "SIO_PIN81")
		)
		(pad "82" smd rect
			(at 8.560054 0.750062 180)
			(size 0.2794 1.8034)
			(layers "F.Cu" "F.Mask" "F.Paste")
			(net "SIO_PIN82")
		)
		(pad "83" smd rect
			(at 8.560054 0.249936 180)
			(size 0.2794 1.8034)
			(layers "F.Cu" "F.Mask" "F.Paste")
			(net "SIO_PIN83")
		)
		(pad "84" smd rect
			(at 8.560054 -0.249936 180)
			(size 0.2794 1.8034)
			(layers "F.Cu" "F.Mask" "F.Paste")
			(net "Net_325")
		)
		(pad "85" smd rect
			(at 8.560054 -0.750062 180)
			(size 0.2794 1.8034)
			(layers "F.Cu" "F.Mask" "F.Paste")
			(net "UART_RTS_P6_N")
		)
		(pad "86" smd rect
			(at 8.560054 -1.249934 180)
			(size 0.2794 1.8034)
			(layers "F.Cu" "F.Mask" "F.Paste")
			(net "GNDA")
		)
		(pad "87" smd rect
			(at 8.560054 -1.75006 180)
			(size 0.2794 1.8034)
			(layers "F.Cu" "F.Mask" "F.Paste")
			(net "UART_RI_P6_N")
		)
		(pad "88" smd rect
			(at 8.560054 -2.249932 180)
			(size 0.2794 1.8034)
			(layers "F.Cu" "F.Mask" "F.Paste")
			(net "Net_1841")
		)
		(pad "89" smd rect
			(at 8.560054 -2.750058 180)
			(size 0.2794 1.8034)
			(layers "F.Cu" "F.Mask" "F.Paste")
			(net "Net_1840")
		)
		(pad "90" smd rect
			(at 8.560054 -3.24993 180)
			(size 0.2794 1.8034)
			(layers "F.Cu" "F.Mask" "F.Paste")
			(net "SIO_VREF")
		)
		(pad "91" smd rect
			(at 8.560054 -3.750056 180)
			(size 0.2794 1.8034)
			(layers "F.Cu" "F.Mask" "F.Paste")
			(net "SIO_JTAG_CPLD1_TDO")
		)
		(pad "92" smd rect
			(at 8.560054 -4.249928 180)
			(size 0.2794 1.8034)
			(layers "F.Cu" "F.Mask" "F.Paste")
			(net "UART_CTS_P6_N")
		)
		(pad "93" smd rect
			(at 8.560054 -4.750054 180)
			(size 0.2794 1.8034)
			(layers "F.Cu" "F.Mask" "F.Paste")
			(net "UART_RX_P6")
		)
		(pad "94" smd rect
			(at 8.560054 -5.249926 180)
			(size 0.2794 1.8034)
			(layers "F.Cu" "F.Mask" "F.Paste")
			(net "Net_1846")
		)
		(pad "95" smd rect
			(at 8.560054 -5.750052 180)
			(size 0.2794 1.8034)
			(layers "F.Cu" "F.Mask" "F.Paste")
			(net "UART_DSR_P6_N")
		)
		(pad "96" smd rect
			(at 8.560054 -6.249924 180)
			(size 0.2794 1.8034)
			(layers "F.Cu" "F.Mask" "F.Paste")
			(net "Net_1845")
		)
		(pad "97" smd rect
			(at 8.560054 -6.75005 180)
			(size 0.2794 1.8034)
			(layers "F.Cu" "F.Mask" "F.Paste")
			(net "Net_1844")
		)
		(pad "98" smd rect
			(at 8.560054 -7.249922 180)
			(size 0.2794 1.8034)
			(layers "F.Cu" "F.Mask" "F.Paste")
			(net "Net_1843")
		)
		(pad "99" smd rect
			(at 8.560054 -7.750048 180)
			(size 0.2794 1.8034)
			(layers "F.Cu" "F.Mask" "F.Paste")
			(net "SIO_AVCC")
		)
		(pad "100" smd rect
			(at 8.560054 -8.24992 180)
			(size 0.2794 1.8034)
			(layers "F.Cu" "F.Mask" "F.Paste")
			(net "Net_1836")
		)
		(pad "101" smd rect
			(at 8.560054 -8.750046 180)
			(size 0.2794 1.8034)
			(layers "F.Cu" "F.Mask" "F.Paste")
			(net "Net_1833")
		)
		(pad "102" smd rect
			(at 8.560054 -9.249918 180)
			(size 0.2794 1.8034)
			(layers "F.Cu" "F.Mask" "F.Paste")
			(net "Net_1823")
		)
		(pad "103" smd rect
			(at 6.249924 -11.560048 270)
			(size 0.2794 1.8034)
			(layers "F.Cu" "F.Mask" "F.Paste")
			(net "Net_1821")
		)
		(pad "104" smd rect
			(at 5.750052 -11.560048 270)
			(size 0.2794 1.8034)
			(layers "F.Cu" "F.Mask" "F.Paste")
			(net "Net_1837")
		)
		(pad "105" smd rect
			(at 5.249926 -11.560048 270)
			(size 0.2794 1.8034)
			(layers "F.Cu" "F.Mask" "F.Paste")
			(net "Net_1832")
		)
		(pad "106" smd rect
			(at 4.750054 -11.560048 270)
			(size 0.2794 1.8034)
			(layers "F.Cu" "F.Mask" "F.Paste")
			(net "Net_1826")
		)
		(pad "107" smd rect
			(at 4.249928 -11.560048 270)
			(size 0.2794 1.8034)
			(layers "F.Cu" "F.Mask" "F.Paste")
			(net "Net_1822")
		)
		(pad "108" smd rect
			(at 3.750056 -11.560048 270)
			(size 0.2794 1.8034)
			(layers "F.Cu" "F.Mask" "F.Paste")
			(net "Net_1839")
		)
		(pad "109" smd rect
			(at 3.24993 -11.560048 270)
			(size 0.2794 1.8034)
			(layers "F.Cu" "F.Mask" "F.Paste")
			(net "SIO_CPLD_RSV3_R")
		)
		(pad "110" smd rect
			(at 2.750058 -11.560048 270)
			(size 0.2794 1.8034)
			(layers "F.Cu" "F.Mask" "F.Paste")
			(net "SIO_CPLD_RSV2_R")
		)
		(pad "111" smd rect
			(at 2.249932 -11.560048 270)
			(size 0.2794 1.8034)
			(layers "F.Cu" "F.Mask" "F.Paste")
			(net "SIO_CPLD_RSV1_R")
		)
		(pad "112" smd rect
			(at 1.75006 -11.560048 270)
			(size 0.2794 1.8034)
			(layers "F.Cu" "F.Mask" "F.Paste")
			(net "CPLD_WDT3_R")
		)
		(pad "113" smd rect
			(at 1.249934 -11.560048 270)
			(size 0.2794 1.8034)
			(layers "F.Cu" "F.Mask" "F.Paste")
			(net "SIO_JTAG_CPLD2_TDI_R")
		)
		(pad "114" smd rect
			(at 0.750062 -11.560048 270)
			(size 0.2794 1.8034)
			(layers "F.Cu" "F.Mask" "F.Paste")
			(net "SIO_JTAG_CPLD2_TMS_R")
		)
		(pad "115" smd rect
			(at 0.249936 -11.560048 270)
			(size 0.2794 1.8034)
			(layers "F.Cu" "F.Mask" "F.Paste")
			(net "SIO_JTAG_CPLD2_TDO")
		)
		(pad "116" smd rect
			(at -0.249936 -11.560048 270)
			(size 0.2794 1.8034)
			(layers "F.Cu" "F.Mask" "F.Paste")
			(net "SIO_JTAG_CPLD2_TCK_R")
		)
		(pad "117" smd rect
			(at -0.750062 -11.560048 270)
			(size 0.2794 1.8034)
			(layers "F.Cu" "F.Mask" "F.Paste")
			(net "GND")
		)
		(pad "118" smd rect
			(at -1.249934 -11.560048 270)
			(size 0.2794 1.8034)
			(layers "F.Cu" "F.Mask" "F.Paste")
			(net "Net_512")
		)
		(pad "119" smd rect
			(at -1.75006 -11.560048 270)
			(size 0.2794 1.8034)
			(layers "F.Cu" "F.Mask" "F.Paste")
			(net "UART_RI_P1_N")
		)
		(pad "120" smd rect
			(at -2.249932 -11.560048 270)
			(size 0.2794 1.8034)
			(layers "F.Cu" "F.Mask" "F.Paste")
			(net "UART_CTS_P1_N")
		)
		(pad "121" smd rect
			(at -2.750058 -11.560048 270)
			(size 0.2794 1.8034)
			(layers "F.Cu" "F.Mask" "F.Paste")
			(net "UART_DTR_P1_N")
		)
		(pad "122" smd rect
			(at -3.24993 -11.560048 270)
			(size 0.2794 1.8034)
			(layers "F.Cu" "F.Mask" "F.Paste")
			(net "UART_RTS_P1_N")
		)
		(pad "123" smd rect
			(at -3.750056 -11.560048 270)
			(size 0.2794 1.8034)
			(layers "F.Cu" "F.Mask" "F.Paste")
			(net "UART_DSR_P1_N")
		)
		(pad "124" smd rect
			(at -4.249928 -11.560048 270)
			(size 0.2794 1.8034)
			(layers "F.Cu" "F.Mask" "F.Paste")
			(net "UART_TX_P1")
		)
		(pad "125" smd rect
			(at -4.750054 -11.560048 270)
			(size 0.2794 1.8034)
			(layers "F.Cu" "F.Mask" "F.Paste")
			(net "UART_RX_P1")
		)
		(pad "126" smd rect
			(at -5.249926 -11.560048 270)
			(size 0.2794 1.8034)
			(layers "F.Cu" "F.Mask" "F.Paste")
			(net "Net_513")
		)
		(pad "127" smd rect
			(at -5.750052 -11.560048 270)
			(size 0.2794 1.8034)
			(layers "F.Cu" "F.Mask" "F.Paste")
			(net "UART_RI_P2_N")
		)
		(pad "128" smd rect
			(at -6.249924 -11.560048 270)
			(size 0.2794 1.8034)
			(layers "F.Cu" "F.Mask" "F.Paste")
			(net "UART_CTS_P2_N")
		)
	)
	(footprint ""
		(layer "F.Cu")
		(at 64.622172 -154.448002)
		(property "Reference" "PC5"
			(at -32.154368 -5.388864 0)
			(unlocked yes)
			(layer "F.SilkS")
			(effects
				(font
					(size 0.7874 0.5842)
					(thickness 0.1524)
				)
				(justify left)
			)
		)
		(property "Value" ""
			(at 0 0 0)
			(layer "F.Fab")
			(effects
				(font
					(size 1.27 1.27)
				)
			)
		)
		(duplicate_pad_numbers_are_jumpers no)
		(fp_line
			(start -1.905 -0.8636)
			(end 1.905 -0.8636)
			(stroke
				(width 0.1524)
				(type default)
			)
			(layer "F.SilkS")
		)
		(fp_line
			(start -1.905 0.8636)
			(end -1.905 -0.8636)
			(stroke
				(width 0.1524)
				(type default)
			)
			(layer "F.SilkS")
		)
		(fp_line
			(start 0 0.8382)
			(end 0 -0.8382)
			(stroke
				(width 0.1524)
				(type default)
			)
			(layer "F.SilkS")
		)
		(fp_line
			(start 1.905 -0.8636)
			(end 1.905 0.8636)
			(stroke
				(width 0.1524)
				(type default)
			)
			(layer "F.SilkS")
		)
		(fp_line
			(start 1.905 0.8636)
			(end -1.905 0.8636)
			(stroke
				(width 0.1524)
				(type default)
			)
			(layer "F.SilkS")
		)
		(fp_rect
			(start -1.524 0.7366)
			(end 1.524 -0.7366)
			(stroke
				(width 0)
				(type default)
			)
			(fill no)
			(layer "F.CrtYd")
		)
		(pad "1" smd rect
			(at 0.94996 0)
			(size 1.1176 1.3716)
			(layers "F.Cu" "F.Mask" "F.Paste")
			(net "P5V_STB_NODE1")
		)
		(pad "2" smd rect
			(at -0.94996 0)
			(size 1.1176 1.3716)
			(layers "F.Cu" "F.Mask" "F.Paste")
			(net "GND")
		)
	)
	(footprint ""
		(layer "F.Cu")
		(at 141.00556 -114.383058 90)
		(property "Reference" "R21"
			(at -1.995678 3.165856 90)
			(unlocked yes)
			(layer "F.SilkS")
			(effects
				(font
					(size 0.7874 0.5842)
					(thickness 0.1524)
				)
				(justify left)
			)
		)
		(property "Value" ""
			(at 0 0 90)
			(layer "F.Fab")
			(effects
				(font
					(size 1.27 1.27)
				)
			)
		)
		(duplicate_pad_numbers_are_jumpers no)
		(fp_line
			(start 0.7874 -0.4064)
			(end 0.7874 0.4064)
			(stroke
				(width 0.1524)
				(type default)
			)
			(layer "F.SilkS")
		)
		(fp_line
			(start -0.7874 -0.4064)
			(end 0.7874 -0.4064)
			(stroke
				(width 0.1524)
				(type default)
			)
			(layer "F.SilkS")
		)
		(fp_line
			(start 0.7874 0.4064)
			(end -0.7874 0.4064)
			(stroke
				(width 0.1524)
				(type default)
			)
			(layer "F.SilkS")
		)
		(fp_line
			(start -0.7874 0.4064)
			(end -0.7874 -0.4064)
			(stroke
				(width 0.1524)
				(type default)
			)
			(layer "F.SilkS")
		)
		(fp_poly
			(pts
				(xy -0.508 0.2794) (xy -0.508 0.2286) (xy -0.635 0.2286) (xy -0.635 -0.254) (xy -0.5334 -0.254)
				(xy -0.5334 -0.2794) (xy 0.5334 -0.2794) (xy 0.5334 -0.254) (xy 0.635 -0.254) (xy 0.635 0.254) (xy 0.5334 0.254)
				(xy 0.5334 0.2794)
			)
			(stroke
				(width 0)
				(type default)
			)
			(fill no)
			(layer "F.CrtYd")
		)
		(pad "1" smd rect
			(at 0.40005 0 90)
			(size 0.4572 0.508)
			(layers "F.Cu" "F.Mask" "F.Paste")
			(net "CLKREQC_NODE1_N")
		)
		(pad "2" smd rect
			(at -0.40005 0 90)
			(size 0.4572 0.508)
			(layers "F.Cu" "F.Mask" "F.Paste")
			(net "P3V3_CLK_NODE1")
		)
	)
	(footprint ""
		(layer "F.Cu")
		(at 176.1236 -192.582292 -90)
		(property "Reference" ""
			(at 0 0 270)
			(layer "F.SilkS")
			(hide yes)
			(effects
				(font
					(size 1.27 1.27)
				)
			)
		)
		(property "Value" ""
			(at 0 0 270)
			(layer "F.Fab")
			(effects
				(font
					(size 1.27 1.27)
				)
			)
		)
		(duplicate_pad_numbers_are_jumpers no)
		(fp_poly
			(pts
				(arc
					(start 0 -1.4986)
					(mid 0 1.4986)
					(end 0 -1.4986)
				)
			)
			(stroke
				(width 0)
				(type default)
			)
			(fill no)
			(layer "F.CrtYd")
		)
		(pad "1" smd circle
			(at 0 0 270)
			(size 0.9906 0.9906)
			(layers "F.Cu" "F.Mask" "F.Paste")
			(net "Net_37")
		)
		(zone
			(layer "F.Cu")
			(hatch none 0.5)
			(connect_pads
				(clearance 0)
			)
			(min_thickness 0.25)
			(keepout
				(tracks not_allowed)
				(vias allowed)
				(pads allowed)
				(copperpour not_allowed)
				(footprints allowed)
			)
			(placement
				(enabled no)
				(sheetname "")
			)
			(fill
				(thermal_gap 0.5)
				(thermal_bridge_width 0.5)
				(island_removal_mode 0)
			)
			(polygon
				(pts
					(arc
						(start 177.7492 -192.582292)
						(mid 174.498 -192.582292)
						(end 177.7492 -192.582292)
					)
				)
			)
		)
	)
	(footprint ""
		(layer "F.Cu")
		(at 80.6831 -82.902044 180)
		(property "Reference" "R170"
			(at -0.219964 -16.94815 0)
			(unlocked yes)
			(layer "F.SilkS")
			(effects
				(font
					(size 0.7874 0.5842)
					(thickness 0.1524)
				)
				(justify left)
			)
		)
		(property "Value" ""
			(at 0 0 180)
			(layer "F.Fab")
			(effects
				(font
					(size 1.27 1.27)
				)
			)
		)
		(duplicate_pad_numbers_are_jumpers no)
		(fp_line
			(start 0.7874 0.4064)
			(end -0.7874 0.4064)
			(stroke
				(width 0.1524)
				(type default)
			)
			(layer "F.SilkS")
		)
		(fp_line
			(start 0.7874 -0.4064)
			(end 0.7874 0.4064)
			(stroke
				(width 0.1524)
				(type default)
			)
			(layer "F.SilkS")
		)
		(fp_line
			(start -0.7874 0.4064)
			(end -0.7874 -0.4064)
			(stroke
				(width 0.1524)
				(type default)
			)
			(layer "F.SilkS")
		)
		(fp_line
			(start -0.7874 -0.4064)
			(end 0.7874 -0.4064)
			(stroke
				(width 0.1524)
				(type default)
			)
			(layer "F.SilkS")
		)
		(fp_poly
			(pts
				(xy -0.508 0.2794) (xy -0.508 0.2286) (xy -0.635 0.2286) (xy -0.635 -0.254) (xy -0.5334 -0.254)
				(xy -0.5334 -0.2794) (xy 0.5334 -0.2794) (xy 0.5334 -0.254) (xy 0.635 -0.254) (xy 0.635 0.254) (xy 0.5334 0.254)
				(xy 0.5334 0.2794)
			)
			(stroke
				(width 0)
				(type default)
			)
			(fill no)
			(layer "F.CrtYd")
		)
		(pad "1" smd rect
			(at 0.40005 0 180)
			(size 0.4572 0.508)
			(layers "F.Cu" "F.Mask" "F.Paste")
			(net "LPC_CPU_NODE1_CLK0_DS")
		)
		(pad "2" smd rect
			(at -0.40005 0 180)
			(size 0.4572 0.508)
			(layers "F.Cu" "F.Mask" "F.Paste")
			(net "GND")
		)
	)
	(footprint ""
		(layer "F.Cu")
		(at 103.481124 -140.818108)
		(property "Reference" "PC97"
			(at -1.865122 -4.26085 0)
			(unlocked yes)
			(layer "F.SilkS")
			(effects
				(font
					(size 0.635 0.4064)
					(thickness 0.1524)
				)
				(justify left)
			)
		)
		(property "Value" ""
			(at 0 0 0)
			(layer "F.Fab")
			(effects
				(font
					(size 1.27 1.27)
				)
			)
		)
		(duplicate_pad_numbers_are_jumpers no)
		(fp_line
			(start -0.7874 -0.4064)
			(end 0.7874 -0.4064)
			(stroke
				(width 0.1524)
				(type default)
			)
			(layer "F.SilkS")
		)
		(fp_line
			(start -0.7874 0.4064)
			(end -0.7874 -0.4064)
			(stroke
				(width 0.1524)
				(type default)
			)
			(layer "F.SilkS")
		)
		(fp_line
			(start 0 0.381)
			(end 0 -0.381)
			(stroke
				(width 0.1524)
				(type default)
			)
			(layer "F.SilkS")
		)
		(fp_line
			(start 0.7874 -0.4064)
			(end 0.7874 0.4064)
			(stroke
				(width 0.1524)
				(type default)
			)
			(layer "F.SilkS")
		)
		(fp_line
			(start 0.7874 0.4064)
			(end -0.7874 0.4064)
			(stroke
				(width 0.1524)
				(type default)
			)
			(layer "F.SilkS")
		)
		(fp_poly
			(pts
				(xy -0.5334 0.254) (xy -0.635 0.254) (xy -0.635 0.2286) (xy -0.635 -0.254) (xy -0.5334 -0.254) (xy -0.5334 -0.2794)
				(xy 0.5334 -0.2794) (xy 0.5334 -0.254) (xy 0.635 -0.254) (xy 0.635 0.254) (xy 0.5334 0.254) (xy 0.5334 0.2794)
				(xy -0.508 0.2794) (xy -0.5334 0.2794)
			)
			(stroke
				(width 0)
				(type default)
			)
			(fill no)
			(layer "F.CrtYd")
		)
		(pad "1" smd rect
			(at 0.40005 0)
			(size 0.4572 0.508)
			(layers "F.Cu" "F.Mask" "F.Paste")
			(net "AGND_PVCCP_NODE1")
		)
		(pad "2" smd rect
			(at -0.40005 0)
			(size 0.4572 0.508)
			(layers "F.Cu" "F.Mask" "F.Paste")
			(net "P1V05_NODE1")
		)
	)
	(footprint ""
		(layer "F.Cu")
		(at 91.102434 -187.842398 180)
		(property "Reference" "C681"
			(at 1.437894 7.294372 0)
			(unlocked yes)
			(layer "F.SilkS")
			(effects
				(font
					(size 0.7874 0.5842)
					(thickness 0.1524)
				)
				(justify left)
			)
		)
		(property "Value" ""
			(at 0 0 180)
			(layer "F.Fab")
			(effects
				(font
					(size 1.27 1.27)
				)
			)
		)
		(duplicate_pad_numbers_are_jumpers no)
		(fp_line
			(start 0.7874 0.4064)
			(end -0.7874 0.4064)
			(stroke
				(width 0.1524)
				(type default)
			)
			(layer "F.SilkS")
		)
		(fp_line
			(start 0.7874 -0.4064)
			(end 0.7874 0.4064)
			(stroke
				(width 0.1524)
				(type default)
			)
			(layer "F.SilkS")
		)
		(fp_line
			(start 0 0.381)
			(end 0 -0.381)
			(stroke
				(width 0.1524)
				(type default)
			)
			(layer "F.SilkS")
		)
		(fp_line
			(start -0.7874 0.4064)
			(end -0.7874 -0.4064)
			(stroke
				(width 0.1524)
				(type default)
			)
			(layer "F.SilkS")
		)
		(fp_line
			(start -0.7874 -0.4064)
			(end 0.7874 -0.4064)
			(stroke
				(width 0.1524)
				(type default)
			)
			(layer "F.SilkS")
		)
		(fp_poly
			(pts
				(xy -0.5334 0.254) (xy -0.635 0.254) (xy -0.635 0.2286) (xy -0.635 -0.254) (xy -0.5334 -0.254) (xy -0.5334 -0.2794)
				(xy 0.5334 -0.2794) (xy 0.5334 -0.254) (xy 0.635 -0.254) (xy 0.635 0.254) (xy 0.5334 0.254) (xy 0.5334 0.2794)
				(xy -0.508 0.2794) (xy -0.5334 0.2794)
			)
			(stroke
				(width 0)
				(type default)
			)
			(fill no)
			(layer "F.CrtYd")
		)
		(pad "1" smd rect
			(at 0.40005 0 180)
			(size 0.4572 0.508)
			(layers "F.Cu" "F.Mask" "F.Paste")
			(net "UART_T5_NODE2_TXD_R")
		)
		(pad "2" smd rect
			(at -0.40005 0 180)
			(size 0.4572 0.508)
			(layers "F.Cu" "F.Mask" "F.Paste")
			(net "GND")
		)
	)
	(footprint ""
		(layer "F.Cu")
		(at 29.50591 -143.697706 90)
		(property "Reference" "C429"
			(at 0.004826 1.406144 90)
			(unlocked yes)
			(layer "F.SilkS")
			(effects
				(font
					(size 0.7874 0.5842)
					(thickness 0.1524)
				)
			)
		)
		(property "Value" ""
			(at 0 0 90)
			(layer "F.Fab")
			(effects
				(font
					(size 1.27 1.27)
				)
			)
		)
		(duplicate_pad_numbers_are_jumpers no)
		(fp_line
			(start 1.2954 -0.5842)
			(end 1.2954 0.5842)
			(stroke
				(width 0.1524)
				(type default)
			)
			(layer "F.SilkS")
		)
		(fp_line
			(start 0 -0.5842)
			(end 0 0.5842)
			(stroke
				(width 0.1524)
				(type default)
			)
			(layer "F.SilkS")
		)
		(fp_line
			(start -1.2954 -0.5842)
			(end 1.2954 -0.5842)
			(stroke
				(width 0.1524)
				(type default)
			)
			(layer "F.SilkS")
		)
		(fp_line
			(start 1.2954 0.5842)
			(end -1.2954 0.5842)
			(stroke
				(width 0.1524)
				(type default)
			)
			(layer "F.SilkS")
		)
		(fp_line
			(start -1.2954 0.5842)
			(end -1.2954 -0.5842)
			(stroke
				(width 0.1524)
				(type default)
			)
			(layer "F.SilkS")
		)
		(fp_poly
			(pts
				(xy 0.8636 -0.4572) (xy 0.8636 -0.3556) (xy 1.143 -0.3556) (xy 1.143 0.3556) (xy 0.8636 0.3556)
				(xy 0.8636 0.4572) (xy -0.8636 0.4572) (xy -0.8636 0.3556) (xy -1.143 0.3556) (xy -1.143 -0.3556)
				(xy -0.8636 -0.3556) (xy -0.8636 -0.4572)
			)
			(stroke
				(width 0)
				(type default)
			)
			(fill no)
			(layer "F.CrtYd")
		)
		(fp_line
			(start 0.884936 -0.504952)
			(end 0.884936 0.504952)
			(stroke
				(width 0.1)
				(type default)
			)
			(layer "F.Fab")
		)
		(fp_line
			(start -0.884936 -0.504952)
			(end 0.884936 -0.504952)
			(stroke
				(width 0.1)
				(type default)
			)
			(layer "F.Fab")
		)
		(fp_line
			(start 0.884936 0.504952)
			(end -0.884936 0.504952)
			(stroke
				(width 0.1)
				(type default)
			)
			(layer "F.Fab")
		)
		(fp_line
			(start -0.884936 0.504952)
			(end -0.884936 -0.504952)
			(stroke
				(width 0.1)
				(type default)
			)
			(layer "F.Fab")
		)
		(pad "1" smd rect
			(at 0.7366 0 180)
			(size 0.7112 0.8128)
			(layers "F.Cu" "F.Mask" "F.Paste")
			(net "LAN1_CTRL_P1V9_R")
		)
		(pad "2" smd rect
			(at -0.7366 0 180)
			(size 0.7112 0.8128)
			(layers "F.Cu" "F.Mask" "F.Paste")
			(net "P1V9_LAN1")
		)
	)
	(footprint ""
		(layer "F.Cu")
		(at 6.64083 -138.632184 -90)
		(property "Reference" "R1311"
			(at 4.294632 4.254246 90)
			(unlocked yes)
			(layer "F.SilkS")
			(effects
				(font
					(size 0.7874 0.5842)
					(thickness 0.1524)
				)
				(justify left)
			)
		)
		(property "Value" ""
			(at 0 0 270)
			(layer "F.Fab")
			(effects
				(font
					(size 1.27 1.27)
				)
			)
		)
		(duplicate_pad_numbers_are_jumpers no)
		(fp_line
			(start -0.7874 0.4064)
			(end -0.7874 -0.4064)
			(stroke
				(width 0.1524)
				(type default)
			)
			(layer "F.SilkS")
		)
		(fp_line
			(start 0.7874 0.4064)
			(end -0.7874 0.4064)
			(stroke
				(width 0.1524)
				(type default)
			)
			(layer "F.SilkS")
		)
		(fp_line
			(start -0.7874 -0.4064)
			(end 0.7874 -0.4064)
			(stroke
				(width 0.1524)
				(type default)
			)
			(layer "F.SilkS")
		)
		(fp_line
			(start 0.7874 -0.4064)
			(end 0.7874 0.4064)
			(stroke
				(width 0.1524)
				(type default)
			)
			(layer "F.SilkS")
		)
		(fp_poly
			(pts
				(xy -0.508 0.2794) (xy -0.508 0.2286) (xy -0.635 0.2286) (xy -0.635 -0.254) (xy -0.5334 -0.254)
				(xy -0.5334 -0.2794) (xy 0.5334 -0.2794) (xy 0.5334 -0.254) (xy 0.635 -0.254) (xy 0.635 0.254) (xy 0.5334 0.254)
				(xy 0.5334 0.2794)
			)
			(stroke
				(width 0)
				(type default)
			)
			(fill no)
			(layer "F.CrtYd")
		)
		(pad "1" smd rect
			(at 0.40005 0 270)
			(size 0.4572 0.508)
			(layers "F.Cu" "F.Mask" "F.Paste")
			(net "P3V3_NODE1")
		)
		(pad "2" smd rect
			(at -0.40005 0 270)
			(size 0.4572 0.508)
			(layers "F.Cu" "F.Mask" "F.Paste")
			(net "UART_RI_P6_LS_N")
		)
	)
	(footprint ""
		(layer "F.Cu")
		(at 11.576812 -11.613896 -90)
		(property "Reference" "R218"
			(at 0.984758 4.672076 90)
			(unlocked yes)
			(layer "F.SilkS")
			(effects
				(font
					(size 0.7874 0.5842)
					(thickness 0.1524)
				)
				(justify left)
			)
		)
		(property "Value" ""
			(at 0 0 270)
			(layer "F.Fab")
			(effects
				(font
					(size 1.27 1.27)
				)
			)
		)
		(duplicate_pad_numbers_are_jumpers no)
		(fp_line
			(start -0.7874 0.4064)
			(end -0.7874 -0.4064)
			(stroke
				(width 0.1524)
				(type default)
			)
			(layer "F.SilkS")
		)
		(fp_line
			(start 0.7874 0.4064)
			(end -0.7874 0.4064)
			(stroke
				(width 0.1524)
				(type default)
			)
			(layer "F.SilkS")
		)
		(fp_line
			(start -0.7874 -0.4064)
			(end 0.7874 -0.4064)
			(stroke
				(width 0.1524)
				(type default)
			)
			(layer "F.SilkS")
		)
		(fp_line
			(start 0.7874 -0.4064)
			(end 0.7874 0.4064)
			(stroke
				(width 0.1524)
				(type default)
			)
			(layer "F.SilkS")
		)
		(fp_poly
			(pts
				(xy -0.508 0.2794) (xy -0.508 0.2286) (xy -0.635 0.2286) (xy -0.635 -0.254) (xy -0.5334 -0.254)
				(xy -0.5334 -0.2794) (xy 0.5334 -0.2794) (xy 0.5334 -0.254) (xy 0.635 -0.254) (xy 0.635 0.254) (xy 0.5334 0.254)
				(xy 0.5334 0.2794)
			)
			(stroke
				(width 0)
				(type default)
			)
			(fill no)
			(layer "F.CrtYd")
		)
		(pad "1" smd rect
			(at 0.40005 0 270)
			(size 0.4572 0.508)
			(layers "F.Cu" "F.Mask" "F.Paste")
			(net "PV_VDDR_NODE1_VREF_R")
		)
		(pad "2" smd rect
			(at -0.40005 0 270)
			(size 0.4572 0.508)
			(layers "F.Cu" "F.Mask" "F.Paste")
			(net "GND")
		)
	)
	(footprint ""
		(layer "F.Cu")
		(at 179.415694 -134.42442 -90)
		(property "Reference" "Q25"
			(at 2.223262 -14.328902 90)
			(unlocked yes)
			(layer "F.SilkS")
			(effects
				(font
					(size 0.7874 0.5842)
					(thickness 0.1524)
				)
				(justify left)
			)
		)
		(property "Value" ""
			(at 0 0 270)
			(layer "F.Fab")
			(effects
				(font
					(size 1.27 1.27)
				)
			)
		)
		(duplicate_pad_numbers_are_jumpers no)
		(fp_line
			(start -0.5842 2.48412)
			(end -0.5842 -0.5842)
			(stroke
				(width 0.1524)
				(type default)
			)
			(layer "F.SilkS")
		)
		(fp_line
			(start 2.584196 2.48412)
			(end -0.5842 2.48412)
			(stroke
				(width 0.1524)
				(type default)
			)
			(layer "F.SilkS")
		)
		(fp_line
			(start -0.5842 -0.5842)
			(end 2.584196 -0.5842)
			(stroke
				(width 0.1524)
				(type default)
			)
			(layer "F.SilkS")
		)
		(fp_line
			(start 2.584196 -0.5842)
			(end 2.584196 2.48412)
			(stroke
				(width 0.1524)
				(type default)
			)
			(layer "F.SilkS")
		)
		(fp_poly
			(pts
				(xy -0.508 -0.4572) (xy 0.299974 -0.4572) (xy 0.299974 -0.54991) (xy 1.700022 -0.54991) (xy 1.700022 0.49276)
				(xy 2.507996 0.49276) (xy 2.507996 1.40716) (xy 1.700022 1.40716) (xy 1.700022 2.450084) (xy 0.299974 2.450084)
				(xy 0.299974 2.35712) (xy -0.508 2.35712)
			)
			(stroke
				(width 0)
				(type default)
			)
			(fill no)
			(layer "F.CrtYd")
		)
		(fp_line
			(start 0.299974 2.450084)
			(end 0.299974 -0.54991)
			(stroke
				(width 0.1)
				(type default)
			)
			(layer "F.Fab")
		)
		(fp_line
			(start 1.700022 2.450084)
			(end 0.299974 2.450084)
			(stroke
				(width 0.1)
				(type default)
			)
			(layer "F.Fab")
		)
		(fp_line
			(start 0.299974 -0.54991)
			(end 1.700022 -0.54991)
			(stroke
				(width 0.1)
				(type default)
			)
			(layer "F.Fab")
		)
		(fp_line
			(start 1.700022 -0.54991)
			(end 1.700022 2.450084)
			(stroke
				(width 0.1)
				(type default)
			)
			(layer "F.Fab")
		)
		(fp_text user "E"
			(at -1.159764 1.751838 90)
			(unlocked yes)
			(layer "F.SilkS")
			(effects
				(font
					(size 0.635 0.4064)
					(thickness 0.1524)
				)
				(justify left)
			)
		)
		(fp_text user "C"
			(at 3.179572 0.787146 90)
			(unlocked yes)
			(layer "F.SilkS")
			(effects
				(font
					(size 0.635 0.4064)
					(thickness 0.1524)
				)
				(justify left)
			)
		)
		(fp_text user "B"
			(at -1.59258 -0.594614 0)
			(unlocked yes)
			(layer "F.SilkS")
			(effects
				(font
					(size 0.635 0.4064)
					(thickness 0.1524)
				)
				(justify left)
			)
		)
		(fp_text user "E"
			(at -1.5748 1.95707 270)
			(unlocked yes)
			(layer "F.Fab")
			(effects
				(font
					(size 0.7874 0.5842)
					(thickness 0.000001)
				)
				(justify left)
			)
		)
		(fp_text user "C"
			(at 2.8702 0.99187 270)
			(unlocked yes)
			(layer "F.Fab")
			(effects
				(font
					(size 0.7874 0.5842)
					(thickness 0.000001)
				)
				(justify left)
			)
		)
		(fp_text user "B"
			(at -1.5494 0.00127 270)
			(unlocked yes)
			(layer "F.Fab")
			(effects
				(font
					(size 0.7874 0.5842)
					(thickness 0.000001)
				)
				(justify left)
			)
		)
		(pad "B" smd rect
			(at 0 0)
			(size 0.8128 0.9144)
			(layers "F.Cu" "F.Mask" "F.Paste")
			(net "FM_CPLD_NODE1_WDT_R")
		)
		(pad "C" smd rect
			(at 1.999996 0.94996)
			(size 0.8128 0.9144)
			(layers "F.Cu" "F.Mask" "F.Paste")
			(net "FM_CPLD_NODE1_WDT")
		)
		(pad "E" smd rect
			(at 0 1.89992)
			(size 0.8128 0.9144)
			(layers "F.Cu" "F.Mask" "F.Paste")
			(net "FM_CPU_NODE1_OWDTOUT")
		)
	)
	(footprint ""
		(layer "F.Cu")
		(at 157.58668 -102.121208 180)
		(property "Reference" "C363"
			(at 1.524 -2.075688 0)
			(unlocked yes)
			(layer "F.SilkS")
			(effects
				(font
					(size 0.7874 0.5842)
					(thickness 0.1524)
				)
				(justify left)
			)
		)
		(property "Value" ""
			(at 0 0 180)
			(layer "F.Fab")
			(effects
				(font
					(size 1.27 1.27)
				)
			)
		)
		(duplicate_pad_numbers_are_jumpers no)
		(fp_line
			(start 0.7874 0.4064)
			(end -0.7874 0.4064)
			(stroke
				(width 0.1524)
				(type default)
			)
			(layer "F.SilkS")
		)
		(fp_line
			(start 0.7874 -0.4064)
			(end 0.7874 0.4064)
			(stroke
				(width 0.1524)
				(type default)
			)
			(layer "F.SilkS")
		)
		(fp_line
			(start 0 0.381)
			(end 0 -0.381)
			(stroke
				(width 0.1524)
				(type default)
			)
			(layer "F.SilkS")
		)
		(fp_line
			(start -0.7874 0.4064)
			(end -0.7874 -0.4064)
			(stroke
				(width 0.1524)
				(type default)
			)
			(layer "F.SilkS")
		)
		(fp_line
			(start -0.7874 -0.4064)
			(end 0.7874 -0.4064)
			(stroke
				(width 0.1524)
				(type default)
			)
			(layer "F.SilkS")
		)
		(fp_poly
			(pts
				(xy -0.5334 0.254) (xy -0.635 0.254) (xy -0.635 0.2286) (xy -0.635 -0.254) (xy -0.5334 -0.254) (xy -0.5334 -0.2794)
				(xy 0.5334 -0.2794) (xy 0.5334 -0.254) (xy 0.635 -0.254) (xy 0.635 0.254) (xy 0.5334 0.254) (xy 0.5334 0.2794)
				(xy -0.508 0.2794) (xy -0.5334 0.2794)
			)
			(stroke
				(width 0)
				(type default)
			)
			(fill no)
			(layer "F.CrtYd")
		)
		(pad "1" smd rect
			(at 0.40005 0 180)
			(size 0.4572 0.508)
			(layers "F.Cu" "F.Mask" "F.Paste")
			(net "P2E_CPU_USB_NODE1_RX_DP")
		)
		(pad "2" smd rect
			(at -0.40005 0 180)
			(size 0.4572 0.508)
			(layers "F.Cu" "F.Mask" "F.Paste")
			(net "P2E_CPU_USB_NODE1_RX_C_DP")
		)
	)
	(footprint ""
		(layer "F.Cu")
		(at 148.261578 -57.249822 -90)
		(property "Reference" "R514"
			(at -14.50213 -26.0858 90)
			(unlocked yes)
			(layer "F.SilkS")
			(effects
				(font
					(size 0.7874 0.5842)
					(thickness 0.1524)
				)
				(justify left)
			)
		)
		(property "Value" ""
			(at 0 0 270)
			(layer "F.Fab")
			(effects
				(font
					(size 1.27 1.27)
				)
			)
		)
		(duplicate_pad_numbers_are_jumpers no)
		(fp_line
			(start -0.7874 0.4064)
			(end -0.7874 -0.4064)
			(stroke
				(width 0.1524)
				(type default)
			)
			(layer "F.SilkS")
		)
		(fp_line
			(start 0.7874 0.4064)
			(end -0.7874 0.4064)
			(stroke
				(width 0.1524)
				(type default)
			)
			(layer "F.SilkS")
		)
		(fp_line
			(start -0.7874 -0.4064)
			(end 0.7874 -0.4064)
			(stroke
				(width 0.1524)
				(type default)
			)
			(layer "F.SilkS")
		)
		(fp_line
			(start 0.7874 -0.4064)
			(end 0.7874 0.4064)
			(stroke
				(width 0.1524)
				(type default)
			)
			(layer "F.SilkS")
		)
		(fp_poly
			(pts
				(xy -0.508 0.2794) (xy -0.508 0.2286) (xy -0.635 0.2286) (xy -0.635 -0.254) (xy -0.5334 -0.254)
				(xy -0.5334 -0.2794) (xy 0.5334 -0.2794) (xy 0.5334 -0.254) (xy 0.635 -0.254) (xy 0.635 0.254) (xy 0.5334 0.254)
				(xy 0.5334 0.2794)
			)
			(stroke
				(width 0)
				(type default)
			)
			(fill no)
			(layer "F.CrtYd")
		)
		(pad "1" smd rect
			(at 0.40005 0 270)
			(size 0.4572 0.508)
			(layers "F.Cu" "F.Mask" "F.Paste")
			(net "P3V3_NODE1")
		)
		(pad "2" smd rect
			(at -0.40005 0 270)
			(size 0.4572 0.508)
			(layers "F.Cu" "F.Mask" "F.Paste")
			(net "SATA_NODE1_GPIO3")
		)
	)
	(footprint ""
		(layer "F.Cu")
		(at 142.22476 -185.205624 -90)
		(property "Reference" "R1002"
			(at -4.768088 0.535432 90)
			(unlocked yes)
			(layer "F.SilkS")
			(effects
				(font
					(size 0.7874 0.5842)
					(thickness 0.1524)
				)
				(justify left)
			)
		)
		(property "Value" ""
			(at 0 0 270)
			(layer "F.Fab")
			(effects
				(font
					(size 1.27 1.27)
				)
			)
		)
		(duplicate_pad_numbers_are_jumpers no)
		(fp_line
			(start -0.7874 0.4064)
			(end -0.7874 -0.4064)
			(stroke
				(width 0.1524)
				(type default)
			)
			(layer "F.SilkS")
		)
		(fp_line
			(start 0.7874 0.4064)
			(end -0.7874 0.4064)
			(stroke
				(width 0.1524)
				(type default)
			)
			(layer "F.SilkS")
		)
		(fp_line
			(start -0.7874 -0.4064)
			(end 0.7874 -0.4064)
			(stroke
				(width 0.1524)
				(type default)
			)
			(layer "F.SilkS")
		)
		(fp_line
			(start 0.7874 -0.4064)
			(end 0.7874 0.4064)
			(stroke
				(width 0.1524)
				(type default)
			)
			(layer "F.SilkS")
		)
		(fp_poly
			(pts
				(xy -0.508 0.2794) (xy -0.508 0.2286) (xy -0.635 0.2286) (xy -0.635 -0.254) (xy -0.5334 -0.254)
				(xy -0.5334 -0.2794) (xy 0.5334 -0.2794) (xy 0.5334 -0.254) (xy 0.635 -0.254) (xy 0.635 0.254) (xy 0.5334 0.254)
				(xy 0.5334 0.2794)
			)
			(stroke
				(width 0)
				(type default)
			)
			(fill no)
			(layer "F.CrtYd")
		)
		(pad "1" smd rect
			(at 0.40005 0 270)
			(size 0.4572 0.508)
			(layers "F.Cu" "F.Mask" "F.Paste")
			(net "UART_T12_NODE4_TXD")
		)
		(pad "2" smd rect
			(at -0.40005 0 270)
			(size 0.4572 0.508)
			(layers "F.Cu" "F.Mask" "F.Paste")
			(net "UART_T12_NODE4_TXD_R")
		)
	)
	(footprint ""
		(layer "F.Cu")
		(at 106.28376 -188.126624 90)
		(property "Reference" "C699"
			(at 5.151882 0.764794 90)
			(unlocked yes)
			(layer "F.SilkS")
			(effects
				(font
					(size 0.7874 0.5842)
					(thickness 0.1524)
				)
				(justify left)
			)
		)
		(property "Value" ""
			(at 0 0 90)
			(layer "F.Fab")
			(effects
				(font
					(size 1.27 1.27)
				)
			)
		)
		(duplicate_pad_numbers_are_jumpers no)
		(fp_line
			(start 0.7874 -0.4064)
			(end 0.7874 0.4064)
			(stroke
				(width 0.1524)
				(type default)
			)
			(layer "F.SilkS")
		)
		(fp_line
			(start -0.7874 -0.4064)
			(end 0.7874 -0.4064)
			(stroke
				(width 0.1524)
				(type default)
			)
			(layer "F.SilkS")
		)
		(fp_line
			(start 0 0.381)
			(end 0 -0.381)
			(stroke
				(width 0.1524)
				(type default)
			)
			(layer "F.SilkS")
		)
		(fp_line
			(start 0.7874 0.4064)
			(end -0.7874 0.4064)
			(stroke
				(width 0.1524)
				(type default)
			)
			(layer "F.SilkS")
		)
		(fp_line
			(start -0.7874 0.4064)
			(end -0.7874 -0.4064)
			(stroke
				(width 0.1524)
				(type default)
			)
			(layer "F.SilkS")
		)
		(fp_poly
			(pts
				(xy -0.5334 0.254) (xy -0.635 0.254) (xy -0.635 0.2286) (xy -0.635 -0.254) (xy -0.5334 -0.254) (xy -0.5334 -0.2794)
				(xy 0.5334 -0.2794) (xy 0.5334 -0.254) (xy 0.635 -0.254) (xy 0.635 0.254) (xy 0.5334 0.254) (xy 0.5334 0.2794)
				(xy -0.508 0.2794) (xy -0.5334 0.2794)
			)
			(stroke
				(width 0)
				(type default)
			)
			(fill no)
			(layer "F.CrtYd")
		)
		(pad "1" smd rect
			(at 0.40005 0 90)
			(size 0.4572 0.508)
			(layers "F.Cu" "F.Mask" "F.Paste")
			(net "UART_T6_NODE1_TXD_R")
		)
		(pad "2" smd rect
			(at -0.40005 0 90)
			(size 0.4572 0.508)
			(layers "F.Cu" "F.Mask" "F.Paste")
			(net "GND")
		)
	)
	(footprint ""
		(layer "F.Cu")
		(at 79.10576 -188.126624 90)
		(property "Reference" "C667"
			(at 4.548886 -1.622298 90)
			(unlocked yes)
			(layer "F.SilkS")
			(effects
				(font
					(size 0.7874 0.5842)
					(thickness 0.1524)
				)
				(justify left)
			)
		)
		(property "Value" ""
			(at 0 0 90)
			(layer "F.Fab")
			(effects
				(font
					(size 1.27 1.27)
				)
			)
		)
		(duplicate_pad_numbers_are_jumpers no)
		(fp_line
			(start 0.7874 -0.4064)
			(end 0.7874 0.4064)
			(stroke
				(width 0.1524)
				(type default)
			)
			(layer "F.SilkS")
		)
		(fp_line
			(start -0.7874 -0.4064)
			(end 0.7874 -0.4064)
			(stroke
				(width 0.1524)
				(type default)
			)
			(layer "F.SilkS")
		)
		(fp_line
			(start 0 0.381)
			(end 0 -0.381)
			(stroke
				(width 0.1524)
				(type default)
			)
			(layer "F.SilkS")
		)
		(fp_line
			(start 0.7874 0.4064)
			(end -0.7874 0.4064)
			(stroke
				(width 0.1524)
				(type default)
			)
			(layer "F.SilkS")
		)
		(fp_line
			(start -0.7874 0.4064)
			(end -0.7874 -0.4064)
			(stroke
				(width 0.1524)
				(type default)
			)
			(layer "F.SilkS")
		)
		(fp_poly
			(pts
				(xy -0.5334 0.254) (xy -0.635 0.254) (xy -0.635 0.2286) (xy -0.635 -0.254) (xy -0.5334 -0.254) (xy -0.5334 -0.2794)
				(xy 0.5334 -0.2794) (xy 0.5334 -0.254) (xy 0.635 -0.254) (xy 0.635 0.254) (xy 0.5334 0.254) (xy 0.5334 0.2794)
				(xy -0.508 0.2794) (xy -0.5334 0.2794)
			)
			(stroke
				(width 0)
				(type default)
			)
			(fill no)
			(layer "F.CrtYd")
		)
		(pad "1" smd rect
			(at 0.40005 0 90)
			(size 0.4572 0.508)
			(layers "F.Cu" "F.Mask" "F.Paste")
			(net "T4_NODE4_EN_R")
		)
		(pad "2" smd rect
			(at -0.40005 0 90)
			(size 0.4572 0.508)
			(layers "F.Cu" "F.Mask" "F.Paste")
			(net "GND")
		)
	)
	(footprint ""
		(layer "F.Cu")
		(at 66.875406 -4.601464 -90)
		(property "Reference" "PC52"
			(at 1.20396 1.716532 90)
			(unlocked yes)
			(layer "F.SilkS")
			(effects
				(font
					(size 0.7874 0.5842)
					(thickness 0.1524)
				)
				(justify left)
			)
		)
		(property "Value" ""
			(at 0 0 270)
			(layer "F.Fab")
			(effects
				(font
					(size 1.27 1.27)
				)
			)
		)
		(duplicate_pad_numbers_are_jumpers no)
		(fp_line
			(start -0.7874 0.4064)
			(end -0.7874 -0.4064)
			(stroke
				(width 0.1524)
				(type default)
			)
			(layer "F.SilkS")
		)
		(fp_line
			(start 0.7874 0.4064)
			(end -0.7874 0.4064)
			(stroke
				(width 0.1524)
				(type default)
			)
			(layer "F.SilkS")
		)
		(fp_line
			(start 0 0.381)
			(end 0 -0.381)
			(stroke
				(width 0.1524)
				(type default)
			)
			(layer "F.SilkS")
		)
		(fp_line
			(start -0.7874 -0.4064)
			(end 0.7874 -0.4064)
			(stroke
				(width 0.1524)
				(type default)
			)
			(layer "F.SilkS")
		)
		(fp_line
			(start 0.7874 -0.4064)
			(end 0.7874 0.4064)
			(stroke
				(width 0.1524)
				(type default)
			)
			(layer "F.SilkS")
		)
		(fp_poly
			(pts
				(xy -0.5334 0.254) (xy -0.635 0.254) (xy -0.635 0.2286) (xy -0.635 -0.254) (xy -0.5334 -0.254) (xy -0.5334 -0.2794)
				(xy 0.5334 -0.2794) (xy 0.5334 -0.254) (xy 0.635 -0.254) (xy 0.635 0.254) (xy 0.5334 0.254) (xy 0.5334 0.2794)
				(xy -0.508 0.2794) (xy -0.5334 0.2794)
			)
			(stroke
				(width 0)
				(type default)
			)
			(fill no)
			(layer "F.CrtYd")
		)
		(pad "1" smd rect
			(at 0.40005 0 270)
			(size 0.4572 0.508)
			(layers "F.Cu" "F.Mask" "F.Paste")
			(net "GND")
		)
		(pad "2" smd rect
			(at -0.40005 0 270)
			(size 0.4572 0.508)
			(layers "F.Cu" "F.Mask" "F.Paste")
			(net "P3V3_NODE1_SS")
		)
	)
	(footprint ""
		(layer "F.Cu")
		(at 156.445712 -103.99395 -90)
		(property "Reference" "R534"
			(at 0.801878 2.04089 90)
			(unlocked yes)
			(layer "F.SilkS")
			(effects
				(font
					(size 0.7874 0.5842)
					(thickness 0.1524)
				)
				(justify left)
			)
		)
		(property "Value" ""
			(at 0 0 270)
			(layer "F.Fab")
			(effects
				(font
					(size 1.27 1.27)
				)
			)
		)
		(duplicate_pad_numbers_are_jumpers no)
		(fp_line
			(start -0.7874 0.4064)
			(end -0.7874 -0.4064)
			(stroke
				(width 0.1524)
				(type default)
			)
			(layer "F.SilkS")
		)
		(fp_line
			(start 0.7874 0.4064)
			(end -0.7874 0.4064)
			(stroke
				(width 0.1524)
				(type default)
			)
			(layer "F.SilkS")
		)
		(fp_line
			(start -0.7874 -0.4064)
			(end 0.7874 -0.4064)
			(stroke
				(width 0.1524)
				(type default)
			)
			(layer "F.SilkS")
		)
		(fp_line
			(start 0.7874 -0.4064)
			(end 0.7874 0.4064)
			(stroke
				(width 0.1524)
				(type default)
			)
			(layer "F.SilkS")
		)
		(fp_poly
			(pts
				(xy -0.508 0.2794) (xy -0.508 0.2286) (xy -0.635 0.2286) (xy -0.635 -0.254) (xy -0.5334 -0.254)
				(xy -0.5334 -0.2794) (xy 0.5334 -0.2794) (xy 0.5334 -0.254) (xy 0.635 -0.254) (xy 0.635 0.254) (xy 0.5334 0.254)
				(xy 0.5334 0.2794)
			)
			(stroke
				(width 0)
				(type default)
			)
			(fill no)
			(layer "F.CrtYd")
		)
		(pad "1" smd rect
			(at 0.40005 0 270)
			(size 0.4572 0.508)
			(layers "F.Cu" "F.Mask" "F.Paste")
			(net "P3V3_NODE1")
		)
		(pad "2" smd rect
			(at -0.40005 0 270)
			(size 0.4572 0.508)
			(layers "F.Cu" "F.Mask" "F.Paste")
			(net "USB_WAKE_N")
		)
	)
	(footprint ""
		(layer "F.Cu")
		(at 35.802824 -84.339684)
		(property "Reference" "R108"
			(at -4.721606 0.049784 0)
			(unlocked yes)
			(layer "F.SilkS")
			(effects
				(font
					(size 0.7874 0.5842)
					(thickness 0.1524)
				)
				(justify left)
			)
		)
		(property "Value" ""
			(at 0 0 0)
			(layer "F.Fab")
			(effects
				(font
					(size 1.27 1.27)
				)
			)
		)
		(duplicate_pad_numbers_are_jumpers no)
		(fp_line
			(start -0.7874 -0.4064)
			(end 0.7874 -0.4064)
			(stroke
				(width 0.1524)
				(type default)
			)
			(layer "F.SilkS")
		)
		(fp_line
			(start -0.7874 0.4064)
			(end -0.7874 -0.4064)
			(stroke
				(width 0.1524)
				(type default)
			)
			(layer "F.SilkS")
		)
		(fp_line
			(start 0.7874 -0.4064)
			(end 0.7874 0.4064)
			(stroke
				(width 0.1524)
				(type default)
			)
			(layer "F.SilkS")
		)
		(fp_line
			(start 0.7874 0.4064)
			(end -0.7874 0.4064)
			(stroke
				(width 0.1524)
				(type default)
			)
			(layer "F.SilkS")
		)
		(fp_poly
			(pts
				(xy -0.508 0.2794) (xy -0.508 0.2286) (xy -0.635 0.2286) (xy -0.635 -0.254) (xy -0.5334 -0.254)
				(xy -0.5334 -0.2794) (xy 0.5334 -0.2794) (xy 0.5334 -0.254) (xy 0.635 -0.254) (xy 0.635 0.254) (xy 0.5334 0.254)
				(xy 0.5334 0.2794)
			)
			(stroke
				(width 0)
				(type default)
			)
			(fill no)
			(layer "F.CrtYd")
		)
		(pad "1" smd rect
			(at 0.40005 0)
			(size 0.4572 0.508)
			(layers "F.Cu" "F.Mask" "F.Paste")
			(net "PD_NODE1_NTB_PERN")
		)
		(pad "2" smd rect
			(at -0.40005 0)
			(size 0.4572 0.508)
			(layers "F.Cu" "F.Mask" "F.Paste")
			(net "GND")
		)
	)
	(footprint ""
		(layer "F.Cu")
		(at 137.593578 -61.720222 180)
		(property "Reference" "R509"
			(at 0.802894 -4.848098 0)
			(unlocked yes)
			(layer "F.SilkS")
			(effects
				(font
					(size 0.7874 0.5842)
					(thickness 0.1524)
				)
				(justify left)
			)
		)
		(property "Value" ""
			(at 0 0 180)
			(layer "F.Fab")
			(effects
				(font
					(size 1.27 1.27)
				)
			)
		)
		(duplicate_pad_numbers_are_jumpers no)
		(fp_line
			(start 0.7874 0.4064)
			(end -0.7874 0.4064)
			(stroke
				(width 0.1524)
				(type default)
			)
			(layer "F.SilkS")
		)
		(fp_line
			(start 0.7874 -0.4064)
			(end 0.7874 0.4064)
			(stroke
				(width 0.1524)
				(type default)
			)
			(layer "F.SilkS")
		)
		(fp_line
			(start -0.7874 0.4064)
			(end -0.7874 -0.4064)
			(stroke
				(width 0.1524)
				(type default)
			)
			(layer "F.SilkS")
		)
		(fp_line
			(start -0.7874 -0.4064)
			(end 0.7874 -0.4064)
			(stroke
				(width 0.1524)
				(type default)
			)
			(layer "F.SilkS")
		)
		(fp_poly
			(pts
				(xy -0.508 0.2794) (xy -0.508 0.2286) (xy -0.635 0.2286) (xy -0.635 -0.254) (xy -0.5334 -0.254)
				(xy -0.5334 -0.2794) (xy 0.5334 -0.2794) (xy 0.5334 -0.254) (xy 0.635 -0.254) (xy 0.635 0.254) (xy 0.5334 0.254)
				(xy 0.5334 0.2794)
			)
			(stroke
				(width 0)
				(type default)
			)
			(fill no)
			(layer "F.CrtYd")
		)
		(pad "1" smd rect
			(at 0.40005 0 180)
			(size 0.4572 0.508)
			(layers "F.Cu" "F.Mask" "F.Paste")
			(net "P3V3_NODE1")
		)
		(pad "2" smd rect
			(at -0.40005 0 180)
			(size 0.4572 0.508)
			(layers "F.Cu" "F.Mask" "F.Paste")
			(net "SATA_NODE1_GPIO1")
		)
	)
	(footprint ""
		(layer "F.Cu")
		(at 122.846592 -154.541728 180)
		(property "Reference" "U117"
			(at 58.090562 -110.992412 0)
			(unlocked yes)
			(layer "F.SilkS")
			(effects
				(font
					(size 0.7874 0.5842)
					(thickness 0.1524)
				)
			)
		)
		(property "Value" ""
			(at 0 0 180)
			(layer "F.Fab")
			(effects
				(font
					(size 1.27 1.27)
				)
			)
		)
		(duplicate_pad_numbers_are_jumpers no)
		(fp_line
			(start 1.651 1.905)
			(end -1.651 1.905)
			(stroke
				(width 0.1524)
				(type default)
			)
			(layer "F.SilkS")
		)
		(fp_line
			(start 1.651 -1.905)
			(end 1.651 1.905)
			(stroke
				(width 0.1524)
				(type default)
			)
			(layer "F.SilkS")
		)
		(fp_line
			(start -1.651 1.905)
			(end -1.651 -1.905)
			(stroke
				(width 0.1524)
				(type default)
			)
			(layer "F.SilkS")
		)
		(fp_line
			(start -1.651 -1.905)
			(end 1.651 -1.905)
			(stroke
				(width 0.1524)
				(type default)
			)
			(layer "F.SilkS")
		)
		(fp_poly
			(pts
				(xy -1.524 0.7112) (xy -1.524 1.7526) (xy -0.508 1.7526) (xy -0.508 0.6985) (xy 0.508 0.6985) (xy 0.508 1.7526)
				(xy 1.524 1.7526) (xy 1.524 0.6985) (xy 1.524 -0.6985) (xy 0.508 -0.6985) (xy 0.508 -1.7526) (xy -0.508 -1.7526)
				(xy -0.508 -0.6985) (xy -1.524 -0.6985) (xy -1.524 0.6985)
			)
			(stroke
				(width 0)
				(type default)
			)
			(fill no)
			(layer "F.CrtYd")
		)
		(fp_text user "S"
			(at 2.198878 1.18237 0)
			(unlocked yes)
			(layer "F.SilkS")
			(effects
				(font
					(size 0.635 0.4064)
					(thickness 0.1524)
				)
			)
		)
		(fp_text user "D"
			(at -2.035048 -1.44272 0)
			(unlocked yes)
			(layer "F.SilkS")
			(effects
				(font
					(size 0.635 0.4064)
					(thickness 0.1524)
				)
			)
		)
		(fp_text user "G"
			(at -2.224532 1.277366 0)
			(unlocked yes)
			(layer "F.SilkS")
			(effects
				(font
					(size 0.635 0.4064)
					(thickness 0.1524)
				)
			)
		)
		(pad "D" smd rect
			(at 0 -1.1176 180)
			(size 1.016 1.27)
			(layers "F.Cu" "F.Mask" "F.Paste")
			(net "I2C_PSU1_SDA")
		)
		(pad "G" smd rect
			(at -1.016 1.1176 180)
			(size 1.016 1.27)
			(layers "F.Cu" "F.Mask" "F.Paste")
			(net "PMBUS1_EN")
		)
		(pad "S" smd rect
			(at 1.016 1.1176 180)
			(size 1.016 1.27)
			(layers "F.Cu" "F.Mask" "F.Paste")
			(net "I2C_PSU1_SDA_MOS")
		)
	)
	(footprint ""
		(layer "F.Cu")
		(at 181.45633 -130.412236)
		(property "Reference" "R1046"
			(at 11.790426 0.416814 0)
			(unlocked yes)
			(layer "F.SilkS")
			(effects
				(font
					(size 0.7874 0.5842)
					(thickness 0.1524)
				)
				(justify left)
			)
		)
		(property "Value" ""
			(at 0 0 0)
			(layer "F.Fab")
			(effects
				(font
					(size 1.27 1.27)
				)
			)
		)
		(duplicate_pad_numbers_are_jumpers no)
		(fp_line
			(start -0.7874 -0.4064)
			(end 0.7874 -0.4064)
			(stroke
				(width 0.1524)
				(type default)
			)
			(layer "F.SilkS")
		)
		(fp_line
			(start -0.7874 0.4064)
			(end -0.7874 -0.4064)
			(stroke
				(width 0.1524)
				(type default)
			)
			(layer "F.SilkS")
		)
		(fp_line
			(start 0.7874 -0.4064)
			(end 0.7874 0.4064)
			(stroke
				(width 0.1524)
				(type default)
			)
			(layer "F.SilkS")
		)
		(fp_line
			(start 0.7874 0.4064)
			(end -0.7874 0.4064)
			(stroke
				(width 0.1524)
				(type default)
			)
			(layer "F.SilkS")
		)
		(fp_poly
			(pts
				(xy -0.508 0.2794) (xy -0.508 0.2286) (xy -0.635 0.2286) (xy -0.635 -0.254) (xy -0.5334 -0.254)
				(xy -0.5334 -0.2794) (xy 0.5334 -0.2794) (xy 0.5334 -0.254) (xy 0.635 -0.254) (xy 0.635 0.254) (xy 0.5334 0.254)
				(xy 0.5334 0.2794)
			)
			(stroke
				(width 0)
				(type default)
			)
			(fill no)
			(layer "F.CrtYd")
		)
		(pad "1" smd rect
			(at 0.40005 0)
			(size 0.4572 0.508)
			(layers "F.Cu" "F.Mask" "F.Paste")
			(net "FM_NODE1_CORE0_1_RST_L")
		)
		(pad "2" smd rect
			(at -0.40005 0)
			(size 0.4572 0.508)
			(layers "F.Cu" "F.Mask" "F.Paste")
			(net "P3V3_STB_NODE1")
		)
	)
	(footprint ""
		(layer "F.Cu")
		(at 11.24458 -154.13736 -90)
		(property "Reference" "C551"
			(at 5.109464 -8.015732 90)
			(unlocked yes)
			(layer "F.SilkS")
			(effects
				(font
					(size 0.7874 0.5842)
					(thickness 0.1524)
				)
				(justify left)
			)
		)
		(property "Value" ""
			(at 0 0 270)
			(layer "F.Fab")
			(effects
				(font
					(size 1.27 1.27)
				)
			)
		)
		(duplicate_pad_numbers_are_jumpers no)
		(fp_line
			(start -0.7874 0.4064)
			(end -0.7874 -0.4064)
			(stroke
				(width 0.1524)
				(type default)
			)
			(layer "F.SilkS")
		)
		(fp_line
			(start 0.7874 0.4064)
			(end -0.7874 0.4064)
			(stroke
				(width 0.1524)
				(type default)
			)
			(layer "F.SilkS")
		)
		(fp_line
			(start 0 0.381)
			(end 0 -0.381)
			(stroke
				(width 0.1524)
				(type default)
			)
			(layer "F.SilkS")
		)
		(fp_line
			(start -0.7874 -0.4064)
			(end 0.7874 -0.4064)
			(stroke
				(width 0.1524)
				(type default)
			)
			(layer "F.SilkS")
		)
		(fp_line
			(start 0.7874 -0.4064)
			(end 0.7874 0.4064)
			(stroke
				(width 0.1524)
				(type default)
			)
			(layer "F.SilkS")
		)
		(fp_poly
			(pts
				(xy -0.5334 0.254) (xy -0.635 0.254) (xy -0.635 0.2286) (xy -0.635 -0.254) (xy -0.5334 -0.254) (xy -0.5334 -0.2794)
				(xy 0.5334 -0.2794) (xy 0.5334 -0.254) (xy 0.635 -0.254) (xy 0.635 0.254) (xy 0.5334 0.254) (xy 0.5334 0.2794)
				(xy -0.508 0.2794) (xy -0.5334 0.2794)
			)
			(stroke
				(width 0)
				(type default)
			)
			(fill no)
			(layer "F.CrtYd")
		)
		(pad "1" smd rect
			(at 0.40005 0 270)
			(size 0.4572 0.508)
			(layers "F.Cu" "F.Mask" "F.Paste")
			(net "GND")
		)
		(pad "2" smd rect
			(at -0.40005 0 270)
			(size 0.4572 0.508)
			(layers "F.Cu" "F.Mask" "F.Paste")
			(net "N54258535")
		)
	)
	(footprint ""
		(layer "F.Cu")
		(at 90.81262 -168.434512 180)
		(property "Reference" "R918"
			(at -85.97392 -72.627744 0)
			(unlocked yes)
			(layer "F.SilkS")
			(effects
				(font
					(size 0.7874 0.5842)
					(thickness 0.1524)
				)
				(justify left)
			)
		)
		(property "Value" ""
			(at 0 0 180)
			(layer "F.Fab")
			(effects
				(font
					(size 1.27 1.27)
				)
			)
		)
		(duplicate_pad_numbers_are_jumpers no)
		(fp_line
			(start 0.7874 0.4064)
			(end -0.7874 0.4064)
			(stroke
				(width 0.1524)
				(type default)
			)
			(layer "F.SilkS")
		)
		(fp_line
			(start 0.7874 -0.4064)
			(end 0.7874 0.4064)
			(stroke
				(width 0.1524)
				(type default)
			)
			(layer "F.SilkS")
		)
		(fp_line
			(start -0.7874 0.4064)
			(end -0.7874 -0.4064)
			(stroke
				(width 0.1524)
				(type default)
			)
			(layer "F.SilkS")
		)
		(fp_line
			(start -0.7874 -0.4064)
			(end 0.7874 -0.4064)
			(stroke
				(width 0.1524)
				(type default)
			)
			(layer "F.SilkS")
		)
		(fp_poly
			(pts
				(xy -0.508 0.2794) (xy -0.508 0.2286) (xy -0.635 0.2286) (xy -0.635 -0.254) (xy -0.5334 -0.254)
				(xy -0.5334 -0.2794) (xy 0.5334 -0.2794) (xy 0.5334 -0.254) (xy 0.635 -0.254) (xy 0.635 0.254) (xy 0.5334 0.254)
				(xy 0.5334 0.2794)
			)
			(stroke
				(width 0)
				(type default)
			)
			(fill no)
			(layer "F.CrtYd")
		)
		(pad "1" smd rect
			(at 0.40005 0 180)
			(size 0.4572 0.508)
			(layers "F.Cu" "F.Mask" "F.Paste")
			(net "UART_T5_NODE2_TXD")
		)
		(pad "2" smd rect
			(at -0.40005 0 180)
			(size 0.4572 0.508)
			(layers "F.Cu" "F.Mask" "F.Paste")
			(net "UART_T5_NODE2_TXD_R")
		)
	)
	(footprint ""
		(layer "F.Cu")
		(at 34.360358 -130.506216 180)
		(property "Reference" "C832"
			(at 2.386076 1.076706 0)
			(unlocked yes)
			(layer "F.SilkS")
			(effects
				(font
					(size 0.7874 0.5842)
					(thickness 0.1524)
				)
				(justify left)
			)
		)
		(property "Value" ""
			(at 0 0 180)
			(layer "F.Fab")
			(effects
				(font
					(size 1.27 1.27)
				)
			)
		)
		(duplicate_pad_numbers_are_jumpers no)
		(fp_line
			(start 0.7874 0.4064)
			(end -0.7874 0.4064)
			(stroke
				(width 0.1524)
				(type default)
			)
			(layer "F.SilkS")
		)
		(fp_line
			(start 0.7874 -0.4064)
			(end 0.7874 0.4064)
			(stroke
				(width 0.1524)
				(type default)
			)
			(layer "F.SilkS")
		)
		(fp_line
			(start 0 0.381)
			(end 0 -0.381)
			(stroke
				(width 0.1524)
				(type default)
			)
			(layer "F.SilkS")
		)
		(fp_line
			(start -0.7874 0.4064)
			(end -0.7874 -0.4064)
			(stroke
				(width 0.1524)
				(type default)
			)
			(layer "F.SilkS")
		)
		(fp_line
			(start -0.7874 -0.4064)
			(end 0.7874 -0.4064)
			(stroke
				(width 0.1524)
				(type default)
			)
			(layer "F.SilkS")
		)
		(fp_poly
			(pts
				(xy -0.5334 0.254) (xy -0.635 0.254) (xy -0.635 0.2286) (xy -0.635 -0.254) (xy -0.5334 -0.254) (xy -0.5334 -0.2794)
				(xy 0.5334 -0.2794) (xy 0.5334 -0.254) (xy 0.635 -0.254) (xy 0.635 0.254) (xy 0.5334 0.254) (xy 0.5334 0.2794)
				(xy -0.508 0.2794) (xy -0.5334 0.2794)
			)
			(stroke
				(width 0)
				(type default)
			)
			(fill no)
			(layer "F.CrtYd")
		)
		(pad "1" smd rect
			(at 0.40005 0 180)
			(size 0.4572 0.508)
			(layers "F.Cu" "F.Mask" "F.Paste")
			(net "P1V538_BMC_NODE1")
		)
		(pad "2" smd rect
			(at -0.40005 0 180)
			(size 0.4572 0.508)
			(layers "F.Cu" "F.Mask" "F.Paste")
			(net "GND")
		)
	)
	(footprint ""
		(layer "F.Cu")
		(at 169.728896 -40.663114)
		(property "Reference" "R267"
			(at -1.178814 -2.168398 0)
			(unlocked yes)
			(layer "F.SilkS")
			(effects
				(font
					(size 0.7874 0.5842)
					(thickness 0.1524)
				)
				(justify left)
			)
		)
		(property "Value" ""
			(at 0 0 0)
			(layer "F.Fab")
			(effects
				(font
					(size 1.27 1.27)
				)
			)
		)
		(duplicate_pad_numbers_are_jumpers no)
		(fp_line
			(start -0.7874 -0.4064)
			(end 0.7874 -0.4064)
			(stroke
				(width 0.1524)
				(type default)
			)
			(layer "F.SilkS")
		)
		(fp_line
			(start -0.7874 0.4064)
			(end -0.7874 -0.4064)
			(stroke
				(width 0.1524)
				(type default)
			)
			(layer "F.SilkS")
		)
		(fp_line
			(start 0.7874 -0.4064)
			(end 0.7874 0.4064)
			(stroke
				(width 0.1524)
				(type default)
			)
			(layer "F.SilkS")
		)
		(fp_line
			(start 0.7874 0.4064)
			(end -0.7874 0.4064)
			(stroke
				(width 0.1524)
				(type default)
			)
			(layer "F.SilkS")
		)
		(fp_poly
			(pts
				(xy -0.508 0.2794) (xy -0.508 0.2286) (xy -0.635 0.2286) (xy -0.635 -0.254) (xy -0.5334 -0.254)
				(xy -0.5334 -0.2794) (xy 0.5334 -0.2794) (xy 0.5334 -0.254) (xy 0.635 -0.254) (xy 0.635 0.254) (xy 0.5334 0.254)
				(xy 0.5334 0.2794)
			)
			(stroke
				(width 0)
				(type default)
			)
			(fill no)
			(layer "F.CrtYd")
		)
		(pad "1" smd rect
			(at 0.40005 0)
			(size 0.4572 0.508)
			(layers "F.Cu" "F.Mask" "F.Paste")
			(net "USB1_L_DN")
		)
		(pad "2" smd rect
			(at -0.40005 0)
			(size 0.4572 0.508)
			(layers "F.Cu" "F.Mask" "F.Paste")
			(net "USB1_DN")
		)
	)
	(footprint ""
		(layer "F.Cu")
		(at 159.652462 -75.31735 180)
		(property "Reference" "PR10"
			(at 3.90271 2.927096 0)
			(unlocked yes)
			(layer "F.SilkS")
			(effects
				(font
					(size 0.7874 0.5842)
					(thickness 0.1524)
				)
				(justify left)
			)
		)
		(property "Value" ""
			(at 0 0 180)
			(layer "F.Fab")
			(effects
				(font
					(size 1.27 1.27)
				)
			)
		)
		(duplicate_pad_numbers_are_jumpers no)
		(fp_line
			(start 0.7874 0.4064)
			(end -0.7874 0.4064)
			(stroke
				(width 0.1524)
				(type default)
			)
			(layer "F.SilkS")
		)
		(fp_line
			(start 0.7874 -0.4064)
			(end 0.7874 0.4064)
			(stroke
				(width 0.1524)
				(type default)
			)
			(layer "F.SilkS")
		)
		(fp_line
			(start -0.7874 0.4064)
			(end -0.7874 -0.4064)
			(stroke
				(width 0.1524)
				(type default)
			)
			(layer "F.SilkS")
		)
		(fp_line
			(start -0.7874 -0.4064)
			(end 0.7874 -0.4064)
			(stroke
				(width 0.1524)
				(type default)
			)
			(layer "F.SilkS")
		)
		(fp_poly
			(pts
				(xy -0.508 0.2794) (xy -0.508 0.2286) (xy -0.635 0.2286) (xy -0.635 -0.254) (xy -0.5334 -0.254)
				(xy -0.5334 -0.2794) (xy 0.5334 -0.2794) (xy 0.5334 -0.254) (xy 0.635 -0.254) (xy 0.635 0.254) (xy 0.5334 0.254)
				(xy 0.5334 0.2794)
			)
			(stroke
				(width 0)
				(type default)
			)
			(fill no)
			(layer "F.CrtYd")
		)
		(pad "1" smd rect
			(at 0.40005 0 180)
			(size 0.4572 0.508)
			(layers "F.Cu" "F.Mask" "F.Paste")
			(net "GND")
		)
		(pad "2" smd rect
			(at -0.40005 0 180)
			(size 0.4572 0.508)
			(layers "F.Cu" "F.Mask" "F.Paste")
			(net "P1V0_ADJ")
		)
	)
	(footprint ""
		(layer "F.Cu")
		(at 156.19476 -188.126624 90)
		(property "Reference" "R1221"
			(at 5.519674 -3.433826 90)
			(unlocked yes)
			(layer "F.SilkS")
			(effects
				(font
					(size 0.7874 0.5842)
					(thickness 0.1524)
				)
				(justify left)
			)
		)
		(property "Value" ""
			(at 0 0 90)
			(layer "F.Fab")
			(effects
				(font
					(size 1.27 1.27)
				)
			)
		)
		(duplicate_pad_numbers_are_jumpers no)
		(fp_line
			(start 0.7874 -0.4064)
			(end 0.7874 0.4064)
			(stroke
				(width 0.1524)
				(type default)
			)
			(layer "F.SilkS")
		)
		(fp_line
			(start -0.7874 -0.4064)
			(end 0.7874 -0.4064)
			(stroke
				(width 0.1524)
				(type default)
			)
			(layer "F.SilkS")
		)
		(fp_line
			(start 0.7874 0.4064)
			(end -0.7874 0.4064)
			(stroke
				(width 0.1524)
				(type default)
			)
			(layer "F.SilkS")
		)
		(fp_line
			(start -0.7874 0.4064)
			(end -0.7874 -0.4064)
			(stroke
				(width 0.1524)
				(type default)
			)
			(layer "F.SilkS")
		)
		(fp_poly
			(pts
				(xy -0.508 0.2794) (xy -0.508 0.2286) (xy -0.635 0.2286) (xy -0.635 -0.254) (xy -0.5334 -0.254)
				(xy -0.5334 -0.2794) (xy 0.5334 -0.2794) (xy 0.5334 -0.254) (xy 0.635 -0.254) (xy 0.635 0.254) (xy 0.5334 0.254)
				(xy 0.5334 0.2794)
			)
			(stroke
				(width 0)
				(type default)
			)
			(fill no)
			(layer "F.CrtYd")
		)
		(pad "1" smd rect
			(at 0.40005 0 90)
			(size 0.4572 0.508)
			(layers "F.Cu" "F.Mask" "F.Paste")
			(net "FAN3_TACH_R")
		)
		(pad "2" smd rect
			(at -0.40005 0 90)
			(size 0.4572 0.508)
			(layers "F.Cu" "F.Mask" "F.Paste")
			(net "GND")
		)
	)
	(footprint ""
		(layer "F.Cu")
		(at 115.30076 -179.363624 -90)
		(property "Reference" "D22"
			(at -3.11785 -7.56412 90)
			(unlocked yes)
			(layer "F.SilkS")
			(effects
				(font
					(size 0.635 0.4064)
					(thickness 0.1524)
				)
				(justify left)
			)
		)
		(property "Value" ""
			(at 0 0 270)
			(layer "F.Fab")
			(effects
				(font
					(size 1.27 1.27)
				)
			)
		)
		(duplicate_pad_numbers_are_jumpers no)
		(fp_line
			(start -1.3208 0.5588)
			(end -1.3208 -0.5588)
			(stroke
				(width 0.1524)
				(type default)
			)
			(layer "F.SilkS")
		)
		(fp_line
			(start 1.3208 0.5588)
			(end -1.3208 0.5588)
			(stroke
				(width 0.1524)
				(type default)
			)
			(layer "F.SilkS")
		)
		(fp_line
			(start 1.6256 0.5588)
			(end 1.6256 -0.5588)
			(stroke
				(width 0.1524)
				(type default)
			)
			(layer "F.SilkS")
		)
		(fp_line
			(start 1.778 0.5588)
			(end 1.3208 0.5588)
			(stroke
				(width 0.1524)
				(type default)
			)
			(layer "F.SilkS")
		)
		(fp_line
			(start -1.3208 -0.5588)
			(end 1.3208 -0.5588)
			(stroke
				(width 0.1524)
				(type default)
			)
			(layer "F.SilkS")
		)
		(fp_line
			(start 1.3208 -0.5588)
			(end 1.3208 0.5588)
			(stroke
				(width 0.1524)
				(type default)
			)
			(layer "F.SilkS")
		)
		(fp_line
			(start 1.4732 -0.5588)
			(end 1.4732 0.5588)
			(stroke
				(width 0.1524)
				(type default)
			)
			(layer "F.SilkS")
		)
		(fp_line
			(start 1.778 -0.5588)
			(end 1.778 0.5588)
			(stroke
				(width 0.1524)
				(type default)
			)
			(layer "F.SilkS")
		)
		(fp_line
			(start 1.778 -0.5588)
			(end 1.3208 -0.5588)
			(stroke
				(width 0.1524)
				(type default)
			)
			(layer "F.SilkS")
		)
		(fp_rect
			(start -1.1684 0.508)
			(end 1.1684 -0.508)
			(stroke
				(width 0)
				(type default)
			)
			(fill no)
			(layer "F.CrtYd")
		)
		(pad "A" smd rect
			(at -0.750062 0 270)
			(size 0.8128 0.8128)
			(layers "F.Cu" "F.Mask" "F.Paste")
			(net "UART_SW_S4_N")
		)
		(pad "C" smd rect
			(at 0.750062 0 270)
			(size 0.8128 0.8128)
			(layers "F.Cu" "F.Mask" "F.Paste")
			(net "N31341801")
		)
	)
	(footprint ""
		(layer "F.Cu")
		(at 82.340196 -109.114082 180)
		(property "Reference" "C842"
			(at 5.505196 0.567944 0)
			(unlocked yes)
			(layer "F.SilkS")
			(effects
				(font
					(size 0.7874 0.5842)
					(thickness 0.1524)
				)
				(justify left)
			)
		)
		(property "Value" ""
			(at 0 0 180)
			(layer "F.Fab")
			(effects
				(font
					(size 1.27 1.27)
				)
			)
		)
		(duplicate_pad_numbers_are_jumpers no)
		(fp_line
			(start 0.7874 0.4064)
			(end -0.7874 0.4064)
			(stroke
				(width 0.1524)
				(type default)
			)
			(layer "F.SilkS")
		)
		(fp_line
			(start 0.7874 -0.4064)
			(end 0.7874 0.4064)
			(stroke
				(width 0.1524)
				(type default)
			)
			(layer "F.SilkS")
		)
		(fp_line
			(start 0 0.381)
			(end 0 -0.381)
			(stroke
				(width 0.1524)
				(type default)
			)
			(layer "F.SilkS")
		)
		(fp_line
			(start -0.7874 0.4064)
			(end -0.7874 -0.4064)
			(stroke
				(width 0.1524)
				(type default)
			)
			(layer "F.SilkS")
		)
		(fp_line
			(start -0.7874 -0.4064)
			(end 0.7874 -0.4064)
			(stroke
				(width 0.1524)
				(type default)
			)
			(layer "F.SilkS")
		)
		(fp_poly
			(pts
				(xy -0.5334 0.254) (xy -0.635 0.254) (xy -0.635 0.2286) (xy -0.635 -0.254) (xy -0.5334 -0.254) (xy -0.5334 -0.2794)
				(xy 0.5334 -0.2794) (xy 0.5334 -0.254) (xy 0.635 -0.254) (xy 0.635 0.254) (xy 0.5334 0.254) (xy 0.5334 0.2794)
				(xy -0.508 0.2794) (xy -0.5334 0.2794)
			)
			(stroke
				(width 0)
				(type default)
			)
			(fill no)
			(layer "F.CrtYd")
		)
		(pad "1" smd rect
			(at 0.40005 0 180)
			(size 0.4572 0.508)
			(layers "F.Cu" "F.Mask" "F.Paste")
			(net "FM_CPLD_NODE1_P3V3_SUS_EN")
		)
		(pad "2" smd rect
			(at -0.40005 0 180)
			(size 0.4572 0.508)
			(layers "F.Cu" "F.Mask" "F.Paste")
			(net "GND")
		)
	)
	(footprint ""
		(layer "F.Cu")
		(at 83.866228 -133.213094 -90)
		(property "Reference" "D33"
			(at 5.3213 2.668524 90)
			(unlocked yes)
			(layer "F.SilkS")
			(effects
				(font
					(size 0.7874 0.5842)
					(thickness 0.1524)
				)
				(justify left)
			)
		)
		(property "Value" ""
			(at 0 0 270)
			(layer "F.Fab")
			(effects
				(font
					(size 1.27 1.27)
				)
			)
		)
		(duplicate_pad_numbers_are_jumpers no)
		(fp_line
			(start -1.3208 0.5588)
			(end -1.3208 -0.5588)
			(stroke
				(width 0.1524)
				(type default)
			)
			(layer "F.SilkS")
		)
		(fp_line
			(start 1.3208 0.5588)
			(end -1.3208 0.5588)
			(stroke
				(width 0.1524)
				(type default)
			)
			(layer "F.SilkS")
		)
		(fp_line
			(start 1.6256 0.5588)
			(end 1.6256 -0.5588)
			(stroke
				(width 0.1524)
				(type default)
			)
			(layer "F.SilkS")
		)
		(fp_line
			(start 1.778 0.5588)
			(end 1.3208 0.5588)
			(stroke
				(width 0.1524)
				(type default)
			)
			(layer "F.SilkS")
		)
		(fp_line
			(start -1.3208 -0.5588)
			(end 1.3208 -0.5588)
			(stroke
				(width 0.1524)
				(type default)
			)
			(layer "F.SilkS")
		)
		(fp_line
			(start 1.3208 -0.5588)
			(end 1.3208 0.5588)
			(stroke
				(width 0.1524)
				(type default)
			)
			(layer "F.SilkS")
		)
		(fp_line
			(start 1.4732 -0.5588)
			(end 1.4732 0.5588)
			(stroke
				(width 0.1524)
				(type default)
			)
			(layer "F.SilkS")
		)
		(fp_line
			(start 1.778 -0.5588)
			(end 1.778 0.5588)
			(stroke
				(width 0.1524)
				(type default)
			)
			(layer "F.SilkS")
		)
		(fp_line
			(start 1.778 -0.5588)
			(end 1.3208 -0.5588)
			(stroke
				(width 0.1524)
				(type default)
			)
			(layer "F.SilkS")
		)
		(fp_circle
			(center 2.4384 0)
			(end 2.4384 -0.413512)
			(stroke
				(width 0.1524)
				(type default)
			)
			(fill no)
			(layer "F.SilkS")
		)
		(fp_rect
			(start -1.1684 0.508)
			(end 1.1684 -0.508)
			(stroke
				(width 0)
				(type default)
			)
			(fill no)
			(layer "F.CrtYd")
		)
		(fp_text user "-"
			(at 2.481834 0.54356 270)
			(unlocked yes)
			(layer "F.SilkS")
			(effects
				(font
					(size 0.7874 0.5842)
					(thickness 0.1524)
				)
				(justify left)
			)
		)
		(pad "A" smd rect
			(at -0.750062 0 270)
			(size 0.8128 0.8128)
			(layers "F.Cu" "F.Mask" "F.Paste")
			(net "P3V3_NODE1")
		)
		(pad "C" smd rect
			(at 0.750062 0 270)
			(size 0.8128 0.8128)
			(layers "F.Cu" "F.Mask" "F.Paste")
			(net "N53313479")
		)
	)
	(footprint ""
		(layer "F.Cu")
		(at 18.04924 -47.992284 180)
		(property "Reference" "R641"
			(at -12.91336 -4.116324 0)
			(unlocked yes)
			(layer "F.SilkS")
			(effects
				(font
					(size 0.7874 0.5842)
					(thickness 0.1524)
				)
				(justify left)
			)
		)
		(property "Value" ""
			(at 0 0 180)
			(layer "F.Fab")
			(effects
				(font
					(size 1.27 1.27)
				)
			)
		)
		(duplicate_pad_numbers_are_jumpers no)
		(fp_line
			(start 0.7874 0.4064)
			(end -0.7874 0.4064)
			(stroke
				(width 0.1524)
				(type default)
			)
			(layer "F.SilkS")
		)
		(fp_line
			(start 0.7874 -0.4064)
			(end 0.7874 0.4064)
			(stroke
				(width 0.1524)
				(type default)
			)
			(layer "F.SilkS")
		)
		(fp_line
			(start -0.7874 0.4064)
			(end -0.7874 -0.4064)
			(stroke
				(width 0.1524)
				(type default)
			)
			(layer "F.SilkS")
		)
		(fp_line
			(start -0.7874 -0.4064)
			(end 0.7874 -0.4064)
			(stroke
				(width 0.1524)
				(type default)
			)
			(layer "F.SilkS")
		)
		(fp_poly
			(pts
				(xy -0.508 0.2794) (xy -0.508 0.2286) (xy -0.635 0.2286) (xy -0.635 -0.254) (xy -0.5334 -0.254)
				(xy -0.5334 -0.2794) (xy 0.5334 -0.2794) (xy 0.5334 -0.254) (xy 0.635 -0.254) (xy 0.635 0.254) (xy 0.5334 0.254)
				(xy 0.5334 0.2794)
			)
			(stroke
				(width 0)
				(type default)
			)
			(fill no)
			(layer "F.CrtYd")
		)
		(pad "1" smd rect
			(at 0.40005 0 180)
			(size 0.4572 0.508)
			(layers "F.Cu" "F.Mask" "F.Paste")
			(net "CRT_G_L")
		)
		(pad "2" smd rect
			(at -0.40005 0 180)
			(size 0.4572 0.508)
			(layers "F.Cu" "F.Mask" "F.Paste")
			(net "GND")
		)
	)
	(footprint ""
		(layer "F.Cu")
		(at 44.567602 -154.922982 90)
		(property "Reference" "U35"
			(at -0.534416 -6.27888 90)
			(unlocked yes)
			(layer "F.SilkS")
			(effects
				(font
					(size 0.7874 0.5842)
					(thickness 0.1524)
				)
				(justify left)
			)
		)
		(property "Value" ""
			(at 0 0 90)
			(layer "F.Fab")
			(effects
				(font
					(size 1.27 1.27)
				)
			)
		)
		(duplicate_pad_numbers_are_jumpers no)
		(fp_line
			(start 0.750062 -5.207)
			(end 0.750062 -5.715)
			(stroke
				(width 0.1524)
				(type default)
			)
			(layer "F.SilkS")
		)
		(fp_line
			(start 4.500118 -4.500118)
			(end 4.500118 -4.0132)
			(stroke
				(width 0.1524)
				(type default)
			)
			(layer "F.SilkS")
		)
		(fp_line
			(start 4.0386 -4.500118)
			(end 4.500118 -4.500118)
			(stroke
				(width 0.1524)
				(type default)
			)
			(layer "F.SilkS")
		)
		(fp_line
			(start -4.487418 -4.004818)
			(end -4.004818 -4.487418)
			(stroke
				(width 0.1524)
				(type default)
			)
			(layer "F.SilkS")
		)
		(fp_line
			(start 5.207 -1.75006)
			(end 5.715 -1.75006)
			(stroke
				(width 0.1524)
				(type default)
			)
			(layer "F.SilkS")
		)
		(fp_line
			(start -5.207 -1.75006)
			(end -5.715 -1.75006)
			(stroke
				(width 0.1524)
				(type default)
			)
			(layer "F.SilkS")
		)
		(fp_line
			(start 5.207 0.249936)
			(end 6.223 0.249936)
			(stroke
				(width 0.1524)
				(type default)
			)
			(layer "F.SilkS")
		)
		(fp_line
			(start -5.207 0.750062)
			(end -6.223 0.750062)
			(stroke
				(width 0.1524)
				(type default)
			)
			(layer "F.SilkS")
		)
		(fp_line
			(start 5.207 2.750058)
			(end 5.715 2.750058)
			(stroke
				(width 0.1524)
				(type default)
			)
			(layer "F.SilkS")
		)
		(fp_line
			(start -5.207 3.24993)
			(end -5.715 3.24993)
			(stroke
				(width 0.1524)
				(type default)
			)
			(layer "F.SilkS")
		)
		(fp_line
			(start 4.500118 4.0386)
			(end 4.500118 4.500118)
			(stroke
				(width 0.1524)
				(type default)
			)
			(layer "F.SilkS")
		)
		(fp_line
			(start -4.500118 4.474718)
			(end -4.500118 4.0132)
			(stroke
				(width 0.1524)
				(type default)
			)
			(layer "F.SilkS")
		)
		(fp_line
			(start 4.500118 4.500118)
			(end 4.0132 4.500118)
			(stroke
				(width 0.1524)
				(type default)
			)
			(layer "F.SilkS")
		)
		(fp_line
			(start -4.0132 4.500118)
			(end -4.474718 4.500118)
			(stroke
				(width 0.1524)
				(type default)
			)
			(layer "F.SilkS")
		)
		(fp_line
			(start -4.474718 4.500118)
			(end -4.500118 4.474718)
			(stroke
				(width 0.1524)
				(type default)
			)
			(layer "F.SilkS")
		)
		(fp_line
			(start 2.750058 5.207)
			(end 2.750058 6.223)
			(stroke
				(width 0.1524)
				(type default)
			)
			(layer "F.SilkS")
		)
		(fp_line
			(start 0.249936 5.207)
			(end 0.249936 5.715)
			(stroke
				(width 0.1524)
				(type default)
			)
			(layer "F.SilkS")
		)
		(fp_line
			(start -2.249932 5.207)
			(end -2.249932 6.223)
			(stroke
				(width 0.1524)
				(type default)
			)
			(layer "F.SilkS")
		)
		(fp_poly
			(pts
				(xy -5.1562 -3.761486) (xy -6.6802 -4.321556) (xy -6.6802 -3.178556)
			)
			(stroke
				(width 0)
				(type default)
			)
			(fill yes)
			(layer "F.SilkS")
		)
		(fp_poly
			(pts
				(xy -4.500118 4.500118) (xy -3.8862 4.500118) (xy -3.8862 5.0292) (xy -3.8608 5.0292) (xy 3.8608 5.0292)
				(xy 3.8862 5.0292) (xy 3.8862 4.500118) (xy 4.500118 4.500118) (xy 4.500118 3.8862) (xy 5.0292 3.8862)
				(xy 5.0292 3.8608) (xy 5.0292 -3.8608) (xy 5.0292 -3.8862) (xy 4.500118 -3.8862) (xy 4.500118 -4.500118)
				(xy 3.8862 -4.500118) (xy 3.8862 -5.0292) (xy 3.8608 -5.0292) (xy -3.8608 -5.0292) (xy -3.8862 -5.0292)
				(xy -3.8862 -4.500118) (xy -4.500118 -4.500118) (xy -4.500118 -3.8862) (xy -5.0292 -3.8862) (xy -5.0292 -3.8608)
				(xy -5.0292 3.8608) (xy -5.0292 3.8862) (xy -4.500118 3.8862)
			)
			(stroke
				(width 0)
				(type default)
			)
			(fill no)
			(layer "F.CrtYd")
		)
		(fp_line
			(start 4.500118 -4.500118)
			(end 4.500118 4.500118)
			(stroke
				(width 0.1)
				(type default)
			)
			(layer "F.Fab")
		)
		(fp_line
			(start -4.500118 -4.500118)
			(end 4.500118 -4.500118)
			(stroke
				(width 0.1)
				(type default)
			)
			(layer "F.Fab")
		)
		(fp_line
			(start 4.500118 4.500118)
			(end -4.500118 4.500118)
			(stroke
				(width 0.1)
				(type default)
			)
			(layer "F.Fab")
		)
		(fp_line
			(start -4.500118 4.500118)
			(end -4.500118 -4.500118)
			(stroke
				(width 0.1)
				(type default)
			)
			(layer "F.Fab")
		)
		(fp_text user "49"
			(at 3.602228 -5.41782 90)
			(unlocked yes)
			(layer "F.SilkS")
			(effects
				(font
					(size 0.635 0.4064)
					(thickness 0.1524)
				)
				(justify left)
			)
		)
		(fp_text user "48"
			(at 4.753864 -4.321556 90)
			(unlocked yes)
			(layer "F.SilkS")
			(effects
				(font
					(size 0.635 0.4064)
					(thickness 0.1524)
				)
				(justify left)
			)
		)
		(fp_text user "33"
			(at 5.189728 3.653028 90)
			(unlocked yes)
			(layer "F.SilkS")
			(effects
				(font
					(size 0.635 0.4064)
					(thickness 0.1524)
				)
				(justify left)
			)
		)
		(fp_text user "16"
			(at -6.089904 4.025392 90)
			(unlocked yes)
			(layer "F.SilkS")
			(effects
				(font
					(size 0.635 0.4064)
					(thickness 0.1524)
				)
				(justify left)
			)
		)
		(fp_text user "32"
			(at 4.118356 5.121402 90)
			(unlocked yes)
			(layer "F.SilkS")
			(effects
				(font
					(size 0.635 0.4064)
					(thickness 0.1524)
				)
				(justify left)
			)
		)
		(fp_text user "17"
			(at -4.20116 5.569204 90)
			(unlocked yes)
			(layer "F.SilkS")
			(effects
				(font
					(size 0.635 0.4064)
					(thickness 0.1524)
				)
				(justify left)
			)
		)
		(pad "1" smd rect
			(at -4.549902 -3.750056)
			(size 0.254 0.9144)
			(layers "F.Cu" "F.Mask" "F.Paste")
			(net "P3V3_NODE1")
		)
		(pad "2" smd rect
			(at -4.549902 -3.24993)
			(size 0.254 0.9144)
			(layers "F.Cu" "F.Mask" "F.Paste")
			(net "LAN1_NC_SI_CLK_IN")
		)
		(pad "3" smd rect
			(at -4.549902 -2.750058)
			(size 0.254 0.9144)
			(layers "F.Cu" "F.Mask" "F.Paste")
			(net "LAN1_NC_SI_CRS_DV")
		)
		(pad "4" smd rect
			(at -4.549902 -2.249932)
			(size 0.254 0.9144)
			(layers "F.Cu" "F.Mask" "F.Paste")
			(net "P1V05_LAN1")
		)
		(pad "5" smd rect
			(at -4.549902 -1.75006)
			(size 0.254 0.9144)
			(layers "F.Cu" "F.Mask" "F.Paste")
			(net "LAN1_NC_SI_RXD1")
		)
		(pad "6" smd rect
			(at -4.549902 -1.249934)
			(size 0.254 0.9144)
			(layers "F.Cu" "F.Mask" "F.Paste")
			(net "LAN1_NC_SI_RXD0")
		)
		(pad "7" smd rect
			(at -4.549902 -0.750062)
			(size 0.254 0.9144)
			(layers "F.Cu" "F.Mask" "F.Paste")
			(net "LAN1_NC_SI_TX_EN")
		)
		(pad "8" smd rect
			(at -4.549902 -0.249936)
			(size 0.254 0.9144)
			(layers "F.Cu" "F.Mask" "F.Paste")
			(net "LAN1_NC_SI_TDX1")
		)
		(pad "9" smd rect
			(at -4.549902 0.249936)
			(size 0.254 0.9144)
			(layers "F.Cu" "F.Mask" "F.Paste")
			(net "LAN1_NC_SI_TDX0")
		)
		(pad "10" smd rect
			(at -4.549902 0.750062)
			(size 0.254 0.9144)
			(layers "F.Cu" "F.Mask" "F.Paste")
			(net "P3V3_NODE1")
		)
		(pad "11" smd rect
			(at -4.549902 1.249934)
			(size 0.254 0.9144)
			(layers "F.Cu" "F.Mask" "F.Paste")
			(net "P1V05_LAN1")
		)
		(pad "12" smd rect
			(at -4.549902 1.75006)
			(size 0.254 0.9144)
			(layers "F.Cu" "F.Mask" "F.Paste")
			(net "SPI_LAN1_NVM_SI")
		)
		(pad "13" smd rect
			(at -4.549902 2.249932)
			(size 0.254 0.9144)
			(layers "F.Cu" "F.Mask" "F.Paste")
			(net "SPI_LAN1_NVM_SK")
		)
		(pad "14" smd rect
			(at -4.549902 2.750058)
			(size 0.254 0.9144)
			(layers "F.Cu" "F.Mask" "F.Paste")
			(net "SPI_LAN1_NVM_SO")
		)
		(pad "15" smd rect
			(at -4.549902 3.24993)
			(size 0.254 0.9144)
			(layers "F.Cu" "F.Mask" "F.Paste")
			(net "SPI_LAN1_NVM_CS_N")
		)
		(pad "16" smd rect
			(at -4.549902 3.750056)
			(size 0.254 0.9144)
			(layers "F.Cu" "F.Mask" "F.Paste")
			(net "IRQ_LVC3_CPU_NODE1_WAKE_L")
		)
		(pad "17" smd rect
			(at -3.750056 4.549902 90)
			(size 0.254 0.9144)
			(layers "F.Cu" "F.Mask" "F.Paste")
			(net "PLT_RST_LAN1_N")
		)
		(pad "18" smd rect
			(at -3.24993 4.549902 90)
			(size 0.254 0.9144)
			(layers "F.Cu" "F.Mask" "F.Paste")
			(net "P1V05_LAN1")
		)
		(pad "19" smd rect
			(at -2.750058 4.549902 90)
			(size 0.254 0.9144)
			(layers "F.Cu" "F.Mask" "F.Paste")
			(net "P1V9_LAN1")
		)
		(pad "20" smd rect
			(at -2.249932 4.549902 90)
			(size 0.254 0.9144)
			(layers "F.Cu" "F.Mask" "F.Paste")
			(net "PCIE_LAN1_RX_C_DN")
		)
		(pad "21" smd rect
			(at -1.75006 4.549902 90)
			(size 0.254 0.9144)
			(layers "F.Cu" "F.Mask" "F.Paste")
			(net "PCIE_LAN1_RX_C_DP")
		)
		(pad "22" smd rect
			(at -1.249934 4.549902 90)
			(size 0.254 0.9144)
			(layers "F.Cu" "F.Mask" "F.Paste")
			(net "P1V9_LAN1")
		)
		(pad "23" smd rect
			(at -0.750062 4.549902 90)
			(size 0.254 0.9144)
			(layers "F.Cu" "F.Mask" "F.Paste")
			(net "P2E_CPU_NIC1_NODE1_TX_DN")
		)
		(pad "24" smd rect
			(at -0.249936 4.549902 90)
			(size 0.254 0.9144)
			(layers "F.Cu" "F.Mask" "F.Paste")
			(net "P2E_CPU_NIC1_NODE1_TX_DP")
		)
		(pad "25" smd rect
			(at 0.249936 4.549902 90)
			(size 0.254 0.9144)
			(layers "F.Cu" "F.Mask" "F.Paste")
			(net "CLK_100M_NIC1_NODE1_DN")
		)
		(pad "26" smd rect
			(at 0.750062 4.549902 90)
			(size 0.254 0.9144)
			(layers "F.Cu" "F.Mask" "F.Paste")
			(net "CLK_100M_NIC1_NODE1_DP")
		)
		(pad "27" smd rect
			(at 1.249934 4.549902 90)
			(size 0.254 0.9144)
			(layers "F.Cu" "F.Mask" "F.Paste")
			(net "P1V05_LAN1")
		)
		(pad "28" smd rect
			(at 1.75006 4.549902 90)
			(size 0.254 0.9144)
			(layers "F.Cu" "F.Mask" "F.Paste")
			(net "LAN1_DISABLE_N")
		)
		(pad "29" smd rect
			(at 2.249932 4.549902 90)
			(size 0.254 0.9144)
			(layers "F.Cu" "F.Mask" "F.Paste")
			(net "LAN1_TEST_EN")
		)
		(pad "30" smd rect
			(at 2.750058 4.549902 90)
			(size 0.254 0.9144)
			(layers "F.Cu" "F.Mask" "F.Paste")
			(net "LAN1_LED_ACT_N")
		)
		(pad "31" smd rect
			(at 3.24993 4.549902 90)
			(size 0.254 0.9144)
			(layers "F.Cu" "F.Mask" "F.Paste")
			(net "LAN1_LED_LINK_100_N")
		)
		(pad "32" smd rect
			(at 3.750056 4.549902 90)
			(size 0.254 0.9144)
			(layers "F.Cu" "F.Mask" "F.Paste")
			(net "P3V3_NODE1")
		)
		(pad "33" smd rect
			(at 4.549902 3.750056 180)
			(size 0.254 0.9144)
			(layers "F.Cu" "F.Mask" "F.Paste")
			(net "LAN1_LED_LINK_1000_N")
		)
		(pad "34" smd rect
			(at 4.549902 3.24993 180)
			(size 0.254 0.9144)
			(layers "F.Cu" "F.Mask" "F.Paste")
			(net "SMB_LAN1_CLK")
		)
		(pad "35" smd rect
			(at 4.549902 2.750058 180)
			(size 0.254 0.9144)
			(layers "F.Cu" "F.Mask" "F.Paste")
			(net "SMB_LAN1_ALT_N")
		)
		(pad "36" smd rect
			(at 4.549902 2.249932 180)
			(size 0.254 0.9144)
			(layers "F.Cu" "F.Mask" "F.Paste")
			(net "SMB_LAN1_DAT")
		)
		(pad "37" smd rect
			(at 4.549902 1.75006 180)
			(size 0.254 0.9144)
			(layers "F.Cu" "F.Mask" "F.Paste")
			(net "P1V05_LAN1")
		)
		(pad "38" smd rect
			(at 4.549902 1.249934 180)
			(size 0.254 0.9144)
			(layers "F.Cu" "F.Mask" "F.Paste")
			(net "PU_LAN1_TMS")
		)
		(pad "39" smd rect
			(at 4.549902 0.750062 180)
			(size 0.254 0.9144)
			(layers "F.Cu" "F.Mask" "F.Paste")
			(net "LAN1_AUX_PWR")
		)
		(pad "40" smd rect
			(at 4.549902 0.249936 180)
			(size 0.254 0.9144)
			(layers "F.Cu" "F.Mask" "F.Paste")
			(net "PU_LAN1_TDI")
		)
		(pad "41" smd rect
			(at 4.549902 -0.249936 180)
			(size 0.254 0.9144)
			(layers "F.Cu" "F.Mask" "F.Paste")
			(net "P1V05_LAN1")
		)
		(pad "42" smd rect
			(at 4.549902 -0.750062 180)
			(size 0.254 0.9144)
			(layers "F.Cu" "F.Mask" "F.Paste")
			(net "LAN1_XTAL_OUT")
		)
		(pad "43" smd rect
			(at 4.549902 -1.249934 180)
			(size 0.254 0.9144)
			(layers "F.Cu" "F.Mask" "F.Paste")
			(net "LAN1_XTAL_IN")
		)
		(pad "44" smd rect
			(at 4.549902 -1.75006 180)
			(size 0.254 0.9144)
			(layers "F.Cu" "F.Mask" "F.Paste")
			(net "P1V9_LAN1")
		)
		(pad "45" smd rect
			(at 4.549902 -2.249932 180)
			(size 0.254 0.9144)
			(layers "F.Cu" "F.Mask" "F.Paste")
			(net "N21311590")
		)
		(pad "46" smd rect
			(at 4.549902 -2.750058 180)
			(size 0.254 0.9144)
			(layers "F.Cu" "F.Mask" "F.Paste")
			(net "N21311592")
		)
		(pad "47" smd rect
			(at 4.549902 -3.24993 180)
			(size 0.254 0.9144)
			(layers "F.Cu" "F.Mask" "F.Paste")
			(net "P1V9_LAN1")
		)
		(pad "48" smd rect
			(at 4.549902 -3.750056 180)
			(size 0.254 0.9144)
			(layers "F.Cu" "F.Mask" "F.Paste")
			(net "LAN1_RST")
		)
		(pad "49" smd rect
			(at 3.750056 -4.549902 90)
			(size 0.254 0.9144)
			(layers "F.Cu" "F.Mask" "F.Paste")
			(net "LAN1_MDI3_DN")
		)
		(pad "50" smd rect
			(at 3.24993 -4.549902 90)
			(size 0.254 0.9144)
			(layers "F.Cu" "F.Mask" "F.Paste")
			(net "LAN1_MDI3_DP")
		)
		(pad "51" smd rect
			(at 2.750058 -4.549902 90)
			(size 0.254 0.9144)
			(layers "F.Cu" "F.Mask" "F.Paste")
			(net "P1V9_LAN1")
		)
		(pad "52" smd rect
			(at 2.249932 -4.549902 90)
			(size 0.254 0.9144)
			(layers "F.Cu" "F.Mask" "F.Paste")
			(net "LAN1_MDI2_DN")
		)
		(pad "53" smd rect
			(at 1.75006 -4.549902 90)
			(size 0.254 0.9144)
			(layers "F.Cu" "F.Mask" "F.Paste")
			(net "LAN1_MDI2_DP")
		)
		(pad "54" smd rect
			(at 1.249934 -4.549902 90)
			(size 0.254 0.9144)
			(layers "F.Cu" "F.Mask" "F.Paste")
			(net "LAN1_MDI1_DN")
		)
		(pad "55" smd rect
			(at 0.750062 -4.549902 90)
			(size 0.254 0.9144)
			(layers "F.Cu" "F.Mask" "F.Paste")
			(net "LAN1_MDI1_DP")
		)
		(pad "56" smd rect
			(at 0.249936 -4.549902 90)
			(size 0.254 0.9144)
			(layers "F.Cu" "F.Mask" "F.Paste")
			(net "P1V9_LAN1")
		)
		(pad "57" smd rect
			(at -0.249936 -4.549902 90)
			(size 0.254 0.9144)
			(layers "F.Cu" "F.Mask" "F.Paste")
			(net "LAN1_MDI0_DN")
		)
		(pad "58" smd rect
			(at -0.750062 -4.549902 90)
			(size 0.254 0.9144)
			(layers "F.Cu" "F.Mask" "F.Paste")
			(net "LAN1_MDI0_DP")
		)
		(pad "59" smd rect
			(at -1.249934 -4.549902 90)
			(size 0.254 0.9144)
			(layers "F.Cu" "F.Mask" "F.Paste")
			(net "LAN1_DIS_REG10")
		)
		(pad "60" smd rect
			(at -1.75006 -4.549902 90)
			(size 0.254 0.9144)
			(layers "F.Cu" "F.Mask" "F.Paste")
			(net "P1V05_LAN1")
		)
		(pad "61" smd rect
			(at -2.249932 -4.549902 90)
			(size 0.254 0.9144)
			(layers "F.Cu" "F.Mask" "F.Paste")
			(net "P1V9_LAN1")
		)
		(pad "62" smd rect
			(at -2.750058 -4.549902 90)
			(size 0.254 0.9144)
			(layers "F.Cu" "F.Mask" "F.Paste")
			(net "Net_1819")
		)
		(pad "63" smd rect
			(at -3.24993 -4.549902 90)
			(size 0.254 0.9144)
			(layers "F.Cu" "F.Mask" "F.Paste")
			(net "P1V9_LAN1")
		)
		(pad "64" smd rect
			(at -3.750056 -4.549902 90)
			(size 0.254 0.9144)
			(layers "F.Cu" "F.Mask" "F.Paste")
			(net "LAN1_CTRL_P1V9")
		)
		(pad "TH" smd rect
			(at 0 0 90)
			(size 5.4102 5.4102)
			(layers "F.Cu" "F.Mask" "F.Paste")
			(net "GND")
		)
		(zone
			(layer "F.Cu")
			(hatch none 0.5)
			(connect_pads
				(clearance 0)
			)
			(min_thickness 0.25)
			(keepout
				(tracks not_allowed)
				(vias allowed)
				(pads allowed)
				(copperpour not_allowed)
				(footprints allowed)
			)
			(placement
				(enabled no)
				(sheetname "")
			)
			(fill
				(thermal_gap 0.5)
				(thermal_bridge_width 0.5)
				(island_removal_mode 0)
			)
			(polygon
				(pts
					(xy 40.554402 -150.909782) (xy 40.554402 -158.936182) (xy 48.580802 -158.936182) (xy 48.580802 -150.909782)
					(xy 41.799002 -150.909782) (xy 41.799002 -152.128982) (xy 47.361602 -152.128982) (xy 47.361602 -157.716982)
					(xy 41.773602 -157.716982) (xy 41.773602 -150.909782) (xy 41.367202 -150.909782)
				)
			)
		)
		(zone
			(layers "F.Cu" "B.Cu" "In1.Cu" "In2.Cu" "In3.Cu" "In4.Cu" "In5.Cu" "In6.Cu"
				"In7.Cu" "In8.Cu"
			)
			(hatch none 0.5)
			(connect_pads
				(clearance 0)
			)
			(min_thickness 0.25)
			(keepout
				(tracks allowed)
				(vias not_allowed)
				(pads allowed)
				(copperpour not_allowed)
				(footprints allowed)
			)
			(placement
				(enabled no)
				(sheetname "")
			)
			(fill
				(thermal_gap 0.5)
				(thermal_bridge_width 0.5)
				(island_removal_mode 0)
			)
			(polygon
				(pts
					(xy 40.554402 -150.909782) (xy 40.554402 -158.936182) (xy 48.580802 -158.936182) (xy 48.580802 -150.909782)
					(xy 41.799002 -150.909782) (xy 41.799002 -152.128982) (xy 47.361602 -152.128982) (xy 47.361602 -157.716982)
					(xy 41.773602 -157.716982) (xy 41.773602 -150.909782)
				)
			)
		)
	)
	(footprint ""
		(layer "F.Cu")
		(at 75.67676 -185.205624 90)
		(property "Reference" "C701"
			(at 4.006088 -1.429258 90)
			(unlocked yes)
			(layer "F.SilkS")
			(effects
				(font
					(size 0.7874 0.5842)
					(thickness 0.1524)
				)
				(justify left)
			)
		)
		(property "Value" ""
			(at 0 0 90)
			(layer "F.Fab")
			(effects
				(font
					(size 1.27 1.27)
				)
			)
		)
		(duplicate_pad_numbers_are_jumpers no)
		(fp_line
			(start 0.7874 -0.4064)
			(end 0.7874 0.4064)
			(stroke
				(width 0.1524)
				(type default)
			)
			(layer "F.SilkS")
		)
		(fp_line
			(start -0.7874 -0.4064)
			(end 0.7874 -0.4064)
			(stroke
				(width 0.1524)
				(type default)
			)
			(layer "F.SilkS")
		)
		(fp_line
			(start 0 0.381)
			(end 0 -0.381)
			(stroke
				(width 0.1524)
				(type default)
			)
			(layer "F.SilkS")
		)
		(fp_line
			(start 0.7874 0.4064)
			(end -0.7874 0.4064)
			(stroke
				(width 0.1524)
				(type default)
			)
			(layer "F.SilkS")
		)
		(fp_line
			(start -0.7874 0.4064)
			(end -0.7874 -0.4064)
			(stroke
				(width 0.1524)
				(type default)
			)
			(layer "F.SilkS")
		)
		(fp_poly
			(pts
				(xy -0.5334 0.254) (xy -0.635 0.254) (xy -0.635 0.2286) (xy -0.635 -0.254) (xy -0.5334 -0.254) (xy -0.5334 -0.2794)
				(xy 0.5334 -0.2794) (xy 0.5334 -0.254) (xy 0.635 -0.254) (xy 0.635 0.254) (xy 0.5334 0.254) (xy 0.5334 0.2794)
				(xy -0.508 0.2794) (xy -0.5334 0.2794)
			)
			(stroke
				(width 0)
				(type default)
			)
			(fill no)
			(layer "F.CrtYd")
		)
		(pad "1" smd rect
			(at 0.40005 0 90)
			(size 0.4572 0.508)
			(layers "F.Cu" "F.Mask" "F.Paste")
			(net "UART_T4_NODE2_RXD")
		)
		(pad "2" smd rect
			(at -0.40005 0 90)
			(size 0.4572 0.508)
			(layers "F.Cu" "F.Mask" "F.Paste")
			(net "GND")
		)
	)
	(footprint ""
		(layer "F.Cu")
		(at 159.652208 -73.271126)
		(property "Reference" "PR9"
			(at -3.902456 -2.833878 0)
			(unlocked yes)
			(layer "F.SilkS")
			(effects
				(font
					(size 0.7874 0.5842)
					(thickness 0.1524)
				)
				(justify left)
			)
		)
		(property "Value" ""
			(at 0 0 0)
			(layer "F.Fab")
			(effects
				(font
					(size 1.27 1.27)
				)
			)
		)
		(duplicate_pad_numbers_are_jumpers no)
		(fp_line
			(start -0.7874 -0.4064)
			(end 0.7874 -0.4064)
			(stroke
				(width 0.1524)
				(type default)
			)
			(layer "F.SilkS")
		)
		(fp_line
			(start -0.7874 0.4064)
			(end -0.7874 -0.4064)
			(stroke
				(width 0.1524)
				(type default)
			)
			(layer "F.SilkS")
		)
		(fp_line
			(start 0.7874 -0.4064)
			(end 0.7874 0.4064)
			(stroke
				(width 0.1524)
				(type default)
			)
			(layer "F.SilkS")
		)
		(fp_line
			(start 0.7874 0.4064)
			(end -0.7874 0.4064)
			(stroke
				(width 0.1524)
				(type default)
			)
			(layer "F.SilkS")
		)
		(fp_poly
			(pts
				(xy -0.508 0.2794) (xy -0.508 0.2286) (xy -0.635 0.2286) (xy -0.635 -0.254) (xy -0.5334 -0.254)
				(xy -0.5334 -0.2794) (xy 0.5334 -0.2794) (xy 0.5334 -0.254) (xy 0.635 -0.254) (xy 0.635 0.254) (xy 0.5334 0.254)
				(xy 0.5334 0.2794)
			)
			(stroke
				(width 0)
				(type default)
			)
			(fill no)
			(layer "F.CrtYd")
		)
		(pad "1" smd rect
			(at 0.40005 0)
			(size 0.4572 0.508)
			(layers "F.Cu" "F.Mask" "F.Paste")
			(net "P1V0_ADJ")
		)
		(pad "2" smd rect
			(at -0.40005 0)
			(size 0.4572 0.508)
			(layers "F.Cu" "F.Mask" "F.Paste")
			(net "P1V0_ADJ_S")
		)
	)
	(footprint ""
		(layer "F.Cu")
		(at 148.19376 -185.205624 -90)
		(property "Reference" "R990"
			(at -4.768088 -0.259588 90)
			(unlocked yes)
			(layer "F.SilkS")
			(effects
				(font
					(size 0.7874 0.5842)
					(thickness 0.1524)
				)
				(justify left)
			)
		)
		(property "Value" ""
			(at 0 0 270)
			(layer "F.Fab")
			(effects
				(font
					(size 1.27 1.27)
				)
			)
		)
		(duplicate_pad_numbers_are_jumpers no)
		(fp_line
			(start -0.7874 0.4064)
			(end -0.7874 -0.4064)
			(stroke
				(width 0.1524)
				(type default)
			)
			(layer "F.SilkS")
		)
		(fp_line
			(start 0.7874 0.4064)
			(end -0.7874 0.4064)
			(stroke
				(width 0.1524)
				(type default)
			)
			(layer "F.SilkS")
		)
		(fp_line
			(start -0.7874 -0.4064)
			(end 0.7874 -0.4064)
			(stroke
				(width 0.1524)
				(type default)
			)
			(layer "F.SilkS")
		)
		(fp_line
			(start 0.7874 -0.4064)
			(end 0.7874 0.4064)
			(stroke
				(width 0.1524)
				(type default)
			)
			(layer "F.SilkS")
		)
		(fp_poly
			(pts
				(xy -0.508 0.2794) (xy -0.508 0.2286) (xy -0.635 0.2286) (xy -0.635 -0.254) (xy -0.5334 -0.254)
				(xy -0.5334 -0.2794) (xy 0.5334 -0.2794) (xy 0.5334 -0.254) (xy 0.635 -0.254) (xy 0.635 0.254) (xy 0.5334 0.254)
				(xy 0.5334 0.2794)
			)
			(stroke
				(width 0)
				(type default)
			)
			(fill no)
			(layer "F.CrtYd")
		)
		(pad "1" smd rect
			(at 0.40005 0 270)
			(size 0.4572 0.508)
			(layers "F.Cu" "F.Mask" "F.Paste")
			(net "UART_T12_NODE2_TXD")
		)
		(pad "2" smd rect
			(at -0.40005 0 270)
			(size 0.4572 0.508)
			(layers "F.Cu" "F.Mask" "F.Paste")
			(net "UART_T12_NODE2_TXD_R")
		)
	)
	(footprint ""
		(layer "F.Cu")
		(at 148.076158 -174.250604 180)
		(property "Reference" "C904"
			(at 0.048514 -3.781806 90)
			(unlocked yes)
			(layer "F.SilkS")
			(effects
				(font
					(size 0.7874 0.5842)
					(thickness 0.1524)
				)
				(justify left)
			)
		)
		(property "Value" ""
			(at 0 0 180)
			(layer "F.Fab")
			(effects
				(font
					(size 1.27 1.27)
				)
			)
		)
		(duplicate_pad_numbers_are_jumpers no)
		(fp_line
			(start 0.7874 0.4064)
			(end -0.7874 0.4064)
			(stroke
				(width 0.1524)
				(type default)
			)
			(layer "F.SilkS")
		)
		(fp_line
			(start 0.7874 -0.4064)
			(end 0.7874 0.4064)
			(stroke
				(width 0.1524)
				(type default)
			)
			(layer "F.SilkS")
		)
		(fp_line
			(start 0 0.381)
			(end 0 -0.381)
			(stroke
				(width 0.1524)
				(type default)
			)
			(layer "F.SilkS")
		)
		(fp_line
			(start -0.7874 0.4064)
			(end -0.7874 -0.4064)
			(stroke
				(width 0.1524)
				(type default)
			)
			(layer "F.SilkS")
		)
		(fp_line
			(start -0.7874 -0.4064)
			(end 0.7874 -0.4064)
			(stroke
				(width 0.1524)
				(type default)
			)
			(layer "F.SilkS")
		)
		(fp_poly
			(pts
				(xy -0.5334 0.254) (xy -0.635 0.254) (xy -0.635 0.2286) (xy -0.635 -0.254) (xy -0.5334 -0.254) (xy -0.5334 -0.2794)
				(xy 0.5334 -0.2794) (xy 0.5334 -0.254) (xy 0.635 -0.254) (xy 0.635 0.254) (xy 0.5334 0.254) (xy 0.5334 0.2794)
				(xy -0.508 0.2794) (xy -0.5334 0.2794)
			)
			(stroke
				(width 0)
				(type default)
			)
			(fill no)
			(layer "F.CrtYd")
		)
		(pad "1" smd rect
			(at 0.40005 0 180)
			(size 0.4572 0.508)
			(layers "F.Cu" "F.Mask" "F.Paste")
			(net "P3V3_NODE1")
		)
		(pad "2" smd rect
			(at -0.40005 0 180)
			(size 0.4572 0.508)
			(layers "F.Cu" "F.Mask" "F.Paste")
			(net "GND")
		)
	)
	(footprint ""
		(layer "F.Cu")
		(at 125.407928 -61.690758)
		(property "Reference" "C335"
			(at -4.630928 0.01397 0)
			(unlocked yes)
			(layer "F.SilkS")
			(effects
				(font
					(size 0.7874 0.5842)
					(thickness 0.1524)
				)
				(justify left)
			)
		)
		(property "Value" ""
			(at 0 0 0)
			(layer "F.Fab")
			(effects
				(font
					(size 1.27 1.27)
				)
			)
		)
		(duplicate_pad_numbers_are_jumpers no)
		(fp_line
			(start -0.7874 -0.4064)
			(end 0.7874 -0.4064)
			(stroke
				(width 0.1524)
				(type default)
			)
			(layer "F.SilkS")
		)
		(fp_line
			(start -0.7874 0.4064)
			(end -0.7874 -0.4064)
			(stroke
				(width 0.1524)
				(type default)
			)
			(layer "F.SilkS")
		)
		(fp_line
			(start 0 0.381)
			(end 0 -0.381)
			(stroke
				(width 0.1524)
				(type default)
			)
			(layer "F.SilkS")
		)
		(fp_line
			(start 0.7874 -0.4064)
			(end 0.7874 0.4064)
			(stroke
				(width 0.1524)
				(type default)
			)
			(layer "F.SilkS")
		)
		(fp_line
			(start 0.7874 0.4064)
			(end -0.7874 0.4064)
			(stroke
				(width 0.1524)
				(type default)
			)
			(layer "F.SilkS")
		)
		(fp_poly
			(pts
				(xy -0.5334 0.254) (xy -0.635 0.254) (xy -0.635 0.2286) (xy -0.635 -0.254) (xy -0.5334 -0.254) (xy -0.5334 -0.2794)
				(xy 0.5334 -0.2794) (xy 0.5334 -0.254) (xy 0.635 -0.254) (xy 0.635 0.254) (xy 0.5334 0.254) (xy 0.5334 0.2794)
				(xy -0.508 0.2794) (xy -0.5334 0.2794)
			)
			(stroke
				(width 0)
				(type default)
			)
			(fill no)
			(layer "F.CrtYd")
		)
		(pad "1" smd rect
			(at 0.40005 0)
			(size 0.4572 0.508)
			(layers "F.Cu" "F.Mask" "F.Paste")
			(net "P3V3_NODE1")
		)
		(pad "2" smd rect
			(at -0.40005 0)
			(size 0.4572 0.508)
			(layers "F.Cu" "F.Mask" "F.Paste")
			(net "GND")
		)
	)
	(footprint ""
		(layer "F.Cu")
		(at 75.174856 -120.964706)
		(property "Reference" "C203"
			(at -4.55422 0.23114 0)
			(unlocked yes)
			(layer "F.SilkS")
			(effects
				(font
					(size 0.7874 0.5842)
					(thickness 0.1524)
				)
				(justify left)
			)
		)
		(property "Value" ""
			(at 0 0 0)
			(layer "F.Fab")
			(effects
				(font
					(size 1.27 1.27)
				)
			)
		)
		(duplicate_pad_numbers_are_jumpers no)
		(fp_line
			(start -0.7874 -0.4064)
			(end 0.7874 -0.4064)
			(stroke
				(width 0.1524)
				(type default)
			)
			(layer "F.SilkS")
		)
		(fp_line
			(start -0.7874 0.4064)
			(end -0.7874 -0.4064)
			(stroke
				(width 0.1524)
				(type default)
			)
			(layer "F.SilkS")
		)
		(fp_line
			(start 0 0.381)
			(end 0 -0.381)
			(stroke
				(width 0.1524)
				(type default)
			)
			(layer "F.SilkS")
		)
		(fp_line
			(start 0.7874 -0.4064)
			(end 0.7874 0.4064)
			(stroke
				(width 0.1524)
				(type default)
			)
			(layer "F.SilkS")
		)
		(fp_line
			(start 0.7874 0.4064)
			(end -0.7874 0.4064)
			(stroke
				(width 0.1524)
				(type default)
			)
			(layer "F.SilkS")
		)
		(fp_poly
			(pts
				(xy -0.5334 0.254) (xy -0.635 0.254) (xy -0.635 0.2286) (xy -0.635 -0.254) (xy -0.5334 -0.254) (xy -0.5334 -0.2794)
				(xy 0.5334 -0.2794) (xy 0.5334 -0.254) (xy 0.635 -0.254) (xy 0.635 0.254) (xy 0.5334 0.254) (xy 0.5334 0.2794)
				(xy -0.508 0.2794) (xy -0.5334 0.2794)
			)
			(stroke
				(width 0)
				(type default)
			)
			(fill no)
			(layer "F.CrtYd")
		)
		(pad "1" smd rect
			(at 0.40005 0)
			(size 0.4572 0.508)
			(layers "F.Cu" "F.Mask" "F.Paste")
			(net "P2E_CPU_BMC_NODE1_RX_DN")
		)
		(pad "2" smd rect
			(at -0.40005 0)
			(size 0.4572 0.508)
			(layers "F.Cu" "F.Mask" "F.Paste")
			(net "P2E_CPU_BMC_NODE1_RX_C_DN")
		)
	)
	(footprint ""
		(layer "F.Cu")
		(at 14.359382 -156.186378 180)
		(property "Reference" "R1273"
			(at 1.619504 -2.243074 0)
			(unlocked yes)
			(layer "F.SilkS")
			(effects
				(font
					(size 0.7874 0.5842)
					(thickness 0.1524)
				)
				(justify left)
			)
		)
		(property "Value" ""
			(at 0 0 180)
			(layer "F.Fab")
			(effects
				(font
					(size 1.27 1.27)
				)
			)
		)
		(duplicate_pad_numbers_are_jumpers no)
		(fp_line
			(start 0.7874 0.4064)
			(end -0.7874 0.4064)
			(stroke
				(width 0.1524)
				(type default)
			)
			(layer "F.SilkS")
		)
		(fp_line
			(start 0.7874 -0.4064)
			(end 0.7874 0.4064)
			(stroke
				(width 0.1524)
				(type default)
			)
			(layer "F.SilkS")
		)
		(fp_line
			(start -0.7874 0.4064)
			(end -0.7874 -0.4064)
			(stroke
				(width 0.1524)
				(type default)
			)
			(layer "F.SilkS")
		)
		(fp_line
			(start -0.7874 -0.4064)
			(end 0.7874 -0.4064)
			(stroke
				(width 0.1524)
				(type default)
			)
			(layer "F.SilkS")
		)
		(fp_poly
			(pts
				(xy -0.508 0.2794) (xy -0.508 0.2286) (xy -0.635 0.2286) (xy -0.635 -0.254) (xy -0.5334 -0.254)
				(xy -0.5334 -0.2794) (xy 0.5334 -0.2794) (xy 0.5334 -0.254) (xy 0.635 -0.254) (xy 0.635 0.254) (xy 0.5334 0.254)
				(xy 0.5334 0.2794)
			)
			(stroke
				(width 0)
				(type default)
			)
			(fill no)
			(layer "F.CrtYd")
		)
		(pad "1" smd rect
			(at 0.40005 0 180)
			(size 0.4572 0.508)
			(layers "F.Cu" "F.Mask" "F.Paste")
			(net "N54065132")
		)
		(pad "2" smd rect
			(at -0.40005 0 180)
			(size 0.4572 0.508)
			(layers "F.Cu" "F.Mask" "F.Paste")
			(net "LAN1_P1_R")
		)
	)
	(footprint ""
		(layer "F.Cu")
		(at 68.068698 -17.679416 90)
		(property "Reference" "C164"
			(at -2.143252 -2.04597 90)
			(unlocked yes)
			(layer "F.SilkS")
			(effects
				(font
					(size 0.7874 0.5842)
					(thickness 0.1524)
				)
				(justify left)
			)
		)
		(property "Value" ""
			(at 0 0 90)
			(layer "F.Fab")
			(effects
				(font
					(size 1.27 1.27)
				)
			)
		)
		(duplicate_pad_numbers_are_jumpers no)
		(fp_line
			(start 0.7874 -0.4064)
			(end 0.7874 0.4064)
			(stroke
				(width 0.1524)
				(type default)
			)
			(layer "F.SilkS")
		)
		(fp_line
			(start -0.7874 -0.4064)
			(end 0.7874 -0.4064)
			(stroke
				(width 0.1524)
				(type default)
			)
			(layer "F.SilkS")
		)
		(fp_line
			(start 0 0.381)
			(end 0 -0.381)
			(stroke
				(width 0.1524)
				(type default)
			)
			(layer "F.SilkS")
		)
		(fp_line
			(start 0.7874 0.4064)
			(end -0.7874 0.4064)
			(stroke
				(width 0.1524)
				(type default)
			)
			(layer "F.SilkS")
		)
		(fp_line
			(start -0.7874 0.4064)
			(end -0.7874 -0.4064)
			(stroke
				(width 0.1524)
				(type default)
			)
			(layer "F.SilkS")
		)
		(fp_poly
			(pts
				(xy -0.5334 0.254) (xy -0.635 0.254) (xy -0.635 0.2286) (xy -0.635 -0.254) (xy -0.5334 -0.254) (xy -0.5334 -0.2794)
				(xy 0.5334 -0.2794) (xy 0.5334 -0.254) (xy 0.635 -0.254) (xy 0.635 0.254) (xy 0.5334 0.254) (xy 0.5334 0.2794)
				(xy -0.508 0.2794) (xy -0.5334 0.2794)
			)
			(stroke
				(width 0)
				(type default)
			)
			(fill no)
			(layer "F.CrtYd")
		)
		(pad "1" smd rect
			(at 0.40005 0 90)
			(size 0.4572 0.508)
			(layers "F.Cu" "F.Mask" "F.Paste")
			(net "PV_VDDR_NODE1")
		)
		(pad "2" smd rect
			(at -0.40005 0 90)
			(size 0.4572 0.508)
			(layers "F.Cu" "F.Mask" "F.Paste")
			(net "GND")
		)
	)
	(footprint ""
		(layer "F.Cu")
		(at 117.243352 -140.217652 90)
		(property "Reference" "PR63"
			(at 3.640328 2.781554 90)
			(unlocked yes)
			(layer "F.SilkS")
			(effects
				(font
					(size 0.7874 0.5842)
					(thickness 0.1524)
				)
				(justify left)
			)
		)
		(property "Value" ""
			(at 0 0 90)
			(layer "F.Fab")
			(effects
				(font
					(size 1.27 1.27)
				)
			)
		)
		(duplicate_pad_numbers_are_jumpers no)
		(fp_line
			(start 0.7874 -0.4064)
			(end 0.7874 0.4064)
			(stroke
				(width 0.1524)
				(type default)
			)
			(layer "F.SilkS")
		)
		(fp_line
			(start -0.7874 -0.4064)
			(end 0.7874 -0.4064)
			(stroke
				(width 0.1524)
				(type default)
			)
			(layer "F.SilkS")
		)
		(fp_line
			(start 0.7874 0.4064)
			(end -0.7874 0.4064)
			(stroke
				(width 0.1524)
				(type default)
			)
			(layer "F.SilkS")
		)
		(fp_line
			(start -0.7874 0.4064)
			(end -0.7874 -0.4064)
			(stroke
				(width 0.1524)
				(type default)
			)
			(layer "F.SilkS")
		)
		(fp_poly
			(pts
				(xy -0.508 0.2794) (xy -0.508 0.2286) (xy -0.635 0.2286) (xy -0.635 -0.254) (xy -0.5334 -0.254)
				(xy -0.5334 -0.2794) (xy 0.5334 -0.2794) (xy 0.5334 -0.254) (xy 0.635 -0.254) (xy 0.635 0.254) (xy 0.5334 0.254)
				(xy 0.5334 0.2794)
			)
			(stroke
				(width 0)
				(type default)
			)
			(fill no)
			(layer "F.CrtYd")
		)
		(pad "1" smd rect
			(at 0.40005 0 90)
			(size 0.4572 0.508)
			(layers "F.Cu" "F.Mask" "F.Paste")
			(net "VSENSE_VCC_CPU_NODE1")
		)
		(pad "2" smd rect
			(at -0.40005 0 90)
			(size 0.4572 0.508)
			(layers "F.Cu" "F.Mask" "F.Paste")
			(net "PV_VCCP_NODE1")
		)
	)
	(footprint ""
		(layer "F.Cu")
		(at 100.168456 -4.449826)
		(property "Reference" "C134"
			(at 0.613918 1.10363 0)
			(unlocked yes)
			(layer "F.SilkS")
			(effects
				(font
					(size 0.7874 0.5842)
					(thickness 0.1524)
				)
				(justify left)
			)
		)
		(property "Value" ""
			(at 0 0 0)
			(layer "F.Fab")
			(effects
				(font
					(size 1.27 1.27)
				)
			)
		)
		(duplicate_pad_numbers_are_jumpers no)
		(fp_line
			(start -0.7874 -0.4064)
			(end 0.7874 -0.4064)
			(stroke
				(width 0.1524)
				(type default)
			)
			(layer "F.SilkS")
		)
		(fp_line
			(start -0.7874 0.4064)
			(end -0.7874 -0.4064)
			(stroke
				(width 0.1524)
				(type default)
			)
			(layer "F.SilkS")
		)
		(fp_line
			(start 0 0.381)
			(end 0 -0.381)
			(stroke
				(width 0.1524)
				(type default)
			)
			(layer "F.SilkS")
		)
		(fp_line
			(start 0.7874 -0.4064)
			(end 0.7874 0.4064)
			(stroke
				(width 0.1524)
				(type default)
			)
			(layer "F.SilkS")
		)
		(fp_line
			(start 0.7874 0.4064)
			(end -0.7874 0.4064)
			(stroke
				(width 0.1524)
				(type default)
			)
			(layer "F.SilkS")
		)
		(fp_poly
			(pts
				(xy -0.5334 0.254) (xy -0.635 0.254) (xy -0.635 0.2286) (xy -0.635 -0.254) (xy -0.5334 -0.254) (xy -0.5334 -0.2794)
				(xy 0.5334 -0.2794) (xy 0.5334 -0.254) (xy 0.635 -0.254) (xy 0.635 0.254) (xy 0.5334 0.254) (xy 0.5334 0.2794)
				(xy -0.508 0.2794) (xy -0.5334 0.2794)
			)
			(stroke
				(width 0)
				(type default)
			)
			(fill no)
			(layer "F.CrtYd")
		)
		(pad "1" smd rect
			(at 0.40005 0)
			(size 0.4572 0.508)
			(layers "F.Cu" "F.Mask" "F.Paste")
			(net "GND")
		)
		(pad "2" smd rect
			(at -0.40005 0)
			(size 0.4572 0.508)
			(layers "F.Cu" "F.Mask" "F.Paste")
			(net "P3V3_NODE1")
		)
	)
	(footprint ""
		(layer "F.Cu")
		(at 64.441324 -98.542856)
		(property "Reference" "C825"
			(at 27.668982 53.292502 0)
			(unlocked yes)
			(layer "F.SilkS")
			(effects
				(font
					(size 0.7874 0.5842)
					(thickness 0.1524)
				)
			)
		)
		(property "Value" ""
			(at 0 0 0)
			(layer "F.Fab")
			(effects
				(font
					(size 1.27 1.27)
				)
			)
		)
		(duplicate_pad_numbers_are_jumpers no)
		(fp_line
			(start -1.2954 -0.5842)
			(end 1.2954 -0.5842)
			(stroke
				(width 0.1524)
				(type default)
			)
			(layer "F.SilkS")
		)
		(fp_line
			(start -1.2954 0.5842)
			(end -1.2954 -0.5842)
			(stroke
				(width 0.1524)
				(type default)
			)
			(layer "F.SilkS")
		)
		(fp_line
			(start 0 -0.5842)
			(end 0 0.5842)
			(stroke
				(width 0.1524)
				(type default)
			)
			(layer "F.SilkS")
		)
		(fp_line
			(start 1.2954 -0.5842)
			(end 1.2954 0.5842)
			(stroke
				(width 0.1524)
				(type default)
			)
			(layer "F.SilkS")
		)
		(fp_line
			(start 1.2954 0.5842)
			(end -1.2954 0.5842)
			(stroke
				(width 0.1524)
				(type default)
			)
			(layer "F.SilkS")
		)
		(fp_poly
			(pts
				(xy 0.8636 -0.4572) (xy 0.8636 -0.3556) (xy 1.143 -0.3556) (xy 1.143 0.3556) (xy 0.8636 0.3556)
				(xy 0.8636 0.4572) (xy -0.8636 0.4572) (xy -0.8636 0.3556) (xy -1.143 0.3556) (xy -1.143 -0.3556)
				(xy -0.8636 -0.3556) (xy -0.8636 -0.4572)
			)
			(stroke
				(width 0)
				(type default)
			)
			(fill no)
			(layer "F.CrtYd")
		)
		(fp_line
			(start -0.884936 -0.504952)
			(end 0.884936 -0.504952)
			(stroke
				(width 0.1)
				(type default)
			)
			(layer "F.Fab")
		)
		(fp_line
			(start -0.884936 0.504952)
			(end -0.884936 -0.504952)
			(stroke
				(width 0.1)
				(type default)
			)
			(layer "F.Fab")
		)
		(fp_line
			(start 0.884936 -0.504952)
			(end 0.884936 0.504952)
			(stroke
				(width 0.1)
				(type default)
			)
			(layer "F.Fab")
		)
		(fp_line
			(start 0.884936 0.504952)
			(end -0.884936 0.504952)
			(stroke
				(width 0.1)
				(type default)
			)
			(layer "F.Fab")
		)
		(pad "1" smd rect
			(at 0.7366 0 90)
			(size 0.7112 0.8128)
			(layers "F.Cu" "F.Mask" "F.Paste")
			(net "FM_CPLD_NODE1_P1V8_SUS_EN_LV")
		)
		(pad "2" smd rect
			(at -0.7366 0 90)
			(size 0.7112 0.8128)
			(layers "F.Cu" "F.Mask" "F.Paste")
			(net "P1V8_SUS_NODE1")
		)
	)
	(footprint ""
		(layer "F.Cu")
		(at 95.627444 -118.63705 180)
		(property "Reference" "R1258"
			(at 1.326388 -1.22047 0)
			(unlocked yes)
			(layer "F.SilkS")
			(effects
				(font
					(size 0.7874 0.5842)
					(thickness 0.1524)
				)
				(justify left)
			)
		)
		(property "Value" ""
			(at 0 0 180)
			(layer "F.Fab")
			(effects
				(font
					(size 1.27 1.27)
				)
			)
		)
		(duplicate_pad_numbers_are_jumpers no)
		(fp_line
			(start 0.7874 0.4064)
			(end -0.7874 0.4064)
			(stroke
				(width 0.1524)
				(type default)
			)
			(layer "F.SilkS")
		)
		(fp_line
			(start 0.7874 -0.4064)
			(end 0.7874 0.4064)
			(stroke
				(width 0.1524)
				(type default)
			)
			(layer "F.SilkS")
		)
		(fp_line
			(start -0.7874 0.4064)
			(end -0.7874 -0.4064)
			(stroke
				(width 0.1524)
				(type default)
			)
			(layer "F.SilkS")
		)
		(fp_line
			(start -0.7874 -0.4064)
			(end 0.7874 -0.4064)
			(stroke
				(width 0.1524)
				(type default)
			)
			(layer "F.SilkS")
		)
		(fp_poly
			(pts
				(xy -0.508 0.2794) (xy -0.508 0.2286) (xy -0.635 0.2286) (xy -0.635 -0.254) (xy -0.5334 -0.254)
				(xy -0.5334 -0.2794) (xy 0.5334 -0.2794) (xy 0.5334 -0.254) (xy 0.635 -0.254) (xy 0.635 0.254) (xy 0.5334 0.254)
				(xy 0.5334 0.2794)
			)
			(stroke
				(width 0)
				(type default)
			)
			(fill no)
			(layer "F.CrtYd")
		)
		(pad "1" smd rect
			(at 0.40005 0 180)
			(size 0.4572 0.508)
			(layers "F.Cu" "F.Mask" "F.Paste")
			(net "PORT80_LOUT5")
		)
		(pad "2" smd rect
			(at -0.40005 0 180)
			(size 0.4572 0.508)
			(layers "F.Cu" "F.Mask" "F.Paste")
			(net "N53313558")
		)
	)
	(footprint ""
		(layer "F.Cu")
		(at 135.798052 -154.81935 90)
		(property "Reference" "R231"
			(at -110.78337 -60.386722 90)
			(unlocked yes)
			(layer "F.SilkS")
			(effects
				(font
					(size 0.7874 0.5842)
					(thickness 0.1524)
				)
				(justify left)
			)
		)
		(property "Value" ""
			(at 0 0 90)
			(layer "F.Fab")
			(effects
				(font
					(size 1.27 1.27)
				)
			)
		)
		(duplicate_pad_numbers_are_jumpers no)
		(fp_line
			(start 0.7874 -0.4064)
			(end 0.7874 0.4064)
			(stroke
				(width 0.1524)
				(type default)
			)
			(layer "F.SilkS")
		)
		(fp_line
			(start -0.7874 -0.4064)
			(end 0.7874 -0.4064)
			(stroke
				(width 0.1524)
				(type default)
			)
			(layer "F.SilkS")
		)
		(fp_line
			(start 0.7874 0.4064)
			(end -0.7874 0.4064)
			(stroke
				(width 0.1524)
				(type default)
			)
			(layer "F.SilkS")
		)
		(fp_line
			(start -0.7874 0.4064)
			(end -0.7874 -0.4064)
			(stroke
				(width 0.1524)
				(type default)
			)
			(layer "F.SilkS")
		)
		(fp_poly
			(pts
				(xy -0.508 0.2794) (xy -0.508 0.2286) (xy -0.635 0.2286) (xy -0.635 -0.254) (xy -0.5334 -0.254)
				(xy -0.5334 -0.2794) (xy 0.5334 -0.2794) (xy 0.5334 -0.254) (xy 0.635 -0.254) (xy 0.635 0.254) (xy 0.5334 0.254)
				(xy 0.5334 0.2794)
			)
			(stroke
				(width 0)
				(type default)
			)
			(fill no)
			(layer "F.CrtYd")
		)
		(pad "1" smd rect
			(at 0.40005 0 90)
			(size 0.4572 0.508)
			(layers "F.Cu" "F.Mask" "F.Paste")
			(net "FM_CPLD_PCIE_SW_PERST_L")
		)
		(pad "2" smd rect
			(at -0.40005 0 90)
			(size 0.4572 0.508)
			(layers "F.Cu" "F.Mask" "F.Paste")
			(net "PCIE_SW_RST_N")
		)
	)
	(footprint ""
		(layer "F.Cu")
		(at 57.488074 -6.726682)
		(property "Reference" "PC80"
			(at -2.040382 5.12318 0)
			(unlocked yes)
			(layer "F.SilkS")
			(effects
				(font
					(size 0.7874 0.5842)
					(thickness 0.1524)
				)
				(justify left)
			)
		)
		(property "Value" ""
			(at 0 0 0)
			(layer "F.Fab")
			(effects
				(font
					(size 1.27 1.27)
				)
			)
		)
		(duplicate_pad_numbers_are_jumpers no)
		(fp_line
			(start -2.249932 -4.533392)
			(end 2.249932 -4.533392)
			(stroke
				(width 0.1524)
				(type default)
			)
			(layer "F.SilkS")
		)
		(fp_line
			(start -2.249932 4.533392)
			(end -2.249932 -4.533392)
			(stroke
				(width 0.1524)
				(type default)
			)
			(layer "F.SilkS")
		)
		(fp_line
			(start 2.249932 -4.533392)
			(end 2.249932 4.533392)
			(stroke
				(width 0.1524)
				(type default)
			)
			(layer "F.SilkS")
		)
		(fp_line
			(start 2.249932 4.533392)
			(end -2.249932 4.533392)
			(stroke
				(width 0.1524)
				(type default)
			)
			(layer "F.SilkS")
		)
		(fp_poly
			(pts
				(xy 2.326132 -4.533392) (xy 2.326132 -5.39242) (xy -2.326132 -5.39242) (xy -2.326132 -4.533392)
			)
			(stroke
				(width 0)
				(type default)
			)
			(fill yes)
			(layer "F.SilkS")
		)
		(fp_poly
			(pts
				(xy -1.4605 4.457192) (xy -1.4605 3.750056) (xy -2.249932 3.750056) (xy -2.249932 -3.750056) (xy -1.4605 -3.750056)
				(xy -1.4605 -4.457192) (xy 1.4605 -4.457192) (xy 1.4605 -3.750056) (xy 2.249932 -3.750056) (xy 2.249932 3.750056)
				(xy 1.4605 3.750056) (xy 1.4605 4.457192)
			)
			(stroke
				(width 0)
				(type default)
			)
			(fill no)
			(layer "F.CrtYd")
		)
		(fp_line
			(start -2.249932 -3.750056)
			(end 2.249932 -3.750056)
			(stroke
				(width 0.1)
				(type default)
			)
			(layer "F.Fab")
		)
		(fp_line
			(start -2.249932 3.750056)
			(end -2.249932 -3.750056)
			(stroke
				(width 0.1)
				(type default)
			)
			(layer "F.Fab")
		)
		(fp_line
			(start 2.249932 -3.750056)
			(end 2.249932 3.750056)
			(stroke
				(width 0.1)
				(type default)
			)
			(layer "F.Fab")
		)
		(fp_line
			(start 2.249932 3.750056)
			(end -2.249932 3.750056)
			(stroke
				(width 0.1)
				(type default)
			)
			(layer "F.Fab")
		)
		(fp_text user "+"
			(at -2.463292 -5.479542 90)
			(unlocked yes)
			(layer "F.SilkS")
			(effects
				(font
					(size 1.6002 1.1938)
					(thickness 0.1524)
				)
				(justify left)
			)
		)
		(fp_text user "+"
			(at -0.786384 -6.322314 0)
			(unlocked yes)
			(layer "F.Fab")
			(effects
				(font
					(size 1.905 1.4224)
					(thickness 0.000001)
				)
				(justify left)
			)
		)
		(pad "1" smd rect
			(at 0 -3.199892 270)
			(size 2.413 2.8194)
			(layers "F.Cu" "F.Mask" "F.Paste")
			(net "PV_VDDR_NODE1")
		)
		(pad "2" smd rect
			(at 0 3.199892 270)
			(size 2.413 2.8194)
			(layers "F.Cu" "F.Mask" "F.Paste")
			(net "GND")
		)
	)
	(footprint ""
		(layer "F.Cu")
		(at 19.943826 -101.069902 180)
		(property "Reference" "R187"
			(at 5.197856 0.500888 0)
			(unlocked yes)
			(layer "F.SilkS")
			(effects
				(font
					(size 0.7874 0.5842)
					(thickness 0.1524)
				)
				(justify left)
			)
		)
		(property "Value" ""
			(at 0 0 180)
			(layer "F.Fab")
			(effects
				(font
					(size 1.27 1.27)
				)
			)
		)
		(duplicate_pad_numbers_are_jumpers no)
		(fp_line
			(start 0.7874 0.4064)
			(end -0.7874 0.4064)
			(stroke
				(width 0.1524)
				(type default)
			)
			(layer "F.SilkS")
		)
		(fp_line
			(start 0.7874 -0.4064)
			(end 0.7874 0.4064)
			(stroke
				(width 0.1524)
				(type default)
			)
			(layer "F.SilkS")
		)
		(fp_line
			(start -0.7874 0.4064)
			(end -0.7874 -0.4064)
			(stroke
				(width 0.1524)
				(type default)
			)
			(layer "F.SilkS")
		)
		(fp_line
			(start -0.7874 -0.4064)
			(end 0.7874 -0.4064)
			(stroke
				(width 0.1524)
				(type default)
			)
			(layer "F.SilkS")
		)
		(fp_poly
			(pts
				(xy -0.508 0.2794) (xy -0.508 0.2286) (xy -0.635 0.2286) (xy -0.635 -0.254) (xy -0.5334 -0.254)
				(xy -0.5334 -0.2794) (xy 0.5334 -0.2794) (xy 0.5334 -0.254) (xy 0.635 -0.254) (xy 0.635 0.254) (xy 0.5334 0.254)
				(xy 0.5334 0.2794)
			)
			(stroke
				(width 0)
				(type default)
			)
			(fill no)
			(layer "F.CrtYd")
		)
		(pad "1" smd rect
			(at 0.40005 0 180)
			(size 0.4572 0.508)
			(layers "F.Cu" "F.Mask" "F.Paste")
			(net "P3V3_NODE1")
		)
		(pad "2" smd rect
			(at -0.40005 0 180)
			(size 0.4572 0.508)
			(layers "F.Cu" "F.Mask" "F.Paste")
			(net "FRU_SYS_A2")
		)
	)
	(footprint ""
		(layer "F.Cu")
		(at 88.438228 -133.213094 -90)
		(property "Reference" "D36"
			(at -3.582162 -1.214374 90)
			(unlocked yes)
			(layer "F.SilkS")
			(effects
				(font
					(size 0.7874 0.5842)
					(thickness 0.1524)
				)
				(justify left)
			)
		)
		(property "Value" ""
			(at 0 0 270)
			(layer "F.Fab")
			(effects
				(font
					(size 1.27 1.27)
				)
			)
		)
		(duplicate_pad_numbers_are_jumpers no)
		(fp_line
			(start -1.3208 0.5588)
			(end -1.3208 -0.5588)
			(stroke
				(width 0.1524)
				(type default)
			)
			(layer "F.SilkS")
		)
		(fp_line
			(start 1.3208 0.5588)
			(end -1.3208 0.5588)
			(stroke
				(width 0.1524)
				(type default)
			)
			(layer "F.SilkS")
		)
		(fp_line
			(start 1.6256 0.5588)
			(end 1.6256 -0.5588)
			(stroke
				(width 0.1524)
				(type default)
			)
			(layer "F.SilkS")
		)
		(fp_line
			(start 1.778 0.5588)
			(end 1.3208 0.5588)
			(stroke
				(width 0.1524)
				(type default)
			)
			(layer "F.SilkS")
		)
		(fp_line
			(start -1.3208 -0.5588)
			(end 1.3208 -0.5588)
			(stroke
				(width 0.1524)
				(type default)
			)
			(layer "F.SilkS")
		)
		(fp_line
			(start 1.3208 -0.5588)
			(end 1.3208 0.5588)
			(stroke
				(width 0.1524)
				(type default)
			)
			(layer "F.SilkS")
		)
		(fp_line
			(start 1.4732 -0.5588)
			(end 1.4732 0.5588)
			(stroke
				(width 0.1524)
				(type default)
			)
			(layer "F.SilkS")
		)
		(fp_line
			(start 1.778 -0.5588)
			(end 1.778 0.5588)
			(stroke
				(width 0.1524)
				(type default)
			)
			(layer "F.SilkS")
		)
		(fp_line
			(start 1.778 -0.5588)
			(end 1.3208 -0.5588)
			(stroke
				(width 0.1524)
				(type default)
			)
			(layer "F.SilkS")
		)
		(fp_circle
			(center 2.453894 0.218948)
			(end 2.453894 -0.194564)
			(stroke
				(width 0.1524)
				(type default)
			)
			(fill no)
			(layer "F.SilkS")
		)
		(fp_rect
			(start -1.1684 0.508)
			(end 1.1684 -0.508)
			(stroke
				(width 0)
				(type default)
			)
			(fill no)
			(layer "F.CrtYd")
		)
		(fp_text user "-"
			(at 2.670048 0.70866 270)
			(unlocked yes)
			(layer "F.SilkS")
			(effects
				(font
					(size 0.7874 0.5842)
					(thickness 0.1524)
				)
				(justify left)
			)
		)
		(pad "A" smd rect
			(at -0.750062 0 270)
			(size 0.8128 0.8128)
			(layers "F.Cu" "F.Mask" "F.Paste")
			(net "P3V3_NODE1")
		)
		(pad "C" smd rect
			(at 0.750062 0 270)
			(size 0.8128 0.8128)
			(layers "F.Cu" "F.Mask" "F.Paste")
			(net "N53313558")
		)
	)
	(footprint ""
		(layer "F.Cu")
		(at 100.628196 -158.523686)
		(property "Reference" "PC30"
			(at 86.996016 70.784974 0)
			(unlocked yes)
			(layer "F.SilkS")
			(effects
				(font
					(size 0.7874 0.5842)
					(thickness 0.1524)
				)
				(justify left)
			)
		)
		(property "Value" ""
			(at 0 0 0)
			(layer "F.Fab")
			(effects
				(font
					(size 1.27 1.27)
				)
			)
		)
		(duplicate_pad_numbers_are_jumpers no)
		(fp_line
			(start -0.7874 -0.4064)
			(end 0.7874 -0.4064)
			(stroke
				(width 0.1524)
				(type default)
			)
			(layer "F.SilkS")
		)
		(fp_line
			(start -0.7874 0.4064)
			(end -0.7874 -0.4064)
			(stroke
				(width 0.1524)
				(type default)
			)
			(layer "F.SilkS")
		)
		(fp_line
			(start 0 0.381)
			(end 0 -0.381)
			(stroke
				(width 0.1524)
				(type default)
			)
			(layer "F.SilkS")
		)
		(fp_line
			(start 0.7874 -0.4064)
			(end 0.7874 0.4064)
			(stroke
				(width 0.1524)
				(type default)
			)
			(layer "F.SilkS")
		)
		(fp_line
			(start 0.7874 0.4064)
			(end -0.7874 0.4064)
			(stroke
				(width 0.1524)
				(type default)
			)
			(layer "F.SilkS")
		)
		(fp_poly
			(pts
				(xy -0.5334 0.254) (xy -0.635 0.254) (xy -0.635 0.2286) (xy -0.635 -0.254) (xy -0.5334 -0.254) (xy -0.5334 -0.2794)
				(xy 0.5334 -0.2794) (xy 0.5334 -0.254) (xy 0.635 -0.254) (xy 0.635 0.254) (xy 0.5334 0.254) (xy 0.5334 0.2794)
				(xy -0.508 0.2794) (xy -0.5334 0.2794)
			)
			(stroke
				(width 0)
				(type default)
			)
			(fill no)
			(layer "F.CrtYd")
		)
		(pad "1" smd rect
			(at 0.40005 0)
			(size 0.4572 0.508)
			(layers "F.Cu" "F.Mask" "F.Paste")
			(net "FM_CPLD_NODE1_P1V8_STB_EN")
		)
		(pad "2" smd rect
			(at -0.40005 0)
			(size 0.4572 0.508)
			(layers "F.Cu" "F.Mask" "F.Paste")
			(net "GND")
		)
	)
	(footprint ""
		(layer "F.Cu")
		(at 132.889752 -156.308298)
		(property "Reference" "R1284"
			(at -64.415162 110.150402 0)
			(unlocked yes)
			(layer "F.SilkS")
			(effects
				(font
					(size 0.7874 0.5842)
					(thickness 0.1524)
				)
				(justify left)
			)
		)
		(property "Value" ""
			(at 0 0 0)
			(layer "F.Fab")
			(effects
				(font
					(size 1.27 1.27)
				)
			)
		)
		(duplicate_pad_numbers_are_jumpers no)
		(fp_line
			(start -0.7874 -0.4064)
			(end 0.7874 -0.4064)
			(stroke
				(width 0.1524)
				(type default)
			)
			(layer "F.SilkS")
		)
		(fp_line
			(start -0.7874 0.4064)
			(end -0.7874 -0.4064)
			(stroke
				(width 0.1524)
				(type default)
			)
			(layer "F.SilkS")
		)
		(fp_line
			(start 0.7874 -0.4064)
			(end 0.7874 0.4064)
			(stroke
				(width 0.1524)
				(type default)
			)
			(layer "F.SilkS")
		)
		(fp_line
			(start 0.7874 0.4064)
			(end -0.7874 0.4064)
			(stroke
				(width 0.1524)
				(type default)
			)
			(layer "F.SilkS")
		)
		(fp_poly
			(pts
				(xy -0.508 0.2794) (xy -0.508 0.2286) (xy -0.635 0.2286) (xy -0.635 -0.254) (xy -0.5334 -0.254)
				(xy -0.5334 -0.2794) (xy 0.5334 -0.2794) (xy 0.5334 -0.254) (xy 0.635 -0.254) (xy 0.635 0.254) (xy 0.5334 0.254)
				(xy 0.5334 0.2794)
			)
			(stroke
				(width 0)
				(type default)
			)
			(fill no)
			(layer "F.CrtYd")
		)
		(pad "1" smd rect
			(at 0.40005 0)
			(size 0.4572 0.508)
			(layers "F.Cu" "F.Mask" "F.Paste")
			(net "P5V_NODE1")
		)
		(pad "2" smd rect
			(at -0.40005 0)
			(size 0.4572 0.508)
			(layers "F.Cu" "F.Mask" "F.Paste")
			(net "PMBUS3_EN")
		)
	)
	(footprint ""
		(layer "F.Cu")
		(at 38.250368 -6.550914 -90)
		(property "Reference" "R1123"
			(at 1.42494 9.35863 90)
			(unlocked yes)
			(layer "F.SilkS")
			(effects
				(font
					(size 0.7874 0.5842)
					(thickness 0.1524)
				)
				(justify left)
			)
		)
		(property "Value" ""
			(at 0 0 270)
			(layer "F.Fab")
			(effects
				(font
					(size 1.27 1.27)
				)
			)
		)
		(duplicate_pad_numbers_are_jumpers no)
		(fp_line
			(start -0.7874 0.4064)
			(end -0.7874 -0.4064)
			(stroke
				(width 0.1524)
				(type default)
			)
			(layer "F.SilkS")
		)
		(fp_line
			(start 0.7874 0.4064)
			(end -0.7874 0.4064)
			(stroke
				(width 0.1524)
				(type default)
			)
			(layer "F.SilkS")
		)
		(fp_line
			(start -0.7874 -0.4064)
			(end 0.7874 -0.4064)
			(stroke
				(width 0.1524)
				(type default)
			)
			(layer "F.SilkS")
		)
		(fp_line
			(start 0.7874 -0.4064)
			(end 0.7874 0.4064)
			(stroke
				(width 0.1524)
				(type default)
			)
			(layer "F.SilkS")
		)
		(fp_poly
			(pts
				(xy -0.508 0.2794) (xy -0.508 0.2286) (xy -0.635 0.2286) (xy -0.635 -0.254) (xy -0.5334 -0.254)
				(xy -0.5334 -0.2794) (xy 0.5334 -0.2794) (xy 0.5334 -0.254) (xy 0.635 -0.254) (xy 0.635 0.254) (xy 0.5334 0.254)
				(xy 0.5334 0.2794)
			)
			(stroke
				(width 0)
				(type default)
			)
			(fill no)
			(layer "F.CrtYd")
		)
		(pad "1" smd rect
			(at 0.40005 0 270)
			(size 0.4572 0.508)
			(layers "F.Cu" "F.Mask" "F.Paste")
			(net "P3V3_STB_NODE1")
		)
		(pad "2" smd rect
			(at -0.40005 0 270)
			(size 0.4572 0.508)
			(layers "F.Cu" "F.Mask" "F.Paste")
			(net "PV_VDDR_NODE1_VID0")
		)
	)
	(footprint ""
		(layer "F.Cu")
		(at 161.632646 -78.363318 90)
		(property "Reference" "U130"
			(at 0.87122 -2.072894 90)
			(unlocked yes)
			(layer "F.SilkS")
			(effects
				(font
					(size 0.7874 0.5842)
					(thickness 0.1524)
				)
				(justify left)
			)
		)
		(property "Value" ""
			(at 0 0 90)
			(layer "F.Fab")
			(effects
				(font
					(size 1.27 1.27)
				)
			)
		)
		(duplicate_pad_numbers_are_jumpers no)
		(fp_line
			(start 0.525018 0.025146)
			(end 0.320802 0.025146)
			(stroke
				(width 0.1524)
				(type default)
			)
			(layer "F.SilkS")
		)
		(fp_line
			(start -2.320798 0.025146)
			(end -2.525014 0.025146)
			(stroke
				(width 0.1524)
				(type default)
			)
			(layer "F.SilkS")
		)
		(fp_line
			(start -2.525014 0.025146)
			(end -2.525014 0.661162)
			(stroke
				(width 0.1524)
				(type default)
			)
			(layer "F.SilkS")
		)
		(fp_line
			(start 0.525018 0.686562)
			(end 0.525018 0.025146)
			(stroke
				(width 0.1524)
				(type default)
			)
			(layer "F.SilkS")
		)
		(fp_line
			(start -2.525014 2.540762)
			(end -2.525014 3.075178)
			(stroke
				(width 0.1524)
				(type default)
			)
			(layer "F.SilkS")
		)
		(fp_line
			(start 0.525018 3.075178)
			(end 0.525018 0.025146)
			(stroke
				(width 0.1524)
				(type default)
			)
			(layer "F.SilkS")
		)
		(fp_line
			(start 0.525018 3.075178)
			(end 0.525018 2.489962)
			(stroke
				(width 0.1524)
				(type default)
			)
			(layer "F.SilkS")
		)
		(fp_line
			(start 0.320802 3.075178)
			(end 0.525018 3.075178)
			(stroke
				(width 0.1524)
				(type default)
			)
			(layer "F.SilkS")
		)
		(fp_line
			(start -2.525014 3.075178)
			(end -2.525014 0.025146)
			(stroke
				(width 0.1524)
				(type default)
			)
			(layer "F.SilkS")
		)
		(fp_line
			(start -2.525014 3.075178)
			(end -2.320798 3.075178)
			(stroke
				(width 0.1524)
				(type default)
			)
			(layer "F.SilkS")
		)
		(fp_poly
			(pts
				(xy 0.106172 -1.266444) (xy 0.406146 -2.16662) (xy -0.193802 -2.16662)
			)
			(stroke
				(width 0)
				(type default)
			)
			(fill yes)
			(layer "F.SilkS")
		)
		(fp_poly
			(pts
				(xy 0.525018 0.025146) (xy 0.244602 0.025146) (xy 0.244602 -0.532638) (xy -2.244598 -0.532638) (xy -2.244598 0.025146)
				(xy -2.525014 0.025146) (xy -2.525014 3.075178) (xy -2.244598 3.075178) (xy -2.244598 3.632962)
				(xy 0.244602 3.632962) (xy 0.244602 3.075178) (xy 0.525018 3.075178)
			)
			(stroke
				(width 0)
				(type default)
			)
			(fill no)
			(layer "F.CrtYd")
		)
		(fp_line
			(start 0.525018 0.025146)
			(end 0.525018 3.075178)
			(stroke
				(width 0.1)
				(type default)
			)
			(layer "F.Fab")
		)
		(fp_line
			(start -2.525014 0.025146)
			(end 0.525018 0.025146)
			(stroke
				(width 0.1)
				(type default)
			)
			(layer "F.Fab")
		)
		(fp_line
			(start 0.525018 3.075178)
			(end -2.525014 3.075178)
			(stroke
				(width 0.1)
				(type default)
			)
			(layer "F.Fab")
		)
		(fp_line
			(start -2.525014 3.075178)
			(end -2.525014 0.025146)
			(stroke
				(width 0.1)
				(type default)
			)
			(layer "F.Fab")
		)
		(fp_poly
			(pts
				(xy 0 -0.519938) (xy 0.302514 -1.427734) (xy -0.302514 -1.427734)
			)
			(stroke
				(width 0)
				(type default)
			)
			(fill yes)
			(layer "F.Fab")
		)
		(fp_text user "1"
			(at 0.677672 -1.741932 0)
			(unlocked yes)
			(layer "F.SilkS")
			(effects
				(font
					(size 0.635 0.4064)
					(thickness 0.1524)
				)
				(justify left)
			)
		)
		(fp_text user "5"
			(at -2.791968 -0.622046 0)
			(unlocked yes)
			(layer "F.SilkS")
			(effects
				(font
					(size 0.635 0.4064)
					(thickness 0.1524)
				)
				(justify left)
			)
		)
		(fp_text user "10"
			(at 0.84074 3.118612 0)
			(unlocked yes)
			(layer "F.SilkS")
			(effects
				(font
					(size 0.635 0.4064)
					(thickness 0.1524)
				)
				(justify left)
			)
		)
		(fp_text user "6"
			(at -2.753868 3.772154 180)
			(unlocked yes)
			(layer "F.SilkS")
			(effects
				(font
					(size 0.635 0.4064)
					(thickness 0.1524)
				)
				(justify left)
			)
		)
		(fp_text user "1"
			(at 0.790702 -0.695706 270)
			(unlocked yes)
			(layer "F.Fab")
			(effects
				(font
					(size 0.7874 0.5842)
					(thickness 0.000001)
				)
				(justify left)
			)
		)
		(fp_text user "5"
			(at -2.155698 -0.695706 270)
			(unlocked yes)
			(layer "F.Fab")
			(effects
				(font
					(size 0.7874 0.5842)
					(thickness 0.000001)
				)
				(justify left)
			)
		)
		(fp_text user "10"
			(at 1.565402 3.700272 270)
			(unlocked yes)
			(layer "F.Fab")
			(effects
				(font
					(size 0.7874 0.5842)
					(thickness 0.000001)
				)
				(justify left)
			)
		)
		(fp_text user "6"
			(at -2.155698 3.725672 270)
			(unlocked yes)
			(layer "F.Fab")
			(effects
				(font
					(size 0.7874 0.5842)
					(thickness 0.000001)
				)
				(justify left)
			)
		)
		(pad "1" smd rect
			(at 0 0 270)
			(size 0.2794 0.9144)
			(layers "F.Cu" "F.Mask" "F.Paste")
			(net "P1V0_NODE1")
		)
		(pad "2" smd rect
			(at -0.499872 0 270)
			(size 0.2794 0.9144)
			(layers "F.Cu" "F.Mask" "F.Paste")
			(net "P1V0_NODE1")
		)
		(pad "3" smd rect
			(at -0.999998 0 270)
			(size 0.2794 0.9144)
			(layers "F.Cu" "F.Mask" "F.Paste")
			(net "P1V0_NODE1")
		)
		(pad "4" smd rect
			(at -1.500124 0 270)
			(size 0.2794 0.9144)
			(layers "F.Cu" "F.Mask" "F.Paste")
			(net "P1V0_ADJ")
		)
		(pad "5" smd rect
			(at -1.999996 0 90)
			(size 0.2794 0.9144)
			(layers "F.Cu" "F.Mask" "F.Paste")
			(net "PWRGD_NODE1_P1V0")
		)
		(pad "6" smd rect
			(at -1.999996 3.100324 90)
			(size 0.2794 0.9144)
			(layers "F.Cu" "F.Mask" "F.Paste")
			(net "N47241340")
		)
		(pad "7" smd rect
			(at -1.500124 3.100324 270)
			(size 0.2794 0.9144)
			(layers "F.Cu" "F.Mask" "F.Paste")
			(net "P1V8_NODE1")
		)
		(pad "8" smd rect
			(at -0.999998 3.100324 270)
			(size 0.2794 0.9144)
			(layers "F.Cu" "F.Mask" "F.Paste")
			(net "P1V8_NODE1")
		)
		(pad "9" smd rect
			(at -0.499872 3.100324 270)
			(size 0.2794 0.9144)
			(layers "F.Cu" "F.Mask" "F.Paste")
			(net "P1V8_NODE1")
		)
		(pad "10" smd rect
			(at 0 3.100324 270)
			(size 0.2794 0.9144)
			(layers "F.Cu" "F.Mask" "F.Paste")
			(net "P5V_STB_NODE1")
		)
		(pad "TH" smd rect
			(at -0.999998 1.550162)
			(size 1.7526 2.667)
			(layers "F.Cu" "F.Mask" "F.Paste")
			(net "GND")
		)
		(zone
			(layer "F.Cu")
			(hatch none 0.5)
			(connect_pads
				(clearance 0)
			)
			(min_thickness 0.25)
			(keepout
				(tracks allowed)
				(vias not_allowed)
				(pads allowed)
				(copperpour not_allowed)
				(footprints allowed)
			)
			(placement
				(enabled no)
				(sheetname "")
			)
			(fill
				(thermal_gap 0.5)
				(thermal_bridge_width 0.5)
				(island_removal_mode 0)
			)
			(polygon
				(pts
					(xy 162.166046 -78.896718) (xy 162.166046 -75.848718) (xy 164.198046 -75.848718) (xy 164.198046 -78.896718)
					(xy 162.267646 -78.896718) (xy 162.267646 -78.769718) (xy 164.121846 -78.769718) (xy 164.121846 -75.950318)
					(xy 162.242246 -75.950318) (xy 162.242246 -78.896718)
				)
			)
		)
	)
	(footprint ""
		(layer "F.Cu")
		(at 38.379654 -114.906298 90)
		(property "Reference" "C849"
			(at 1.549146 1.299718 90)
			(unlocked yes)
			(layer "F.SilkS")
			(effects
				(font
					(size 0.7874 0.5842)
					(thickness 0.1524)
				)
			)
		)
		(property "Value" ""
			(at 0 0 90)
			(layer "F.Fab")
			(effects
				(font
					(size 1.27 1.27)
				)
			)
		)
		(duplicate_pad_numbers_are_jumpers no)
		(fp_line
			(start 1.2954 -0.5842)
			(end 1.2954 0.5842)
			(stroke
				(width 0.1524)
				(type default)
			)
			(layer "F.SilkS")
		)
		(fp_line
			(start 0 -0.5842)
			(end 0 0.5842)
			(stroke
				(width 0.1524)
				(type default)
			)
			(layer "F.SilkS")
		)
		(fp_line
			(start -1.2954 -0.5842)
			(end 1.2954 -0.5842)
			(stroke
				(width 0.1524)
				(type default)
			)
			(layer "F.SilkS")
		)
		(fp_line
			(start 1.2954 0.5842)
			(end -1.2954 0.5842)
			(stroke
				(width 0.1524)
				(type default)
			)
			(layer "F.SilkS")
		)
		(fp_line
			(start -1.2954 0.5842)
			(end -1.2954 -0.5842)
			(stroke
				(width 0.1524)
				(type default)
			)
			(layer "F.SilkS")
		)
		(fp_poly
			(pts
				(xy 0.8636 -0.4572) (xy 0.8636 -0.3556) (xy 1.143 -0.3556) (xy 1.143 0.3556) (xy 0.8636 0.3556)
				(xy 0.8636 0.4572) (xy -0.8636 0.4572) (xy -0.8636 0.3556) (xy -1.143 0.3556) (xy -1.143 -0.3556)
				(xy -0.8636 -0.3556) (xy -0.8636 -0.4572)
			)
			(stroke
				(width 0)
				(type default)
			)
			(fill no)
			(layer "F.CrtYd")
		)
		(fp_line
			(start 0.884936 -0.504952)
			(end 0.884936 0.504952)
			(stroke
				(width 0.1)
				(type default)
			)
			(layer "F.Fab")
		)
		(fp_line
			(start -0.884936 -0.504952)
			(end 0.884936 -0.504952)
			(stroke
				(width 0.1)
				(type default)
			)
			(layer "F.Fab")
		)
		(fp_line
			(start 0.884936 0.504952)
			(end -0.884936 0.504952)
			(stroke
				(width 0.1)
				(type default)
			)
			(layer "F.Fab")
		)
		(fp_line
			(start -0.884936 0.504952)
			(end -0.884936 -0.504952)
			(stroke
				(width 0.1)
				(type default)
			)
			(layer "F.Fab")
		)
		(pad "1" smd rect
			(at 0.7366 0 180)
			(size 0.7112 0.8128)
			(layers "F.Cu" "F.Mask" "F.Paste")
			(net "FM_CPLD_NODE1_P1V5_EN_LV")
		)
		(pad "2" smd rect
			(at -0.7366 0 180)
			(size 0.7112 0.8128)
			(layers "F.Cu" "F.Mask" "F.Paste")
			(net "P1V5_NODE1")
		)
	)
	(footprint ""
		(layer "F.Cu")
		(at 83.67776 -185.205624 -90)
		(property "Reference" "R822"
			(at -4.198112 1.876552 90)
			(unlocked yes)
			(layer "F.SilkS")
			(effects
				(font
					(size 0.7874 0.5842)
					(thickness 0.1524)
				)
				(justify left)
			)
		)
		(property "Value" ""
			(at 0 0 270)
			(layer "F.Fab")
			(effects
				(font
					(size 1.27 1.27)
				)
			)
		)
		(duplicate_pad_numbers_are_jumpers no)
		(fp_line
			(start -0.7874 0.4064)
			(end -0.7874 -0.4064)
			(stroke
				(width 0.1524)
				(type default)
			)
			(layer "F.SilkS")
		)
		(fp_line
			(start 0.7874 0.4064)
			(end -0.7874 0.4064)
			(stroke
				(width 0.1524)
				(type default)
			)
			(layer "F.SilkS")
		)
		(fp_line
			(start -0.7874 -0.4064)
			(end 0.7874 -0.4064)
			(stroke
				(width 0.1524)
				(type default)
			)
			(layer "F.SilkS")
		)
		(fp_line
			(start 0.7874 -0.4064)
			(end 0.7874 0.4064)
			(stroke
				(width 0.1524)
				(type default)
			)
			(layer "F.SilkS")
		)
		(fp_poly
			(pts
				(xy -0.508 0.2794) (xy -0.508 0.2286) (xy -0.635 0.2286) (xy -0.635 -0.254) (xy -0.5334 -0.254)
				(xy -0.5334 -0.2794) (xy 0.5334 -0.2794) (xy 0.5334 -0.254) (xy 0.635 -0.254) (xy 0.635 0.254) (xy 0.5334 0.254)
				(xy 0.5334 0.2794)
			)
			(stroke
				(width 0)
				(type default)
			)
			(fill no)
			(layer "F.CrtYd")
		)
		(pad "1" smd rect
			(at 0.40005 0 270)
			(size 0.4572 0.508)
			(layers "F.Cu" "F.Mask" "F.Paste")
			(net "I2C_PSU2_SDA")
		)
		(pad "2" smd rect
			(at -0.40005 0 270)
			(size 0.4572 0.508)
			(layers "F.Cu" "F.Mask" "F.Paste")
			(net "I2C_PSU2_R_SDA")
		)
	)
	(footprint ""
		(layer "F.Cu")
		(at 90.81262 -177.578512 180)
		(property "Reference" "R809"
			(at -85.97392 -76.287122 0)
			(unlocked yes)
			(layer "F.SilkS")
			(effects
				(font
					(size 0.7874 0.5842)
					(thickness 0.1524)
				)
				(justify left)
			)
		)
		(property "Value" ""
			(at 0 0 180)
			(layer "F.Fab")
			(effects
				(font
					(size 1.27 1.27)
				)
			)
		)
		(duplicate_pad_numbers_are_jumpers no)
		(fp_line
			(start 0.7874 0.4064)
			(end -0.7874 0.4064)
			(stroke
				(width 0.1524)
				(type default)
			)
			(layer "F.SilkS")
		)
		(fp_line
			(start 0.7874 -0.4064)
			(end 0.7874 0.4064)
			(stroke
				(width 0.1524)
				(type default)
			)
			(layer "F.SilkS")
		)
		(fp_line
			(start -0.7874 0.4064)
			(end -0.7874 -0.4064)
			(stroke
				(width 0.1524)
				(type default)
			)
			(layer "F.SilkS")
		)
		(fp_line
			(start -0.7874 -0.4064)
			(end 0.7874 -0.4064)
			(stroke
				(width 0.1524)
				(type default)
			)
			(layer "F.SilkS")
		)
		(fp_poly
			(pts
				(xy -0.508 0.2794) (xy -0.508 0.2286) (xy -0.635 0.2286) (xy -0.635 -0.254) (xy -0.5334 -0.254)
				(xy -0.5334 -0.2794) (xy 0.5334 -0.2794) (xy 0.5334 -0.254) (xy 0.635 -0.254) (xy 0.635 0.254) (xy 0.5334 0.254)
				(xy 0.5334 0.2794)
			)
			(stroke
				(width 0)
				(type default)
			)
			(fill no)
			(layer "F.CrtYd")
		)
		(pad "1" smd rect
			(at 0.40005 0 180)
			(size 0.4572 0.508)
			(layers "F.Cu" "F.Mask" "F.Paste")
			(net "CPLD_UART_RTS_P4_N")
		)
		(pad "2" smd rect
			(at -0.40005 0 180)
			(size 0.4572 0.508)
			(layers "F.Cu" "F.Mask" "F.Paste")
			(net "GND")
		)
	)
	(footprint ""
		(layer "F.Cu")
		(at 149.039326 -41.881044 -90)
		(property "Reference" "R1013"
			(at -0.345948 -10.157968 90)
			(unlocked yes)
			(layer "F.SilkS")
			(effects
				(font
					(size 0.7874 0.5842)
					(thickness 0.1524)
				)
				(justify left)
			)
		)
		(property "Value" ""
			(at 0 0 270)
			(layer "F.Fab")
			(effects
				(font
					(size 1.27 1.27)
				)
			)
		)
		(duplicate_pad_numbers_are_jumpers no)
		(fp_line
			(start -0.7874 0.4064)
			(end -0.7874 -0.4064)
			(stroke
				(width 0.1524)
				(type default)
			)
			(layer "F.SilkS")
		)
		(fp_line
			(start 0.7874 0.4064)
			(end -0.7874 0.4064)
			(stroke
				(width 0.1524)
				(type default)
			)
			(layer "F.SilkS")
		)
		(fp_line
			(start -0.7874 -0.4064)
			(end 0.7874 -0.4064)
			(stroke
				(width 0.1524)
				(type default)
			)
			(layer "F.SilkS")
		)
		(fp_line
			(start 0.7874 -0.4064)
			(end 0.7874 0.4064)
			(stroke
				(width 0.1524)
				(type default)
			)
			(layer "F.SilkS")
		)
		(fp_poly
			(pts
				(xy -0.508 0.2794) (xy -0.508 0.2286) (xy -0.635 0.2286) (xy -0.635 -0.254) (xy -0.5334 -0.254)
				(xy -0.5334 -0.2794) (xy 0.5334 -0.2794) (xy 0.5334 -0.254) (xy 0.635 -0.254) (xy 0.635 0.254) (xy 0.5334 0.254)
				(xy 0.5334 0.2794)
			)
			(stroke
				(width 0)
				(type default)
			)
			(fill no)
			(layer "F.CrtYd")
		)
		(pad "1" smd rect
			(at 0.40005 0 270)
			(size 0.4572 0.508)
			(layers "F.Cu" "F.Mask" "F.Paste")
			(net "GND")
		)
		(pad "2" smd rect
			(at -0.40005 0 270)
			(size 0.4572 0.508)
			(layers "F.Cu" "F.Mask" "F.Paste")
			(net "UART_RTS_P1_N")
		)
	)
	(footprint ""
		(layer "F.Cu")
		(at 110.60176 -185.205624 -90)
		(property "Reference" "R887"
			(at -4.768088 -0.724408 90)
			(unlocked yes)
			(layer "F.SilkS")
			(effects
				(font
					(size 0.7874 0.5842)
					(thickness 0.1524)
				)
				(justify left)
			)
		)
		(property "Value" ""
			(at 0 0 270)
			(layer "F.Fab")
			(effects
				(font
					(size 1.27 1.27)
				)
			)
		)
		(duplicate_pad_numbers_are_jumpers no)
		(fp_line
			(start -0.7874 0.4064)
			(end -0.7874 -0.4064)
			(stroke
				(width 0.1524)
				(type default)
			)
			(layer "F.SilkS")
		)
		(fp_line
			(start 0.7874 0.4064)
			(end -0.7874 0.4064)
			(stroke
				(width 0.1524)
				(type default)
			)
			(layer "F.SilkS")
		)
		(fp_line
			(start -0.7874 -0.4064)
			(end 0.7874 -0.4064)
			(stroke
				(width 0.1524)
				(type default)
			)
			(layer "F.SilkS")
		)
		(fp_line
			(start 0.7874 -0.4064)
			(end 0.7874 0.4064)
			(stroke
				(width 0.1524)
				(type default)
			)
			(layer "F.SilkS")
		)
		(fp_poly
			(pts
				(xy -0.508 0.2794) (xy -0.508 0.2286) (xy -0.635 0.2286) (xy -0.635 -0.254) (xy -0.5334 -0.254)
				(xy -0.5334 -0.2794) (xy 0.5334 -0.2794) (xy 0.5334 -0.254) (xy 0.635 -0.254) (xy 0.635 0.254) (xy 0.5334 0.254)
				(xy 0.5334 0.2794)
			)
			(stroke
				(width 0)
				(type default)
			)
			(fill no)
			(layer "F.CrtYd")
		)
		(pad "1" smd rect
			(at 0.40005 0 270)
			(size 0.4572 0.508)
			(layers "F.Cu" "F.Mask" "F.Paste")
			(net "T6_NODE2_EN")
		)
		(pad "2" smd rect
			(at -0.40005 0 270)
			(size 0.4572 0.508)
			(layers "F.Cu" "F.Mask" "F.Paste")
			(net "T6_NODE2_EN_R")
		)
	)
	(footprint ""
		(layer "F.Cu")
		(at 69.755004 -175.523652)
		(property "Reference" "C583"
			(at -1.652524 1.504188 0)
			(unlocked yes)
			(layer "F.SilkS")
			(effects
				(font
					(size 0.7874 0.5842)
					(thickness 0.1524)
				)
				(justify left)
			)
		)
		(property "Value" ""
			(at 0 0 0)
			(layer "F.Fab")
			(effects
				(font
					(size 1.27 1.27)
				)
			)
		)
		(duplicate_pad_numbers_are_jumpers no)
		(fp_line
			(start -0.7874 -0.4064)
			(end 0.7874 -0.4064)
			(stroke
				(width 0.1524)
				(type default)
			)
			(layer "F.SilkS")
		)
		(fp_line
			(start -0.7874 0.4064)
			(end -0.7874 -0.4064)
			(stroke
				(width 0.1524)
				(type default)
			)
			(layer "F.SilkS")
		)
		(fp_line
			(start 0 0.381)
			(end 0 -0.381)
			(stroke
				(width 0.1524)
				(type default)
			)
			(layer "F.SilkS")
		)
		(fp_line
			(start 0.7874 -0.4064)
			(end 0.7874 0.4064)
			(stroke
				(width 0.1524)
				(type default)
			)
			(layer "F.SilkS")
		)
		(fp_line
			(start 0.7874 0.4064)
			(end -0.7874 0.4064)
			(stroke
				(width 0.1524)
				(type default)
			)
			(layer "F.SilkS")
		)
		(fp_poly
			(pts
				(xy -0.5334 0.254) (xy -0.635 0.254) (xy -0.635 0.2286) (xy -0.635 -0.254) (xy -0.5334 -0.254) (xy -0.5334 -0.2794)
				(xy 0.5334 -0.2794) (xy 0.5334 -0.254) (xy 0.635 -0.254) (xy 0.635 0.254) (xy 0.5334 0.254) (xy 0.5334 0.2794)
				(xy -0.508 0.2794) (xy -0.5334 0.2794)
			)
			(stroke
				(width 0)
				(type default)
			)
			(fill no)
			(layer "F.CrtYd")
		)
		(pad "1" smd rect
			(at 0.40005 0)
			(size 0.4572 0.508)
			(layers "F.Cu" "F.Mask" "F.Paste")
			(net "P3V3_NODE1")
		)
		(pad "2" smd rect
			(at -0.40005 0)
			(size 0.4572 0.508)
			(layers "F.Cu" "F.Mask" "F.Paste")
			(net "GND")
		)
	)
	(footprint ""
		(layer "F.Cu")
		(at 79.39786 -92.076524)
		(property "Reference" "R142"
			(at -0.62992 18.989294 0)
			(unlocked yes)
			(layer "F.SilkS")
			(effects
				(font
					(size 0.7874 0.5842)
					(thickness 0.1524)
				)
				(justify left)
			)
		)
		(property "Value" ""
			(at 0 0 0)
			(layer "F.Fab")
			(effects
				(font
					(size 1.27 1.27)
				)
			)
		)
		(duplicate_pad_numbers_are_jumpers no)
		(fp_line
			(start -0.7874 -0.4064)
			(end 0.7874 -0.4064)
			(stroke
				(width 0.1524)
				(type default)
			)
			(layer "F.SilkS")
		)
		(fp_line
			(start -0.7874 0.4064)
			(end -0.7874 -0.4064)
			(stroke
				(width 0.1524)
				(type default)
			)
			(layer "F.SilkS")
		)
		(fp_line
			(start 0.7874 -0.4064)
			(end 0.7874 0.4064)
			(stroke
				(width 0.1524)
				(type default)
			)
			(layer "F.SilkS")
		)
		(fp_line
			(start 0.7874 0.4064)
			(end -0.7874 0.4064)
			(stroke
				(width 0.1524)
				(type default)
			)
			(layer "F.SilkS")
		)
		(fp_poly
			(pts
				(xy -0.508 0.2794) (xy -0.508 0.2286) (xy -0.635 0.2286) (xy -0.635 -0.254) (xy -0.5334 -0.254)
				(xy -0.5334 -0.2794) (xy 0.5334 -0.2794) (xy 0.5334 -0.254) (xy 0.635 -0.254) (xy 0.635 0.254) (xy 0.5334 0.254)
				(xy 0.5334 0.2794)
			)
			(stroke
				(width 0)
				(type default)
			)
			(fill no)
			(layer "F.CrtYd")
		)
		(pad "1" smd rect
			(at 0.40005 0)
			(size 0.4572 0.508)
			(layers "F.Cu" "F.Mask" "F.Paste")
			(net "GND")
		)
		(pad "2" smd rect
			(at -0.40005 0)
			(size 0.4572 0.508)
			(layers "F.Cu" "F.Mask" "F.Paste")
			(net "FM_CPLD_NODE1_SYS_PG")
		)
	)
	(footprint ""
		(layer "F.Cu")
		(at 111.87176 -172.625512 180)
		(property "Reference" "R663"
			(at 2.0701 10.374376 0)
			(unlocked yes)
			(layer "F.SilkS")
			(effects
				(font
					(size 0.7874 0.5842)
					(thickness 0.1524)
				)
				(justify left)
			)
		)
		(property "Value" ""
			(at 0 0 180)
			(layer "F.Fab")
			(effects
				(font
					(size 1.27 1.27)
				)
			)
		)
		(duplicate_pad_numbers_are_jumpers no)
		(fp_line
			(start 0.7874 0.4064)
			(end -0.7874 0.4064)
			(stroke
				(width 0.1524)
				(type default)
			)
			(layer "F.SilkS")
		)
		(fp_line
			(start 0.7874 -0.4064)
			(end 0.7874 0.4064)
			(stroke
				(width 0.1524)
				(type default)
			)
			(layer "F.SilkS")
		)
		(fp_line
			(start -0.7874 0.4064)
			(end -0.7874 -0.4064)
			(stroke
				(width 0.1524)
				(type default)
			)
			(layer "F.SilkS")
		)
		(fp_line
			(start -0.7874 -0.4064)
			(end 0.7874 -0.4064)
			(stroke
				(width 0.1524)
				(type default)
			)
			(layer "F.SilkS")
		)
		(fp_poly
			(pts
				(xy -0.508 0.2794) (xy -0.508 0.2286) (xy -0.635 0.2286) (xy -0.635 -0.254) (xy -0.5334 -0.254)
				(xy -0.5334 -0.2794) (xy 0.5334 -0.2794) (xy 0.5334 -0.254) (xy 0.635 -0.254) (xy 0.635 0.254) (xy 0.5334 0.254)
				(xy 0.5334 0.2794)
			)
			(stroke
				(width 0)
				(type default)
			)
			(fill no)
			(layer "F.CrtYd")
		)
		(pad "1" smd rect
			(at 0.40005 0 180)
			(size 0.4572 0.508)
			(layers "F.Cu" "F.Mask" "F.Paste")
			(net "P3V3_NODE1")
		)
		(pad "2" smd rect
			(at -0.40005 0 180)
			(size 0.4572 0.508)
			(layers "F.Cu" "F.Mask" "F.Paste")
			(net "I2C_COM3_SCL")
		)
	)
	(footprint ""
		(layer "F.Cu")
		(at 42.169588 -109.860334)
		(property "Reference" "PC19"
			(at -1.389634 -4.695444 0)
			(unlocked yes)
			(layer "F.SilkS")
			(effects
				(font
					(size 0.7874 0.5842)
					(thickness 0.1524)
				)
				(justify left)
			)
		)
		(property "Value" ""
			(at 0 0 0)
			(layer "F.Fab")
			(effects
				(font
					(size 1.27 1.27)
				)
			)
		)
		(duplicate_pad_numbers_are_jumpers no)
		(fp_line
			(start -0.7874 -0.4064)
			(end 0.7874 -0.4064)
			(stroke
				(width 0.1524)
				(type default)
			)
			(layer "F.SilkS")
		)
		(fp_line
			(start -0.7874 0.4064)
			(end -0.7874 -0.4064)
			(stroke
				(width 0.1524)
				(type default)
			)
			(layer "F.SilkS")
		)
		(fp_line
			(start 0 0.381)
			(end 0 -0.381)
			(stroke
				(width 0.1524)
				(type default)
			)
			(layer "F.SilkS")
		)
		(fp_line
			(start 0.7874 -0.4064)
			(end 0.7874 0.4064)
			(stroke
				(width 0.1524)
				(type default)
			)
			(layer "F.SilkS")
		)
		(fp_line
			(start 0.7874 0.4064)
			(end -0.7874 0.4064)
			(stroke
				(width 0.1524)
				(type default)
			)
			(layer "F.SilkS")
		)
		(fp_poly
			(pts
				(xy -0.5334 0.254) (xy -0.635 0.254) (xy -0.635 0.2286) (xy -0.635 -0.254) (xy -0.5334 -0.254) (xy -0.5334 -0.2794)
				(xy 0.5334 -0.2794) (xy 0.5334 -0.254) (xy 0.635 -0.254) (xy 0.635 0.254) (xy 0.5334 0.254) (xy 0.5334 0.2794)
				(xy -0.508 0.2794) (xy -0.5334 0.2794)
			)
			(stroke
				(width 0)
				(type default)
			)
			(fill no)
			(layer "F.CrtYd")
		)
		(pad "1" smd rect
			(at 0.40005 0)
			(size 0.4572 0.508)
			(layers "F.Cu" "F.Mask" "F.Paste")
			(net "P3V3_STB_NODE1_VREG5")
		)
		(pad "2" smd rect
			(at -0.40005 0)
			(size 0.4572 0.508)
			(layers "F.Cu" "F.Mask" "F.Paste")
			(net "GND")
		)
	)
	(footprint ""
		(layer "F.Cu")
		(at 20.79752 -36.390326)
		(property "Reference" "J34"
			(at -0.05842 2.632202 0)
			(unlocked yes)
			(layer "F.SilkS")
			(effects
				(font
					(size 0.7874 0.5842)
					(thickness 0.1524)
				)
				(justify left)
			)
		)
		(property "Value" ""
			(at 0 0 0)
			(layer "F.Fab")
			(effects
				(font
					(size 1.27 1.27)
				)
			)
		)
		(duplicate_pad_numbers_are_jumpers no)
		(fp_line
			(start -2.739898 -1.27)
			(end -2.739898 1.27)
			(stroke
				(width 0.1524)
				(type default)
			)
			(layer "F.SilkS")
		)
		(fp_line
			(start -2.739898 1.27)
			(end -2.690114 1.27)
			(stroke
				(width 0.1524)
				(type default)
			)
			(layer "F.SilkS")
		)
		(fp_line
			(start -2.739898 1.27)
			(end 2.739898 1.27)
			(stroke
				(width 0.1524)
				(type default)
			)
			(layer "F.SilkS")
		)
		(fp_line
			(start 2.739898 -1.27)
			(end -2.739898 -1.27)
			(stroke
				(width 0.1524)
				(type default)
			)
			(layer "F.SilkS")
		)
		(fp_line
			(start 2.739898 1.27)
			(end 2.739898 -1.27)
			(stroke
				(width 0.1524)
				(type default)
			)
			(layer "F.SilkS")
		)
		(fp_poly
			(pts
				(xy -1.2192 1.7653) (xy -1.9558 3.5687) (xy -0.5842 3.5687)
			)
			(stroke
				(width 0)
				(type default)
			)
			(fill yes)
			(layer "F.SilkS")
		)
		(fp_rect
			(start -2.1844 0.9144)
			(end 2.1844 -0.9144)
			(stroke
				(width 0)
				(type default)
			)
			(fill no)
			(layer "B.CrtYd")
		)
		(fp_poly
			(pts
				(xy -2.739898 1.27) (xy 2.739898 1.27) (xy 2.739898 -1.27) (xy -2.739898 -1.27)
			)
			(stroke
				(width 0)
				(type default)
			)
			(fill no)
			(layer "F.CrtYd")
		)
		(fp_line
			(start -2.739898 -1.27)
			(end -2.739898 1.27)
			(stroke
				(width 0.1)
				(type default)
			)
			(layer "F.Fab")
		)
		(fp_line
			(start -2.739898 1.27)
			(end -2.690114 1.27)
			(stroke
				(width 0.1)
				(type default)
			)
			(layer "F.Fab")
		)
		(fp_line
			(start -2.739898 1.27)
			(end 2.739898 1.27)
			(stroke
				(width 0.1)
				(type default)
			)
			(layer "F.Fab")
		)
		(fp_line
			(start 2.739898 -1.27)
			(end -2.739898 -1.27)
			(stroke
				(width 0.1)
				(type default)
			)
			(layer "F.Fab")
		)
		(fp_line
			(start 2.739898 1.27)
			(end 2.739898 -1.27)
			(stroke
				(width 0.1)
				(type default)
			)
			(layer "F.Fab")
		)
		(fp_poly
			(pts
				(xy -1.2192 1.7653) (xy -1.9558 3.5687) (xy -0.5842 3.5687)
			)
			(stroke
				(width 0)
				(type default)
			)
			(fill yes)
			(layer "F.Fab")
		)
		(fp_text user "1"
			(at -2.49174 2.146046 0)
			(unlocked yes)
			(layer "F.SilkS")
			(effects
				(font
					(size 0.7874 0.5842)
					(thickness 0.1524)
				)
				(justify left)
			)
		)
		(fp_text user "2"
			(at 3.09118 -0.73279 0)
			(unlocked yes)
			(layer "F.SilkS")
			(effects
				(font
					(size 0.7874 0.5842)
					(thickness 0.1524)
				)
				(justify left)
			)
		)
		(fp_text user "1"
			(at -0.97536 -1.573784 0)
			(unlocked yes)
			(layer "B.SilkS")
			(effects
				(font
					(size 0.7874 0.5842)
					(thickness 0.1524)
				)
				(justify left mirror)
			)
		)
		(fp_text user "2"
			(at 1.59512 -1.492504 0)
			(unlocked yes)
			(layer "B.SilkS")
			(effects
				(font
					(size 0.7874 0.5842)
					(thickness 0.1524)
				)
				(justify left mirror)
			)
		)
		(fp_text user "1"
			(at -1.9431 -0.18669 0)
			(unlocked yes)
			(layer "B.Fab")
			(effects
				(font
					(size 1.6002 1.1938)
					(thickness 0.000001)
				)
				(justify left mirror)
			)
		)
		(fp_text user "2"
			(at 3.1369 -0.18669 0)
			(unlocked yes)
			(layer "B.Fab")
			(effects
				(font
					(size 1.6002 1.1938)
					(thickness 0.000001)
				)
				(justify left mirror)
			)
		)
		(fp_text user "1"
			(at -2.8829 2.48031 0)
			(unlocked yes)
			(layer "F.Fab")
			(effects
				(font
					(size 1.6002 1.1938)
					(thickness 0.000001)
				)
				(justify left)
			)
		)
		(fp_text user "2"
			(at 0.6731 2.48031 0)
			(unlocked yes)
			(layer "F.Fab")
			(effects
				(font
					(size 1.6002 1.1938)
					(thickness 0.000001)
				)
				(justify left)
			)
		)
		(pad "1" thru_hole rect
			(at -1.27 0)
			(size 1.7272 1.7272)
			(drill 1.2192)
			(layers "*.Cu" "*.Mask")
			(remove_unused_layers no)
			(net "CONSOLE_SELECT_N")
			(clearance 0)
			(padstack
				(mode front_inner_back)
				(layer "Inner"
					(shape circle)
					(size 1.7272 1.7272)
					(clearance 0)
				)
				(layer "B.Cu"
					(shape rect)
					(size 1.7272 1.7272)
					(clearance 0)
				)
			)
		)
		(pad "2" thru_hole circle
			(at 1.27 0)
			(size 1.7272 1.7272)
			(drill 1.2192)
			(layers "*.Cu" "*.Mask")
			(remove_unused_layers no)
			(net "GND")
			(clearance 0)
		)
	)
	(footprint ""
		(layer "F.Cu")
		(at 79.366364 -17.679416 90)
		(property "Reference" "C149"
			(at -4.546854 5.52323 90)
			(unlocked yes)
			(layer "F.SilkS")
			(effects
				(font
					(size 0.7874 0.5842)
					(thickness 0.1524)
				)
				(justify left)
			)
		)
		(property "Value" ""
			(at 0 0 90)
			(layer "F.Fab")
			(effects
				(font
					(size 1.27 1.27)
				)
			)
		)
		(duplicate_pad_numbers_are_jumpers no)
		(fp_line
			(start 0.7874 -0.4064)
			(end 0.7874 0.4064)
			(stroke
				(width 0.1524)
				(type default)
			)
			(layer "F.SilkS")
		)
		(fp_line
			(start -0.7874 -0.4064)
			(end 0.7874 -0.4064)
			(stroke
				(width 0.1524)
				(type default)
			)
			(layer "F.SilkS")
		)
		(fp_line
			(start 0 0.381)
			(end 0 -0.381)
			(stroke
				(width 0.1524)
				(type default)
			)
			(layer "F.SilkS")
		)
		(fp_line
			(start 0.7874 0.4064)
			(end -0.7874 0.4064)
			(stroke
				(width 0.1524)
				(type default)
			)
			(layer "F.SilkS")
		)
		(fp_line
			(start -0.7874 0.4064)
			(end -0.7874 -0.4064)
			(stroke
				(width 0.1524)
				(type default)
			)
			(layer "F.SilkS")
		)
		(fp_poly
			(pts
				(xy -0.5334 0.254) (xy -0.635 0.254) (xy -0.635 0.2286) (xy -0.635 -0.254) (xy -0.5334 -0.254) (xy -0.5334 -0.2794)
				(xy 0.5334 -0.2794) (xy 0.5334 -0.254) (xy 0.635 -0.254) (xy 0.635 0.254) (xy 0.5334 0.254) (xy 0.5334 0.2794)
				(xy -0.508 0.2794) (xy -0.5334 0.2794)
			)
			(stroke
				(width 0)
				(type default)
			)
			(fill no)
			(layer "F.CrtYd")
		)
		(pad "1" smd rect
			(at 0.40005 0 90)
			(size 0.4572 0.508)
			(layers "F.Cu" "F.Mask" "F.Paste")
			(net "PV_VDDR_NODE1")
		)
		(pad "2" smd rect
			(at -0.40005 0 90)
			(size 0.4572 0.508)
			(layers "F.Cu" "F.Mask" "F.Paste")
			(net "GND")
		)
	)
	(footprint ""
		(layer "F.Cu")
		(at 142.73276 -115.863624 180)
		(property "Reference" "R13"
			(at -1.512824 0.105918 0)
			(unlocked yes)
			(layer "F.SilkS")
			(effects
				(font
					(size 0.7874 0.5842)
					(thickness 0.1524)
				)
				(justify left)
			)
		)
		(property "Value" ""
			(at 0 0 180)
			(layer "F.Fab")
			(effects
				(font
					(size 1.27 1.27)
				)
			)
		)
		(duplicate_pad_numbers_are_jumpers no)
		(fp_line
			(start 0.7874 0.4064)
			(end -0.7874 0.4064)
			(stroke
				(width 0.1524)
				(type default)
			)
			(layer "F.SilkS")
		)
		(fp_line
			(start 0.7874 -0.4064)
			(end 0.7874 0.4064)
			(stroke
				(width 0.1524)
				(type default)
			)
			(layer "F.SilkS")
		)
		(fp_line
			(start -0.7874 0.4064)
			(end -0.7874 -0.4064)
			(stroke
				(width 0.1524)
				(type default)
			)
			(layer "F.SilkS")
		)
		(fp_line
			(start -0.7874 -0.4064)
			(end 0.7874 -0.4064)
			(stroke
				(width 0.1524)
				(type default)
			)
			(layer "F.SilkS")
		)
		(fp_poly
			(pts
				(xy -0.508 0.2794) (xy -0.508 0.2286) (xy -0.635 0.2286) (xy -0.635 -0.254) (xy -0.5334 -0.254)
				(xy -0.5334 -0.2794) (xy 0.5334 -0.2794) (xy 0.5334 -0.254) (xy 0.635 -0.254) (xy 0.635 0.254) (xy 0.5334 0.254)
				(xy 0.5334 0.2794)
			)
			(stroke
				(width 0)
				(type default)
			)
			(fill no)
			(layer "F.CrtYd")
		)
		(pad "1" smd rect
			(at 0.40005 0 180)
			(size 0.4572 0.508)
			(layers "F.Cu" "F.Mask" "F.Paste")
			(net "CLKREQB_NODE1_N")
		)
		(pad "2" smd rect
			(at -0.40005 0 180)
			(size 0.4572 0.508)
			(layers "F.Cu" "F.Mask" "F.Paste")
			(net "P3V3_CLK_NODE1")
		)
	)
	(footprint ""
		(layer "F.Cu")
		(at 191.369442 -114.562128 180)
		(property "Reference" "R1028"
			(at -1.483614 -0.118364 0)
			(unlocked yes)
			(layer "F.SilkS")
			(effects
				(font
					(size 0.7874 0.5842)
					(thickness 0.1524)
				)
				(justify left)
			)
		)
		(property "Value" ""
			(at 0 0 180)
			(layer "F.Fab")
			(effects
				(font
					(size 1.27 1.27)
				)
			)
		)
		(duplicate_pad_numbers_are_jumpers no)
		(fp_line
			(start 0.7874 0.4064)
			(end -0.7874 0.4064)
			(stroke
				(width 0.1524)
				(type default)
			)
			(layer "F.SilkS")
		)
		(fp_line
			(start 0.7874 -0.4064)
			(end 0.7874 0.4064)
			(stroke
				(width 0.1524)
				(type default)
			)
			(layer "F.SilkS")
		)
		(fp_line
			(start -0.7874 0.4064)
			(end -0.7874 -0.4064)
			(stroke
				(width 0.1524)
				(type default)
			)
			(layer "F.SilkS")
		)
		(fp_line
			(start -0.7874 -0.4064)
			(end 0.7874 -0.4064)
			(stroke
				(width 0.1524)
				(type default)
			)
			(layer "F.SilkS")
		)
		(fp_poly
			(pts
				(xy -0.508 0.2794) (xy -0.508 0.2286) (xy -0.635 0.2286) (xy -0.635 -0.254) (xy -0.5334 -0.254)
				(xy -0.5334 -0.2794) (xy 0.5334 -0.2794) (xy 0.5334 -0.254) (xy 0.635 -0.254) (xy 0.635 0.254) (xy 0.5334 0.254)
				(xy 0.5334 0.2794)
			)
			(stroke
				(width 0)
				(type default)
			)
			(fill no)
			(layer "F.CrtYd")
		)
		(pad "1" smd rect
			(at 0.40005 0 180)
			(size 0.4572 0.508)
			(layers "F.Cu" "F.Mask" "F.Paste")
			(net "P12V_NODE1_PWRGD_EN")
		)
		(pad "2" smd rect
			(at -0.40005 0 180)
			(size 0.4572 0.508)
			(layers "F.Cu" "F.Mask" "F.Paste")
			(net "GND")
		)
	)
	(footprint ""
		(layer "F.Cu")
		(at 95.047562 -123.558046 -90)
		(property "Reference" "C1119"
			(at -0.09144 -0.626364 0)
			(unlocked yes)
			(layer "F.SilkS")
			(effects
				(font
					(size 0.7874 0.5842)
					(thickness 0.1524)
				)
				(justify left)
			)
		)
		(property "Value" ""
			(at 0 0 270)
			(layer "F.Fab")
			(effects
				(font
					(size 1.27 1.27)
				)
			)
		)
		(duplicate_pad_numbers_are_jumpers no)
		(fp_line
			(start -0.7874 0.4064)
			(end -0.7874 -0.4064)
			(stroke
				(width 0.1524)
				(type default)
			)
			(layer "F.SilkS")
		)
		(fp_line
			(start 0.7874 0.4064)
			(end -0.7874 0.4064)
			(stroke
				(width 0.1524)
				(type default)
			)
			(layer "F.SilkS")
		)
		(fp_line
			(start 0 0.381)
			(end 0 -0.381)
			(stroke
				(width 0.1524)
				(type default)
			)
			(layer "F.SilkS")
		)
		(fp_line
			(start -0.7874 -0.4064)
			(end 0.7874 -0.4064)
			(stroke
				(width 0.1524)
				(type default)
			)
			(layer "F.SilkS")
		)
		(fp_line
			(start 0.7874 -0.4064)
			(end 0.7874 0.4064)
			(stroke
				(width 0.1524)
				(type default)
			)
			(layer "F.SilkS")
		)
		(fp_poly
			(pts
				(xy -0.5334 0.254) (xy -0.635 0.254) (xy -0.635 0.2286) (xy -0.635 -0.254) (xy -0.5334 -0.254) (xy -0.5334 -0.2794)
				(xy 0.5334 -0.2794) (xy 0.5334 -0.254) (xy 0.635 -0.254) (xy 0.635 0.254) (xy 0.5334 0.254) (xy 0.5334 0.2794)
				(xy -0.508 0.2794) (xy -0.5334 0.2794)
			)
			(stroke
				(width 0)
				(type default)
			)
			(fill no)
			(layer "F.CrtYd")
		)
		(pad "1" smd rect
			(at 0.40005 0 270)
			(size 0.4572 0.508)
			(layers "F.Cu" "F.Mask" "F.Paste")
			(net "GND")
		)
		(pad "2" smd rect
			(at -0.40005 0 270)
			(size 0.4572 0.508)
			(layers "F.Cu" "F.Mask" "F.Paste")
			(net "P3V3_NODE1")
		)
	)
	(footprint ""
		(layer "F.Cu")
		(at 85.96376 -188.126624 90)
		(property "Reference" "C717"
			(at 4.548886 -1.831848 90)
			(unlocked yes)
			(layer "F.SilkS")
			(effects
				(font
					(size 0.7874 0.5842)
					(thickness 0.1524)
				)
				(justify left)
			)
		)
		(property "Value" ""
			(at 0 0 90)
			(layer "F.Fab")
			(effects
				(font
					(size 1.27 1.27)
				)
			)
		)
		(duplicate_pad_numbers_are_jumpers no)
		(fp_line
			(start 0.7874 -0.4064)
			(end 0.7874 0.4064)
			(stroke
				(width 0.1524)
				(type default)
			)
			(layer "F.SilkS")
		)
		(fp_line
			(start -0.7874 -0.4064)
			(end 0.7874 -0.4064)
			(stroke
				(width 0.1524)
				(type default)
			)
			(layer "F.SilkS")
		)
		(fp_line
			(start 0 0.381)
			(end 0 -0.381)
			(stroke
				(width 0.1524)
				(type default)
			)
			(layer "F.SilkS")
		)
		(fp_line
			(start 0.7874 0.4064)
			(end -0.7874 0.4064)
			(stroke
				(width 0.1524)
				(type default)
			)
			(layer "F.SilkS")
		)
		(fp_line
			(start -0.7874 0.4064)
			(end -0.7874 -0.4064)
			(stroke
				(width 0.1524)
				(type default)
			)
			(layer "F.SilkS")
		)
		(fp_poly
			(pts
				(xy -0.5334 0.254) (xy -0.635 0.254) (xy -0.635 0.2286) (xy -0.635 -0.254) (xy -0.5334 -0.254) (xy -0.5334 -0.2794)
				(xy 0.5334 -0.2794) (xy 0.5334 -0.254) (xy 0.635 -0.254) (xy 0.635 0.254) (xy 0.5334 0.254) (xy 0.5334 0.2794)
				(xy -0.508 0.2794) (xy -0.5334 0.2794)
			)
			(stroke
				(width 0)
				(type default)
			)
			(fill no)
			(layer "F.CrtYd")
		)
		(pad "1" smd rect
			(at 0.40005 0 90)
			(size 0.4572 0.508)
			(layers "F.Cu" "F.Mask" "F.Paste")
			(net "UART_T6_NODE4_TXD_R")
		)
		(pad "2" smd rect
			(at -0.40005 0 90)
			(size 0.4572 0.508)
			(layers "F.Cu" "F.Mask" "F.Paste")
			(net "GND")
		)
	)
	(footprint ""
		(layer "F.Cu")
		(at 11.71956 -138.620246 -90)
		(property "Reference" "C562"
			(at 4.252468 5.096002 90)
			(unlocked yes)
			(layer "F.SilkS")
			(effects
				(font
					(size 0.7874 0.5842)
					(thickness 0.1524)
				)
				(justify left)
			)
		)
		(property "Value" ""
			(at 0 0 270)
			(layer "F.Fab")
			(effects
				(font
					(size 1.27 1.27)
				)
			)
		)
		(duplicate_pad_numbers_are_jumpers no)
		(fp_line
			(start -0.7874 0.4064)
			(end -0.7874 -0.4064)
			(stroke
				(width 0.1524)
				(type default)
			)
			(layer "F.SilkS")
		)
		(fp_line
			(start 0.7874 0.4064)
			(end -0.7874 0.4064)
			(stroke
				(width 0.1524)
				(type default)
			)
			(layer "F.SilkS")
		)
		(fp_line
			(start 0 0.381)
			(end 0 -0.381)
			(stroke
				(width 0.1524)
				(type default)
			)
			(layer "F.SilkS")
		)
		(fp_line
			(start -0.7874 -0.4064)
			(end 0.7874 -0.4064)
			(stroke
				(width 0.1524)
				(type default)
			)
			(layer "F.SilkS")
		)
		(fp_line
			(start 0.7874 -0.4064)
			(end 0.7874 0.4064)
			(stroke
				(width 0.1524)
				(type default)
			)
			(layer "F.SilkS")
		)
		(fp_poly
			(pts
				(xy -0.5334 0.254) (xy -0.635 0.254) (xy -0.635 0.2286) (xy -0.635 -0.254) (xy -0.5334 -0.254) (xy -0.5334 -0.2794)
				(xy 0.5334 -0.2794) (xy 0.5334 -0.254) (xy 0.635 -0.254) (xy 0.635 0.254) (xy 0.5334 0.254) (xy 0.5334 0.2794)
				(xy -0.508 0.2794) (xy -0.5334 0.2794)
			)
			(stroke
				(width 0)
				(type default)
			)
			(fill no)
			(layer "F.CrtYd")
		)
		(pad "1" smd rect
			(at 0.40005 0 270)
			(size 0.4572 0.508)
			(layers "F.Cu" "F.Mask" "F.Paste")
			(net "GND")
		)
		(pad "2" smd rect
			(at -0.40005 0 270)
			(size 0.4572 0.508)
			(layers "F.Cu" "F.Mask" "F.Paste")
			(net "N54310604")
		)
	)
	(footprint ""
		(layer "F.Cu")
		(at 75.18527 -119.870728)
		(property "Reference" "C202"
			(at -4.55422 0.23114 0)
			(unlocked yes)
			(layer "F.SilkS")
			(effects
				(font
					(size 0.7874 0.5842)
					(thickness 0.1524)
				)
				(justify left)
			)
		)
		(property "Value" ""
			(at 0 0 0)
			(layer "F.Fab")
			(effects
				(font
					(size 1.27 1.27)
				)
			)
		)
		(duplicate_pad_numbers_are_jumpers no)
		(fp_line
			(start -0.7874 -0.4064)
			(end 0.7874 -0.4064)
			(stroke
				(width 0.1524)
				(type default)
			)
			(layer "F.SilkS")
		)
		(fp_line
			(start -0.7874 0.4064)
			(end -0.7874 -0.4064)
			(stroke
				(width 0.1524)
				(type default)
			)
			(layer "F.SilkS")
		)
		(fp_line
			(start 0 0.381)
			(end 0 -0.381)
			(stroke
				(width 0.1524)
				(type default)
			)
			(layer "F.SilkS")
		)
		(fp_line
			(start 0.7874 -0.4064)
			(end 0.7874 0.4064)
			(stroke
				(width 0.1524)
				(type default)
			)
			(layer "F.SilkS")
		)
		(fp_line
			(start 0.7874 0.4064)
			(end -0.7874 0.4064)
			(stroke
				(width 0.1524)
				(type default)
			)
			(layer "F.SilkS")
		)
		(fp_poly
			(pts
				(xy -0.5334 0.254) (xy -0.635 0.254) (xy -0.635 0.2286) (xy -0.635 -0.254) (xy -0.5334 -0.254) (xy -0.5334 -0.2794)
				(xy 0.5334 -0.2794) (xy 0.5334 -0.254) (xy 0.635 -0.254) (xy 0.635 0.254) (xy 0.5334 0.254) (xy 0.5334 0.2794)
				(xy -0.508 0.2794) (xy -0.5334 0.2794)
			)
			(stroke
				(width 0)
				(type default)
			)
			(fill no)
			(layer "F.CrtYd")
		)
		(pad "1" smd rect
			(at 0.40005 0)
			(size 0.4572 0.508)
			(layers "F.Cu" "F.Mask" "F.Paste")
			(net "P2E_CPU_BMC_NODE1_RX_DP")
		)
		(pad "2" smd rect
			(at -0.40005 0)
			(size 0.4572 0.508)
			(layers "F.Cu" "F.Mask" "F.Paste")
			(net "P2E_CPU_BMC_NODE1_RX_C_DP")
		)
	)
	(footprint ""
		(layer "F.Cu")
		(at 42.332402 -145.804382 -90)
		(property "Reference" "R548"
			(at 0.86106 6.618732 90)
			(unlocked yes)
			(layer "F.SilkS")
			(effects
				(font
					(size 0.7874 0.5842)
					(thickness 0.1524)
				)
				(justify left)
			)
		)
		(property "Value" ""
			(at 0 0 270)
			(layer "F.Fab")
			(effects
				(font
					(size 1.27 1.27)
				)
			)
		)
		(duplicate_pad_numbers_are_jumpers no)
		(fp_line
			(start -0.7874 0.4064)
			(end -0.7874 -0.4064)
			(stroke
				(width 0.1524)
				(type default)
			)
			(layer "F.SilkS")
		)
		(fp_line
			(start 0.7874 0.4064)
			(end -0.7874 0.4064)
			(stroke
				(width 0.1524)
				(type default)
			)
			(layer "F.SilkS")
		)
		(fp_line
			(start -0.7874 -0.4064)
			(end 0.7874 -0.4064)
			(stroke
				(width 0.1524)
				(type default)
			)
			(layer "F.SilkS")
		)
		(fp_line
			(start 0.7874 -0.4064)
			(end 0.7874 0.4064)
			(stroke
				(width 0.1524)
				(type default)
			)
			(layer "F.SilkS")
		)
		(fp_poly
			(pts
				(xy -0.508 0.2794) (xy -0.508 0.2286) (xy -0.635 0.2286) (xy -0.635 -0.254) (xy -0.5334 -0.254)
				(xy -0.5334 -0.2794) (xy 0.5334 -0.2794) (xy 0.5334 -0.254) (xy 0.635 -0.254) (xy 0.635 0.254) (xy 0.5334 0.254)
				(xy 0.5334 0.2794)
			)
			(stroke
				(width 0)
				(type default)
			)
			(fill no)
			(layer "F.CrtYd")
		)
		(pad "1" smd rect
			(at 0.40005 0 270)
			(size 0.4572 0.508)
			(layers "F.Cu" "F.Mask" "F.Paste")
			(net "P3V3_NODE1")
		)
		(pad "2" smd rect
			(at -0.40005 0 270)
			(size 0.4572 0.508)
			(layers "F.Cu" "F.Mask" "F.Paste")
			(net "LAN1_NC_SI_RXD0")
		)
	)
	(footprint ""
		(layer "F.Cu")
		(at 149.213824 -20.568412 90)
		(property "Reference" "J6"
			(at -2.457196 3.232658 90)
			(unlocked yes)
			(layer "F.SilkS")
			(effects
				(font
					(size 0.7874 0.5842)
					(thickness 0.1524)
				)
				(justify left)
			)
		)
		(property "Value" ""
			(at 0 0 90)
			(layer "F.Fab")
			(effects
				(font
					(size 1.27 1.27)
				)
			)
		)
		(duplicate_pad_numbers_are_jumpers no)
		(fp_line
			(start 4.99999 -2.100072)
			(end -4.99999 -2.100072)
			(stroke
				(width 0.1524)
				(type default)
			)
			(layer "F.SilkS")
		)
		(fp_line
			(start -4.99999 -2.100072)
			(end -4.99999 0)
			(stroke
				(width 0.1524)
				(type default)
			)
			(layer "F.SilkS")
		)
		(fp_line
			(start 4.500118 -1.599946)
			(end 4.500118 2.100072)
			(stroke
				(width 0.1524)
				(type default)
			)
			(layer "F.SilkS")
		)
		(fp_line
			(start -2.3876 -1.599946)
			(end 4.500118 -1.599946)
			(stroke
				(width 0.1524)
				(type default)
			)
			(layer "F.SilkS")
		)
		(fp_line
			(start -4.500118 -1.599946)
			(end -3.6068 -1.599946)
			(stroke
				(width 0.1524)
				(type default)
			)
			(layer "F.SilkS")
		)
		(fp_line
			(start -4.99999 0)
			(end -4.99999 2.599944)
			(stroke
				(width 0.1524)
				(type default)
			)
			(layer "F.SilkS")
		)
		(fp_line
			(start 4.500118 2.100072)
			(end 1.999996 2.100072)
			(stroke
				(width 0.1524)
				(type default)
			)
			(layer "F.SilkS")
		)
		(fp_line
			(start 1.999996 2.100072)
			(end 1.999996 2.599944)
			(stroke
				(width 0.1524)
				(type default)
			)
			(layer "F.SilkS")
		)
		(fp_line
			(start -1.999996 2.100072)
			(end -4.500118 2.100072)
			(stroke
				(width 0.1524)
				(type default)
			)
			(layer "F.SilkS")
		)
		(fp_line
			(start -4.500118 2.100072)
			(end -4.500118 -1.599946)
			(stroke
				(width 0.1524)
				(type default)
			)
			(layer "F.SilkS")
		)
		(fp_line
			(start 4.99999 2.599944)
			(end 4.99999 -2.100072)
			(stroke
				(width 0.1524)
				(type default)
			)
			(layer "F.SilkS")
		)
		(fp_line
			(start -1.999996 2.599944)
			(end -1.999996 2.100072)
			(stroke
				(width 0.1524)
				(type default)
			)
			(layer "F.SilkS")
		)
		(fp_line
			(start -4.99999 2.599944)
			(end 4.99999 2.599944)
			(stroke
				(width 0.1524)
				(type default)
			)
			(layer "F.SilkS")
		)
		(fp_poly
			(pts
				(xy 5.115306 -0.578358) (xy 6.639306 -1.340358) (xy 6.639306 0.183642)
			)
			(stroke
				(width 0)
				(type default)
			)
			(fill yes)
			(layer "F.SilkS")
		)
		(fp_poly
			(pts
				(xy -3.7084 0.1778) (xy 3.683 0.1778) (xy 3.683 1.6256) (xy -3.7084 1.6256)
			)
			(stroke
				(width 0)
				(type default)
			)
			(fill no)
			(layer "B.CrtYd")
		)
		(fp_poly
			(pts
				(arc
					(start -2.9972 -1.7526)
					(mid -3.607857 -1.499657)
					(end -3.8608 -0.889)
				)
				(arc
					(start -3.8608 -0.889)
					(mid -3.615297 -0.296303)
					(end -3.0226 -0.0508)
				)
				(arc
					(start -2.9972 -0.0508)
					(mid -2.1463 -0.9017)
					(end -2.9972 -1.7526)
				)
			)
			(stroke
				(width 0)
				(type default)
			)
			(fill no)
			(layer "B.CrtYd")
		)
		(fp_rect
			(start -4.99999 2.599944)
			(end 4.99999 -2.100072)
			(stroke
				(width 0)
				(type default)
			)
			(fill no)
			(layer "F.CrtYd")
		)
		(fp_line
			(start 4.99999 -2.100072)
			(end -4.99999 -2.100072)
			(stroke
				(width 0.1)
				(type default)
			)
			(layer "F.Fab")
		)
		(fp_line
			(start -4.99999 -2.100072)
			(end -4.99999 0)
			(stroke
				(width 0.1)
				(type default)
			)
			(layer "F.Fab")
		)
		(fp_line
			(start 4.500118 -1.599946)
			(end 4.500118 2.100072)
			(stroke
				(width 0.1)
				(type default)
			)
			(layer "F.Fab")
		)
		(fp_line
			(start -3.6576 -1.599946)
			(end 4.500118 -1.599946)
			(stroke
				(width 0.1)
				(type default)
			)
			(layer "F.Fab")
		)
		(fp_line
			(start -4.500118 -1.599946)
			(end -3.6068 -1.599946)
			(stroke
				(width 0.1)
				(type default)
			)
			(layer "F.Fab")
		)
		(fp_line
			(start -4.99999 0)
			(end -4.99999 2.599944)
			(stroke
				(width 0.1)
				(type default)
			)
			(layer "F.Fab")
		)
		(fp_line
			(start 4.500118 2.100072)
			(end 1.999996 2.100072)
			(stroke
				(width 0.1)
				(type default)
			)
			(layer "F.Fab")
		)
		(fp_line
			(start 1.999996 2.100072)
			(end 1.999996 2.599944)
			(stroke
				(width 0.1)
				(type default)
			)
			(layer "F.Fab")
		)
		(fp_line
			(start -1.999996 2.100072)
			(end -4.500118 2.100072)
			(stroke
				(width 0.1)
				(type default)
			)
			(layer "F.Fab")
		)
		(fp_line
			(start -4.500118 2.100072)
			(end -4.500118 -1.599946)
			(stroke
				(width 0.1)
				(type default)
			)
			(layer "F.Fab")
		)
		(fp_line
			(start 4.99999 2.599944)
			(end 4.99999 -2.100072)
			(stroke
				(width 0.1)
				(type default)
			)
			(layer "F.Fab")
		)
		(fp_line
			(start -1.999996 2.599944)
			(end -1.999996 2.100072)
			(stroke
				(width 0.1)
				(type default)
			)
			(layer "F.Fab")
		)
		(fp_line
			(start -4.99999 2.599944)
			(end 4.99999 2.599944)
			(stroke
				(width 0.1)
				(type default)
			)
			(layer "F.Fab")
		)
		(fp_poly
			(pts
				(xy 5.715 0.899922) (xy 7.239 0.137922) (xy 7.239 1.661922)
			)
			(stroke
				(width 0)
				(type default)
			)
			(fill yes)
			(layer "F.Fab")
		)
		(fp_text user "1"
			(at 4.39674 -2.86766 0)
			(unlocked yes)
			(layer "F.SilkS")
			(effects
				(font
					(size 0.7874 0.5842)
					(thickness 0.1524)
				)
				(justify left)
			)
		)
		(fp_text user "4"
			(at -5.4356 -0.850646 0)
			(unlocked yes)
			(layer "F.SilkS")
			(effects
				(font
					(size 0.7874 0.5842)
					(thickness 0.1524)
				)
				(justify left)
			)
		)
		(fp_text user "4"
			(at -4.471162 1.331214 0)
			(unlocked yes)
			(layer "B.SilkS")
			(effects
				(font
					(size 0.7874 0.5842)
					(thickness 0.1524)
				)
				(justify left mirror)
			)
		)
		(fp_text user "1"
			(at 3.991864 2.68732 0)
			(unlocked yes)
			(layer "B.SilkS")
			(effects
				(font
					(size 0.7874 0.5842)
					(thickness 0.1524)
				)
				(justify left mirror)
			)
		)
		(fp_text user "1"
			(at 4.4831 0.808203 90)
			(unlocked yes)
			(layer "B.Fab")
			(effects
				(font
					(size 0.786892 0.583946)
					(thickness 0.000001)
				)
				(justify left mirror)
			)
		)
		(fp_text user "4"
			(at -3.8989 0.808203 90)
			(unlocked yes)
			(layer "B.Fab")
			(effects
				(font
					(size 0.786892 0.583946)
					(thickness 0.000001)
				)
				(justify left mirror)
			)
		)
		(fp_text user "1"
			(at 5.0419 0.808203 90)
			(unlocked yes)
			(layer "F.Fab")
			(effects
				(font
					(size 0.786892 0.583946)
					(thickness 0.000001)
				)
				(justify left)
			)
		)
		(fp_text user "4"
			(at -6.0071 0.808203 90)
			(unlocked yes)
			(layer "F.Fab")
			(effects
				(font
					(size 0.786892 0.583946)
					(thickness 0.000001)
				)
				(justify left)
			)
		)
		(pad "" np_thru_hole circle
			(at -2.999994 -0.899922 90)
			(size 1.1938 1.1938)
			(drill 1.1938)
			(layers "*.Cu" "*.Mask")
			(clearance 0.381)
			(thermal_gap 0.381)
		)
		(pad "1" thru_hole rect
			(at 2.999994 0.899922 90)
			(size 1.3208 1.3208)
			(drill 0.9144)
			(layers "*.Cu" "*.Mask")
			(remove_unused_layers no)
			(net "P3V3_NODE1")
			(clearance 0.0508)
			(thermal_gap 0.0508)
			(padstack
				(mode front_inner_back)
				(layer "Inner"
					(shape circle)
					(size 1.3208 1.3208)
					(clearance 0.0508)
				)
				(layer "B.Cu"
					(shape rect)
					(size 1.3208 1.3208)
					(clearance 0.0508)
				)
			)
		)
		(pad "2" thru_hole circle
			(at 0.999998 0.899922 90)
			(size 1.3208 1.3208)
			(drill 0.9144)
			(layers "*.Cu" "*.Mask")
			(remove_unused_layers no)
			(net "UART_TX_P4")
			(clearance 0.0508)
			(thermal_gap 0.0508)
		)
		(pad "3" thru_hole circle
			(at -0.999998 0.899922 90)
			(size 1.3208 1.3208)
			(drill 0.9144)
			(layers "*.Cu" "*.Mask")
			(remove_unused_layers no)
			(net "UART_RX_P4_BUF")
			(clearance 0.0508)
			(thermal_gap 0.0508)
		)
		(pad "4" thru_hole circle
			(at -2.999994 0.899922 90)
			(size 1.3208 1.3208)
			(drill 0.9144)
			(layers "*.Cu" "*.Mask")
			(remove_unused_layers no)
			(net "GND")
			(clearance 0.0508)
			(thermal_gap 0.0508)
		)
		(zone
			(layers "F.Cu" "B.Cu" "In1.Cu" "In2.Cu" "In3.Cu" "In4.Cu" "In5.Cu" "In6.Cu"
				"In7.Cu" "In8.Cu"
			)
			(hatch none 0.5)
			(connect_pads
				(clearance 0)
			)
			(min_thickness 0.25)
			(keepout
				(tracks not_allowed)
				(vias allowed)
				(pads allowed)
				(copperpour not_allowed)
				(footprints allowed)
			)
			(placement
				(enabled no)
				(sheetname "")
			)
			(fill
				(thermal_gap 0.5)
				(thermal_bridge_width 0.5)
				(island_removal_mode 0)
			)
			(polygon
				(pts
					(arc
						(start 147.308824 -17.571212)
						(mid 147.606404 -16.852792)
						(end 148.324824 -16.555212)
					)
					(arc
						(start 148.324824 -16.555212)
						(mid 149.025284 -16.845352)
						(end 149.315424 -17.545812)
					)
					(arc
						(start 149.315424 -17.571212)
						(mid 148.312124 -18.574512)
						(end 147.308824 -17.571212)
					)
				)
			)
		)
	)
	(footprint ""
		(layer "F.Cu")
		(at 132.31876 -188.126624 90)
		(property "Reference" "C752"
			(at 4.949444 -0.957072 90)
			(unlocked yes)
			(layer "F.SilkS")
			(effects
				(font
					(size 0.7874 0.5842)
					(thickness 0.1524)
				)
				(justify left)
			)
		)
		(property "Value" ""
			(at 0 0 90)
			(layer "F.Fab")
			(effects
				(font
					(size 1.27 1.27)
				)
			)
		)
		(duplicate_pad_numbers_are_jumpers no)
		(fp_line
			(start 0.7874 -0.4064)
			(end 0.7874 0.4064)
			(stroke
				(width 0.1524)
				(type default)
			)
			(layer "F.SilkS")
		)
		(fp_line
			(start -0.7874 -0.4064)
			(end 0.7874 -0.4064)
			(stroke
				(width 0.1524)
				(type default)
			)
			(layer "F.SilkS")
		)
		(fp_line
			(start 0 0.381)
			(end 0 -0.381)
			(stroke
				(width 0.1524)
				(type default)
			)
			(layer "F.SilkS")
		)
		(fp_line
			(start 0.7874 0.4064)
			(end -0.7874 0.4064)
			(stroke
				(width 0.1524)
				(type default)
			)
			(layer "F.SilkS")
		)
		(fp_line
			(start -0.7874 0.4064)
			(end -0.7874 -0.4064)
			(stroke
				(width 0.1524)
				(type default)
			)
			(layer "F.SilkS")
		)
		(fp_poly
			(pts
				(xy -0.5334 0.254) (xy -0.635 0.254) (xy -0.635 0.2286) (xy -0.635 -0.254) (xy -0.5334 -0.254) (xy -0.5334 -0.2794)
				(xy 0.5334 -0.2794) (xy 0.5334 -0.254) (xy 0.635 -0.254) (xy 0.635 0.254) (xy 0.5334 0.254) (xy 0.5334 0.2794)
				(xy -0.508 0.2794) (xy -0.5334 0.2794)
			)
			(stroke
				(width 0)
				(type default)
			)
			(fill no)
			(layer "F.CrtYd")
		)
		(pad "1" smd rect
			(at 0.40005 0 90)
			(size 0.4572 0.508)
			(layers "F.Cu" "F.Mask" "F.Paste")
			(net "UART_T10_NODE2_TXD_R")
		)
		(pad "2" smd rect
			(at -0.40005 0 90)
			(size 0.4572 0.508)
			(layers "F.Cu" "F.Mask" "F.Paste")
			(net "GND")
		)
	)
	(footprint ""
		(layer "F.Cu")
		(at 149.392894 -45.70857)
		(property "Reference" "R626"
			(at -2.3368 -2.962148 0)
			(unlocked yes)
			(layer "F.SilkS")
			(effects
				(font
					(size 0.7874 0.5842)
					(thickness 0.1524)
				)
				(justify left)
			)
		)
		(property "Value" ""
			(at 0 0 0)
			(layer "F.Fab")
			(effects
				(font
					(size 1.27 1.27)
				)
			)
		)
		(duplicate_pad_numbers_are_jumpers no)
		(fp_line
			(start -0.7874 -0.4064)
			(end 0.7874 -0.4064)
			(stroke
				(width 0.1524)
				(type default)
			)
			(layer "F.SilkS")
		)
		(fp_line
			(start -0.7874 0.4064)
			(end -0.7874 -0.4064)
			(stroke
				(width 0.1524)
				(type default)
			)
			(layer "F.SilkS")
		)
		(fp_line
			(start 0.7874 -0.4064)
			(end 0.7874 0.4064)
			(stroke
				(width 0.1524)
				(type default)
			)
			(layer "F.SilkS")
		)
		(fp_line
			(start 0.7874 0.4064)
			(end -0.7874 0.4064)
			(stroke
				(width 0.1524)
				(type default)
			)
			(layer "F.SilkS")
		)
		(fp_poly
			(pts
				(xy -0.508 0.2794) (xy -0.508 0.2286) (xy -0.635 0.2286) (xy -0.635 -0.254) (xy -0.5334 -0.254)
				(xy -0.5334 -0.2794) (xy 0.5334 -0.2794) (xy 0.5334 -0.254) (xy 0.635 -0.254) (xy 0.635 0.254) (xy 0.5334 0.254)
				(xy 0.5334 0.2794)
			)
			(stroke
				(width 0)
				(type default)
			)
			(fill no)
			(layer "F.CrtYd")
		)
		(pad "1" smd rect
			(at 0.40005 0)
			(size 0.4572 0.508)
			(layers "F.Cu" "F.Mask" "F.Paste")
			(net "P3V3_NODE1")
		)
		(pad "2" smd rect
			(at -0.40005 0)
			(size 0.4572 0.508)
			(layers "F.Cu" "F.Mask" "F.Paste")
			(net "UART_RI_P2_N")
		)
	)
	(footprint ""
		(layer "F.Cu")
		(at 150.47976 -188.126624 90)
		(property "Reference" "C747"
			(at 5.519674 -2.808732 90)
			(unlocked yes)
			(layer "F.SilkS")
			(effects
				(font
					(size 0.7874 0.5842)
					(thickness 0.1524)
				)
				(justify left)
			)
		)
		(property "Value" ""
			(at 0 0 90)
			(layer "F.Fab")
			(effects
				(font
					(size 1.27 1.27)
				)
			)
		)
		(duplicate_pad_numbers_are_jumpers no)
		(fp_line
			(start 0.7874 -0.4064)
			(end 0.7874 0.4064)
			(stroke
				(width 0.1524)
				(type default)
			)
			(layer "F.SilkS")
		)
		(fp_line
			(start -0.7874 -0.4064)
			(end 0.7874 -0.4064)
			(stroke
				(width 0.1524)
				(type default)
			)
			(layer "F.SilkS")
		)
		(fp_line
			(start 0 0.381)
			(end 0 -0.381)
			(stroke
				(width 0.1524)
				(type default)
			)
			(layer "F.SilkS")
		)
		(fp_line
			(start 0.7874 0.4064)
			(end -0.7874 0.4064)
			(stroke
				(width 0.1524)
				(type default)
			)
			(layer "F.SilkS")
		)
		(fp_line
			(start -0.7874 0.4064)
			(end -0.7874 -0.4064)
			(stroke
				(width 0.1524)
				(type default)
			)
			(layer "F.SilkS")
		)
		(fp_poly
			(pts
				(xy -0.5334 0.254) (xy -0.635 0.254) (xy -0.635 0.2286) (xy -0.635 -0.254) (xy -0.5334 -0.254) (xy -0.5334 -0.2794)
				(xy 0.5334 -0.2794) (xy 0.5334 -0.254) (xy 0.635 -0.254) (xy 0.635 0.254) (xy 0.5334 0.254) (xy 0.5334 0.2794)
				(xy -0.508 0.2794) (xy -0.5334 0.2794)
			)
			(stroke
				(width 0)
				(type default)
			)
			(fill no)
			(layer "F.CrtYd")
		)
		(pad "1" smd rect
			(at 0.40005 0 90)
			(size 0.4572 0.508)
			(layers "F.Cu" "F.Mask" "F.Paste")
			(net "UART_T12_NODE1_TXD_R")
		)
		(pad "2" smd rect
			(at -0.40005 0 90)
			(size 0.4572 0.508)
			(layers "F.Cu" "F.Mask" "F.Paste")
			(net "GND")
		)
	)
	(footprint ""
		(layer "F.Cu")
		(at 40.122602 -162.187382 90)
		(property "Reference" "R559"
			(at -1.312672 -1.041654 90)
			(unlocked yes)
			(layer "F.SilkS")
			(effects
				(font
					(size 0.7874 0.5842)
					(thickness 0.1524)
				)
				(justify left)
			)
		)
		(property "Value" ""
			(at 0 0 90)
			(layer "F.Fab")
			(effects
				(font
					(size 1.27 1.27)
				)
			)
		)
		(duplicate_pad_numbers_are_jumpers no)
		(fp_line
			(start 0.7874 -0.4064)
			(end 0.7874 0.4064)
			(stroke
				(width 0.1524)
				(type default)
			)
			(layer "F.SilkS")
		)
		(fp_line
			(start -0.7874 -0.4064)
			(end 0.7874 -0.4064)
			(stroke
				(width 0.1524)
				(type default)
			)
			(layer "F.SilkS")
		)
		(fp_line
			(start 0.7874 0.4064)
			(end -0.7874 0.4064)
			(stroke
				(width 0.1524)
				(type default)
			)
			(layer "F.SilkS")
		)
		(fp_line
			(start -0.7874 0.4064)
			(end -0.7874 -0.4064)
			(stroke
				(width 0.1524)
				(type default)
			)
			(layer "F.SilkS")
		)
		(fp_poly
			(pts
				(xy -0.508 0.2794) (xy -0.508 0.2286) (xy -0.635 0.2286) (xy -0.635 -0.254) (xy -0.5334 -0.254)
				(xy -0.5334 -0.2794) (xy 0.5334 -0.2794) (xy 0.5334 -0.254) (xy 0.635 -0.254) (xy 0.635 0.254) (xy 0.5334 0.254)
				(xy 0.5334 0.2794)
			)
			(stroke
				(width 0)
				(type default)
			)
			(fill no)
			(layer "F.CrtYd")
		)
		(pad "1" smd rect
			(at 0.40005 0 90)
			(size 0.4572 0.508)
			(layers "F.Cu" "F.Mask" "F.Paste")
			(net "GND")
		)
		(pad "2" smd rect
			(at -0.40005 0 90)
			(size 0.4572 0.508)
			(layers "F.Cu" "F.Mask" "F.Paste")
			(net "LAN1_RST")
		)
	)
	(footprint ""
		(layer "F.Cu")
		(at 102.34168 -154.7749 180)
		(property "Reference" "PU4"
			(at -2.512314 -0.688848 90)
			(unlocked yes)
			(layer "F.SilkS")
			(effects
				(font
					(size 0.635 0.4064)
					(thickness 0.1524)
				)
				(justify left)
			)
		)
		(property "Value" ""
			(at 0 0 180)
			(layer "F.Fab")
			(effects
				(font
					(size 1.27 1.27)
				)
			)
		)
		(duplicate_pad_numbers_are_jumpers no)
		(fp_line
			(start 2.055622 0.25019)
			(end 2.563622 0.25019)
			(stroke
				(width 0.1524)
				(type default)
			)
			(layer "F.SilkS")
		)
		(fp_line
			(start 1.575054 1.575054)
			(end 1.575054 1.143)
			(stroke
				(width 0.1524)
				(type default)
			)
			(layer "F.SilkS")
		)
		(fp_line
			(start 1.575054 -1.0668)
			(end 1.575054 -1.575054)
			(stroke
				(width 0.1524)
				(type default)
			)
			(layer "F.SilkS")
		)
		(fp_line
			(start 1.575054 -1.575054)
			(end 1.0414 -1.575054)
			(stroke
				(width 0.1524)
				(type default)
			)
			(layer "F.SilkS")
		)
		(fp_line
			(start 1.0414 1.575054)
			(end 1.575054 1.575054)
			(stroke
				(width 0.1524)
				(type default)
			)
			(layer "F.SilkS")
		)
		(fp_line
			(start -0.255778 -2.350262)
			(end -0.255778 -2.045462)
			(stroke
				(width 0.1524)
				(type default)
			)
			(layer "F.SilkS")
		)
		(fp_line
			(start -0.750062 2.043938)
			(end -0.750062 2.348738)
			(stroke
				(width 0.1524)
				(type default)
			)
			(layer "F.SilkS")
		)
		(fp_line
			(start -1.0668 -1.575054)
			(end -1.575054 -1.575054)
			(stroke
				(width 0.1524)
				(type default)
			)
			(layer "F.SilkS")
		)
		(fp_line
			(start -1.575054 1.575054)
			(end -1.0922 1.575054)
			(stroke
				(width 0.1524)
				(type default)
			)
			(layer "F.SilkS")
		)
		(fp_line
			(start -1.575054 1.0922)
			(end -1.575054 1.575054)
			(stroke
				(width 0.1524)
				(type default)
			)
			(layer "F.SilkS")
		)
		(fp_line
			(start -1.575054 -1.575054)
			(end -1.575054 -1.0414)
			(stroke
				(width 0.1524)
				(type default)
			)
			(layer "F.SilkS")
		)
		(fp_poly
			(pts
				(xy -1.687576 -0.998474) (xy -2.22504 -2.073148) (xy -2.76225 -1.535938)
			)
			(stroke
				(width 0)
				(type default)
			)
			(fill yes)
			(layer "F.SilkS")
		)
		(fp_poly
			(pts
				(xy -1.575054 1.575054) (xy -0.9398 1.575054) (xy -0.9398 1.9558) (xy 0.9398 1.9558) (xy 0.9398 1.575054)
				(xy 1.575054 1.575054) (xy 1.575054 0.9398) (xy 1.9558 0.9398) (xy 1.9558 -0.9398) (xy 1.575054 -0.9398)
				(xy 1.575054 -1.575054) (xy 0.9398 -1.575054) (xy 0.9398 -1.9558) (xy -0.9398 -1.9558) (xy -0.9398 -1.575054)
				(xy -1.575054 -1.575054) (xy -1.575054 -0.9398) (xy -1.9558 -0.9398) (xy -1.9558 0.9398) (xy -1.575054 0.9398)
			)
			(stroke
				(width 0)
				(type default)
			)
			(fill no)
			(layer "F.CrtYd")
		)
		(fp_line
			(start 2.055622 0.25019)
			(end 2.563622 0.25019)
			(stroke
				(width 0.1)
				(type default)
			)
			(layer "F.Fab")
		)
		(fp_line
			(start 1.575054 1.575054)
			(end -1.575054 1.575054)
			(stroke
				(width 0.1)
				(type default)
			)
			(layer "F.Fab")
		)
		(fp_line
			(start 1.575054 -1.575054)
			(end 1.575054 1.575054)
			(stroke
				(width 0.1)
				(type default)
			)
			(layer "F.Fab")
		)
		(fp_line
			(start -0.255778 -2.350262)
			(end -0.255778 -2.045462)
			(stroke
				(width 0.1)
				(type default)
			)
			(layer "F.Fab")
		)
		(fp_line
			(start -0.750062 2.043938)
			(end -0.750062 2.348738)
			(stroke
				(width 0.1)
				(type default)
			)
			(layer "F.Fab")
		)
		(fp_line
			(start -1.575054 1.575054)
			(end -1.575054 -1.575054)
			(stroke
				(width 0.1)
				(type default)
			)
			(layer "F.Fab")
		)
		(fp_line
			(start -1.575054 -1.575054)
			(end 1.575054 -1.575054)
			(stroke
				(width 0.1)
				(type default)
			)
			(layer "F.Fab")
		)
		(fp_poly
			(pts
				(xy -2.100072 -0.750062) (xy -3.240024 -1.130046) (xy -3.240024 -0.370078)
			)
			(stroke
				(width 0)
				(type default)
			)
			(fill yes)
			(layer "F.Fab")
		)
		(fp_text user "12"
			(at 2.65049 -1.886458 0)
			(unlocked yes)
			(layer "F.SilkS")
			(effects
				(font
					(size 0.635 0.4064)
					(thickness 0.1524)
				)
				(justify left)
			)
		)
		(fp_text user "9"
			(at 2.144014 1.3335 0)
			(unlocked yes)
			(layer "F.SilkS")
			(effects
				(font
					(size 0.635 0.4064)
					(thickness 0.1524)
				)
				(justify left)
			)
		)
		(fp_text user "16"
			(at -0.864362 -2.029206 0)
			(unlocked yes)
			(layer "F.SilkS")
			(effects
				(font
					(size 0.635 0.4064)
					(thickness 0.1524)
				)
				(justify left)
			)
		)
		(fp_text user "5"
			(at -0.979424 2.084578 0)
			(unlocked yes)
			(layer "F.SilkS")
			(effects
				(font
					(size 0.635 0.4064)
					(thickness 0.1524)
				)
				(justify left)
			)
		)
		(fp_text user "9"
			(at 1.767586 1.584325 180)
			(unlocked yes)
			(layer "F.Fab")
			(effects
				(font
					(size 0.78994 0.579882)
					(thickness 0.000001)
				)
				(justify left)
			)
		)
		(fp_text user "12"
			(at 1.708912 -1.514475 180)
			(unlocked yes)
			(layer "F.Fab")
			(effects
				(font
					(size 0.78994 0.579882)
					(thickness 0.000001)
				)
				(justify left)
			)
		)
		(fp_text user "5"
			(at -1.737868 2.295525 180)
			(unlocked yes)
			(layer "F.Fab")
			(effects
				(font
					(size 0.78994 0.579882)
					(thickness 0.000001)
				)
				(justify left)
			)
		)
		(fp_text user "16"
			(at -2.457958 -2.225675 180)
			(unlocked yes)
			(layer "F.Fab")
			(effects
				(font
					(size 0.78994 0.579882)
					(thickness 0.000001)
				)
				(justify left)
			)
		)
		(pad "1" smd rect
			(at -1.474978 -0.750062 270)
			(size 0.254 0.8382)
			(layers "F.Cu" "F.Mask" "F.Paste")
			(net "P1V8_STB_NODE1_FB")
		)
		(pad "2" smd rect
			(at -1.474978 -0.249936 270)
			(size 0.254 0.8382)
			(layers "F.Cu" "F.Mask" "F.Paste")
			(net "P1V8_STB_NODE1_VREG5")
		)
		(pad "3" smd rect
			(at -1.474978 0.249936 270)
			(size 0.254 0.8382)
			(layers "F.Cu" "F.Mask" "F.Paste")
			(net "P1V8_STB_NODE1_SS")
		)
		(pad "4" smd rect
			(at -1.474978 0.750062 270)
			(size 0.254 0.8382)
			(layers "F.Cu" "F.Mask" "F.Paste")
			(net "GND")
		)
		(pad "5" smd rect
			(at -0.750062 1.474978 180)
			(size 0.254 0.8382)
			(layers "F.Cu" "F.Mask" "F.Paste")
			(net "PWRGD_NODE1_P1V8_STB_PG")
		)
		(pad "6" smd rect
			(at -0.249936 1.474978 180)
			(size 0.254 0.8382)
			(layers "F.Cu" "F.Mask" "F.Paste")
			(net "FM_CPLD_NODE1_P1V8_STB_S_EN")
		)
		(pad "7" smd rect
			(at 0.249936 1.474978 180)
			(size 0.254 0.8382)
			(layers "F.Cu" "F.Mask" "F.Paste")
			(net "GND")
		)
		(pad "8" smd rect
			(at 0.750062 1.474978 180)
			(size 0.254 0.8382)
			(layers "F.Cu" "F.Mask" "F.Paste")
			(net "GND")
		)
		(pad "9" smd rect
			(at 1.474978 0.750062 270)
			(size 0.254 0.8382)
			(layers "F.Cu" "F.Mask" "F.Paste")
			(net "SW_P1V8_STB_NODE1_PH")
		)
		(pad "10" smd rect
			(at 1.474978 0.249936 270)
			(size 0.254 0.8382)
			(layers "F.Cu" "F.Mask" "F.Paste")
			(net "SW_P1V8_STB_NODE1_PH")
		)
		(pad "11" smd rect
			(at 1.474978 -0.249936 270)
			(size 0.254 0.8382)
			(layers "F.Cu" "F.Mask" "F.Paste")
			(net "SW_P1V8_STB_NODE1_PH")
		)
		(pad "12" smd rect
			(at 1.474978 -0.750062 270)
			(size 0.254 0.8382)
			(layers "F.Cu" "F.Mask" "F.Paste")
			(net "SW_P1V8_STB_NODE1_BT")
		)
		(pad "13" smd rect
			(at 0.750062 -1.474978 180)
			(size 0.254 0.8382)
			(layers "F.Cu" "F.Mask" "F.Paste")
			(net "P12V_AUX")
		)
		(pad "14" smd rect
			(at 0.249936 -1.474978 180)
			(size 0.254 0.8382)
			(layers "F.Cu" "F.Mask" "F.Paste")
			(net "P12V_AUX")
		)
		(pad "15" smd rect
			(at -0.249936 -1.474978 180)
			(size 0.254 0.8382)
			(layers "F.Cu" "F.Mask" "F.Paste")
			(net "P5V_STB_NODE1")
		)
		(pad "16" smd rect
			(at -0.750062 -1.474978 180)
			(size 0.254 0.8382)
			(layers "F.Cu" "F.Mask" "F.Paste")
			(net "P1V8_STB_NODE1")
		)
		(pad "TH" smd rect
			(at 0 0 270)
			(size 1.7018 1.7018)
			(layers "F.Cu" "F.Mask" "F.Paste")
			(net "GND")
		)
		(zone
			(layer "F.Cu")
			(hatch none 0.5)
			(connect_pads
				(clearance 0)
			)
			(min_thickness 0.25)
			(keepout
				(tracks not_allowed)
				(vias allowed)
				(pads allowed)
				(copperpour not_allowed)
				(footprints allowed)
			)
			(placement
				(enabled no)
				(sheetname "")
			)
			(fill
				(thermal_gap 0.5)
				(thermal_bridge_width 0.5)
				(island_removal_mode 0)
			)
			(polygon
				(pts
					(xy 103.33228 -153.7843) (xy 101.35108 -153.7843) (xy 101.35108 -155.7655) (xy 101.42728 -155.7655)
					(xy 101.42728 -155.6893) (xy 101.42728 -153.8605) (xy 103.25608 -153.8605) (xy 103.25608 -155.6639)
					(xy 103.33228 -155.6639)
				)
			)
		)
		(zone
			(layer "F.Cu")
			(hatch none 0.5)
			(connect_pads
				(clearance 0)
			)
			(min_thickness 0.25)
			(keepout
				(tracks allowed)
				(vias not_allowed)
				(pads allowed)
				(copperpour not_allowed)
				(footprints allowed)
			)
			(placement
				(enabled no)
				(sheetname "")
			)
			(fill
				(thermal_gap 0.5)
				(thermal_bridge_width 0.5)
				(island_removal_mode 0)
			)
			(polygon
				(pts
					(xy 103.33228 -153.7843) (xy 101.35108 -153.7843) (xy 101.35108 -155.7655) (xy 103.33228 -155.7655)
					(xy 103.33228 -155.6893) (xy 101.42728 -155.6893) (xy 101.42728 -153.8605) (xy 103.25608 -153.8605)
					(xy 103.25608 -155.6639) (xy 103.33228 -155.6639)
				)
			)
		)
	)
	(footprint ""
		(layer "F.Cu")
		(at 74.458068 -94.131892 -90)
		(property "Reference" "R154"
			(at 55.53329 -24.083264 90)
			(unlocked yes)
			(layer "F.SilkS")
			(effects
				(font
					(size 0.7874 0.5842)
					(thickness 0.1524)
				)
				(justify left)
			)
		)
		(property "Value" ""
			(at 0 0 270)
			(layer "F.Fab")
			(effects
				(font
					(size 1.27 1.27)
				)
			)
		)
		(duplicate_pad_numbers_are_jumpers no)
		(fp_line
			(start -0.7874 0.4064)
			(end -0.7874 -0.4064)
			(stroke
				(width 0.1524)
				(type default)
			)
			(layer "F.SilkS")
		)
		(fp_line
			(start 0.7874 0.4064)
			(end -0.7874 0.4064)
			(stroke
				(width 0.1524)
				(type default)
			)
			(layer "F.SilkS")
		)
		(fp_line
			(start -0.7874 -0.4064)
			(end 0.7874 -0.4064)
			(stroke
				(width 0.1524)
				(type default)
			)
			(layer "F.SilkS")
		)
		(fp_line
			(start 0.7874 -0.4064)
			(end 0.7874 0.4064)
			(stroke
				(width 0.1524)
				(type default)
			)
			(layer "F.SilkS")
		)
		(fp_poly
			(pts
				(xy -0.508 0.2794) (xy -0.508 0.2286) (xy -0.635 0.2286) (xy -0.635 -0.254) (xy -0.5334 -0.254)
				(xy -0.5334 -0.2794) (xy 0.5334 -0.2794) (xy 0.5334 -0.254) (xy 0.635 -0.254) (xy 0.635 0.254) (xy 0.5334 0.254)
				(xy 0.5334 0.2794)
			)
			(stroke
				(width 0)
				(type default)
			)
			(fill no)
			(layer "F.CrtYd")
		)
		(pad "1" smd rect
			(at 0.40005 0 270)
			(size 0.4572 0.508)
			(layers "F.Cu" "F.Mask" "F.Paste")
			(net "PD_CPU_NODE1_BOOTDEVSEL")
		)
		(pad "2" smd rect
			(at -0.40005 0 270)
			(size 0.4572 0.508)
			(layers "F.Cu" "F.Mask" "F.Paste")
			(net "GND")
		)
	)
	(footprint ""
		(layer "F.Cu")
		(at 88.43518 -84.118704 180)
		(property "Reference" "C813"
			(at 2.10566 1.588008 0)
			(unlocked yes)
			(layer "F.SilkS")
			(effects
				(font
					(size 0.7874 0.5842)
					(thickness 0.1524)
				)
				(justify left)
			)
		)
		(property "Value" ""
			(at 0 0 180)
			(layer "F.Fab")
			(effects
				(font
					(size 1.27 1.27)
				)
			)
		)
		(duplicate_pad_numbers_are_jumpers no)
		(fp_line
			(start 1.905 0.8636)
			(end -1.905 0.8636)
			(stroke
				(width 0.1524)
				(type default)
			)
			(layer "F.SilkS")
		)
		(fp_line
			(start 1.905 -0.8636)
			(end 1.905 0.8636)
			(stroke
				(width 0.1524)
				(type default)
			)
			(layer "F.SilkS")
		)
		(fp_line
			(start 0 0.8382)
			(end 0 -0.8382)
			(stroke
				(width 0.1524)
				(type default)
			)
			(layer "F.SilkS")
		)
		(fp_line
			(start -1.905 0.8636)
			(end -1.905 -0.8636)
			(stroke
				(width 0.1524)
				(type default)
			)
			(layer "F.SilkS")
		)
		(fp_line
			(start -1.905 -0.8636)
			(end 1.905 -0.8636)
			(stroke
				(width 0.1524)
				(type default)
			)
			(layer "F.SilkS")
		)
		(fp_rect
			(start -1.524 0.7366)
			(end 1.524 -0.7366)
			(stroke
				(width 0)
				(type default)
			)
			(fill no)
			(layer "F.CrtYd")
		)
		(pad "1" smd rect
			(at 0.94996 0 180)
			(size 1.1176 1.3716)
			(layers "F.Cu" "F.Mask" "F.Paste")
			(net "P1V05_SUS_NODE1")
		)
		(pad "2" smd rect
			(at -0.94996 0 180)
			(size 1.1176 1.3716)
			(layers "F.Cu" "F.Mask" "F.Paste")
			(net "GND")
		)
	)
	(footprint ""
		(layer "F.Cu")
		(at 43.686222 -106.475784 -90)
		(property "Reference" "PR5"
			(at 2.327148 3.311144 90)
			(unlocked yes)
			(layer "F.SilkS")
			(effects
				(font
					(size 0.7874 0.5842)
					(thickness 0.1524)
				)
				(justify left)
			)
		)
		(property "Value" ""
			(at 0 0 270)
			(layer "F.Fab")
			(effects
				(font
					(size 1.27 1.27)
				)
			)
		)
		(duplicate_pad_numbers_are_jumpers no)
		(fp_line
			(start -0.7874 0.4064)
			(end -0.7874 -0.4064)
			(stroke
				(width 0.1524)
				(type default)
			)
			(layer "F.SilkS")
		)
		(fp_line
			(start 0.7874 0.4064)
			(end -0.7874 0.4064)
			(stroke
				(width 0.1524)
				(type default)
			)
			(layer "F.SilkS")
		)
		(fp_line
			(start -0.7874 -0.4064)
			(end 0.7874 -0.4064)
			(stroke
				(width 0.1524)
				(type default)
			)
			(layer "F.SilkS")
		)
		(fp_line
			(start 0.7874 -0.4064)
			(end 0.7874 0.4064)
			(stroke
				(width 0.1524)
				(type default)
			)
			(layer "F.SilkS")
		)
		(fp_poly
			(pts
				(xy -0.508 0.2794) (xy -0.508 0.2286) (xy -0.635 0.2286) (xy -0.635 -0.254) (xy -0.5334 -0.254)
				(xy -0.5334 -0.2794) (xy 0.5334 -0.2794) (xy 0.5334 -0.254) (xy 0.635 -0.254) (xy 0.635 0.254) (xy 0.5334 0.254)
				(xy 0.5334 0.2794)
			)
			(stroke
				(width 0)
				(type default)
			)
			(fill no)
			(layer "F.CrtYd")
		)
		(pad "1" smd rect
			(at 0.40005 0 270)
			(size 0.4572 0.508)
			(layers "F.Cu" "F.Mask" "F.Paste")
			(net "P3V3_STB_NODE1_VREG5")
		)
		(pad "2" smd rect
			(at -0.40005 0 270)
			(size 0.4572 0.508)
			(layers "F.Cu" "F.Mask" "F.Paste")
			(net "PWRGD_NODE1_P3V3_STB_PG")
		)
	)
	(footprint ""
		(layer "F.Cu")
		(at 128.029208 -51.745134 90)
		(property "Reference" "R616"
			(at 15.971266 30.925262 90)
			(unlocked yes)
			(layer "F.SilkS")
			(effects
				(font
					(size 0.7874 0.5842)
					(thickness 0.1524)
				)
				(justify left)
			)
		)
		(property "Value" ""
			(at 0 0 90)
			(layer "F.Fab")
			(effects
				(font
					(size 1.27 1.27)
				)
			)
		)
		(duplicate_pad_numbers_are_jumpers no)
		(fp_line
			(start 0.7874 -0.4064)
			(end 0.7874 0.4064)
			(stroke
				(width 0.1524)
				(type default)
			)
			(layer "F.SilkS")
		)
		(fp_line
			(start -0.7874 -0.4064)
			(end 0.7874 -0.4064)
			(stroke
				(width 0.1524)
				(type default)
			)
			(layer "F.SilkS")
		)
		(fp_line
			(start 0.7874 0.4064)
			(end -0.7874 0.4064)
			(stroke
				(width 0.1524)
				(type default)
			)
			(layer "F.SilkS")
		)
		(fp_line
			(start -0.7874 0.4064)
			(end -0.7874 -0.4064)
			(stroke
				(width 0.1524)
				(type default)
			)
			(layer "F.SilkS")
		)
		(fp_poly
			(pts
				(xy -0.508 0.2794) (xy -0.508 0.2286) (xy -0.635 0.2286) (xy -0.635 -0.254) (xy -0.5334 -0.254)
				(xy -0.5334 -0.2794) (xy 0.5334 -0.2794) (xy 0.5334 -0.254) (xy 0.635 -0.254) (xy 0.635 0.254) (xy 0.5334 0.254)
				(xy 0.5334 0.2794)
			)
			(stroke
				(width 0)
				(type default)
			)
			(fill no)
			(layer "F.CrtYd")
		)
		(pad "1" smd rect
			(at 0.40005 0 90)
			(size 0.4572 0.508)
			(layers "F.Cu" "F.Mask" "F.Paste")
			(net "P3V3_NODE1")
		)
		(pad "2" smd rect
			(at -0.40005 0 90)
			(size 0.4572 0.508)
			(layers "F.Cu" "F.Mask" "F.Paste")
			(net "UART_CTS_P5_N")
		)
	)
	(footprint ""
		(layer "F.Cu")
		(at 94.451932 -178.370992)
		(property "Reference" "R752"
			(at 86.67369 74.174096 0)
			(unlocked yes)
			(layer "F.SilkS")
			(effects
				(font
					(size 0.7874 0.5842)
					(thickness 0.1524)
				)
				(justify left)
			)
		)
		(property "Value" ""
			(at 0 0 0)
			(layer "F.Fab")
			(effects
				(font
					(size 1.27 1.27)
				)
			)
		)
		(duplicate_pad_numbers_are_jumpers no)
		(fp_line
			(start -0.7874 -0.4064)
			(end 0.7874 -0.4064)
			(stroke
				(width 0.1524)
				(type default)
			)
			(layer "F.SilkS")
		)
		(fp_line
			(start -0.7874 0.4064)
			(end -0.7874 -0.4064)
			(stroke
				(width 0.1524)
				(type default)
			)
			(layer "F.SilkS")
		)
		(fp_line
			(start 0.7874 -0.4064)
			(end 0.7874 0.4064)
			(stroke
				(width 0.1524)
				(type default)
			)
			(layer "F.SilkS")
		)
		(fp_line
			(start 0.7874 0.4064)
			(end -0.7874 0.4064)
			(stroke
				(width 0.1524)
				(type default)
			)
			(layer "F.SilkS")
		)
		(fp_poly
			(pts
				(xy -0.508 0.2794) (xy -0.508 0.2286) (xy -0.635 0.2286) (xy -0.635 -0.254) (xy -0.5334 -0.254)
				(xy -0.5334 -0.2794) (xy 0.5334 -0.2794) (xy 0.5334 -0.254) (xy 0.635 -0.254) (xy 0.635 0.254) (xy 0.5334 0.254)
				(xy 0.5334 0.2794)
			)
			(stroke
				(width 0)
				(type default)
			)
			(fill no)
			(layer "F.CrtYd")
		)
		(pad "1" smd rect
			(at 0.40005 0)
			(size 0.4572 0.508)
			(layers "F.Cu" "F.Mask" "F.Paste")
			(net "N21700941")
		)
		(pad "2" smd rect
			(at -0.40005 0)
			(size 0.4572 0.508)
			(layers "F.Cu" "F.Mask" "F.Paste")
			(net "GND")
		)
	)
	(footprint ""
		(layer "F.Cu")
		(at 150.073868 -39.972996 90)
		(property "Reference" "R1005"
			(at -1.681226 10.212832 90)
			(unlocked yes)
			(layer "F.SilkS")
			(effects
				(font
					(size 0.7874 0.5842)
					(thickness 0.1524)
				)
				(justify left)
			)
		)
		(property "Value" ""
			(at 0 0 90)
			(layer "F.Fab")
			(effects
				(font
					(size 1.27 1.27)
				)
			)
		)
		(duplicate_pad_numbers_are_jumpers no)
		(fp_line
			(start 0.7874 -0.4064)
			(end 0.7874 0.4064)
			(stroke
				(width 0.1524)
				(type default)
			)
			(layer "F.SilkS")
		)
		(fp_line
			(start -0.7874 -0.4064)
			(end 0.7874 -0.4064)
			(stroke
				(width 0.1524)
				(type default)
			)
			(layer "F.SilkS")
		)
		(fp_line
			(start 0.7874 0.4064)
			(end -0.7874 0.4064)
			(stroke
				(width 0.1524)
				(type default)
			)
			(layer "F.SilkS")
		)
		(fp_line
			(start -0.7874 0.4064)
			(end -0.7874 -0.4064)
			(stroke
				(width 0.1524)
				(type default)
			)
			(layer "F.SilkS")
		)
		(fp_poly
			(pts
				(xy -0.508 0.2794) (xy -0.508 0.2286) (xy -0.635 0.2286) (xy -0.635 -0.254) (xy -0.5334 -0.254)
				(xy -0.5334 -0.2794) (xy 0.5334 -0.2794) (xy 0.5334 -0.254) (xy 0.635 -0.254) (xy 0.635 0.254) (xy 0.5334 0.254)
				(xy 0.5334 0.2794)
			)
			(stroke
				(width 0)
				(type default)
			)
			(fill no)
			(layer "F.CrtYd")
		)
		(pad "1" smd rect
			(at 0.40005 0 90)
			(size 0.4572 0.508)
			(layers "F.Cu" "F.Mask" "F.Paste")
			(net "P5V_NODE1")
		)
		(pad "2" smd rect
			(at -0.40005 0 90)
			(size 0.4572 0.508)
			(layers "F.Cu" "F.Mask" "F.Paste")
			(net "UART_DTR_P1_N")
		)
	)
	(footprint ""
		(layer "F.Cu")
		(at 71.10476 -185.205624 90)
		(property "Reference" "C713"
			(at 4.006088 -0.94488 90)
			(unlocked yes)
			(layer "F.SilkS")
			(effects
				(font
					(size 0.7874 0.5842)
					(thickness 0.1524)
				)
				(justify left)
			)
		)
		(property "Value" ""
			(at 0 0 90)
			(layer "F.Fab")
			(effects
				(font
					(size 1.27 1.27)
				)
			)
		)
		(duplicate_pad_numbers_are_jumpers no)
		(fp_line
			(start 0.7874 -0.4064)
			(end 0.7874 0.4064)
			(stroke
				(width 0.1524)
				(type default)
			)
			(layer "F.SilkS")
		)
		(fp_line
			(start -0.7874 -0.4064)
			(end 0.7874 -0.4064)
			(stroke
				(width 0.1524)
				(type default)
			)
			(layer "F.SilkS")
		)
		(fp_line
			(start 0 0.381)
			(end 0 -0.381)
			(stroke
				(width 0.1524)
				(type default)
			)
			(layer "F.SilkS")
		)
		(fp_line
			(start 0.7874 0.4064)
			(end -0.7874 0.4064)
			(stroke
				(width 0.1524)
				(type default)
			)
			(layer "F.SilkS")
		)
		(fp_line
			(start -0.7874 0.4064)
			(end -0.7874 -0.4064)
			(stroke
				(width 0.1524)
				(type default)
			)
			(layer "F.SilkS")
		)
		(fp_poly
			(pts
				(xy -0.5334 0.254) (xy -0.635 0.254) (xy -0.635 0.2286) (xy -0.635 -0.254) (xy -0.5334 -0.254) (xy -0.5334 -0.2794)
				(xy 0.5334 -0.2794) (xy 0.5334 -0.254) (xy 0.635 -0.254) (xy 0.635 0.254) (xy 0.5334 0.254) (xy 0.5334 0.2794)
				(xy -0.508 0.2794) (xy -0.5334 0.2794)
			)
			(stroke
				(width 0)
				(type default)
			)
			(fill no)
			(layer "F.CrtYd")
		)
		(pad "1" smd rect
			(at 0.40005 0 90)
			(size 0.4572 0.508)
			(layers "F.Cu" "F.Mask" "F.Paste")
			(net "UART_T4_NODE4_RXD")
		)
		(pad "2" smd rect
			(at -0.40005 0 90)
			(size 0.4572 0.508)
			(layers "F.Cu" "F.Mask" "F.Paste")
			(net "GND")
		)
	)
	(footprint ""
		(layer "F.Cu")
		(at 62.035182 -173.527466 180)
		(property "Reference" "U88"
			(at 10.67943 -133.039612 90)
			(unlocked yes)
			(layer "F.SilkS")
			(effects
				(font
					(size 0.7874 0.5842)
					(thickness 0.1524)
				)
				(justify left)
			)
		)
		(property "Value" ""
			(at 0 0 180)
			(layer "F.Fab")
			(effects
				(font
					(size 1.27 1.27)
				)
			)
		)
		(duplicate_pad_numbers_are_jumpers no)
		(fp_line
			(start 1.549908 2.032)
			(end -1.549908 2.032)
			(stroke
				(width 0.1524)
				(type default)
			)
			(layer "F.SilkS")
		)
		(fp_line
			(start 1.549908 -2.032)
			(end 1.549908 2.032)
			(stroke
				(width 0.1524)
				(type default)
			)
			(layer "F.SilkS")
		)
		(fp_line
			(start -1.549908 2.032)
			(end -1.549908 -2.032)
			(stroke
				(width 0.1524)
				(type default)
			)
			(layer "F.SilkS")
		)
		(fp_line
			(start -1.549908 -2.032)
			(end 1.549908 -2.032)
			(stroke
				(width 0.1524)
				(type default)
			)
			(layer "F.SilkS")
		)
		(fp_poly
			(pts
				(xy -2.9464 1.016) (xy -2.9464 1.524) (xy -2.1844 1.27)
			)
			(stroke
				(width 0)
				(type default)
			)
			(fill yes)
			(layer "F.SilkS")
		)
		(fp_poly
			(pts
				(xy -1.549908 0.849884) (xy -1.2319 0.849884) (xy -1.2319 1.9431) (xy -1.1811 1.9431) (xy 1.1811 1.9431)
				(xy 1.2319 1.9431) (xy 1.2319 0.849884) (xy 1.549908 0.849884) (xy 1.549908 -0.849884) (xy 1.2319 -0.849884)
				(xy 1.2319 -1.9431) (xy 1.1811 -1.9431) (xy -1.1811 -1.9431) (xy -1.2319 -1.9431) (xy -1.2319 -0.849884)
				(xy -1.549908 -0.849884)
			)
			(stroke
				(width 0)
				(type default)
			)
			(fill no)
			(layer "F.CrtYd")
		)
		(fp_line
			(start 1.549908 0.849884)
			(end 1.549908 -0.849884)
			(stroke
				(width 0.1)
				(type default)
			)
			(layer "F.Fab")
		)
		(fp_line
			(start 1.549908 -0.849884)
			(end -1.549908 -0.849884)
			(stroke
				(width 0.1)
				(type default)
			)
			(layer "F.Fab")
		)
		(fp_line
			(start -1.549908 0.849884)
			(end 1.549908 0.849884)
			(stroke
				(width 0.1)
				(type default)
			)
			(layer "F.Fab")
		)
		(fp_line
			(start -1.549908 -0.849884)
			(end -1.549908 0.849884)
			(stroke
				(width 0.1)
				(type default)
			)
			(layer "F.Fab")
		)
		(fp_text user "3"
			(at 1.553972 2.531618 0)
			(unlocked yes)
			(layer "F.SilkS")
			(effects
				(font
					(size 0.635 0.4064)
					(thickness 0.1524)
				)
				(justify left)
			)
		)
		(fp_text user "4"
			(at 0.724916 -2.537968 0)
			(unlocked yes)
			(layer "F.SilkS")
			(effects
				(font
					(size 0.635 0.4064)
					(thickness 0.1524)
				)
				(justify left)
			)
		)
		(fp_text user "1"
			(at -1.126744 2.531618 0)
			(unlocked yes)
			(layer "F.SilkS")
			(effects
				(font
					(size 0.635 0.4064)
					(thickness 0.1524)
				)
				(justify left)
			)
		)
		(fp_text user "5"
			(at -1.872996 -2.637028 0)
			(unlocked yes)
			(layer "F.SilkS")
			(effects
				(font
					(size 0.635 0.4064)
					(thickness 0.1524)
				)
				(justify left)
			)
		)
		(pad "1" smd rect
			(at -0.94996 1.225042 180)
			(size 0.4572 1.3208)
			(layers "F.Cu" "F.Mask" "F.Paste")
			(net "Net_1709")
		)
		(pad "2" smd rect
			(at 0 1.225042 180)
			(size 0.4572 1.3208)
			(layers "F.Cu" "F.Mask" "F.Paste")
			(net "PSU2_DC_OK_R_BUF")
		)
		(pad "3" smd rect
			(at 0.94996 1.225042 180)
			(size 0.4572 1.3208)
			(layers "F.Cu" "F.Mask" "F.Paste")
			(net "GND")
		)
		(pad "4" smd rect
			(at 0.94996 -1.225042 180)
			(size 0.4572 1.3208)
			(layers "F.Cu" "F.Mask" "F.Paste")
			(net "PSU2_DC_OK")
		)
		(pad "5" smd rect
			(at -0.94996 -1.225042 180)
			(size 0.4572 1.3208)
			(layers "F.Cu" "F.Mask" "F.Paste")
			(net "P3V3_NODE1")
		)
	)
	(footprint ""
		(layer "F.Cu")
		(at 59.330336 -164.534596 -90)
		(property "Reference" "R1108"
			(at -1.509776 0.065532 90)
			(unlocked yes)
			(layer "F.SilkS")
			(effects
				(font
					(size 0.7874 0.5842)
					(thickness 0.1524)
				)
				(justify left)
			)
		)
		(property "Value" ""
			(at 0 0 270)
			(layer "F.Fab")
			(effects
				(font
					(size 1.27 1.27)
				)
			)
		)
		(duplicate_pad_numbers_are_jumpers no)
		(fp_line
			(start -0.7874 0.4064)
			(end -0.7874 -0.4064)
			(stroke
				(width 0.1524)
				(type default)
			)
			(layer "F.SilkS")
		)
		(fp_line
			(start 0.7874 0.4064)
			(end -0.7874 0.4064)
			(stroke
				(width 0.1524)
				(type default)
			)
			(layer "F.SilkS")
		)
		(fp_line
			(start -0.7874 -0.4064)
			(end 0.7874 -0.4064)
			(stroke
				(width 0.1524)
				(type default)
			)
			(layer "F.SilkS")
		)
		(fp_line
			(start 0.7874 -0.4064)
			(end 0.7874 0.4064)
			(stroke
				(width 0.1524)
				(type default)
			)
			(layer "F.SilkS")
		)
		(fp_poly
			(pts
				(xy -0.508 0.2794) (xy -0.508 0.2286) (xy -0.635 0.2286) (xy -0.635 -0.254) (xy -0.5334 -0.254)
				(xy -0.5334 -0.2794) (xy 0.5334 -0.2794) (xy 0.5334 -0.254) (xy 0.635 -0.254) (xy 0.635 0.254) (xy 0.5334 0.254)
				(xy 0.5334 0.2794)
			)
			(stroke
				(width 0)
				(type default)
			)
			(fill no)
			(layer "F.CrtYd")
		)
		(pad "1" smd rect
			(at 0.40005 0 270)
			(size 0.4572 0.508)
			(layers "F.Cu" "F.Mask" "F.Paste")
			(net "FM_CPLD_NODE1_P5V_EN")
		)
		(pad "2" smd rect
			(at -0.40005 0 270)
			(size 0.4572 0.508)
			(layers "F.Cu" "F.Mask" "F.Paste")
			(net "P3V3_STB_NODE1")
		)
	)
	(footprint ""
		(layer "F.Cu")
		(at 114.655854 -28.99791 -90)
		(property "Reference" "C857"
			(at -2.186432 -0.954532 90)
			(unlocked yes)
			(layer "F.SilkS")
			(effects
				(font
					(size 0.7874 0.5842)
					(thickness 0.1524)
				)
				(justify left)
			)
		)
		(property "Value" ""
			(at 0 0 270)
			(layer "F.Fab")
			(effects
				(font
					(size 1.27 1.27)
				)
			)
		)
		(duplicate_pad_numbers_are_jumpers no)
		(fp_line
			(start -1.905 0.8636)
			(end -1.905 -0.8636)
			(stroke
				(width 0.1524)
				(type default)
			)
			(layer "F.SilkS")
		)
		(fp_line
			(start 1.905 0.8636)
			(end -1.905 0.8636)
			(stroke
				(width 0.1524)
				(type default)
			)
			(layer "F.SilkS")
		)
		(fp_line
			(start 0 0.8382)
			(end 0 -0.8382)
			(stroke
				(width 0.1524)
				(type default)
			)
			(layer "F.SilkS")
		)
		(fp_line
			(start -1.905 -0.8636)
			(end 1.905 -0.8636)
			(stroke
				(width 0.1524)
				(type default)
			)
			(layer "F.SilkS")
		)
		(fp_line
			(start 1.905 -0.8636)
			(end 1.905 0.8636)
			(stroke
				(width 0.1524)
				(type default)
			)
			(layer "F.SilkS")
		)
		(fp_rect
			(start -1.524 0.7366)
			(end 1.524 -0.7366)
			(stroke
				(width 0)
				(type default)
			)
			(fill no)
			(layer "F.CrtYd")
		)
		(pad "1" smd rect
			(at 0.94996 0 270)
			(size 1.1176 1.3716)
			(layers "F.Cu" "F.Mask" "F.Paste")
			(net "PV_VTT_DDR_NODE1")
		)
		(pad "2" smd rect
			(at -0.94996 0 270)
			(size 1.1176 1.3716)
			(layers "F.Cu" "F.Mask" "F.Paste")
			(net "GND")
		)
	)
	(footprint ""
		(layer "F.Cu")
		(at 94.451932 -179.386992)
		(property "Reference" "R737"
			(at 86.67369 74.174096 0)
			(unlocked yes)
			(layer "F.SilkS")
			(effects
				(font
					(size 0.7874 0.5842)
					(thickness 0.1524)
				)
				(justify left)
			)
		)
		(property "Value" ""
			(at 0 0 0)
			(layer "F.Fab")
			(effects
				(font
					(size 1.27 1.27)
				)
			)
		)
		(duplicate_pad_numbers_are_jumpers no)
		(fp_line
			(start -0.7874 -0.4064)
			(end 0.7874 -0.4064)
			(stroke
				(width 0.1524)
				(type default)
			)
			(layer "F.SilkS")
		)
		(fp_line
			(start -0.7874 0.4064)
			(end -0.7874 -0.4064)
			(stroke
				(width 0.1524)
				(type default)
			)
			(layer "F.SilkS")
		)
		(fp_line
			(start 0.7874 -0.4064)
			(end 0.7874 0.4064)
			(stroke
				(width 0.1524)
				(type default)
			)
			(layer "F.SilkS")
		)
		(fp_line
			(start 0.7874 0.4064)
			(end -0.7874 0.4064)
			(stroke
				(width 0.1524)
				(type default)
			)
			(layer "F.SilkS")
		)
		(fp_poly
			(pts
				(xy -0.508 0.2794) (xy -0.508 0.2286) (xy -0.635 0.2286) (xy -0.635 -0.254) (xy -0.5334 -0.254)
				(xy -0.5334 -0.2794) (xy 0.5334 -0.2794) (xy 0.5334 -0.254) (xy 0.635 -0.254) (xy 0.635 0.254) (xy 0.5334 0.254)
				(xy 0.5334 0.2794)
			)
			(stroke
				(width 0)
				(type default)
			)
			(fill no)
			(layer "F.CrtYd")
		)
		(pad "1" smd rect
			(at 0.40005 0)
			(size 0.4572 0.508)
			(layers "F.Cu" "F.Mask" "F.Paste")
			(net "N21700941")
		)
		(pad "2" smd rect
			(at -0.40005 0)
			(size 0.4572 0.508)
			(layers "F.Cu" "F.Mask" "F.Paste")
			(net "P3V3_NODE1")
		)
	)
	(footprint ""
		(layer "F.Cu")
		(at 161.485072 -73.428606)
		(property "Reference" "C884"
			(at -6.732778 0.930656 0)
			(unlocked yes)
			(layer "F.SilkS")
			(effects
				(font
					(size 0.7874 0.5842)
					(thickness 0.1524)
				)
				(justify left)
			)
		)
		(property "Value" ""
			(at 0 0 0)
			(layer "F.Fab")
			(effects
				(font
					(size 1.27 1.27)
				)
			)
		)
		(duplicate_pad_numbers_are_jumpers no)
		(fp_line
			(start -0.7874 -0.4064)
			(end 0.7874 -0.4064)
			(stroke
				(width 0.1524)
				(type default)
			)
			(layer "F.SilkS")
		)
		(fp_line
			(start -0.7874 0.4064)
			(end -0.7874 -0.4064)
			(stroke
				(width 0.1524)
				(type default)
			)
			(layer "F.SilkS")
		)
		(fp_line
			(start 0 0.381)
			(end 0 -0.381)
			(stroke
				(width 0.1524)
				(type default)
			)
			(layer "F.SilkS")
		)
		(fp_line
			(start 0.7874 -0.4064)
			(end 0.7874 0.4064)
			(stroke
				(width 0.1524)
				(type default)
			)
			(layer "F.SilkS")
		)
		(fp_line
			(start 0.7874 0.4064)
			(end -0.7874 0.4064)
			(stroke
				(width 0.1524)
				(type default)
			)
			(layer "F.SilkS")
		)
		(fp_poly
			(pts
				(xy -0.5334 0.254) (xy -0.635 0.254) (xy -0.635 0.2286) (xy -0.635 -0.254) (xy -0.5334 -0.254) (xy -0.5334 -0.2794)
				(xy 0.5334 -0.2794) (xy 0.5334 -0.254) (xy 0.635 -0.254) (xy 0.635 0.254) (xy 0.5334 0.254) (xy 0.5334 0.2794)
				(xy -0.508 0.2794) (xy -0.5334 0.2794)
			)
			(stroke
				(width 0)
				(type default)
			)
			(fill no)
			(layer "F.CrtYd")
		)
		(pad "1" smd rect
			(at 0.40005 0)
			(size 0.4572 0.508)
			(layers "F.Cu" "F.Mask" "F.Paste")
			(net "GND")
		)
		(pad "2" smd rect
			(at -0.40005 0)
			(size 0.4572 0.508)
			(layers "F.Cu" "F.Mask" "F.Paste")
			(net "PWRGD_NODE1_P1V0")
		)
	)
	(footprint ""
		(layer "F.Cu")
		(at 65.734692 -107.316016 90)
		(property "Reference" "R1112"
			(at -1.118616 7.779258 90)
			(unlocked yes)
			(layer "F.SilkS")
			(effects
				(font
					(size 0.7874 0.5842)
					(thickness 0.1524)
				)
				(justify left)
			)
		)
		(property "Value" ""
			(at 0 0 90)
			(layer "F.Fab")
			(effects
				(font
					(size 1.27 1.27)
				)
			)
		)
		(duplicate_pad_numbers_are_jumpers no)
		(fp_line
			(start 0.7874 -0.4064)
			(end 0.7874 0.4064)
			(stroke
				(width 0.1524)
				(type default)
			)
			(layer "F.SilkS")
		)
		(fp_line
			(start -0.7874 -0.4064)
			(end 0.7874 -0.4064)
			(stroke
				(width 0.1524)
				(type default)
			)
			(layer "F.SilkS")
		)
		(fp_line
			(start 0.7874 0.4064)
			(end -0.7874 0.4064)
			(stroke
				(width 0.1524)
				(type default)
			)
			(layer "F.SilkS")
		)
		(fp_line
			(start -0.7874 0.4064)
			(end -0.7874 -0.4064)
			(stroke
				(width 0.1524)
				(type default)
			)
			(layer "F.SilkS")
		)
		(fp_poly
			(pts
				(xy -0.508 0.2794) (xy -0.508 0.2286) (xy -0.635 0.2286) (xy -0.635 -0.254) (xy -0.5334 -0.254)
				(xy -0.5334 -0.2794) (xy 0.5334 -0.2794) (xy 0.5334 -0.254) (xy 0.635 -0.254) (xy 0.635 0.254) (xy 0.5334 0.254)
				(xy 0.5334 0.2794)
			)
			(stroke
				(width 0)
				(type default)
			)
			(fill no)
			(layer "F.CrtYd")
		)
		(pad "1" smd rect
			(at 0.40005 0 90)
			(size 0.4572 0.508)
			(layers "F.Cu" "F.Mask" "F.Paste")
			(net "FM_CPLD_NODE1_P1V8_EN")
		)
		(pad "2" smd rect
			(at -0.40005 0 90)
			(size 0.4572 0.508)
			(layers "F.Cu" "F.Mask" "F.Paste")
			(net "P3V3_STB_NODE1")
		)
	)
	(footprint ""
		(layer "F.Cu")
		(at 17.96923 -43.589194 90)
		(property "Reference" "R789"
			(at -8.854186 -1.581404 90)
			(unlocked yes)
			(layer "F.SilkS")
			(effects
				(font
					(size 0.7874 0.5842)
					(thickness 0.1524)
				)
				(justify left)
			)
		)
		(property "Value" ""
			(at 0 0 90)
			(layer "F.Fab")
			(effects
				(font
					(size 1.27 1.27)
				)
			)
		)
		(duplicate_pad_numbers_are_jumpers no)
		(fp_line
			(start 0.7874 -0.4064)
			(end 0.7874 0.4064)
			(stroke
				(width 0.1524)
				(type default)
			)
			(layer "F.SilkS")
		)
		(fp_line
			(start -0.7874 -0.4064)
			(end 0.7874 -0.4064)
			(stroke
				(width 0.1524)
				(type default)
			)
			(layer "F.SilkS")
		)
		(fp_line
			(start 0.7874 0.4064)
			(end -0.7874 0.4064)
			(stroke
				(width 0.1524)
				(type default)
			)
			(layer "F.SilkS")
		)
		(fp_line
			(start -0.7874 0.4064)
			(end -0.7874 -0.4064)
			(stroke
				(width 0.1524)
				(type default)
			)
			(layer "F.SilkS")
		)
		(fp_poly
			(pts
				(xy -0.508 0.2794) (xy -0.508 0.2286) (xy -0.635 0.2286) (xy -0.635 -0.254) (xy -0.5334 -0.254)
				(xy -0.5334 -0.2794) (xy 0.5334 -0.2794) (xy 0.5334 -0.254) (xy 0.635 -0.254) (xy 0.635 0.254) (xy 0.5334 0.254)
				(xy 0.5334 0.2794)
			)
			(stroke
				(width 0)
				(type default)
			)
			(fill no)
			(layer "F.CrtYd")
		)
		(pad "1" smd rect
			(at 0.40005 0 90)
			(size 0.4572 0.508)
			(layers "F.Cu" "F.Mask" "F.Paste")
			(net "CRT_R_L")
		)
		(pad "2" smd rect
			(at -0.40005 0 90)
			(size 0.4572 0.508)
			(layers "F.Cu" "F.Mask" "F.Paste")
			(net "CRT_R")
		)
	)
	(footprint ""
		(layer "F.Cu")
		(at 11.246866 -97.354136 90)
		(property "Reference" "R1071"
			(at 3.306064 -0.6731 90)
			(unlocked yes)
			(layer "F.SilkS")
			(effects
				(font
					(size 0.7874 0.5842)
					(thickness 0.1524)
				)
				(justify left)
			)
		)
		(property "Value" ""
			(at 0 0 90)
			(layer "F.Fab")
			(effects
				(font
					(size 1.27 1.27)
				)
			)
		)
		(duplicate_pad_numbers_are_jumpers no)
		(fp_line
			(start 3.2258 -1.3462)
			(end 3.2258 1.3462)
			(stroke
				(width 0.1524)
				(type default)
			)
			(layer "F.SilkS")
		)
		(fp_line
			(start -3.2258 -1.3462)
			(end 3.2258 -1.3462)
			(stroke
				(width 0.1524)
				(type default)
			)
			(layer "F.SilkS")
		)
		(fp_line
			(start 3.2258 1.3462)
			(end -3.2258 1.3462)
			(stroke
				(width 0.1524)
				(type default)
			)
			(layer "F.SilkS")
		)
		(fp_line
			(start -3.2258 1.3462)
			(end -3.2258 -1.3462)
			(stroke
				(width 0.1524)
				(type default)
			)
			(layer "F.SilkS")
		)
		(fp_poly
			(pts
				(xy -2.5654 1.3462) (xy -2.5654 1.2192) (xy -3.0734 1.2192) (xy -3.0734 -1.2192) (xy -2.5654 -1.2192)
				(xy -2.5654 -1.3462) (xy 2.5654 -1.3462) (xy 2.5654 -1.2192) (xy 3.0734 -1.2192) (xy 3.0734 1.2192)
				(xy 2.5654 1.2192) (xy 2.5654 1.3462)
			)
			(stroke
				(width 0)
				(type default)
			)
			(fill no)
			(layer "F.CrtYd")
		)
		(pad "1" smd rect
			(at -2.350008 0 90)
			(size 1.4224 2.413)
			(layers "F.Cu" "F.Mask" "F.Paste")
			(net "P12V_DBG")
		)
		(pad "2" smd rect
			(at 2.350008 0 90)
			(size 1.4224 2.413)
			(layers "F.Cu" "F.Mask" "F.Paste")
			(net "P12V_PDB")
		)
	)
	(footprint ""
		(layer "F.Cu")
		(at 90.000074 -62.799976)
		(property "Reference" "H4"
			(at 1.533144 2.478532 0)
			(unlocked yes)
			(layer "F.SilkS")
			(effects
				(font
					(size 0.7874 0.5842)
					(thickness 0.1524)
				)
				(justify left)
			)
		)
		(property "Value" ""
			(at 0 0 0)
			(layer "F.Fab")
			(effects
				(font
					(size 1.27 1.27)
				)
			)
		)
		(duplicate_pad_numbers_are_jumpers no)
		(fp_circle
			(center 0 0)
			(end 2.3114 0)
			(stroke
				(width 0.1524)
				(type default)
			)
			(fill no)
			(layer "F.SilkS")
		)
		(fp_circle
			(center 0 0)
			(end 2.3114 0)
			(stroke
				(width 0.1524)
				(type default)
			)
			(fill no)
			(layer "B.SilkS")
		)
		(fp_poly
			(pts
				(arc
					(start 0 1.4986)
					(mid 0 -1.4986)
					(end 0 1.4986)
				)
			)
			(stroke
				(width 0)
				(type default)
			)
			(fill no)
			(layer "F.CrtYd")
		)
		(pad "" np_thru_hole circle
			(at 0 0)
			(size 2.9972 2.9972)
			(drill 2.9972)
			(layers "*.Cu" "*.Mask")
			(clearance 0.381)
			(thermal_gap 0.381)
		)
		(zone
			(layers "F.Cu" "B.Cu" "In1.Cu" "In2.Cu" "In3.Cu" "In4.Cu" "In5.Cu" "In6.Cu"
				"In7.Cu" "In8.Cu"
			)
			(hatch none 0.5)
			(connect_pads
				(clearance 0)
			)
			(min_thickness 0.25)
			(keepout
				(tracks not_allowed)
				(vias allowed)
				(pads allowed)
				(copperpour not_allowed)
				(footprints allowed)
			)
			(placement
				(enabled no)
				(sheetname "")
			)
			(fill
				(thermal_gap 0.5)
				(thermal_bridge_width 0.5)
				(island_removal_mode 0)
			)
			(polygon
				(pts
					(arc
						(start 90.000074 -60.793376)
						(mid 90.000074 -64.806576)
						(end 90.000074 -60.793376)
					)
				)
			)
		)
	)
	(footprint ""
		(layer "F.Cu")
		(at 169.817542 -131.721606 90)
		(property "Reference" "R661"
			(at -2.02057 -3.109976 90)
			(unlocked yes)
			(layer "F.SilkS")
			(effects
				(font
					(size 0.7874 0.5842)
					(thickness 0.1524)
				)
				(justify left)
			)
		)
		(property "Value" ""
			(at 0 0 90)
			(layer "F.Fab")
			(effects
				(font
					(size 1.27 1.27)
				)
			)
		)
		(duplicate_pad_numbers_are_jumpers no)
		(fp_line
			(start 0.7874 -0.4064)
			(end 0.7874 0.4064)
			(stroke
				(width 0.1524)
				(type default)
			)
			(layer "F.SilkS")
		)
		(fp_line
			(start -0.7874 -0.4064)
			(end 0.7874 -0.4064)
			(stroke
				(width 0.1524)
				(type default)
			)
			(layer "F.SilkS")
		)
		(fp_line
			(start 0.7874 0.4064)
			(end -0.7874 0.4064)
			(stroke
				(width 0.1524)
				(type default)
			)
			(layer "F.SilkS")
		)
		(fp_line
			(start -0.7874 0.4064)
			(end -0.7874 -0.4064)
			(stroke
				(width 0.1524)
				(type default)
			)
			(layer "F.SilkS")
		)
		(fp_poly
			(pts
				(xy -0.508 0.2794) (xy -0.508 0.2286) (xy -0.635 0.2286) (xy -0.635 -0.254) (xy -0.5334 -0.254)
				(xy -0.5334 -0.2794) (xy 0.5334 -0.2794) (xy 0.5334 -0.254) (xy 0.635 -0.254) (xy 0.635 0.254) (xy 0.5334 0.254)
				(xy 0.5334 0.2794)
			)
			(stroke
				(width 0)
				(type default)
			)
			(fill no)
			(layer "F.CrtYd")
		)
		(pad "1" smd rect
			(at 0.40005 0 90)
			(size 0.4572 0.508)
			(layers "F.Cu" "F.Mask" "F.Paste")
			(net "CPLD123_RSV3")
		)
		(pad "2" smd rect
			(at -0.40005 0 90)
			(size 0.4572 0.508)
			(layers "F.Cu" "F.Mask" "F.Paste")
			(net "CPLD1_RSV3")
		)
	)
	(footprint ""
		(layer "F.Cu")
		(at 86.642448 -107.9119)
		(property "Reference" "C42"
			(at -1.20015 -1.076452 0)
			(unlocked yes)
			(layer "F.SilkS")
			(effects
				(font
					(size 0.7874 0.5842)
					(thickness 0.1524)
				)
				(justify left)
			)
		)
		(property "Value" ""
			(at 0 0 0)
			(layer "F.Fab")
			(effects
				(font
					(size 1.27 1.27)
				)
			)
		)
		(duplicate_pad_numbers_are_jumpers no)
		(fp_line
			(start -0.7874 -0.4064)
			(end 0.7874 -0.4064)
			(stroke
				(width 0.1524)
				(type default)
			)
			(layer "F.SilkS")
		)
		(fp_line
			(start -0.7874 0.4064)
			(end -0.7874 -0.4064)
			(stroke
				(width 0.1524)
				(type default)
			)
			(layer "F.SilkS")
		)
		(fp_line
			(start 0 0.381)
			(end 0 -0.381)
			(stroke
				(width 0.1524)
				(type default)
			)
			(layer "F.SilkS")
		)
		(fp_line
			(start 0.7874 -0.4064)
			(end 0.7874 0.4064)
			(stroke
				(width 0.1524)
				(type default)
			)
			(layer "F.SilkS")
		)
		(fp_line
			(start 0.7874 0.4064)
			(end -0.7874 0.4064)
			(stroke
				(width 0.1524)
				(type default)
			)
			(layer "F.SilkS")
		)
		(fp_poly
			(pts
				(xy -0.5334 0.254) (xy -0.635 0.254) (xy -0.635 0.2286) (xy -0.635 -0.254) (xy -0.5334 -0.254) (xy -0.5334 -0.2794)
				(xy 0.5334 -0.2794) (xy 0.5334 -0.254) (xy 0.635 -0.254) (xy 0.635 0.254) (xy 0.5334 0.254) (xy 0.5334 0.2794)
				(xy -0.508 0.2794) (xy -0.5334 0.2794)
			)
			(stroke
				(width 0)
				(type default)
			)
			(fill no)
			(layer "F.CrtYd")
		)
		(pad "1" smd rect
			(at 0.40005 0)
			(size 0.4572 0.508)
			(layers "F.Cu" "F.Mask" "F.Paste")
			(net "P3V3_NODE1")
		)
		(pad "2" smd rect
			(at -0.40005 0)
			(size 0.4572 0.508)
			(layers "F.Cu" "F.Mask" "F.Paste")
			(net "GND")
		)
	)
	(footprint ""
		(layer "F.Cu")
		(at 25.000204 -182.79999)
		(property "Reference" "H8"
			(at 0 0 0)
			(layer "F.SilkS")
			(hide yes)
			(effects
				(font
					(size 1.27 1.27)
				)
			)
		)
		(property "Value" ""
			(at 0 0 0)
			(layer "F.Fab")
			(effects
				(font
					(size 1.27 1.27)
				)
			)
		)
		(duplicate_pad_numbers_are_jumpers no)
		(fp_poly
			(pts
				(arc
					(start 5.999734 5.050028)
					(mid 0 10.999933)
					(end -5.999734 5.050028)
				)
				(arc
					(start -5.999988 0.000254)
					(mid 0 -5.999988)
					(end 5.999988 0.000254)
				)
			)
			(stroke
				(width 0)
				(type default)
			)
			(fill no)
			(layer "B.CrtYd")
		)
		(fp_poly
			(pts
				(arc
					(start 5.999734 5.050028)
					(mid 0 10.999933)
					(end -5.999734 5.050028)
				)
				(arc
					(start -5.999988 0.000254)
					(mid 0 -5.999988)
					(end 5.999988 0.000254)
				)
			)
			(stroke
				(width 0)
				(type default)
			)
			(fill no)
			(layer "F.CrtYd")
		)
		(pad "" np_thru_hole circle
			(at 0 0)
			(size 3.6068 3.6068)
			(drill 3.6068)
			(layers "*.Cu" "*.Mask")
			(clearance 0.381)
			(thermal_gap 0.381)
		)
	)
	(footprint ""
		(layer "F.Cu")
		(at 68.940934 -2.944114 90)
		(property "Reference" "PR19"
			(at -2.74828 -2.869184 90)
			(unlocked yes)
			(layer "F.SilkS")
			(effects
				(font
					(size 0.7874 0.5842)
					(thickness 0.1524)
				)
				(justify left)
			)
		)
		(property "Value" ""
			(at 0 0 90)
			(layer "F.Fab")
			(effects
				(font
					(size 1.27 1.27)
				)
			)
		)
		(duplicate_pad_numbers_are_jumpers no)
		(fp_line
			(start 0.7874 -0.4064)
			(end 0.7874 0.4064)
			(stroke
				(width 0.1524)
				(type default)
			)
			(layer "F.SilkS")
		)
		(fp_line
			(start -0.7874 -0.4064)
			(end 0.7874 -0.4064)
			(stroke
				(width 0.1524)
				(type default)
			)
			(layer "F.SilkS")
		)
		(fp_line
			(start 0.7874 0.4064)
			(end -0.7874 0.4064)
			(stroke
				(width 0.1524)
				(type default)
			)
			(layer "F.SilkS")
		)
		(fp_line
			(start -0.7874 0.4064)
			(end -0.7874 -0.4064)
			(stroke
				(width 0.1524)
				(type default)
			)
			(layer "F.SilkS")
		)
		(fp_poly
			(pts
				(xy -0.508 0.2794) (xy -0.508 0.2286) (xy -0.635 0.2286) (xy -0.635 -0.254) (xy -0.5334 -0.254)
				(xy -0.5334 -0.2794) (xy 0.5334 -0.2794) (xy 0.5334 -0.254) (xy 0.635 -0.254) (xy 0.635 0.254) (xy 0.5334 0.254)
				(xy 0.5334 0.2794)
			)
			(stroke
				(width 0)
				(type default)
			)
			(fill no)
			(layer "F.CrtYd")
		)
		(pad "1" smd rect
			(at 0.40005 0 90)
			(size 0.4572 0.508)
			(layers "F.Cu" "F.Mask" "F.Paste")
			(net "PWRGD_NODE1_P3V3_PG")
		)
		(pad "2" smd rect
			(at -0.40005 0 90)
			(size 0.4572 0.508)
			(layers "F.Cu" "F.Mask" "F.Paste")
			(net "GND")
		)
	)
	(footprint ""
		(layer "F.Cu")
		(at 126.692152 -166.474902)
		(property "Reference" "C908"
			(at 0.07112 -4.415028 0)
			(unlocked yes)
			(layer "F.SilkS")
			(effects
				(font
					(size 0.7874 0.5842)
					(thickness 0.1524)
				)
			)
		)
		(property "Value" ""
			(at 0 0 0)
			(layer "F.Fab")
			(effects
				(font
					(size 1.27 1.27)
				)
			)
		)
		(duplicate_pad_numbers_are_jumpers no)
		(fp_line
			(start -1.2954 -0.5842)
			(end 1.2954 -0.5842)
			(stroke
				(width 0.1524)
				(type default)
			)
			(layer "F.SilkS")
		)
		(fp_line
			(start -1.2954 0.5842)
			(end -1.2954 -0.5842)
			(stroke
				(width 0.1524)
				(type default)
			)
			(layer "F.SilkS")
		)
		(fp_line
			(start 0 -0.5842)
			(end 0 0.5842)
			(stroke
				(width 0.1524)
				(type default)
			)
			(layer "F.SilkS")
		)
		(fp_line
			(start 1.2954 -0.5842)
			(end 1.2954 0.5842)
			(stroke
				(width 0.1524)
				(type default)
			)
			(layer "F.SilkS")
		)
		(fp_line
			(start 1.2954 0.5842)
			(end -1.2954 0.5842)
			(stroke
				(width 0.1524)
				(type default)
			)
			(layer "F.SilkS")
		)
		(fp_poly
			(pts
				(xy 0.8636 -0.4572) (xy 0.8636 -0.3556) (xy 1.143 -0.3556) (xy 1.143 0.3556) (xy 0.8636 0.3556)
				(xy 0.8636 0.4572) (xy -0.8636 0.4572) (xy -0.8636 0.3556) (xy -1.143 0.3556) (xy -1.143 -0.3556)
				(xy -0.8636 -0.3556) (xy -0.8636 -0.4572)
			)
			(stroke
				(width 0)
				(type default)
			)
			(fill no)
			(layer "F.CrtYd")
		)
		(fp_line
			(start -0.884936 -0.504952)
			(end 0.884936 -0.504952)
			(stroke
				(width 0.1)
				(type default)
			)
			(layer "F.Fab")
		)
		(fp_line
			(start -0.884936 0.504952)
			(end -0.884936 -0.504952)
			(stroke
				(width 0.1)
				(type default)
			)
			(layer "F.Fab")
		)
		(fp_line
			(start 0.884936 -0.504952)
			(end 0.884936 0.504952)
			(stroke
				(width 0.1)
				(type default)
			)
			(layer "F.Fab")
		)
		(fp_line
			(start 0.884936 0.504952)
			(end -0.884936 0.504952)
			(stroke
				(width 0.1)
				(type default)
			)
			(layer "F.Fab")
		)
		(pad "1" smd rect
			(at 0.7366 0 90)
			(size 0.7112 0.8128)
			(layers "F.Cu" "F.Mask" "F.Paste")
			(net "P3V3_NODE1")
		)
		(pad "2" smd rect
			(at -0.7366 0 90)
			(size 0.7112 0.8128)
			(layers "F.Cu" "F.Mask" "F.Paste")
			(net "GND")
		)
	)
	(footprint ""
		(layer "F.Cu")
		(at 156.586936 -171.496482 180)
		(property "Reference" "C914"
			(at 1.309116 -1.503934 0)
			(unlocked yes)
			(layer "F.SilkS")
			(effects
				(font
					(size 0.7874 0.5842)
					(thickness 0.1524)
				)
				(justify left)
			)
		)
		(property "Value" ""
			(at 0 0 180)
			(layer "F.Fab")
			(effects
				(font
					(size 1.27 1.27)
				)
			)
		)
		(duplicate_pad_numbers_are_jumpers no)
		(fp_line
			(start 0.7874 0.4064)
			(end -0.7874 0.4064)
			(stroke
				(width 0.1524)
				(type default)
			)
			(layer "F.SilkS")
		)
		(fp_line
			(start 0.7874 -0.4064)
			(end 0.7874 0.4064)
			(stroke
				(width 0.1524)
				(type default)
			)
			(layer "F.SilkS")
		)
		(fp_line
			(start 0 0.381)
			(end 0 -0.381)
			(stroke
				(width 0.1524)
				(type default)
			)
			(layer "F.SilkS")
		)
		(fp_line
			(start -0.7874 0.4064)
			(end -0.7874 -0.4064)
			(stroke
				(width 0.1524)
				(type default)
			)
			(layer "F.SilkS")
		)
		(fp_line
			(start -0.7874 -0.4064)
			(end 0.7874 -0.4064)
			(stroke
				(width 0.1524)
				(type default)
			)
			(layer "F.SilkS")
		)
		(fp_poly
			(pts
				(xy -0.5334 0.254) (xy -0.635 0.254) (xy -0.635 0.2286) (xy -0.635 -0.254) (xy -0.5334 -0.254) (xy -0.5334 -0.2794)
				(xy 0.5334 -0.2794) (xy 0.5334 -0.254) (xy 0.635 -0.254) (xy 0.635 0.254) (xy 0.5334 0.254) (xy 0.5334 0.2794)
				(xy -0.508 0.2794) (xy -0.5334 0.2794)
			)
			(stroke
				(width 0)
				(type default)
			)
			(fill no)
			(layer "F.CrtYd")
		)
		(pad "1" smd rect
			(at 0.40005 0 180)
			(size 0.4572 0.508)
			(layers "F.Cu" "F.Mask" "F.Paste")
			(net "GND")
		)
		(pad "2" smd rect
			(at -0.40005 0 180)
			(size 0.4572 0.508)
			(layers "F.Cu" "F.Mask" "F.Paste")
			(net "N54365623")
		)
	)
	(footprint ""
		(layer "F.Cu")
		(at 72.82434 -100.89134 -90)
		(property "Reference" "R1231"
			(at -1.651 -0.538226 90)
			(unlocked yes)
			(layer "F.SilkS")
			(effects
				(font
					(size 0.7874 0.5842)
					(thickness 0.1524)
				)
				(justify left)
			)
		)
		(property "Value" ""
			(at 0 0 270)
			(layer "F.Fab")
			(effects
				(font
					(size 1.27 1.27)
				)
			)
		)
		(duplicate_pad_numbers_are_jumpers no)
		(fp_line
			(start -0.7874 0.4064)
			(end -0.7874 -0.4064)
			(stroke
				(width 0.1524)
				(type default)
			)
			(layer "F.SilkS")
		)
		(fp_line
			(start 0.7874 0.4064)
			(end -0.7874 0.4064)
			(stroke
				(width 0.1524)
				(type default)
			)
			(layer "F.SilkS")
		)
		(fp_line
			(start -0.7874 -0.4064)
			(end 0.7874 -0.4064)
			(stroke
				(width 0.1524)
				(type default)
			)
			(layer "F.SilkS")
		)
		(fp_line
			(start 0.7874 -0.4064)
			(end 0.7874 0.4064)
			(stroke
				(width 0.1524)
				(type default)
			)
			(layer "F.SilkS")
		)
		(fp_poly
			(pts
				(xy -0.508 0.2794) (xy -0.508 0.2286) (xy -0.635 0.2286) (xy -0.635 -0.254) (xy -0.5334 -0.254)
				(xy -0.5334 -0.2794) (xy 0.5334 -0.2794) (xy 0.5334 -0.254) (xy 0.635 -0.254) (xy 0.635 0.254) (xy 0.5334 0.254)
				(xy 0.5334 0.2794)
			)
			(stroke
				(width 0)
				(type default)
			)
			(fill no)
			(layer "F.CrtYd")
		)
		(pad "1" smd rect
			(at 0.40005 0 270)
			(size 0.4572 0.508)
			(layers "F.Cu" "F.Mask" "F.Paste")
			(net "GND")
		)
		(pad "2" smd rect
			(at -0.40005 0 270)
			(size 0.4572 0.508)
			(layers "F.Cu" "F.Mask" "F.Paste")
			(net "FM_CPLD_NODE1_P1V8_SUS_EN")
		)
	)
	(footprint ""
		(layer "F.Cu")
		(at 112.069118 -163.282122)
		(property "Reference" "R683"
			(at -2.115058 -12.402566 0)
			(unlocked yes)
			(layer "F.SilkS")
			(effects
				(font
					(size 0.7874 0.5842)
					(thickness 0.1524)
				)
				(justify left)
			)
		)
		(property "Value" ""
			(at 0 0 0)
			(layer "F.Fab")
			(effects
				(font
					(size 1.27 1.27)
				)
			)
		)
		(duplicate_pad_numbers_are_jumpers no)
		(fp_line
			(start -0.7874 -0.4064)
			(end 0.7874 -0.4064)
			(stroke
				(width 0.1524)
				(type default)
			)
			(layer "F.SilkS")
		)
		(fp_line
			(start -0.7874 0.4064)
			(end -0.7874 -0.4064)
			(stroke
				(width 0.1524)
				(type default)
			)
			(layer "F.SilkS")
		)
		(fp_line
			(start 0.7874 -0.4064)
			(end 0.7874 0.4064)
			(stroke
				(width 0.1524)
				(type default)
			)
			(layer "F.SilkS")
		)
		(fp_line
			(start 0.7874 0.4064)
			(end -0.7874 0.4064)
			(stroke
				(width 0.1524)
				(type default)
			)
			(layer "F.SilkS")
		)
		(fp_poly
			(pts
				(xy -0.508 0.2794) (xy -0.508 0.2286) (xy -0.635 0.2286) (xy -0.635 -0.254) (xy -0.5334 -0.254)
				(xy -0.5334 -0.2794) (xy 0.5334 -0.2794) (xy 0.5334 -0.254) (xy 0.635 -0.254) (xy 0.635 0.254) (xy 0.5334 0.254)
				(xy 0.5334 0.2794)
			)
			(stroke
				(width 0)
				(type default)
			)
			(fill no)
			(layer "F.CrtYd")
		)
		(pad "1" smd rect
			(at 0.40005 0)
			(size 0.4572 0.508)
			(layers "F.Cu" "F.Mask" "F.Paste")
			(net "I2C_COM3_SCL")
		)
		(pad "2" smd rect
			(at -0.40005 0)
			(size 0.4572 0.508)
			(layers "F.Cu" "F.Mask" "F.Paste")
			(net "I2C_PDB_SCL")
		)
	)
	(footprint ""
		(layer "F.Cu")
		(at 136.161272 -160.248854 90)
		(property "Reference" "C906"
			(at -109.162342 -62.754256 90)
			(unlocked yes)
			(layer "F.SilkS")
			(effects
				(font
					(size 0.7874 0.5842)
					(thickness 0.1524)
				)
				(justify left)
			)
		)
		(property "Value" ""
			(at 0 0 90)
			(layer "F.Fab")
			(effects
				(font
					(size 1.27 1.27)
				)
			)
		)
		(duplicate_pad_numbers_are_jumpers no)
		(fp_line
			(start 0.7874 -0.4064)
			(end 0.7874 0.4064)
			(stroke
				(width 0.1524)
				(type default)
			)
			(layer "F.SilkS")
		)
		(fp_line
			(start -0.7874 -0.4064)
			(end 0.7874 -0.4064)
			(stroke
				(width 0.1524)
				(type default)
			)
			(layer "F.SilkS")
		)
		(fp_line
			(start 0 0.381)
			(end 0 -0.381)
			(stroke
				(width 0.1524)
				(type default)
			)
			(layer "F.SilkS")
		)
		(fp_line
			(start 0.7874 0.4064)
			(end -0.7874 0.4064)
			(stroke
				(width 0.1524)
				(type default)
			)
			(layer "F.SilkS")
		)
		(fp_line
			(start -0.7874 0.4064)
			(end -0.7874 -0.4064)
			(stroke
				(width 0.1524)
				(type default)
			)
			(layer "F.SilkS")
		)
		(fp_poly
			(pts
				(xy -0.5334 0.254) (xy -0.635 0.254) (xy -0.635 0.2286) (xy -0.635 -0.254) (xy -0.5334 -0.254) (xy -0.5334 -0.2794)
				(xy 0.5334 -0.2794) (xy 0.5334 -0.254) (xy 0.635 -0.254) (xy 0.635 0.254) (xy 0.5334 0.254) (xy 0.5334 0.2794)
				(xy -0.508 0.2794) (xy -0.5334 0.2794)
			)
			(stroke
				(width 0)
				(type default)
			)
			(fill no)
			(layer "F.CrtYd")
		)
		(pad "1" smd rect
			(at 0.40005 0 90)
			(size 0.4572 0.508)
			(layers "F.Cu" "F.Mask" "F.Paste")
			(net "P3V3_NODE1")
		)
		(pad "2" smd rect
			(at -0.40005 0 90)
			(size 0.4572 0.508)
			(layers "F.Cu" "F.Mask" "F.Paste")
			(net "GND")
		)
	)
	(footprint ""
		(layer "F.Cu")
		(at 184.7596 -177.4952 180)
		(property "Reference" "R1312"
			(at -9.9568 -17.45107 0)
			(unlocked yes)
			(layer "F.SilkS")
			(effects
				(font
					(size 0.7874 0.5842)
					(thickness 0.1524)
				)
				(justify left)
			)
		)
		(property "Value" ""
			(at 0 0 180)
			(layer "F.Fab")
			(effects
				(font
					(size 1.27 1.27)
				)
			)
		)
		(duplicate_pad_numbers_are_jumpers no)
		(fp_line
			(start 0.7874 0.4064)
			(end -0.7874 0.4064)
			(stroke
				(width 0.1524)
				(type default)
			)
			(layer "F.SilkS")
		)
		(fp_line
			(start 0.7874 -0.4064)
			(end 0.7874 0.4064)
			(stroke
				(width 0.1524)
				(type default)
			)
			(layer "F.SilkS")
		)
		(fp_line
			(start -0.7874 0.4064)
			(end -0.7874 -0.4064)
			(stroke
				(width 0.1524)
				(type default)
			)
			(layer "F.SilkS")
		)
		(fp_line
			(start -0.7874 -0.4064)
			(end 0.7874 -0.4064)
			(stroke
				(width 0.1524)
				(type default)
			)
			(layer "F.SilkS")
		)
		(fp_poly
			(pts
				(xy -0.508 0.2794) (xy -0.508 0.2286) (xy -0.635 0.2286) (xy -0.635 -0.254) (xy -0.5334 -0.254)
				(xy -0.5334 -0.2794) (xy 0.5334 -0.2794) (xy 0.5334 -0.254) (xy 0.635 -0.254) (xy 0.635 0.254) (xy 0.5334 0.254)
				(xy 0.5334 0.2794)
			)
			(stroke
				(width 0)
				(type default)
			)
			(fill no)
			(layer "F.CrtYd")
		)
		(pad "1" smd rect
			(at 0.40005 0 180)
			(size 0.4572 0.508)
			(layers "F.Cu" "F.Mask" "F.Paste")
			(net "POWER_SW2_PWR_CTR_12V")
		)
		(pad "2" smd rect
			(at -0.40005 0 180)
			(size 0.4572 0.508)
			(layers "F.Cu" "F.Mask" "F.Paste")
			(net "POWER_SW2_PWR_CTR_12V_R")
		)
	)
	(footprint ""
		(layer "F.Cu")
		(at 92.716604 -83.324192 -90)
		(property "Reference" "R1215"
			(at 0.933704 0.991108 90)
			(unlocked yes)
			(layer "F.SilkS")
			(effects
				(font
					(size 0.7874 0.5842)
					(thickness 0.1524)
				)
				(justify left)
			)
		)
		(property "Value" ""
			(at 0 0 270)
			(layer "F.Fab")
			(effects
				(font
					(size 1.27 1.27)
				)
			)
		)
		(duplicate_pad_numbers_are_jumpers no)
		(fp_line
			(start -0.7874 0.4064)
			(end -0.7874 -0.4064)
			(stroke
				(width 0.1524)
				(type default)
			)
			(layer "F.SilkS")
		)
		(fp_line
			(start 0.7874 0.4064)
			(end -0.7874 0.4064)
			(stroke
				(width 0.1524)
				(type default)
			)
			(layer "F.SilkS")
		)
		(fp_line
			(start -0.7874 -0.4064)
			(end 0.7874 -0.4064)
			(stroke
				(width 0.1524)
				(type default)
			)
			(layer "F.SilkS")
		)
		(fp_line
			(start 0.7874 -0.4064)
			(end 0.7874 0.4064)
			(stroke
				(width 0.1524)
				(type default)
			)
			(layer "F.SilkS")
		)
		(fp_poly
			(pts
				(xy -0.508 0.2794) (xy -0.508 0.2286) (xy -0.635 0.2286) (xy -0.635 -0.254) (xy -0.5334 -0.254)
				(xy -0.5334 -0.2794) (xy 0.5334 -0.2794) (xy 0.5334 -0.254) (xy 0.635 -0.254) (xy 0.635 0.254) (xy 0.5334 0.254)
				(xy 0.5334 0.2794)
			)
			(stroke
				(width 0)
				(type default)
			)
			(fill no)
			(layer "F.CrtYd")
		)
		(pad "1" smd rect
			(at 0.40005 0 270)
			(size 0.4572 0.508)
			(layers "F.Cu" "F.Mask" "F.Paste")
			(net "N45787194")
		)
		(pad "2" smd rect
			(at -0.40005 0 270)
			(size 0.4572 0.508)
			(layers "F.Cu" "F.Mask" "F.Paste")
			(net "P1V05_NODE1")
		)
	)
	(footprint ""
		(layer "F.Cu")
		(at 166.100252 -93.84919 90)
		(property "Reference" "R532"
			(at -1.23317 -4.402328 90)
			(unlocked yes)
			(layer "F.SilkS")
			(effects
				(font
					(size 0.7874 0.5842)
					(thickness 0.1524)
				)
				(justify left)
			)
		)
		(property "Value" ""
			(at 0 0 90)
			(layer "F.Fab")
			(effects
				(font
					(size 1.27 1.27)
				)
			)
		)
		(duplicate_pad_numbers_are_jumpers no)
		(fp_line
			(start 0.7874 -0.4064)
			(end 0.7874 0.4064)
			(stroke
				(width 0.1524)
				(type default)
			)
			(layer "F.SilkS")
		)
		(fp_line
			(start -0.7874 -0.4064)
			(end 0.7874 -0.4064)
			(stroke
				(width 0.1524)
				(type default)
			)
			(layer "F.SilkS")
		)
		(fp_line
			(start 0.7874 0.4064)
			(end -0.7874 0.4064)
			(stroke
				(width 0.1524)
				(type default)
			)
			(layer "F.SilkS")
		)
		(fp_line
			(start -0.7874 0.4064)
			(end -0.7874 -0.4064)
			(stroke
				(width 0.1524)
				(type default)
			)
			(layer "F.SilkS")
		)
		(fp_poly
			(pts
				(xy -0.508 0.2794) (xy -0.508 0.2286) (xy -0.635 0.2286) (xy -0.635 -0.254) (xy -0.5334 -0.254)
				(xy -0.5334 -0.2794) (xy 0.5334 -0.2794) (xy 0.5334 -0.254) (xy 0.635 -0.254) (xy 0.635 0.254) (xy 0.5334 0.254)
				(xy 0.5334 0.2794)
			)
			(stroke
				(width 0)
				(type default)
			)
			(fill no)
			(layer "F.CrtYd")
		)
		(pad "1" smd rect
			(at 0.40005 0 90)
			(size 0.4572 0.508)
			(layers "F.Cu" "F.Mask" "F.Paste")
			(net "USB_OC_PU")
		)
		(pad "2" smd rect
			(at -0.40005 0 90)
			(size 0.4572 0.508)
			(layers "F.Cu" "F.Mask" "F.Paste")
			(net "P3V3_NODE1")
		)
	)
	(footprint ""
		(layer "F.Cu")
		(at 185.01233 -150.688548 180)
		(property "Reference" "C468"
			(at -3.137408 0.282956 0)
			(unlocked yes)
			(layer "F.SilkS")
			(effects
				(font
					(size 0.7874 0.5842)
					(thickness 0.1524)
				)
			)
		)
		(property "Value" ""
			(at 0 0 180)
			(layer "F.Fab")
			(effects
				(font
					(size 1.27 1.27)
				)
			)
		)
		(duplicate_pad_numbers_are_jumpers no)
		(fp_line
			(start 1.2954 0.5842)
			(end -1.2954 0.5842)
			(stroke
				(width 0.1524)
				(type default)
			)
			(layer "F.SilkS")
		)
		(fp_line
			(start 1.2954 -0.5842)
			(end 1.2954 0.5842)
			(stroke
				(width 0.1524)
				(type default)
			)
			(layer "F.SilkS")
		)
		(fp_line
			(start 0 -0.5842)
			(end 0 0.5842)
			(stroke
				(width 0.1524)
				(type default)
			)
			(layer "F.SilkS")
		)
		(fp_line
			(start -1.2954 0.5842)
			(end -1.2954 -0.5842)
			(stroke
				(width 0.1524)
				(type default)
			)
			(layer "F.SilkS")
		)
		(fp_line
			(start -1.2954 -0.5842)
			(end 1.2954 -0.5842)
			(stroke
				(width 0.1524)
				(type default)
			)
			(layer "F.SilkS")
		)
		(fp_poly
			(pts
				(xy 0.8636 -0.4572) (xy 0.8636 -0.3556) (xy 1.143 -0.3556) (xy 1.143 0.3556) (xy 0.8636 0.3556)
				(xy 0.8636 0.4572) (xy -0.8636 0.4572) (xy -0.8636 0.3556) (xy -1.143 0.3556) (xy -1.143 -0.3556)
				(xy -0.8636 -0.3556) (xy -0.8636 -0.4572)
			)
			(stroke
				(width 0)
				(type default)
			)
			(fill no)
			(layer "F.CrtYd")
		)
		(fp_line
			(start 0.884936 0.504952)
			(end -0.884936 0.504952)
			(stroke
				(width 0.1)
				(type default)
			)
			(layer "F.Fab")
		)
		(fp_line
			(start 0.884936 -0.504952)
			(end 0.884936 0.504952)
			(stroke
				(width 0.1)
				(type default)
			)
			(layer "F.Fab")
		)
		(fp_line
			(start -0.884936 0.504952)
			(end -0.884936 -0.504952)
			(stroke
				(width 0.1)
				(type default)
			)
			(layer "F.Fab")
		)
		(fp_line
			(start -0.884936 -0.504952)
			(end 0.884936 -0.504952)
			(stroke
				(width 0.1)
				(type default)
			)
			(layer "F.Fab")
		)
		(pad "1" smd rect
			(at 0.7366 0 270)
			(size 0.7112 0.8128)
			(layers "F.Cu" "F.Mask" "F.Paste")
			(net "LAN2_CTRL_P1V9_R")
		)
		(pad "2" smd rect
			(at -0.7366 0 270)
			(size 0.7112 0.8128)
			(layers "F.Cu" "F.Mask" "F.Paste")
			(net "P1V9_LAN2")
		)
	)
	(footprint ""
		(layer "F.Cu")
		(at 62.511686 -121.044462 -90)
		(property "Reference" "R336"
			(at 6.142736 -8.573516 90)
			(unlocked yes)
			(layer "F.SilkS")
			(effects
				(font
					(size 0.7874 0.5842)
					(thickness 0.1524)
				)
				(justify left)
			)
		)
		(property "Value" ""
			(at 0 0 270)
			(layer "F.Fab")
			(effects
				(font
					(size 1.27 1.27)
				)
			)
		)
		(duplicate_pad_numbers_are_jumpers no)
		(fp_line
			(start -0.7874 0.4064)
			(end -0.7874 -0.4064)
			(stroke
				(width 0.1524)
				(type default)
			)
			(layer "F.SilkS")
		)
		(fp_line
			(start 0.7874 0.4064)
			(end -0.7874 0.4064)
			(stroke
				(width 0.1524)
				(type default)
			)
			(layer "F.SilkS")
		)
		(fp_line
			(start -0.7874 -0.4064)
			(end 0.7874 -0.4064)
			(stroke
				(width 0.1524)
				(type default)
			)
			(layer "F.SilkS")
		)
		(fp_line
			(start 0.7874 -0.4064)
			(end 0.7874 0.4064)
			(stroke
				(width 0.1524)
				(type default)
			)
			(layer "F.SilkS")
		)
		(fp_poly
			(pts
				(xy -0.508 0.2794) (xy -0.508 0.2286) (xy -0.635 0.2286) (xy -0.635 -0.254) (xy -0.5334 -0.254)
				(xy -0.5334 -0.2794) (xy 0.5334 -0.2794) (xy 0.5334 -0.254) (xy 0.635 -0.254) (xy 0.635 0.254) (xy 0.5334 0.254)
				(xy 0.5334 0.2794)
			)
			(stroke
				(width 0)
				(type default)
			)
			(fill no)
			(layer "F.CrtYd")
		)
		(pad "1" smd rect
			(at 0.40005 0 270)
			(size 0.4572 0.508)
			(layers "F.Cu" "F.Mask" "F.Paste")
			(net "P3V3_NODE1")
		)
		(pad "2" smd rect
			(at -0.40005 0 270)
			(size 0.4572 0.508)
			(layers "F.Cu" "F.Mask" "F.Paste")
			(net "BMC_ROMA20")
		)
	)
	(footprint ""
		(layer "F.Cu")
		(at 33.173162 -107.26928 180)
		(property "Reference" "R1087"
			(at -1.528318 -0.703072 0)
			(unlocked yes)
			(layer "F.SilkS")
			(effects
				(font
					(size 0.7874 0.5842)
					(thickness 0.1524)
				)
				(justify left)
			)
		)
		(property "Value" ""
			(at 0 0 180)
			(layer "F.Fab")
			(effects
				(font
					(size 1.27 1.27)
				)
			)
		)
		(duplicate_pad_numbers_are_jumpers no)
		(fp_line
			(start 0.7874 0.4064)
			(end -0.7874 0.4064)
			(stroke
				(width 0.1524)
				(type default)
			)
			(layer "F.SilkS")
		)
		(fp_line
			(start 0.7874 -0.4064)
			(end 0.7874 0.4064)
			(stroke
				(width 0.1524)
				(type default)
			)
			(layer "F.SilkS")
		)
		(fp_line
			(start -0.7874 0.4064)
			(end -0.7874 -0.4064)
			(stroke
				(width 0.1524)
				(type default)
			)
			(layer "F.SilkS")
		)
		(fp_line
			(start -0.7874 -0.4064)
			(end 0.7874 -0.4064)
			(stroke
				(width 0.1524)
				(type default)
			)
			(layer "F.SilkS")
		)
		(fp_poly
			(pts
				(xy -0.508 0.2794) (xy -0.508 0.2286) (xy -0.635 0.2286) (xy -0.635 -0.254) (xy -0.5334 -0.254)
				(xy -0.5334 -0.2794) (xy 0.5334 -0.2794) (xy 0.5334 -0.254) (xy 0.635 -0.254) (xy 0.635 0.254) (xy 0.5334 0.254)
				(xy 0.5334 0.2794)
			)
			(stroke
				(width 0)
				(type default)
			)
			(fill no)
			(layer "F.CrtYd")
		)
		(pad "1" smd rect
			(at 0.40005 0 180)
			(size 0.4572 0.508)
			(layers "F.Cu" "F.Mask" "F.Paste")
			(net "P3V3_STB_NODE1")
		)
		(pad "2" smd rect
			(at -0.40005 0 180)
			(size 0.4572 0.508)
			(layers "F.Cu" "F.Mask" "F.Paste")
			(net "PWRGD_NODE1_P1V5_SUS_PG")
		)
	)
	(footprint ""
		(layer "F.Cu")
		(at 94.248986 -138.040618 180)
		(property "Reference" "R1086"
			(at 1.001014 4.063746 0)
			(unlocked yes)
			(layer "F.SilkS")
			(effects
				(font
					(size 0.7874 0.5842)
					(thickness 0.1524)
				)
				(justify left)
			)
		)
		(property "Value" ""
			(at 0 0 180)
			(layer "F.Fab")
			(effects
				(font
					(size 1.27 1.27)
				)
			)
		)
		(duplicate_pad_numbers_are_jumpers no)
		(fp_line
			(start 0.7874 0.4064)
			(end -0.7874 0.4064)
			(stroke
				(width 0.1524)
				(type default)
			)
			(layer "F.SilkS")
		)
		(fp_line
			(start 0.7874 -0.4064)
			(end 0.7874 0.4064)
			(stroke
				(width 0.1524)
				(type default)
			)
			(layer "F.SilkS")
		)
		(fp_line
			(start -0.7874 0.4064)
			(end -0.7874 -0.4064)
			(stroke
				(width 0.1524)
				(type default)
			)
			(layer "F.SilkS")
		)
		(fp_line
			(start -0.7874 -0.4064)
			(end 0.7874 -0.4064)
			(stroke
				(width 0.1524)
				(type default)
			)
			(layer "F.SilkS")
		)
		(fp_poly
			(pts
				(xy -0.508 0.2794) (xy -0.508 0.2286) (xy -0.635 0.2286) (xy -0.635 -0.254) (xy -0.5334 -0.254)
				(xy -0.5334 -0.2794) (xy 0.5334 -0.2794) (xy 0.5334 -0.254) (xy 0.635 -0.254) (xy 0.635 0.254) (xy 0.5334 0.254)
				(xy 0.5334 0.2794)
			)
			(stroke
				(width 0)
				(type default)
			)
			(fill no)
			(layer "F.CrtYd")
		)
		(pad "1" smd rect
			(at 0.40005 0 180)
			(size 0.4572 0.508)
			(layers "F.Cu" "F.Mask" "F.Paste")
			(net "GND")
		)
		(pad "2" smd rect
			(at -0.40005 0 180)
			(size 0.4572 0.508)
			(layers "F.Cu" "F.Mask" "F.Paste")
			(net "P1V05_SUS_NODE1_ADJ")
		)
	)
	(footprint ""
		(layer "F.Cu")
		(at 137.98169 -53.754528 180)
		(property "Reference" "R1156"
			(at 4.53009 -0.212598 0)
			(unlocked yes)
			(layer "F.SilkS")
			(effects
				(font
					(size 0.7874 0.5842)
					(thickness 0.1524)
				)
				(justify left)
			)
		)
		(property "Value" ""
			(at 0 0 180)
			(layer "F.Fab")
			(effects
				(font
					(size 1.27 1.27)
				)
			)
		)
		(duplicate_pad_numbers_are_jumpers no)
		(fp_line
			(start 0.7874 0.4064)
			(end -0.7874 0.4064)
			(stroke
				(width 0.1524)
				(type default)
			)
			(layer "F.SilkS")
		)
		(fp_line
			(start 0.7874 -0.4064)
			(end 0.7874 0.4064)
			(stroke
				(width 0.1524)
				(type default)
			)
			(layer "F.SilkS")
		)
		(fp_line
			(start -0.7874 0.4064)
			(end -0.7874 -0.4064)
			(stroke
				(width 0.1524)
				(type default)
			)
			(layer "F.SilkS")
		)
		(fp_line
			(start -0.7874 -0.4064)
			(end 0.7874 -0.4064)
			(stroke
				(width 0.1524)
				(type default)
			)
			(layer "F.SilkS")
		)
		(fp_poly
			(pts
				(xy -0.508 0.2794) (xy -0.508 0.2286) (xy -0.635 0.2286) (xy -0.635 -0.254) (xy -0.5334 -0.254)
				(xy -0.5334 -0.2794) (xy 0.5334 -0.2794) (xy 0.5334 -0.254) (xy 0.635 -0.254) (xy 0.635 0.254) (xy 0.5334 0.254)
				(xy 0.5334 0.2794)
			)
			(stroke
				(width 0)
				(type default)
			)
			(fill no)
			(layer "F.CrtYd")
		)
		(pad "1" smd rect
			(at 0.40005 0 180)
			(size 0.4572 0.508)
			(layers "F.Cu" "F.Mask" "F.Paste")
			(net "UART_DTR_P3_N")
		)
		(pad "2" smd rect
			(at -0.40005 0 180)
			(size 0.4572 0.508)
			(layers "F.Cu" "F.Mask" "F.Paste")
			(net "GND")
		)
	)
	(footprint ""
		(layer "F.Cu")
		(at 63.10376 -188.126624 90)
		(property "Reference" "C697"
			(at 4.548886 -0.019558 90)
			(unlocked yes)
			(layer "F.SilkS")
			(effects
				(font
					(size 0.7874 0.5842)
					(thickness 0.1524)
				)
				(justify left)
			)
		)
		(property "Value" ""
			(at 0 0 90)
			(layer "F.Fab")
			(effects
				(font
					(size 1.27 1.27)
				)
			)
		)
		(duplicate_pad_numbers_are_jumpers no)
		(fp_line
			(start 0.7874 -0.4064)
			(end 0.7874 0.4064)
			(stroke
				(width 0.1524)
				(type default)
			)
			(layer "F.SilkS")
		)
		(fp_line
			(start -0.7874 -0.4064)
			(end 0.7874 -0.4064)
			(stroke
				(width 0.1524)
				(type default)
			)
			(layer "F.SilkS")
		)
		(fp_line
			(start 0 0.381)
			(end 0 -0.381)
			(stroke
				(width 0.1524)
				(type default)
			)
			(layer "F.SilkS")
		)
		(fp_line
			(start 0.7874 0.4064)
			(end -0.7874 0.4064)
			(stroke
				(width 0.1524)
				(type default)
			)
			(layer "F.SilkS")
		)
		(fp_line
			(start -0.7874 0.4064)
			(end -0.7874 -0.4064)
			(stroke
				(width 0.1524)
				(type default)
			)
			(layer "F.SilkS")
		)
		(fp_poly
			(pts
				(xy -0.5334 0.254) (xy -0.635 0.254) (xy -0.635 0.2286) (xy -0.635 -0.254) (xy -0.5334 -0.254) (xy -0.5334 -0.2794)
				(xy 0.5334 -0.2794) (xy 0.5334 -0.254) (xy 0.635 -0.254) (xy 0.635 0.254) (xy 0.5334 0.254) (xy 0.5334 0.2794)
				(xy -0.508 0.2794) (xy -0.5334 0.2794)
			)
			(stroke
				(width 0)
				(type default)
			)
			(fill no)
			(layer "F.CrtYd")
		)
		(pad "1" smd rect
			(at 0.40005 0 90)
			(size 0.4572 0.508)
			(layers "F.Cu" "F.Mask" "F.Paste")
			(net "UART_T2_NODE1_TXD_R")
		)
		(pad "2" smd rect
			(at -0.40005 0 90)
			(size 0.4572 0.508)
			(layers "F.Cu" "F.Mask" "F.Paste")
			(net "GND")
		)
	)
	(footprint ""
		(layer "F.Cu")
		(at 88.291924 -180.790596 -90)
		(property "Reference" "R1177"
			(at 2.271776 -1.026922 90)
			(unlocked yes)
			(layer "F.SilkS")
			(effects
				(font
					(size 0.635 0.4064)
					(thickness 0.1524)
				)
				(justify left)
			)
		)
		(property "Value" ""
			(at 0 0 270)
			(layer "F.Fab")
			(effects
				(font
					(size 1.27 1.27)
				)
			)
		)
		(duplicate_pad_numbers_are_jumpers no)
		(fp_line
			(start -0.7874 0.4064)
			(end -0.7874 -0.4064)
			(stroke
				(width 0.1524)
				(type default)
			)
			(layer "F.SilkS")
		)
		(fp_line
			(start 0.7874 0.4064)
			(end -0.7874 0.4064)
			(stroke
				(width 0.1524)
				(type default)
			)
			(layer "F.SilkS")
		)
		(fp_line
			(start -0.7874 -0.4064)
			(end 0.7874 -0.4064)
			(stroke
				(width 0.1524)
				(type default)
			)
			(layer "F.SilkS")
		)
		(fp_line
			(start 0.7874 -0.4064)
			(end 0.7874 0.4064)
			(stroke
				(width 0.1524)
				(type default)
			)
			(layer "F.SilkS")
		)
		(fp_poly
			(pts
				(xy -0.508 0.2794) (xy -0.508 0.2286) (xy -0.635 0.2286) (xy -0.635 -0.254) (xy -0.5334 -0.254)
				(xy -0.5334 -0.2794) (xy 0.5334 -0.2794) (xy 0.5334 -0.254) (xy 0.635 -0.254) (xy 0.635 0.254) (xy 0.5334 0.254)
				(xy 0.5334 0.2794)
			)
			(stroke
				(width 0)
				(type default)
			)
			(fill no)
			(layer "F.CrtYd")
		)
		(pad "1" smd rect
			(at 0.40005 0 270)
			(size 0.4572 0.508)
			(layers "F.Cu" "F.Mask" "F.Paste")
			(net "CPLD_UART_DTR_P4_N")
		)
		(pad "2" smd rect
			(at -0.40005 0 270)
			(size 0.4572 0.508)
			(layers "F.Cu" "F.Mask" "F.Paste")
			(net "GND")
		)
	)
	(footprint ""
		(layer "F.Cu")
		(at 55.78856 -121.344182 -90)
		(property "Reference" "R312"
			(at 2.333752 5.8801 90)
			(unlocked yes)
			(layer "F.SilkS")
			(effects
				(font
					(size 0.7874 0.5842)
					(thickness 0.1524)
				)
				(justify left)
			)
		)
		(property "Value" ""
			(at 0 0 270)
			(layer "F.Fab")
			(effects
				(font
					(size 1.27 1.27)
				)
			)
		)
		(duplicate_pad_numbers_are_jumpers no)
		(fp_line
			(start -0.7874 0.4064)
			(end -0.7874 -0.4064)
			(stroke
				(width 0.1524)
				(type default)
			)
			(layer "F.SilkS")
		)
		(fp_line
			(start 0.7874 0.4064)
			(end -0.7874 0.4064)
			(stroke
				(width 0.1524)
				(type default)
			)
			(layer "F.SilkS")
		)
		(fp_line
			(start -0.7874 -0.4064)
			(end 0.7874 -0.4064)
			(stroke
				(width 0.1524)
				(type default)
			)
			(layer "F.SilkS")
		)
		(fp_line
			(start 0.7874 -0.4064)
			(end 0.7874 0.4064)
			(stroke
				(width 0.1524)
				(type default)
			)
			(layer "F.SilkS")
		)
		(fp_poly
			(pts
				(xy -0.508 0.2794) (xy -0.508 0.2286) (xy -0.635 0.2286) (xy -0.635 -0.254) (xy -0.5334 -0.254)
				(xy -0.5334 -0.2794) (xy 0.5334 -0.2794) (xy 0.5334 -0.254) (xy 0.635 -0.254) (xy 0.635 0.254) (xy 0.5334 0.254)
				(xy 0.5334 0.2794)
			)
			(stroke
				(width 0)
				(type default)
			)
			(fill no)
			(layer "F.CrtYd")
		)
		(pad "1" smd rect
			(at 0.40005 0 270)
			(size 0.4572 0.508)
			(layers "F.Cu" "F.Mask" "F.Paste")
			(net "BMC_NODE1_CLK_24M_R")
		)
		(pad "2" smd rect
			(at -0.40005 0 270)
			(size 0.4572 0.508)
			(layers "F.Cu" "F.Mask" "F.Paste")
			(net "BMC_NODE1_CLK_24M")
		)
	)
	(footprint ""
		(layer "F.Cu")
		(at 182.412894 -135.89762)
		(property "Reference" "R1047"
			(at 5.246878 0.058674 0)
			(unlocked yes)
			(layer "F.SilkS")
			(effects
				(font
					(size 0.7874 0.5842)
					(thickness 0.1524)
				)
				(justify left)
			)
		)
		(property "Value" ""
			(at 0 0 0)
			(layer "F.Fab")
			(effects
				(font
					(size 1.27 1.27)
				)
			)
		)
		(duplicate_pad_numbers_are_jumpers no)
		(fp_line
			(start -0.7874 -0.4064)
			(end 0.7874 -0.4064)
			(stroke
				(width 0.1524)
				(type default)
			)
			(layer "F.SilkS")
		)
		(fp_line
			(start -0.7874 0.4064)
			(end -0.7874 -0.4064)
			(stroke
				(width 0.1524)
				(type default)
			)
			(layer "F.SilkS")
		)
		(fp_line
			(start 0.7874 -0.4064)
			(end 0.7874 0.4064)
			(stroke
				(width 0.1524)
				(type default)
			)
			(layer "F.SilkS")
		)
		(fp_line
			(start 0.7874 0.4064)
			(end -0.7874 0.4064)
			(stroke
				(width 0.1524)
				(type default)
			)
			(layer "F.SilkS")
		)
		(fp_poly
			(pts
				(xy -0.508 0.2794) (xy -0.508 0.2286) (xy -0.635 0.2286) (xy -0.635 -0.254) (xy -0.5334 -0.254)
				(xy -0.5334 -0.2794) (xy 0.5334 -0.2794) (xy 0.5334 -0.254) (xy 0.635 -0.254) (xy 0.635 0.254) (xy 0.5334 0.254)
				(xy 0.5334 0.2794)
			)
			(stroke
				(width 0)
				(type default)
			)
			(fill no)
			(layer "F.CrtYd")
		)
		(pad "1" smd rect
			(at 0.40005 0)
			(size 0.4572 0.508)
			(layers "F.Cu" "F.Mask" "F.Paste")
			(net "FM_NODE1_DFX_GPIO_GRP05_R")
		)
		(pad "2" smd rect
			(at -0.40005 0)
			(size 0.4572 0.508)
			(layers "F.Cu" "F.Mask" "F.Paste")
			(net "FM_NODE1_DFX_GPIO_GRP05")
		)
	)
	(footprint ""
		(layer "F.Cu")
		(at 16.730472 -70.778878 180)
		(property "Reference" "FS2"
			(at -3.502152 1.438656 0)
			(unlocked yes)
			(layer "F.SilkS")
			(effects
				(font
					(size 0.7874 0.5842)
					(thickness 0.1524)
				)
				(justify left)
			)
		)
		(property "Value" ""
			(at 0 0 180)
			(layer "F.Fab")
			(effects
				(font
					(size 1.27 1.27)
				)
			)
		)
		(duplicate_pad_numbers_are_jumpers no)
		(fp_line
			(start 2.7686 1.8034)
			(end -2.7686 1.8034)
			(stroke
				(width 0.1524)
				(type default)
			)
			(layer "F.SilkS")
		)
		(fp_line
			(start 2.7686 -1.8034)
			(end 2.7686 1.8034)
			(stroke
				(width 0.1524)
				(type default)
			)
			(layer "F.SilkS")
		)
		(fp_line
			(start -2.7686 1.8034)
			(end -2.7686 -1.8034)
			(stroke
				(width 0.1524)
				(type default)
			)
			(layer "F.SilkS")
		)
		(fp_line
			(start -2.7686 -1.8034)
			(end 2.7686 -1.8034)
			(stroke
				(width 0.1524)
				(type default)
			)
			(layer "F.SilkS")
		)
		(fp_poly
			(pts
				(xy -2.6162 1.6764) (xy -2.6162 -1.6764) (xy -1.3716 -1.6764) (xy -1.3716 -1.6002) (xy 1.3716 -1.6002)
				(xy 1.3716 -1.6764) (xy 2.6162 -1.6764) (xy 2.6162 1.6764) (xy 1.3716 1.6764) (xy 1.3716 1.6002)
				(xy -1.3716 1.6002) (xy -1.3716 1.6764)
			)
			(stroke
				(width 0)
				(type default)
			)
			(fill no)
			(layer "F.CrtYd")
		)
		(pad "1" smd rect
			(at -1.999996 0 180)
			(size 1.2192 3.302)
			(layers "F.Cu" "F.Mask" "F.Paste")
			(net "P5V_CRT")
		)
		(pad "2" smd rect
			(at 1.999996 0 180)
			(size 1.2192 3.302)
			(layers "F.Cu" "F.Mask" "F.Paste")
			(net "N21581564")
		)
	)
	(footprint ""
		(layer "F.Cu")
		(at 90.231468 -163.618164)
		(property "Reference" "R801"
			(at 86.577932 70.003416 0)
			(unlocked yes)
			(layer "F.SilkS")
			(effects
				(font
					(size 0.7874 0.5842)
					(thickness 0.1524)
				)
				(justify left)
			)
		)
		(property "Value" ""
			(at 0 0 0)
			(layer "F.Fab")
			(effects
				(font
					(size 1.27 1.27)
				)
			)
		)
		(duplicate_pad_numbers_are_jumpers no)
		(fp_line
			(start -0.7874 -0.4064)
			(end 0.7874 -0.4064)
			(stroke
				(width 0.1524)
				(type default)
			)
			(layer "F.SilkS")
		)
		(fp_line
			(start -0.7874 0.4064)
			(end -0.7874 -0.4064)
			(stroke
				(width 0.1524)
				(type default)
			)
			(layer "F.SilkS")
		)
		(fp_line
			(start 0.7874 -0.4064)
			(end 0.7874 0.4064)
			(stroke
				(width 0.1524)
				(type default)
			)
			(layer "F.SilkS")
		)
		(fp_line
			(start 0.7874 0.4064)
			(end -0.7874 0.4064)
			(stroke
				(width 0.1524)
				(type default)
			)
			(layer "F.SilkS")
		)
		(fp_poly
			(pts
				(xy -0.508 0.2794) (xy -0.508 0.2286) (xy -0.635 0.2286) (xy -0.635 -0.254) (xy -0.5334 -0.254)
				(xy -0.5334 -0.2794) (xy 0.5334 -0.2794) (xy 0.5334 -0.254) (xy 0.635 -0.254) (xy 0.635 0.254) (xy 0.5334 0.254)
				(xy 0.5334 0.2794)
			)
			(stroke
				(width 0)
				(type default)
			)
			(fill no)
			(layer "F.CrtYd")
		)
		(pad "1" smd rect
			(at 0.40005 0)
			(size 0.4572 0.508)
			(layers "F.Cu" "F.Mask" "F.Paste")
			(net "POWER_SW1_PWR_CTR_N")
		)
		(pad "2" smd rect
			(at -0.40005 0)
			(size 0.4572 0.508)
			(layers "F.Cu" "F.Mask" "F.Paste")
			(net "P3V3_STB_NODE1")
		)
	)
	(footprint ""
		(layer "F.Cu")
		(at 133.470396 -130.487166 90)
		(property "Reference" "C189"
			(at -1.572768 2.122678 90)
			(unlocked yes)
			(layer "F.SilkS")
			(effects
				(font
					(size 0.7874 0.5842)
					(thickness 0.1524)
				)
				(justify left)
			)
		)
		(property "Value" ""
			(at 0 0 90)
			(layer "F.Fab")
			(effects
				(font
					(size 1.27 1.27)
				)
			)
		)
		(duplicate_pad_numbers_are_jumpers no)
		(fp_line
			(start 0.7874 -0.4064)
			(end 0.7874 0.4064)
			(stroke
				(width 0.1524)
				(type default)
			)
			(layer "F.SilkS")
		)
		(fp_line
			(start -0.7874 -0.4064)
			(end 0.7874 -0.4064)
			(stroke
				(width 0.1524)
				(type default)
			)
			(layer "F.SilkS")
		)
		(fp_line
			(start 0 0.381)
			(end 0 -0.381)
			(stroke
				(width 0.1524)
				(type default)
			)
			(layer "F.SilkS")
		)
		(fp_line
			(start 0.7874 0.4064)
			(end -0.7874 0.4064)
			(stroke
				(width 0.1524)
				(type default)
			)
			(layer "F.SilkS")
		)
		(fp_line
			(start -0.7874 0.4064)
			(end -0.7874 -0.4064)
			(stroke
				(width 0.1524)
				(type default)
			)
			(layer "F.SilkS")
		)
		(fp_poly
			(pts
				(xy -0.5334 0.254) (xy -0.635 0.254) (xy -0.635 0.2286) (xy -0.635 -0.254) (xy -0.5334 -0.254) (xy -0.5334 -0.2794)
				(xy 0.5334 -0.2794) (xy 0.5334 -0.254) (xy 0.635 -0.254) (xy 0.635 0.254) (xy 0.5334 0.254) (xy 0.5334 0.2794)
				(xy -0.508 0.2794) (xy -0.5334 0.2794)
			)
			(stroke
				(width 0)
				(type default)
			)
			(fill no)
			(layer "F.CrtYd")
		)
		(pad "1" smd rect
			(at 0.40005 0 90)
			(size 0.4572 0.508)
			(layers "F.Cu" "F.Mask" "F.Paste")
			(net "P2E_CPU_USB_NODE1_TX_C_DP")
		)
		(pad "2" smd rect
			(at -0.40005 0 90)
			(size 0.4572 0.508)
			(layers "F.Cu" "F.Mask" "F.Paste")
			(net "P2E_CPU_USB_NODE1_TX_DP")
		)
	)
	(footprint ""
		(layer "F.Cu")
		(at 54.282086 -118.377462)
		(property "Reference" "OSC3"
			(at -6.004814 0.615442 90)
			(unlocked yes)
			(layer "F.SilkS")
			(effects
				(font
					(size 0.7874 0.5842)
					(thickness 0.1524)
				)
				(justify left)
			)
		)
		(property "Value" ""
			(at 0 0 0)
			(layer "F.Fab")
			(effects
				(font
					(size 1.27 1.27)
				)
			)
		)
		(duplicate_pad_numbers_are_jumpers no)
		(fp_line
			(start -1.9558 -1.6002)
			(end 1.9558 -1.6002)
			(stroke
				(width 0.1524)
				(type default)
			)
			(layer "F.SilkS")
		)
		(fp_line
			(start -1.9558 1.6002)
			(end -1.9558 -1.6002)
			(stroke
				(width 0.1524)
				(type default)
			)
			(layer "F.SilkS")
		)
		(fp_line
			(start -1.903984 -0.1016)
			(end -1.524 0)
			(stroke
				(width 0.1524)
				(type default)
			)
			(layer "F.SilkS")
		)
		(fp_line
			(start -1.524 0)
			(end -1.903984 0.1016)
			(stroke
				(width 0.1524)
				(type default)
			)
			(layer "F.SilkS")
		)
		(fp_line
			(start 1.9558 -1.6002)
			(end 1.9558 1.6002)
			(stroke
				(width 0.1524)
				(type default)
			)
			(layer "F.SilkS")
		)
		(fp_line
			(start 1.9558 1.6002)
			(end -1.9558 1.6002)
			(stroke
				(width 0.1524)
				(type default)
			)
			(layer "F.SilkS")
		)
		(fp_poly
			(pts
				(xy -1.0668 1.7145) (xy -1.651 2.8067) (xy -0.5842 2.8067)
			)
			(stroke
				(width 0)
				(type default)
			)
			(fill yes)
			(layer "F.SilkS")
		)
		(fp_poly
			(pts
				(xy -0.3302 1.299972) (xy 0.3302 1.299972) (xy 0.3302 1.524) (xy 1.8796 1.524) (xy 1.8796 0.1778)
				(xy 1.649984 0.1778) (xy 1.649984 -0.1778) (xy 1.8796 -0.1778) (xy 1.8796 -1.524) (xy 0.3302 -1.524)
				(xy 0.3302 -1.299972) (xy -0.3302 -1.299972) (xy -0.3302 -1.524) (xy -1.8796 -1.524) (xy -1.8796 -0.1778)
				(xy -1.649984 -0.1778) (xy -1.649984 0.1778) (xy -1.8796 0.1778) (xy -1.8796 1.524) (xy -0.3302 1.524)
			)
			(stroke
				(width 0)
				(type default)
			)
			(fill no)
			(layer "F.CrtYd")
		)
		(fp_line
			(start -1.649984 -1.299972)
			(end 1.649984 -1.299972)
			(stroke
				(width 0.1)
				(type default)
			)
			(layer "F.Fab")
		)
		(fp_line
			(start -1.649984 1.299972)
			(end -1.649984 -1.299972)
			(stroke
				(width 0.1)
				(type default)
			)
			(layer "F.Fab")
		)
		(fp_line
			(start 1.649984 -1.299972)
			(end 1.649984 1.299972)
			(stroke
				(width 0.1)
				(type default)
			)
			(layer "F.Fab")
		)
		(fp_line
			(start 1.649984 1.299972)
			(end -1.649984 1.299972)
			(stroke
				(width 0.1)
				(type default)
			)
			(layer "F.Fab")
		)
		(fp_text user "1"
			(at -2.608834 1.98247 0)
			(unlocked yes)
			(layer "F.SilkS")
			(effects
				(font
					(size 0.635 0.4064)
					(thickness 0.1524)
				)
				(justify left)
			)
		)
		(fp_text user "4"
			(at -2.51968 -0.016002 0)
			(unlocked yes)
			(layer "F.SilkS")
			(effects
				(font
					(size 0.635 0.4064)
					(thickness 0.1524)
				)
				(justify left)
			)
		)
		(fp_text user "3"
			(at 1.963166 -1.95453 0)
			(unlocked yes)
			(layer "F.SilkS")
			(effects
				(font
					(size 0.635 0.4064)
					(thickness 0.1524)
				)
				(justify left)
			)
		)
		(fp_text user "2"
			(at 2.090166 2.23647 0)
			(unlocked yes)
			(layer "F.SilkS")
			(effects
				(font
					(size 0.635 0.4064)
					(thickness 0.1524)
				)
				(justify left)
			)
		)
		(pad "1" smd rect
			(at -1.100074 0.849884 90)
			(size 1.2192 1.4224)
			(layers "F.Cu" "F.Mask" "F.Paste")
			(net "BMC_NODE1_OSC1_EN")
		)
		(pad "2" smd rect
			(at 1.100074 0.849884 90)
			(size 1.2192 1.4224)
			(layers "F.Cu" "F.Mask" "F.Paste")
			(net "GND")
		)
		(pad "3" smd rect
			(at 1.100074 -0.849884 90)
			(size 1.2192 1.4224)
			(layers "F.Cu" "F.Mask" "F.Paste")
			(net "BMC_NODE1_CLK_24M_R")
		)
		(pad "4" smd rect
			(at -1.100074 -0.849884 90)
			(size 1.2192 1.4224)
			(layers "F.Cu" "F.Mask" "F.Paste")
			(net "BMC_NODE1_OSC1_VDD")
		)
	)
	(footprint ""
		(layer "F.Cu")
		(at 140.069316 -25.812242 -90)
		(property "Reference" "R1139"
			(at 10.732008 -4.259326 90)
			(unlocked yes)
			(layer "F.SilkS")
			(effects
				(font
					(size 0.7874 0.5842)
					(thickness 0.1524)
				)
				(justify left)
			)
		)
		(property "Value" ""
			(at 0 0 270)
			(layer "F.Fab")
			(effects
				(font
					(size 1.27 1.27)
				)
			)
		)
		(duplicate_pad_numbers_are_jumpers no)
		(fp_line
			(start -0.7874 0.4064)
			(end -0.7874 -0.4064)
			(stroke
				(width 0.1524)
				(type default)
			)
			(layer "F.SilkS")
		)
		(fp_line
			(start 0.7874 0.4064)
			(end -0.7874 0.4064)
			(stroke
				(width 0.1524)
				(type default)
			)
			(layer "F.SilkS")
		)
		(fp_line
			(start -0.7874 -0.4064)
			(end 0.7874 -0.4064)
			(stroke
				(width 0.1524)
				(type default)
			)
			(layer "F.SilkS")
		)
		(fp_line
			(start 0.7874 -0.4064)
			(end 0.7874 0.4064)
			(stroke
				(width 0.1524)
				(type default)
			)
			(layer "F.SilkS")
		)
		(fp_poly
			(pts
				(xy -0.508 0.2794) (xy -0.508 0.2286) (xy -0.635 0.2286) (xy -0.635 -0.254) (xy -0.5334 -0.254)
				(xy -0.5334 -0.2794) (xy 0.5334 -0.2794) (xy 0.5334 -0.254) (xy 0.635 -0.254) (xy 0.635 0.254) (xy 0.5334 0.254)
				(xy 0.5334 0.2794)
			)
			(stroke
				(width 0)
				(type default)
			)
			(fill no)
			(layer "F.CrtYd")
		)
		(pad "1" smd rect
			(at 0.40005 0 270)
			(size 0.4572 0.508)
			(layers "F.Cu" "F.Mask" "F.Paste")
			(net "P3V3_NODE1")
		)
		(pad "2" smd rect
			(at -0.40005 0 270)
			(size 0.4572 0.508)
			(layers "F.Cu" "F.Mask" "F.Paste")
			(net "UART_DSR_P6_N")
		)
	)
	(footprint ""
		(layer "F.Cu")
		(at 94.467426 -167.162734)
		(property "Reference" "C577"
			(at 86.63305 73.147936 0)
			(unlocked yes)
			(layer "F.SilkS")
			(effects
				(font
					(size 0.7874 0.5842)
					(thickness 0.1524)
				)
				(justify left)
			)
		)
		(property "Value" ""
			(at 0 0 0)
			(layer "F.Fab")
			(effects
				(font
					(size 1.27 1.27)
				)
			)
		)
		(duplicate_pad_numbers_are_jumpers no)
		(fp_line
			(start -0.7874 -0.4064)
			(end 0.7874 -0.4064)
			(stroke
				(width 0.1524)
				(type default)
			)
			(layer "F.SilkS")
		)
		(fp_line
			(start -0.7874 0.4064)
			(end -0.7874 -0.4064)
			(stroke
				(width 0.1524)
				(type default)
			)
			(layer "F.SilkS")
		)
		(fp_line
			(start 0 0.381)
			(end 0 -0.381)
			(stroke
				(width 0.1524)
				(type default)
			)
			(layer "F.SilkS")
		)
		(fp_line
			(start 0.7874 -0.4064)
			(end 0.7874 0.4064)
			(stroke
				(width 0.1524)
				(type default)
			)
			(layer "F.SilkS")
		)
		(fp_line
			(start 0.7874 0.4064)
			(end -0.7874 0.4064)
			(stroke
				(width 0.1524)
				(type default)
			)
			(layer "F.SilkS")
		)
		(fp_poly
			(pts
				(xy -0.5334 0.254) (xy -0.635 0.254) (xy -0.635 0.2286) (xy -0.635 -0.254) (xy -0.5334 -0.254) (xy -0.5334 -0.2794)
				(xy 0.5334 -0.2794) (xy 0.5334 -0.254) (xy 0.635 -0.254) (xy 0.635 0.254) (xy 0.5334 0.254) (xy 0.5334 0.2794)
				(xy -0.508 0.2794) (xy -0.5334 0.2794)
			)
			(stroke
				(width 0)
				(type default)
			)
			(fill no)
			(layer "F.CrtYd")
		)
		(pad "1" smd rect
			(at 0.40005 0)
			(size 0.4572 0.508)
			(layers "F.Cu" "F.Mask" "F.Paste")
			(net "P3V3_NODE1")
		)
		(pad "2" smd rect
			(at -0.40005 0)
			(size 0.4572 0.508)
			(layers "F.Cu" "F.Mask" "F.Paste")
			(net "GND")
		)
	)
	(footprint ""
		(layer "F.Cu")
		(at 54.344062 -152.643078)
		(property "Reference" "C391"
			(at -2.277872 -2.017522 0)
			(unlocked yes)
			(layer "F.SilkS")
			(effects
				(font
					(size 0.7874 0.5842)
					(thickness 0.1524)
				)
				(justify left)
			)
		)
		(property "Value" ""
			(at 0 0 0)
			(layer "F.Fab")
			(effects
				(font
					(size 1.27 1.27)
				)
			)
		)
		(duplicate_pad_numbers_are_jumpers no)
		(fp_line
			(start -0.7874 -0.4064)
			(end 0.7874 -0.4064)
			(stroke
				(width 0.1524)
				(type default)
			)
			(layer "F.SilkS")
		)
		(fp_line
			(start -0.7874 0.4064)
			(end -0.7874 -0.4064)
			(stroke
				(width 0.1524)
				(type default)
			)
			(layer "F.SilkS")
		)
		(fp_line
			(start 0 0.381)
			(end 0 -0.381)
			(stroke
				(width 0.1524)
				(type default)
			)
			(layer "F.SilkS")
		)
		(fp_line
			(start 0.7874 -0.4064)
			(end 0.7874 0.4064)
			(stroke
				(width 0.1524)
				(type default)
			)
			(layer "F.SilkS")
		)
		(fp_line
			(start 0.7874 0.4064)
			(end -0.7874 0.4064)
			(stroke
				(width 0.1524)
				(type default)
			)
			(layer "F.SilkS")
		)
		(fp_poly
			(pts
				(xy -0.5334 0.254) (xy -0.635 0.254) (xy -0.635 0.2286) (xy -0.635 -0.254) (xy -0.5334 -0.254) (xy -0.5334 -0.2794)
				(xy 0.5334 -0.2794) (xy 0.5334 -0.254) (xy 0.635 -0.254) (xy 0.635 0.254) (xy 0.5334 0.254) (xy 0.5334 0.2794)
				(xy -0.508 0.2794) (xy -0.5334 0.2794)
			)
			(stroke
				(width 0)
				(type default)
			)
			(fill no)
			(layer "F.CrtYd")
		)
		(pad "1" smd rect
			(at 0.40005 0)
			(size 0.4572 0.508)
			(layers "F.Cu" "F.Mask" "F.Paste")
			(net "P2E_CPU_NIC1_NODE1_RX_DP")
		)
		(pad "2" smd rect
			(at -0.40005 0)
			(size 0.4572 0.508)
			(layers "F.Cu" "F.Mask" "F.Paste")
			(net "PCIE_LAN1_RX_C_DP")
		)
	)
	(footprint ""
		(layer "F.Cu")
		(at 37.885878 -14.22527 -90)
		(property "Reference" "PR103"
			(at 0.98171 3.471926 90)
			(unlocked yes)
			(layer "F.SilkS")
			(effects
				(font
					(size 0.7874 0.5842)
					(thickness 0.1524)
				)
				(justify left)
			)
		)
		(property "Value" ""
			(at 0 0 270)
			(layer "F.Fab")
			(effects
				(font
					(size 1.27 1.27)
				)
			)
		)
		(duplicate_pad_numbers_are_jumpers no)
		(fp_line
			(start -0.7874 0.4064)
			(end -0.7874 -0.4064)
			(stroke
				(width 0.1524)
				(type default)
			)
			(layer "F.SilkS")
		)
		(fp_line
			(start 0.7874 0.4064)
			(end -0.7874 0.4064)
			(stroke
				(width 0.1524)
				(type default)
			)
			(layer "F.SilkS")
		)
		(fp_line
			(start -0.7874 -0.4064)
			(end 0.7874 -0.4064)
			(stroke
				(width 0.1524)
				(type default)
			)
			(layer "F.SilkS")
		)
		(fp_line
			(start 0.7874 -0.4064)
			(end 0.7874 0.4064)
			(stroke
				(width 0.1524)
				(type default)
			)
			(layer "F.SilkS")
		)
		(fp_poly
			(pts
				(xy -0.508 0.2794) (xy -0.508 0.2286) (xy -0.635 0.2286) (xy -0.635 -0.254) (xy -0.5334 -0.254)
				(xy -0.5334 -0.2794) (xy 0.5334 -0.2794) (xy 0.5334 -0.254) (xy 0.635 -0.254) (xy 0.635 0.254) (xy 0.5334 0.254)
				(xy 0.5334 0.2794)
			)
			(stroke
				(width 0)
				(type default)
			)
			(fill no)
			(layer "F.CrtYd")
		)
		(pad "1" smd rect
			(at 0.40005 0 270)
			(size 0.4572 0.508)
			(layers "F.Cu" "F.Mask" "F.Paste")
			(net "PV_VDDR_NODE1_TRIP")
		)
		(pad "2" smd rect
			(at -0.40005 0 270)
			(size 0.4572 0.508)
			(layers "F.Cu" "F.Mask" "F.Paste")
			(net "GND")
		)
	)
	(footprint ""
		(layer "F.Cu")
		(at 166.73322 -124.88291 180)
		(property "Reference" "R1050"
			(at 2.81559 -9.851644 0)
			(unlocked yes)
			(layer "F.SilkS")
			(effects
				(font
					(size 0.7874 0.5842)
					(thickness 0.1524)
				)
				(justify left)
			)
		)
		(property "Value" ""
			(at 0 0 180)
			(layer "F.Fab")
			(effects
				(font
					(size 1.27 1.27)
				)
			)
		)
		(duplicate_pad_numbers_are_jumpers no)
		(fp_line
			(start 0.7874 0.4064)
			(end -0.7874 0.4064)
			(stroke
				(width 0.1524)
				(type default)
			)
			(layer "F.SilkS")
		)
		(fp_line
			(start 0.7874 -0.4064)
			(end 0.7874 0.4064)
			(stroke
				(width 0.1524)
				(type default)
			)
			(layer "F.SilkS")
		)
		(fp_line
			(start -0.7874 0.4064)
			(end -0.7874 -0.4064)
			(stroke
				(width 0.1524)
				(type default)
			)
			(layer "F.SilkS")
		)
		(fp_line
			(start -0.7874 -0.4064)
			(end 0.7874 -0.4064)
			(stroke
				(width 0.1524)
				(type default)
			)
			(layer "F.SilkS")
		)
		(fp_poly
			(pts
				(xy -0.508 0.2794) (xy -0.508 0.2286) (xy -0.635 0.2286) (xy -0.635 -0.254) (xy -0.5334 -0.254)
				(xy -0.5334 -0.2794) (xy 0.5334 -0.2794) (xy 0.5334 -0.254) (xy 0.635 -0.254) (xy 0.635 0.254) (xy 0.5334 0.254)
				(xy 0.5334 0.2794)
			)
			(stroke
				(width 0)
				(type default)
			)
			(fill no)
			(layer "F.CrtYd")
		)
		(pad "1" smd rect
			(at 0.40005 0 180)
			(size 0.4572 0.508)
			(layers "F.Cu" "F.Mask" "F.Paste")
			(net "FM_CPLD_NODE1_JTAG_POK_R_L")
		)
		(pad "2" smd rect
			(at -0.40005 0 180)
			(size 0.4572 0.508)
			(layers "F.Cu" "F.Mask" "F.Paste")
			(net "FM_CPLD_NODE1_JTAG_POK_L")
		)
	)
	(footprint ""
		(layer "F.Cu")
		(at 171.879006 -93.877892 180)
		(property "Reference" "R526"
			(at -3.550158 -0.561594 90)
			(unlocked yes)
			(layer "F.SilkS")
			(effects
				(font
					(size 0.7874 0.5842)
					(thickness 0.1524)
				)
				(justify left)
			)
		)
		(property "Value" ""
			(at 0 0 180)
			(layer "F.Fab")
			(effects
				(font
					(size 1.27 1.27)
				)
			)
		)
		(duplicate_pad_numbers_are_jumpers no)
		(fp_line
			(start 0.7874 0.4064)
			(end -0.7874 0.4064)
			(stroke
				(width 0.1524)
				(type default)
			)
			(layer "F.SilkS")
		)
		(fp_line
			(start 0.7874 -0.4064)
			(end 0.7874 0.4064)
			(stroke
				(width 0.1524)
				(type default)
			)
			(layer "F.SilkS")
		)
		(fp_line
			(start -0.7874 0.4064)
			(end -0.7874 -0.4064)
			(stroke
				(width 0.1524)
				(type default)
			)
			(layer "F.SilkS")
		)
		(fp_line
			(start -0.7874 -0.4064)
			(end 0.7874 -0.4064)
			(stroke
				(width 0.1524)
				(type default)
			)
			(layer "F.SilkS")
		)
		(fp_poly
			(pts
				(xy -0.508 0.2794) (xy -0.508 0.2286) (xy -0.635 0.2286) (xy -0.635 -0.254) (xy -0.5334 -0.254)
				(xy -0.5334 -0.2794) (xy 0.5334 -0.2794) (xy 0.5334 -0.254) (xy 0.635 -0.254) (xy 0.635 0.254) (xy 0.5334 0.254)
				(xy 0.5334 0.2794)
			)
			(stroke
				(width 0)
				(type default)
			)
			(fill no)
			(layer "F.CrtYd")
		)
		(pad "1" smd rect
			(at 0.40005 0 180)
			(size 0.4572 0.508)
			(layers "F.Cu" "F.Mask" "F.Paste")
			(net "USB_NODE1_RREF")
		)
		(pad "2" smd rect
			(at -0.40005 0 180)
			(size 0.4572 0.508)
			(layers "F.Cu" "F.Mask" "F.Paste")
			(net "GND")
		)
	)
	(footprint ""
		(layer "F.Cu")
		(at 151.62276 -188.126624 -90)
		(property "Reference" "R981"
			(at -5.519674 2.935732 90)
			(unlocked yes)
			(layer "F.SilkS")
			(effects
				(font
					(size 0.7874 0.5842)
					(thickness 0.1524)
				)
				(justify left)
			)
		)
		(property "Value" ""
			(at 0 0 270)
			(layer "F.Fab")
			(effects
				(font
					(size 1.27 1.27)
				)
			)
		)
		(duplicate_pad_numbers_are_jumpers no)
		(fp_line
			(start -0.7874 0.4064)
			(end -0.7874 -0.4064)
			(stroke
				(width 0.1524)
				(type default)
			)
			(layer "F.SilkS")
		)
		(fp_line
			(start 0.7874 0.4064)
			(end -0.7874 0.4064)
			(stroke
				(width 0.1524)
				(type default)
			)
			(layer "F.SilkS")
		)
		(fp_line
			(start -0.7874 -0.4064)
			(end 0.7874 -0.4064)
			(stroke
				(width 0.1524)
				(type default)
			)
			(layer "F.SilkS")
		)
		(fp_line
			(start 0.7874 -0.4064)
			(end 0.7874 0.4064)
			(stroke
				(width 0.1524)
				(type default)
			)
			(layer "F.SilkS")
		)
		(fp_poly
			(pts
				(xy -0.508 0.2794) (xy -0.508 0.2286) (xy -0.635 0.2286) (xy -0.635 -0.254) (xy -0.5334 -0.254)
				(xy -0.5334 -0.2794) (xy 0.5334 -0.2794) (xy 0.5334 -0.254) (xy 0.635 -0.254) (xy 0.635 0.254) (xy 0.5334 0.254)
				(xy 0.5334 0.2794)
			)
			(stroke
				(width 0)
				(type default)
			)
			(fill no)
			(layer "F.CrtYd")
		)
		(pad "1" smd rect
			(at 0.40005 0 270)
			(size 0.4572 0.508)
			(layers "F.Cu" "F.Mask" "F.Paste")
			(net "UART_T12_NODE1_RXD")
		)
		(pad "2" smd rect
			(at -0.40005 0 270)
			(size 0.4572 0.508)
			(layers "F.Cu" "F.Mask" "F.Paste")
			(net "UART_T12_NODE1_RXD_R")
		)
	)
	(footprint ""
		(layer "F.Cu")
		(at 164.384482 -73.331324)
		(property "Reference" "C852"
			(at 2.60731 -0.278384 0)
			(unlocked yes)
			(layer "F.SilkS")
			(effects
				(font
					(size 0.7874 0.5842)
					(thickness 0.1524)
				)
				(justify left)
			)
		)
		(property "Value" ""
			(at 0 0 0)
			(layer "F.Fab")
			(effects
				(font
					(size 1.27 1.27)
				)
			)
		)
		(duplicate_pad_numbers_are_jumpers no)
		(fp_line
			(start -0.7874 -0.4064)
			(end 0.7874 -0.4064)
			(stroke
				(width 0.1524)
				(type default)
			)
			(layer "F.SilkS")
		)
		(fp_line
			(start -0.7874 0.4064)
			(end -0.7874 -0.4064)
			(stroke
				(width 0.1524)
				(type default)
			)
			(layer "F.SilkS")
		)
		(fp_line
			(start 0 0.381)
			(end 0 -0.381)
			(stroke
				(width 0.1524)
				(type default)
			)
			(layer "F.SilkS")
		)
		(fp_line
			(start 0.7874 -0.4064)
			(end 0.7874 0.4064)
			(stroke
				(width 0.1524)
				(type default)
			)
			(layer "F.SilkS")
		)
		(fp_line
			(start 0.7874 0.4064)
			(end -0.7874 0.4064)
			(stroke
				(width 0.1524)
				(type default)
			)
			(layer "F.SilkS")
		)
		(fp_poly
			(pts
				(xy -0.5334 0.254) (xy -0.635 0.254) (xy -0.635 0.2286) (xy -0.635 -0.254) (xy -0.5334 -0.254) (xy -0.5334 -0.2794)
				(xy 0.5334 -0.2794) (xy 0.5334 -0.254) (xy 0.635 -0.254) (xy 0.635 0.254) (xy 0.5334 0.254) (xy 0.5334 0.2794)
				(xy -0.508 0.2794) (xy -0.5334 0.2794)
			)
			(stroke
				(width 0)
				(type default)
			)
			(fill no)
			(layer "F.CrtYd")
		)
		(pad "1" smd rect
			(at 0.40005 0)
			(size 0.4572 0.508)
			(layers "F.Cu" "F.Mask" "F.Paste")
			(net "N47241340")
		)
		(pad "2" smd rect
			(at -0.40005 0)
			(size 0.4572 0.508)
			(layers "F.Cu" "F.Mask" "F.Paste")
			(net "GND")
		)
	)
	(footprint ""
		(layer "F.Cu")
		(at 33.639252 -179.990242 180)
		(property "Reference" "U100"
			(at 1.857502 -4.473448 90)
			(unlocked yes)
			(layer "F.SilkS")
			(effects
				(font
					(size 0.7874 0.5842)
					(thickness 0.1524)
				)
				(justify left)
			)
		)
		(property "Value" ""
			(at 0 0 180)
			(layer "F.Fab")
			(effects
				(font
					(size 1.27 1.27)
				)
			)
		)
		(duplicate_pad_numbers_are_jumpers no)
		(fp_line
			(start 1.550924 1.340104)
			(end -1.550924 1.340104)
			(stroke
				(width 0.1524)
				(type default)
			)
			(layer "F.SilkS")
		)
		(fp_line
			(start 1.550924 -1.340104)
			(end 1.550924 1.340104)
			(stroke
				(width 0.1524)
				(type default)
			)
			(layer "F.SilkS")
		)
		(fp_line
			(start -0.929894 0)
			(end -1.550924 -0.499872)
			(stroke
				(width 0.1524)
				(type default)
			)
			(layer "F.SilkS")
		)
		(fp_line
			(start -1.550924 1.340104)
			(end -1.550924 0.499872)
			(stroke
				(width 0.1524)
				(type default)
			)
			(layer "F.SilkS")
		)
		(fp_line
			(start -1.550924 0.499872)
			(end -0.929894 0)
			(stroke
				(width 0.1524)
				(type default)
			)
			(layer "F.SilkS")
		)
		(fp_line
			(start -1.550924 -0.499872)
			(end -1.550924 -1.340104)
			(stroke
				(width 0.1524)
				(type default)
			)
			(layer "F.SilkS")
		)
		(fp_line
			(start -1.550924 -1.340104)
			(end 1.550924 -1.340104)
			(stroke
				(width 0.1524)
				(type default)
			)
			(layer "F.SilkS")
		)
		(fp_poly
			(pts
				(xy -1.500124 1.3716) (xy -1.500124 0.4572) (xy -0.999998 0) (xy -1.500124 -0.4572) (xy -1.500124 -1.3716)
				(xy 1.500124 -1.3716) (xy 1.500124 1.3716)
			)
			(stroke
				(width 0)
				(type default)
			)
			(fill yes)
			(layer "F.SilkS")
		)
		(fp_poly
			(pts
				(xy -1.1684 2.9464) (xy -1.1684 1.3462) (xy -1.5494 1.3462) (xy -1.5494 -1.3462) (xy -1.1684 -1.3462)
				(xy -1.1684 -2.9464) (xy 1.1684 -2.9464) (xy 1.1684 -1.3462) (xy 1.5748 -1.3462) (xy 1.5748 1.3462)
				(xy 1.1684 1.3462) (xy 1.1684 2.9464)
			)
			(stroke
				(width 0)
				(type default)
			)
			(fill no)
			(layer "F.CrtYd")
		)
		(fp_line
			(start 1.5748 1.3462)
			(end -1.5494 1.3462)
			(stroke
				(width 0.1)
				(type default)
			)
			(layer "F.Fab")
		)
		(fp_line
			(start 1.5748 -1.3462)
			(end 1.5748 1.3462)
			(stroke
				(width 0.1)
				(type default)
			)
			(layer "F.Fab")
		)
		(fp_line
			(start -1.5494 1.3462)
			(end -1.5494 0)
			(stroke
				(width 0.1)
				(type default)
			)
			(layer "F.Fab")
		)
		(fp_line
			(start -1.5494 0)
			(end -1.5494 -1.3462)
			(stroke
				(width 0.1)
				(type default)
			)
			(layer "F.Fab")
		)
		(fp_line
			(start -1.5494 -1.3462)
			(end 1.5748 -1.3462)
			(stroke
				(width 0.1)
				(type default)
			)
			(layer "F.Fab")
		)
		(pad "1" smd rect
			(at -0.999998 2.22504 180)
			(size 0.2794 1.4478)
			(layers "F.Cu" "F.Mask" "F.Paste")
			(net "P12V_PDB")
		)
		(pad "2" smd rect
			(at -0.499872 2.22504 180)
			(size 0.2794 1.4478)
			(layers "F.Cu" "F.Mask" "F.Paste")
			(net "VSENSE_HSC_NODE1")
		)
		(pad "3" smd rect
			(at 0 2.22504 180)
			(size 0.2794 1.4478)
			(layers "F.Cu" "F.Mask" "F.Paste")
			(net "P12V_AUX_EN")
		)
		(pad "4" smd rect
			(at 0.499872 2.22504 180)
			(size 0.2794 1.4478)
			(layers "F.Cu" "F.Mask" "F.Paste")
			(net "AGND_HSC_NODE1")
		)
		(pad "5" smd rect
			(at 0.999998 2.22504 180)
			(size 0.2794 1.4478)
			(layers "F.Cu" "F.Mask" "F.Paste")
			(net "VR_HSC_NODE1_TIMER")
		)
		(pad "6" smd rect
			(at 0.999998 -2.22504 180)
			(size 0.2794 1.4478)
			(layers "F.Cu" "F.Mask" "F.Paste")
			(net "SMB_CPU_NODE1_BMC_CLK")
		)
		(pad "7" smd rect
			(at 0.499872 -2.22504 180)
			(size 0.2794 1.4478)
			(layers "F.Cu" "F.Mask" "F.Paste")
			(net "SMB_CPU_NODE1_BMC_DAT")
		)
		(pad "8" smd rect
			(at 0 -2.22504 180)
			(size 0.2794 1.4478)
			(layers "F.Cu" "F.Mask" "F.Paste")
			(net "AGND_HSC_NODE1")
		)
		(pad "9" smd rect
			(at -0.499872 -2.22504 180)
			(size 0.2794 1.4478)
			(layers "F.Cu" "F.Mask" "F.Paste")
			(net "VR_HSC_NODE1_GATE_R")
		)
		(pad "10" smd rect
			(at -0.999998 -2.22504 180)
			(size 0.2794 1.4478)
			(layers "F.Cu" "F.Mask" "F.Paste")
			(net "SMB_BMC_NODE1_HSC_ALERT_R_L")
		)
	)
	(footprint ""
		(layer "F.Cu")
		(at 144.942052 -142.19555)
		(property "Reference" "R233"
			(at -1.015746 17.738344 0)
			(unlocked yes)
			(layer "F.SilkS")
			(effects
				(font
					(size 0.7874 0.5842)
					(thickness 0.1524)
				)
				(justify left)
			)
		)
		(property "Value" ""
			(at 0 0 0)
			(layer "F.Fab")
			(effects
				(font
					(size 1.27 1.27)
				)
			)
		)
		(duplicate_pad_numbers_are_jumpers no)
		(fp_line
			(start -0.7874 -0.4064)
			(end 0.7874 -0.4064)
			(stroke
				(width 0.1524)
				(type default)
			)
			(layer "F.SilkS")
		)
		(fp_line
			(start -0.7874 0.4064)
			(end -0.7874 -0.4064)
			(stroke
				(width 0.1524)
				(type default)
			)
			(layer "F.SilkS")
		)
		(fp_line
			(start 0.7874 -0.4064)
			(end 0.7874 0.4064)
			(stroke
				(width 0.1524)
				(type default)
			)
			(layer "F.SilkS")
		)
		(fp_line
			(start 0.7874 0.4064)
			(end -0.7874 0.4064)
			(stroke
				(width 0.1524)
				(type default)
			)
			(layer "F.SilkS")
		)
		(fp_poly
			(pts
				(xy -0.508 0.2794) (xy -0.508 0.2286) (xy -0.635 0.2286) (xy -0.635 -0.254) (xy -0.5334 -0.254)
				(xy -0.5334 -0.2794) (xy 0.5334 -0.2794) (xy 0.5334 -0.254) (xy 0.635 -0.254) (xy 0.635 0.254) (xy 0.5334 0.254)
				(xy 0.5334 0.2794)
			)
			(stroke
				(width 0)
				(type default)
			)
			(fill no)
			(layer "F.CrtYd")
		)
		(pad "1" smd rect
			(at 0.40005 0)
			(size 0.4572 0.508)
			(layers "F.Cu" "F.Mask" "F.Paste")
			(net "SMB_CPU_NODE1_BMC_DAT")
		)
		(pad "2" smd rect
			(at -0.40005 0)
			(size 0.4572 0.508)
			(layers "F.Cu" "F.Mask" "F.Paste")
			(net "PCIE_SW_I2C_SDA")
		)
	)
	(footprint ""
		(layer "F.Cu")
		(at 184.3786 -184.8612)
		(property "Reference" "R1271"
			(at 9.4234 16.96847 0)
			(unlocked yes)
			(layer "F.SilkS")
			(effects
				(font
					(size 0.7874 0.5842)
					(thickness 0.1524)
				)
				(justify left)
			)
		)
		(property "Value" ""
			(at 0 0 0)
			(layer "F.Fab")
			(effects
				(font
					(size 1.27 1.27)
				)
			)
		)
		(duplicate_pad_numbers_are_jumpers no)
		(fp_line
			(start -0.7874 -0.4064)
			(end 0.7874 -0.4064)
			(stroke
				(width 0.1524)
				(type default)
			)
			(layer "F.SilkS")
		)
		(fp_line
			(start -0.7874 0.4064)
			(end -0.7874 -0.4064)
			(stroke
				(width 0.1524)
				(type default)
			)
			(layer "F.SilkS")
		)
		(fp_line
			(start 0.7874 -0.4064)
			(end 0.7874 0.4064)
			(stroke
				(width 0.1524)
				(type default)
			)
			(layer "F.SilkS")
		)
		(fp_line
			(start 0.7874 0.4064)
			(end -0.7874 0.4064)
			(stroke
				(width 0.1524)
				(type default)
			)
			(layer "F.SilkS")
		)
		(fp_poly
			(pts
				(xy -0.508 0.2794) (xy -0.508 0.2286) (xy -0.635 0.2286) (xy -0.635 -0.254) (xy -0.5334 -0.254)
				(xy -0.5334 -0.2794) (xy 0.5334 -0.2794) (xy 0.5334 -0.254) (xy 0.635 -0.254) (xy 0.635 0.254) (xy 0.5334 0.254)
				(xy 0.5334 0.2794)
			)
			(stroke
				(width 0)
				(type default)
			)
			(fill no)
			(layer "F.CrtYd")
		)
		(pad "1" smd rect
			(at 0.40005 0)
			(size 0.4572 0.508)
			(layers "F.Cu" "F.Mask" "F.Paste")
			(net "POWER_SW3_PWR_CTR_12V")
		)
		(pad "2" smd rect
			(at -0.40005 0)
			(size 0.4572 0.508)
			(layers "F.Cu" "F.Mask" "F.Paste")
			(net "POWER_SW3_PWR_CTR_12V_R")
		)
	)
	(footprint ""
		(layer "F.Cu")
		(at 34.456878 -11.033506 180)
		(property "Reference" "PR36"
			(at 10.748772 0.014478 0)
			(unlocked yes)
			(layer "F.SilkS")
			(effects
				(font
					(size 0.7874 0.5842)
					(thickness 0.1524)
				)
				(justify left)
			)
		)
		(property "Value" ""
			(at 0 0 180)
			(layer "F.Fab")
			(effects
				(font
					(size 1.27 1.27)
				)
			)
		)
		(duplicate_pad_numbers_are_jumpers no)
		(fp_line
			(start 0.7874 0.4064)
			(end -0.7874 0.4064)
			(stroke
				(width 0.1524)
				(type default)
			)
			(layer "F.SilkS")
		)
		(fp_line
			(start 0.7874 -0.4064)
			(end 0.7874 0.4064)
			(stroke
				(width 0.1524)
				(type default)
			)
			(layer "F.SilkS")
		)
		(fp_line
			(start -0.7874 0.4064)
			(end -0.7874 -0.4064)
			(stroke
				(width 0.1524)
				(type default)
			)
			(layer "F.SilkS")
		)
		(fp_line
			(start -0.7874 -0.4064)
			(end 0.7874 -0.4064)
			(stroke
				(width 0.1524)
				(type default)
			)
			(layer "F.SilkS")
		)
		(fp_poly
			(pts
				(xy -0.508 0.2794) (xy -0.508 0.2286) (xy -0.635 0.2286) (xy -0.635 -0.254) (xy -0.5334 -0.254)
				(xy -0.5334 -0.2794) (xy 0.5334 -0.2794) (xy 0.5334 -0.254) (xy 0.635 -0.254) (xy 0.635 0.254) (xy 0.5334 0.254)
				(xy 0.5334 0.2794)
			)
			(stroke
				(width 0)
				(type default)
			)
			(fill no)
			(layer "F.CrtYd")
		)
		(pad "1" smd rect
			(at 0.40005 0 180)
			(size 0.4572 0.508)
			(layers "F.Cu" "F.Mask" "F.Paste")
			(net "GND")
		)
		(pad "2" smd rect
			(at -0.40005 0 180)
			(size 0.4572 0.508)
			(layers "F.Cu" "F.Mask" "F.Paste")
			(net "PV_VDDR_NODE1_V1")
		)
	)
	(footprint ""
		(layer "F.Cu")
		(at 170.176698 -12.474194 90)
		(property "Reference" "R1199"
			(at -0.940054 -0.998728 90)
			(unlocked yes)
			(layer "F.SilkS")
			(effects
				(font
					(size 0.7874 0.5842)
					(thickness 0.1524)
				)
				(justify left)
			)
		)
		(property "Value" ""
			(at 0 0 90)
			(layer "F.Fab")
			(effects
				(font
					(size 1.27 1.27)
				)
			)
		)
		(duplicate_pad_numbers_are_jumpers no)
		(fp_line
			(start 0.7874 -0.4064)
			(end 0.7874 0.4064)
			(stroke
				(width 0.1524)
				(type default)
			)
			(layer "F.SilkS")
		)
		(fp_line
			(start -0.7874 -0.4064)
			(end 0.7874 -0.4064)
			(stroke
				(width 0.1524)
				(type default)
			)
			(layer "F.SilkS")
		)
		(fp_line
			(start 0.7874 0.4064)
			(end -0.7874 0.4064)
			(stroke
				(width 0.1524)
				(type default)
			)
			(layer "F.SilkS")
		)
		(fp_line
			(start -0.7874 0.4064)
			(end -0.7874 -0.4064)
			(stroke
				(width 0.1524)
				(type default)
			)
			(layer "F.SilkS")
		)
		(fp_poly
			(pts
				(xy -0.508 0.2794) (xy -0.508 0.2286) (xy -0.635 0.2286) (xy -0.635 -0.254) (xy -0.5334 -0.254)
				(xy -0.5334 -0.2794) (xy 0.5334 -0.2794) (xy 0.5334 -0.254) (xy 0.635 -0.254) (xy 0.635 0.254) (xy 0.5334 0.254)
				(xy 0.5334 0.2794)
			)
			(stroke
				(width 0)
				(type default)
			)
			(fill no)
			(layer "F.CrtYd")
		)
		(pad "1" smd rect
			(at 0.40005 0 90)
			(size 0.4572 0.508)
			(layers "F.Cu" "F.Mask" "F.Paste")
			(net "SIO_JTAG_CPLD3_TDO")
		)
		(pad "2" smd rect
			(at -0.40005 0 90)
			(size 0.4572 0.508)
			(layers "F.Cu" "F.Mask" "F.Paste")
			(net "JTAG_CPLD3_TDO")
		)
	)
	(footprint ""
		(layer "F.Cu")
		(at 106.170476 -170.965876 180)
		(property "Reference" "R763"
			(at -1.206754 -0.19431 0)
			(unlocked yes)
			(layer "F.SilkS")
			(effects
				(font
					(size 0.7874 0.5842)
					(thickness 0.1524)
				)
				(justify left)
			)
		)
		(property "Value" ""
			(at 0 0 180)
			(layer "F.Fab")
			(effects
				(font
					(size 1.27 1.27)
				)
			)
		)
		(duplicate_pad_numbers_are_jumpers no)
		(fp_line
			(start 0.7874 0.4064)
			(end -0.7874 0.4064)
			(stroke
				(width 0.1524)
				(type default)
			)
			(layer "F.SilkS")
		)
		(fp_line
			(start 0.7874 -0.4064)
			(end 0.7874 0.4064)
			(stroke
				(width 0.1524)
				(type default)
			)
			(layer "F.SilkS")
		)
		(fp_line
			(start -0.7874 0.4064)
			(end -0.7874 -0.4064)
			(stroke
				(width 0.1524)
				(type default)
			)
			(layer "F.SilkS")
		)
		(fp_line
			(start -0.7874 -0.4064)
			(end 0.7874 -0.4064)
			(stroke
				(width 0.1524)
				(type default)
			)
			(layer "F.SilkS")
		)
		(fp_poly
			(pts
				(xy -0.508 0.2794) (xy -0.508 0.2286) (xy -0.635 0.2286) (xy -0.635 -0.254) (xy -0.5334 -0.254)
				(xy -0.5334 -0.2794) (xy 0.5334 -0.2794) (xy 0.5334 -0.254) (xy 0.635 -0.254) (xy 0.635 0.254) (xy 0.5334 0.254)
				(xy 0.5334 0.2794)
			)
			(stroke
				(width 0)
				(type default)
			)
			(fill no)
			(layer "F.CrtYd")
		)
		(pad "1" smd rect
			(at 0.40005 0 180)
			(size 0.4572 0.508)
			(layers "F.Cu" "F.Mask" "F.Paste")
			(net "FNACTRL1_ADD")
		)
		(pad "2" smd rect
			(at -0.40005 0 180)
			(size 0.4572 0.508)
			(layers "F.Cu" "F.Mask" "F.Paste")
			(net "GND")
		)
	)
	(footprint ""
		(layer "F.Cu")
		(at 79.66456 -151.70277)
		(property "Reference" "R1082"
			(at -0.218948 5.82295 90)
			(unlocked yes)
			(layer "F.SilkS")
			(effects
				(font
					(size 0.7874 0.5842)
					(thickness 0.1524)
				)
				(justify left)
			)
		)
		(property "Value" ""
			(at 0 0 0)
			(layer "F.Fab")
			(effects
				(font
					(size 1.27 1.27)
				)
			)
		)
		(duplicate_pad_numbers_are_jumpers no)
		(fp_line
			(start -0.7874 -0.4064)
			(end 0.7874 -0.4064)
			(stroke
				(width 0.1524)
				(type default)
			)
			(layer "F.SilkS")
		)
		(fp_line
			(start -0.7874 0.4064)
			(end -0.7874 -0.4064)
			(stroke
				(width 0.1524)
				(type default)
			)
			(layer "F.SilkS")
		)
		(fp_line
			(start 0.7874 -0.4064)
			(end 0.7874 0.4064)
			(stroke
				(width 0.1524)
				(type default)
			)
			(layer "F.SilkS")
		)
		(fp_line
			(start 0.7874 0.4064)
			(end -0.7874 0.4064)
			(stroke
				(width 0.1524)
				(type default)
			)
			(layer "F.SilkS")
		)
		(fp_poly
			(pts
				(xy -0.508 0.2794) (xy -0.508 0.2286) (xy -0.635 0.2286) (xy -0.635 -0.254) (xy -0.5334 -0.254)
				(xy -0.5334 -0.2794) (xy 0.5334 -0.2794) (xy 0.5334 -0.254) (xy 0.635 -0.254) (xy 0.635 0.254) (xy 0.5334 0.254)
				(xy 0.5334 0.2794)
			)
			(stroke
				(width 0)
				(type default)
			)
			(fill no)
			(layer "F.CrtYd")
		)
		(pad "1" smd rect
			(at 0.40005 0)
			(size 0.4572 0.508)
			(layers "F.Cu" "F.Mask" "F.Paste")
			(net "P5V_STB_NODE1_EN")
		)
		(pad "2" smd rect
			(at -0.40005 0)
			(size 0.4572 0.508)
			(layers "F.Cu" "F.Mask" "F.Paste")
			(net "P12V_AUX")
		)
	)
	(footprint ""
		(layer "F.Cu")
		(at 94.451932 -172.268388)
		(property "Reference" "C575"
			(at 86.67369 74.174096 0)
			(unlocked yes)
			(layer "F.SilkS")
			(effects
				(font
					(size 0.7874 0.5842)
					(thickness 0.1524)
				)
				(justify left)
			)
		)
		(property "Value" ""
			(at 0 0 0)
			(layer "F.Fab")
			(effects
				(font
					(size 1.27 1.27)
				)
			)
		)
		(duplicate_pad_numbers_are_jumpers no)
		(fp_line
			(start -0.7874 -0.4064)
			(end 0.7874 -0.4064)
			(stroke
				(width 0.1524)
				(type default)
			)
			(layer "F.SilkS")
		)
		(fp_line
			(start -0.7874 0.4064)
			(end -0.7874 -0.4064)
			(stroke
				(width 0.1524)
				(type default)
			)
			(layer "F.SilkS")
		)
		(fp_line
			(start 0 0.381)
			(end 0 -0.381)
			(stroke
				(width 0.1524)
				(type default)
			)
			(layer "F.SilkS")
		)
		(fp_line
			(start 0.7874 -0.4064)
			(end 0.7874 0.4064)
			(stroke
				(width 0.1524)
				(type default)
			)
			(layer "F.SilkS")
		)
		(fp_line
			(start 0.7874 0.4064)
			(end -0.7874 0.4064)
			(stroke
				(width 0.1524)
				(type default)
			)
			(layer "F.SilkS")
		)
		(fp_poly
			(pts
				(xy -0.5334 0.254) (xy -0.635 0.254) (xy -0.635 0.2286) (xy -0.635 -0.254) (xy -0.5334 -0.254) (xy -0.5334 -0.2794)
				(xy 0.5334 -0.2794) (xy 0.5334 -0.254) (xy 0.635 -0.254) (xy 0.635 0.254) (xy 0.5334 0.254) (xy 0.5334 0.2794)
				(xy -0.508 0.2794) (xy -0.5334 0.2794)
			)
			(stroke
				(width 0)
				(type default)
			)
			(fill no)
			(layer "F.CrtYd")
		)
		(pad "1" smd rect
			(at 0.40005 0)
			(size 0.4572 0.508)
			(layers "F.Cu" "F.Mask" "F.Paste")
			(net "P3V3_NODE1")
		)
		(pad "2" smd rect
			(at -0.40005 0)
			(size 0.4572 0.508)
			(layers "F.Cu" "F.Mask" "F.Paste")
			(net "GND")
		)
	)
	(footprint ""
		(layer "F.Cu")
		(at 115.04676 -188.126624 90)
		(property "Reference" "C757"
			(at 5.151882 0.485902 90)
			(unlocked yes)
			(layer "F.SilkS")
			(effects
				(font
					(size 0.7874 0.5842)
					(thickness 0.1524)
				)
				(justify left)
			)
		)
		(property "Value" ""
			(at 0 0 90)
			(layer "F.Fab")
			(effects
				(font
					(size 1.27 1.27)
				)
			)
		)
		(duplicate_pad_numbers_are_jumpers no)
		(fp_line
			(start 0.7874 -0.4064)
			(end 0.7874 0.4064)
			(stroke
				(width 0.1524)
				(type default)
			)
			(layer "F.SilkS")
		)
		(fp_line
			(start -0.7874 -0.4064)
			(end 0.7874 -0.4064)
			(stroke
				(width 0.1524)
				(type default)
			)
			(layer "F.SilkS")
		)
		(fp_line
			(start 0 0.381)
			(end 0 -0.381)
			(stroke
				(width 0.1524)
				(type default)
			)
			(layer "F.SilkS")
		)
		(fp_line
			(start 0.7874 0.4064)
			(end -0.7874 0.4064)
			(stroke
				(width 0.1524)
				(type default)
			)
			(layer "F.SilkS")
		)
		(fp_line
			(start -0.7874 0.4064)
			(end -0.7874 -0.4064)
			(stroke
				(width 0.1524)
				(type default)
			)
			(layer "F.SilkS")
		)
		(fp_poly
			(pts
				(xy -0.5334 0.254) (xy -0.635 0.254) (xy -0.635 0.2286) (xy -0.635 -0.254) (xy -0.5334 -0.254) (xy -0.5334 -0.2794)
				(xy 0.5334 -0.2794) (xy 0.5334 -0.254) (xy 0.635 -0.254) (xy 0.635 0.254) (xy 0.5334 0.254) (xy 0.5334 0.2794)
				(xy -0.508 0.2794) (xy -0.5334 0.2794)
			)
			(stroke
				(width 0)
				(type default)
			)
			(fill no)
			(layer "F.CrtYd")
		)
		(pad "1" smd rect
			(at 0.40005 0 90)
			(size 0.4572 0.508)
			(layers "F.Cu" "F.Mask" "F.Paste")
			(net "UART_T8_NODE3_TXD_R")
		)
		(pad "2" smd rect
			(at -0.40005 0 90)
			(size 0.4572 0.508)
			(layers "F.Cu" "F.Mask" "F.Paste")
			(net "GND")
		)
	)
	(footprint ""
		(layer "F.Cu")
		(at 84.82076 -185.205624 -90)
		(property "Reference" "R824"
			(at -4.198112 1.945132 90)
			(unlocked yes)
			(layer "F.SilkS")
			(effects
				(font
					(size 0.7874 0.5842)
					(thickness 0.1524)
				)
				(justify left)
			)
		)
		(property "Value" ""
			(at 0 0 270)
			(layer "F.Fab")
			(effects
				(font
					(size 1.27 1.27)
				)
			)
		)
		(duplicate_pad_numbers_are_jumpers no)
		(fp_line
			(start -0.7874 0.4064)
			(end -0.7874 -0.4064)
			(stroke
				(width 0.1524)
				(type default)
			)
			(layer "F.SilkS")
		)
		(fp_line
			(start 0.7874 0.4064)
			(end -0.7874 0.4064)
			(stroke
				(width 0.1524)
				(type default)
			)
			(layer "F.SilkS")
		)
		(fp_line
			(start -0.7874 -0.4064)
			(end 0.7874 -0.4064)
			(stroke
				(width 0.1524)
				(type default)
			)
			(layer "F.SilkS")
		)
		(fp_line
			(start 0.7874 -0.4064)
			(end 0.7874 0.4064)
			(stroke
				(width 0.1524)
				(type default)
			)
			(layer "F.SilkS")
		)
		(fp_poly
			(pts
				(xy -0.508 0.2794) (xy -0.508 0.2286) (xy -0.635 0.2286) (xy -0.635 -0.254) (xy -0.5334 -0.254)
				(xy -0.5334 -0.2794) (xy 0.5334 -0.2794) (xy 0.5334 -0.254) (xy 0.635 -0.254) (xy 0.635 0.254) (xy 0.5334 0.254)
				(xy 0.5334 0.2794)
			)
			(stroke
				(width 0)
				(type default)
			)
			(fill no)
			(layer "F.CrtYd")
		)
		(pad "1" smd rect
			(at 0.40005 0 270)
			(size 0.4572 0.508)
			(layers "F.Cu" "F.Mask" "F.Paste")
			(net "I2C_PSU2_SCL")
		)
		(pad "2" smd rect
			(at -0.40005 0 270)
			(size 0.4572 0.508)
			(layers "F.Cu" "F.Mask" "F.Paste")
			(net "I2C_PSU2_R_SCL")
		)
	)
	(footprint ""
		(layer "F.Cu")
		(at 87.374984 -81.907888 180)
		(property "Reference" "C79"
			(at -1.232916 0.06858 0)
			(unlocked yes)
			(layer "F.SilkS")
			(effects
				(font
					(size 0.7874 0.5842)
					(thickness 0.1524)
				)
				(justify left)
			)
		)
		(property "Value" ""
			(at 0 0 180)
			(layer "F.Fab")
			(effects
				(font
					(size 1.27 1.27)
				)
			)
		)
		(duplicate_pad_numbers_are_jumpers no)
		(fp_line
			(start 0.7874 0.4064)
			(end -0.7874 0.4064)
			(stroke
				(width 0.1524)
				(type default)
			)
			(layer "F.SilkS")
		)
		(fp_line
			(start 0.7874 -0.4064)
			(end 0.7874 0.4064)
			(stroke
				(width 0.1524)
				(type default)
			)
			(layer "F.SilkS")
		)
		(fp_line
			(start 0 0.381)
			(end 0 -0.381)
			(stroke
				(width 0.1524)
				(type default)
			)
			(layer "F.SilkS")
		)
		(fp_line
			(start -0.7874 0.4064)
			(end -0.7874 -0.4064)
			(stroke
				(width 0.1524)
				(type default)
			)
			(layer "F.SilkS")
		)
		(fp_line
			(start -0.7874 -0.4064)
			(end 0.7874 -0.4064)
			(stroke
				(width 0.1524)
				(type default)
			)
			(layer "F.SilkS")
		)
		(fp_poly
			(pts
				(xy -0.5334 0.254) (xy -0.635 0.254) (xy -0.635 0.2286) (xy -0.635 -0.254) (xy -0.5334 -0.254) (xy -0.5334 -0.2794)
				(xy 0.5334 -0.2794) (xy 0.5334 -0.254) (xy 0.635 -0.254) (xy 0.635 0.254) (xy 0.5334 0.254) (xy 0.5334 0.2794)
				(xy -0.508 0.2794) (xy -0.5334 0.2794)
			)
			(stroke
				(width 0)
				(type default)
			)
			(fill no)
			(layer "F.CrtYd")
		)
		(pad "1" smd rect
			(at 0.40005 0 180)
			(size 0.4572 0.508)
			(layers "F.Cu" "F.Mask" "F.Paste")
			(net "P1V05_VCCPLLCPU1SIO_NODE1")
		)
		(pad "2" smd rect
			(at -0.40005 0 180)
			(size 0.4572 0.508)
			(layers "F.Cu" "F.Mask" "F.Paste")
			(net "GND")
		)
	)
	(footprint ""
		(layer "F.Cu")
		(at 152.76576 -185.205624 -90)
		(property "Reference" "R903"
			(at -4.768088 -0.259588 90)
			(unlocked yes)
			(layer "F.SilkS")
			(effects
				(font
					(size 0.7874 0.5842)
					(thickness 0.1524)
				)
				(justify left)
			)
		)
		(property "Value" ""
			(at 0 0 270)
			(layer "F.Fab")
			(effects
				(font
					(size 1.27 1.27)
				)
			)
		)
		(duplicate_pad_numbers_are_jumpers no)
		(fp_line
			(start -0.7874 0.4064)
			(end -0.7874 -0.4064)
			(stroke
				(width 0.1524)
				(type default)
			)
			(layer "F.SilkS")
		)
		(fp_line
			(start 0.7874 0.4064)
			(end -0.7874 0.4064)
			(stroke
				(width 0.1524)
				(type default)
			)
			(layer "F.SilkS")
		)
		(fp_line
			(start -0.7874 -0.4064)
			(end 0.7874 -0.4064)
			(stroke
				(width 0.1524)
				(type default)
			)
			(layer "F.SilkS")
		)
		(fp_line
			(start 0.7874 -0.4064)
			(end 0.7874 0.4064)
			(stroke
				(width 0.1524)
				(type default)
			)
			(layer "F.SilkS")
		)
		(fp_poly
			(pts
				(xy -0.508 0.2794) (xy -0.508 0.2286) (xy -0.635 0.2286) (xy -0.635 -0.254) (xy -0.5334 -0.254)
				(xy -0.5334 -0.2794) (xy 0.5334 -0.2794) (xy 0.5334 -0.254) (xy 0.635 -0.254) (xy 0.635 0.254) (xy 0.5334 0.254)
				(xy 0.5334 0.2794)
			)
			(stroke
				(width 0)
				(type default)
			)
			(fill no)
			(layer "F.CrtYd")
		)
		(pad "1" smd rect
			(at 0.40005 0 270)
			(size 0.4572 0.508)
			(layers "F.Cu" "F.Mask" "F.Paste")
			(net "T12_NODE3_EN")
		)
		(pad "2" smd rect
			(at -0.40005 0 270)
			(size 0.4572 0.508)
			(layers "F.Cu" "F.Mask" "F.Paste")
			(net "T12_NODE3_EN_R")
		)
	)
	(footprint ""
		(layer "F.Cu")
		(at 117.650768 -19.049238 180)
		(property "Reference" "C856"
			(at -4.579874 -2.101596 90)
			(unlocked yes)
			(layer "F.SilkS")
			(effects
				(font
					(size 0.7874 0.5842)
					(thickness 0.1524)
				)
				(justify left)
			)
		)
		(property "Value" ""
			(at 0 0 180)
			(layer "F.Fab")
			(effects
				(font
					(size 1.27 1.27)
				)
			)
		)
		(duplicate_pad_numbers_are_jumpers no)
		(fp_line
			(start 0.7874 0.4064)
			(end -0.7874 0.4064)
			(stroke
				(width 0.1524)
				(type default)
			)
			(layer "F.SilkS")
		)
		(fp_line
			(start 0.7874 -0.4064)
			(end 0.7874 0.4064)
			(stroke
				(width 0.1524)
				(type default)
			)
			(layer "F.SilkS")
		)
		(fp_line
			(start 0 0.381)
			(end 0 -0.381)
			(stroke
				(width 0.1524)
				(type default)
			)
			(layer "F.SilkS")
		)
		(fp_line
			(start -0.7874 0.4064)
			(end -0.7874 -0.4064)
			(stroke
				(width 0.1524)
				(type default)
			)
			(layer "F.SilkS")
		)
		(fp_line
			(start -0.7874 -0.4064)
			(end 0.7874 -0.4064)
			(stroke
				(width 0.1524)
				(type default)
			)
			(layer "F.SilkS")
		)
		(fp_poly
			(pts
				(xy -0.5334 0.254) (xy -0.635 0.254) (xy -0.635 0.2286) (xy -0.635 -0.254) (xy -0.5334 -0.254) (xy -0.5334 -0.2794)
				(xy 0.5334 -0.2794) (xy 0.5334 -0.254) (xy 0.635 -0.254) (xy 0.635 0.254) (xy 0.5334 0.254) (xy 0.5334 0.2794)
				(xy -0.508 0.2794) (xy -0.5334 0.2794)
			)
			(stroke
				(width 0)
				(type default)
			)
			(fill no)
			(layer "F.CrtYd")
		)
		(pad "1" smd rect
			(at 0.40005 0 180)
			(size 0.4572 0.508)
			(layers "F.Cu" "F.Mask" "F.Paste")
			(net "P3V3_STB_NODE1")
		)
		(pad "2" smd rect
			(at -0.40005 0 180)
			(size 0.4572 0.508)
			(layers "F.Cu" "F.Mask" "F.Paste")
			(net "GND")
		)
	)
	(footprint ""
		(layer "F.Cu")
		(at 188.372242 -114.511328 -90)
		(property "Reference" "U101"
			(at -2.175002 -1.619758 0)
			(unlocked yes)
			(layer "F.SilkS")
			(effects
				(font
					(size 0.7874 0.5842)
					(thickness 0.1524)
				)
			)
		)
		(property "Value" ""
			(at 0 0 270)
			(layer "F.Fab")
			(effects
				(font
					(size 1.27 1.27)
				)
			)
		)
		(duplicate_pad_numbers_are_jumpers no)
		(fp_line
			(start -1.651 1.905)
			(end -1.651 -1.905)
			(stroke
				(width 0.1524)
				(type default)
			)
			(layer "F.SilkS")
		)
		(fp_line
			(start 1.651 1.905)
			(end -1.651 1.905)
			(stroke
				(width 0.1524)
				(type default)
			)
			(layer "F.SilkS")
		)
		(fp_line
			(start -1.651 -1.905)
			(end 1.651 -1.905)
			(stroke
				(width 0.1524)
				(type default)
			)
			(layer "F.SilkS")
		)
		(fp_line
			(start 1.651 -1.905)
			(end 1.651 1.905)
			(stroke
				(width 0.1524)
				(type default)
			)
			(layer "F.SilkS")
		)
		(fp_poly
			(pts
				(xy -1.524 0.7112) (xy -1.524 1.7526) (xy -0.508 1.7526) (xy -0.508 0.6985) (xy 0.508 0.6985) (xy 0.508 1.7526)
				(xy 1.524 1.7526) (xy 1.524 0.6985) (xy 1.524 -0.6985) (xy 0.508 -0.6985) (xy 0.508 -1.7526) (xy -0.508 -1.7526)
				(xy -0.508 -0.6985) (xy -1.524 -0.6985) (xy -1.524 0.6985)
			)
			(stroke
				(width 0)
				(type default)
			)
			(fill no)
			(layer "F.CrtYd")
		)
		(fp_text user "1"
			(at -2.312924 0.545592 0)
			(unlocked yes)
			(layer "F.SilkS")
			(effects
				(font
					(size 0.635 0.4064)
					(thickness 0.1524)
				)
			)
		)
		(fp_text user "2"
			(at 2.17678 0.499618 0)
			(unlocked yes)
			(layer "F.SilkS")
			(effects
				(font
					(size 0.635 0.4064)
					(thickness 0.1524)
				)
			)
		)
		(fp_text user "3"
			(at 2.052066 -1.057402 90)
			(unlocked yes)
			(layer "F.SilkS")
			(effects
				(font
					(size 0.635 0.4064)
					(thickness 0.1524)
				)
			)
		)
		(pad "1" smd rect
			(at -1.016 1.1176 270)
			(size 1.016 1.27)
			(layers "F.Cu" "F.Mask" "F.Paste")
			(net "GND")
		)
		(pad "2" smd rect
			(at 1.016 1.1176 270)
			(size 1.016 1.27)
			(layers "F.Cu" "F.Mask" "F.Paste")
			(net "PWRGD_NODE1_P12V_PG_R")
		)
		(pad "3" smd rect
			(at 0 -1.1176 270)
			(size 1.016 1.27)
			(layers "F.Cu" "F.Mask" "F.Paste")
			(net "P12V_NODE1_PWRGD_EN")
		)
	)
	(footprint ""
		(layer "F.Cu")
		(at 48.74514 -163.89985 90)
		(property "Reference" "R537"
			(at -131.03606 -3.625088 90)
			(unlocked yes)
			(layer "F.SilkS")
			(effects
				(font
					(size 0.7874 0.5842)
					(thickness 0.1524)
				)
				(justify left)
			)
		)
		(property "Value" ""
			(at 0 0 90)
			(layer "F.Fab")
			(effects
				(font
					(size 1.27 1.27)
				)
			)
		)
		(duplicate_pad_numbers_are_jumpers no)
		(fp_line
			(start 0.7874 -0.4064)
			(end 0.7874 0.4064)
			(stroke
				(width 0.1524)
				(type default)
			)
			(layer "F.SilkS")
		)
		(fp_line
			(start -0.7874 -0.4064)
			(end 0.7874 -0.4064)
			(stroke
				(width 0.1524)
				(type default)
			)
			(layer "F.SilkS")
		)
		(fp_line
			(start 0.7874 0.4064)
			(end -0.7874 0.4064)
			(stroke
				(width 0.1524)
				(type default)
			)
			(layer "F.SilkS")
		)
		(fp_line
			(start -0.7874 0.4064)
			(end -0.7874 -0.4064)
			(stroke
				(width 0.1524)
				(type default)
			)
			(layer "F.SilkS")
		)
		(fp_poly
			(pts
				(xy -0.508 0.2794) (xy -0.508 0.2286) (xy -0.635 0.2286) (xy -0.635 -0.254) (xy -0.5334 -0.254)
				(xy -0.5334 -0.2794) (xy 0.5334 -0.2794) (xy 0.5334 -0.254) (xy 0.635 -0.254) (xy 0.635 0.254) (xy 0.5334 0.254)
				(xy 0.5334 0.2794)
			)
			(stroke
				(width 0)
				(type default)
			)
			(fill no)
			(layer "F.CrtYd")
		)
		(pad "1" smd rect
			(at 0.40005 0 90)
			(size 0.4572 0.508)
			(layers "F.Cu" "F.Mask" "F.Paste")
			(net "P3V3_NODE1")
		)
		(pad "2" smd rect
			(at -0.40005 0 90)
			(size 0.4572 0.508)
			(layers "F.Cu" "F.Mask" "F.Paste")
			(net "PU_LAN1_TMS")
		)
	)
	(footprint ""
		(layer "F.Cu")
		(at 21.362162 -128.527048 180)
		(property "Reference" "PJ6"
			(at -4.977384 -2.23647 90)
			(unlocked yes)
			(layer "F.SilkS")
			(effects
				(font
					(size 0.7874 0.5842)
					(thickness 0.1524)
				)
				(justify left)
			)
		)
		(property "Value" ""
			(at 0 0 180)
			(layer "F.Fab")
			(effects
				(font
					(size 1.27 1.27)
				)
			)
		)
		(duplicate_pad_numbers_are_jumpers no)
		(fp_poly
			(pts
				(xy 0.2794 0.907796) (xy 0.254 0.907796) (xy 0.254 1.0414) (xy -0.254 1.0414) (xy -0.254 1.034796)
				(xy -0.254 0.933196) (xy -0.2794 0.933196) (xy -0.2794 -0.133604) (xy -0.254 -0.133604) (xy -0.254 -0.235204)
				(xy 0.254 -0.235204) (xy 0.254 -0.133604) (xy 0.2794 -0.133604)
			)
			(stroke
				(width 0)
				(type default)
			)
			(fill no)
			(layer "F.CrtYd")
		)
		(pad "1" smd custom
			(at 0 -0.000254 180)
			(size 0.127 0.127)
			(layers "F.Cu" "F.Mask" "F.Paste")
			(net "FM_CPLD_NODE1_P1V05_EN")
			(options
				(clearance outline)
				(anchor circle)
			)
			(primitives
				(gr_poly
					(pts
						(xy -0.127 0.508) (xy -0.127 -0.0508) (xy -0.254 -0.0508) (xy -0.254 -0.508) (xy 0.254 -0.508)
						(xy 0.254 -0.0508) (xy 0.127 -0.0508) (xy 0.127 0.508)
					)
					(width 0)
					(fill yes)
				)
			)
		)
		(pad "2" smd rect
			(at 0 0.799846 270)
			(size 0.4572 0.508)
			(layers "F.Cu" "F.Mask" "F.Paste")
			(net "P1V05_NODE1_EN")
		)
		(zone
			(layer "F.Cu")
			(hatch none 0.5)
			(connect_pads
				(clearance 0)
			)
			(min_thickness 0.25)
			(keepout
				(tracks allowed)
				(vias not_allowed)
				(pads allowed)
				(copperpour not_allowed)
				(footprints allowed)
			)
			(placement
				(enabled no)
				(sheetname "")
			)
			(fill
				(thermal_gap 0.5)
				(thermal_bridge_width 0.5)
				(island_removal_mode 0)
			)
			(polygon
				(pts
					(xy 21.666962 -129.612644) (xy 21.057362 -129.612644) (xy 21.057362 -128.241044) (xy 21.666962 -128.241044)
				)
			)
		)
	)
	(footprint ""
		(layer "F.Cu")
		(at 81.39176 -188.126624 90)
		(property "Reference" "C661"
			(at 4.548886 -1.831848 90)
			(unlocked yes)
			(layer "F.SilkS")
			(effects
				(font
					(size 0.7874 0.5842)
					(thickness 0.1524)
				)
				(justify left)
			)
		)
		(property "Value" ""
			(at 0 0 90)
			(layer "F.Fab")
			(effects
				(font
					(size 1.27 1.27)
				)
			)
		)
		(duplicate_pad_numbers_are_jumpers no)
		(fp_line
			(start 0.7874 -0.4064)
			(end 0.7874 0.4064)
			(stroke
				(width 0.1524)
				(type default)
			)
			(layer "F.SilkS")
		)
		(fp_line
			(start -0.7874 -0.4064)
			(end 0.7874 -0.4064)
			(stroke
				(width 0.1524)
				(type default)
			)
			(layer "F.SilkS")
		)
		(fp_line
			(start 0 0.381)
			(end 0 -0.381)
			(stroke
				(width 0.1524)
				(type default)
			)
			(layer "F.SilkS")
		)
		(fp_line
			(start 0.7874 0.4064)
			(end -0.7874 0.4064)
			(stroke
				(width 0.1524)
				(type default)
			)
			(layer "F.SilkS")
		)
		(fp_line
			(start -0.7874 0.4064)
			(end -0.7874 -0.4064)
			(stroke
				(width 0.1524)
				(type default)
			)
			(layer "F.SilkS")
		)
		(fp_poly
			(pts
				(xy -0.5334 0.254) (xy -0.635 0.254) (xy -0.635 0.2286) (xy -0.635 -0.254) (xy -0.5334 -0.254) (xy -0.5334 -0.2794)
				(xy 0.5334 -0.2794) (xy 0.5334 -0.254) (xy 0.635 -0.254) (xy 0.635 0.254) (xy 0.5334 0.254) (xy 0.5334 0.2794)
				(xy -0.508 0.2794) (xy -0.5334 0.2794)
			)
			(stroke
				(width 0)
				(type default)
			)
			(fill no)
			(layer "F.CrtYd")
		)
		(pad "1" smd rect
			(at 0.40005 0 90)
			(size 0.4572 0.508)
			(layers "F.Cu" "F.Mask" "F.Paste")
			(net "T4_NODE2_EN_R")
		)
		(pad "2" smd rect
			(at -0.40005 0 90)
			(size 0.4572 0.508)
			(layers "F.Cu" "F.Mask" "F.Paste")
			(net "GND")
		)
	)
	(footprint ""
		(layer "F.Cu")
		(at 144.764252 -149.20595)
		(property "Reference" "R285"
			(at -0.294386 17.331944 0)
			(unlocked yes)
			(layer "F.SilkS")
			(effects
				(font
					(size 0.7874 0.5842)
					(thickness 0.1524)
				)
				(justify left)
			)
		)
		(property "Value" ""
			(at 0 0 0)
			(layer "F.Fab")
			(effects
				(font
					(size 1.27 1.27)
				)
			)
		)
		(duplicate_pad_numbers_are_jumpers no)
		(fp_line
			(start -0.7874 -0.4064)
			(end 0.7874 -0.4064)
			(stroke
				(width 0.1524)
				(type default)
			)
			(layer "F.SilkS")
		)
		(fp_line
			(start -0.7874 0.4064)
			(end -0.7874 -0.4064)
			(stroke
				(width 0.1524)
				(type default)
			)
			(layer "F.SilkS")
		)
		(fp_line
			(start 0.7874 -0.4064)
			(end 0.7874 0.4064)
			(stroke
				(width 0.1524)
				(type default)
			)
			(layer "F.SilkS")
		)
		(fp_line
			(start 0.7874 0.4064)
			(end -0.7874 0.4064)
			(stroke
				(width 0.1524)
				(type default)
			)
			(layer "F.SilkS")
		)
		(fp_poly
			(pts
				(xy -0.508 0.2794) (xy -0.508 0.2286) (xy -0.635 0.2286) (xy -0.635 -0.254) (xy -0.5334 -0.254)
				(xy -0.5334 -0.2794) (xy 0.5334 -0.2794) (xy 0.5334 -0.254) (xy 0.635 -0.254) (xy 0.635 0.254) (xy 0.5334 0.254)
				(xy 0.5334 0.2794)
			)
			(stroke
				(width 0)
				(type default)
			)
			(fill no)
			(layer "F.CrtYd")
		)
		(pad "1" smd rect
			(at 0.40005 0)
			(size 0.4572 0.508)
			(layers "F.Cu" "F.Mask" "F.Paste")
			(net "GND")
		)
		(pad "2" smd rect
			(at -0.40005 0)
			(size 0.4572 0.508)
			(layers "F.Cu" "F.Mask" "F.Paste")
			(net "PCIE_SW_TEST1")
		)
	)
	(footprint ""
		(layer "F.Cu")
		(at 84.171282 -6.73862 180)
		(property "Reference" "PC48"
			(at -2.299462 -3.661156 0)
			(unlocked yes)
			(layer "F.SilkS")
			(effects
				(font
					(size 0.7874 0.5842)
					(thickness 0.1524)
				)
				(justify left)
			)
		)
		(property "Value" ""
			(at 0 0 180)
			(layer "F.Fab")
			(effects
				(font
					(size 1.27 1.27)
				)
			)
		)
		(duplicate_pad_numbers_are_jumpers no)
		(fp_line
			(start 1.905 0.8636)
			(end -1.905 0.8636)
			(stroke
				(width 0.1524)
				(type default)
			)
			(layer "F.SilkS")
		)
		(fp_line
			(start 1.905 -0.8636)
			(end 1.905 0.8636)
			(stroke
				(width 0.1524)
				(type default)
			)
			(layer "F.SilkS")
		)
		(fp_line
			(start 0 0.8382)
			(end 0 -0.8382)
			(stroke
				(width 0.1524)
				(type default)
			)
			(layer "F.SilkS")
		)
		(fp_line
			(start -1.905 0.8636)
			(end -1.905 -0.8636)
			(stroke
				(width 0.1524)
				(type default)
			)
			(layer "F.SilkS")
		)
		(fp_line
			(start -1.905 -0.8636)
			(end 1.905 -0.8636)
			(stroke
				(width 0.1524)
				(type default)
			)
			(layer "F.SilkS")
		)
		(fp_rect
			(start -1.524 0.7366)
			(end 1.524 -0.7366)
			(stroke
				(width 0)
				(type default)
			)
			(fill no)
			(layer "F.CrtYd")
		)
		(pad "1" smd rect
			(at 0.94996 0 180)
			(size 1.1176 1.3716)
			(layers "F.Cu" "F.Mask" "F.Paste")
			(net "P3V3_NODE1")
		)
		(pad "2" smd rect
			(at -0.94996 0 180)
			(size 1.1176 1.3716)
			(layers "F.Cu" "F.Mask" "F.Paste")
			(net "GND")
		)
	)
	(footprint ""
		(layer "F.Cu")
		(at 59.67476 -188.126624 -90)
		(property "Reference" "R943"
			(at -4.548886 -0.297942 90)
			(unlocked yes)
			(layer "F.SilkS")
			(effects
				(font
					(size 0.7874 0.5842)
					(thickness 0.1524)
				)
				(justify left)
			)
		)
		(property "Value" ""
			(at 0 0 270)
			(layer "F.Fab")
			(effects
				(font
					(size 1.27 1.27)
				)
			)
		)
		(duplicate_pad_numbers_are_jumpers no)
		(fp_line
			(start -0.7874 0.4064)
			(end -0.7874 -0.4064)
			(stroke
				(width 0.1524)
				(type default)
			)
			(layer "F.SilkS")
		)
		(fp_line
			(start 0.7874 0.4064)
			(end -0.7874 0.4064)
			(stroke
				(width 0.1524)
				(type default)
			)
			(layer "F.SilkS")
		)
		(fp_line
			(start -0.7874 -0.4064)
			(end 0.7874 -0.4064)
			(stroke
				(width 0.1524)
				(type default)
			)
			(layer "F.SilkS")
		)
		(fp_line
			(start 0.7874 -0.4064)
			(end 0.7874 0.4064)
			(stroke
				(width 0.1524)
				(type default)
			)
			(layer "F.SilkS")
		)
		(fp_poly
			(pts
				(xy -0.508 0.2794) (xy -0.508 0.2286) (xy -0.635 0.2286) (xy -0.635 -0.254) (xy -0.5334 -0.254)
				(xy -0.5334 -0.2794) (xy 0.5334 -0.2794) (xy 0.5334 -0.254) (xy 0.635 -0.254) (xy 0.635 0.254) (xy 0.5334 0.254)
				(xy 0.5334 0.2794)
			)
			(stroke
				(width 0)
				(type default)
			)
			(fill no)
			(layer "F.CrtYd")
		)
		(pad "1" smd rect
			(at 0.40005 0 270)
			(size 0.4572 0.508)
			(layers "F.Cu" "F.Mask" "F.Paste")
			(net "UART_T2_NODE3_RXD")
		)
		(pad "2" smd rect
			(at -0.40005 0 270)
			(size 0.4572 0.508)
			(layers "F.Cu" "F.Mask" "F.Paste")
			(net "UART_T2_NODE3_RXD_R")
		)
	)
	(footprint ""
		(layer "F.Cu")
		(at 79.963518 -88.995504)
		(property "Reference" "R49"
			(at -1.195578 18.989294 0)
			(unlocked yes)
			(layer "F.SilkS")
			(effects
				(font
					(size 0.7874 0.5842)
					(thickness 0.1524)
				)
				(justify left)
			)
		)
		(property "Value" ""
			(at 0 0 0)
			(layer "F.Fab")
			(effects
				(font
					(size 1.27 1.27)
				)
			)
		)
		(duplicate_pad_numbers_are_jumpers no)
		(fp_line
			(start -0.7874 -0.4064)
			(end 0.7874 -0.4064)
			(stroke
				(width 0.1524)
				(type default)
			)
			(layer "F.SilkS")
		)
		(fp_line
			(start -0.7874 0.4064)
			(end -0.7874 -0.4064)
			(stroke
				(width 0.1524)
				(type default)
			)
			(layer "F.SilkS")
		)
		(fp_line
			(start 0.7874 -0.4064)
			(end 0.7874 0.4064)
			(stroke
				(width 0.1524)
				(type default)
			)
			(layer "F.SilkS")
		)
		(fp_line
			(start 0.7874 0.4064)
			(end -0.7874 0.4064)
			(stroke
				(width 0.1524)
				(type default)
			)
			(layer "F.SilkS")
		)
		(fp_poly
			(pts
				(xy -0.508 0.2794) (xy -0.508 0.2286) (xy -0.635 0.2286) (xy -0.635 -0.254) (xy -0.5334 -0.254)
				(xy -0.5334 -0.2794) (xy 0.5334 -0.2794) (xy 0.5334 -0.254) (xy 0.635 -0.254) (xy 0.635 0.254) (xy 0.5334 0.254)
				(xy 0.5334 0.2794)
			)
			(stroke
				(width 0)
				(type default)
			)
			(fill no)
			(layer "F.CrtYd")
		)
		(pad "1" smd rect
			(at 0.40005 0)
			(size 0.4572 0.508)
			(layers "F.Cu" "F.Mask" "F.Paste")
			(net "SPI_CPU_NODE1_WP_L")
		)
		(pad "2" smd rect
			(at -0.40005 0)
			(size 0.4572 0.508)
			(layers "F.Cu" "F.Mask" "F.Paste")
			(net "SPI_CPU_NODE1_WP_R_L")
		)
	)
	(footprint ""
		(layer "F.Cu")
		(at 166.41318 -161.39541 90)
		(property "Reference" "R584"
			(at -8.09117 17.462754 90)
			(unlocked yes)
			(layer "F.SilkS")
			(effects
				(font
					(size 0.7874 0.5842)
					(thickness 0.1524)
				)
				(justify left)
			)
		)
		(property "Value" ""
			(at 0 0 90)
			(layer "F.Fab")
			(effects
				(font
					(size 1.27 1.27)
				)
			)
		)
		(duplicate_pad_numbers_are_jumpers no)
		(fp_line
			(start 0.7874 -0.4064)
			(end 0.7874 0.4064)
			(stroke
				(width 0.1524)
				(type default)
			)
			(layer "F.SilkS")
		)
		(fp_line
			(start -0.7874 -0.4064)
			(end 0.7874 -0.4064)
			(stroke
				(width 0.1524)
				(type default)
			)
			(layer "F.SilkS")
		)
		(fp_line
			(start 0.7874 0.4064)
			(end -0.7874 0.4064)
			(stroke
				(width 0.1524)
				(type default)
			)
			(layer "F.SilkS")
		)
		(fp_line
			(start -0.7874 0.4064)
			(end -0.7874 -0.4064)
			(stroke
				(width 0.1524)
				(type default)
			)
			(layer "F.SilkS")
		)
		(fp_poly
			(pts
				(xy -0.508 0.2794) (xy -0.508 0.2286) (xy -0.635 0.2286) (xy -0.635 -0.254) (xy -0.5334 -0.254)
				(xy -0.5334 -0.2794) (xy 0.5334 -0.2794) (xy 0.5334 -0.254) (xy 0.635 -0.254) (xy 0.635 0.254) (xy 0.5334 0.254)
				(xy 0.5334 0.2794)
			)
			(stroke
				(width 0)
				(type default)
			)
			(fill no)
			(layer "F.CrtYd")
		)
		(pad "1" smd rect
			(at 0.40005 0 90)
			(size 0.4572 0.508)
			(layers "F.Cu" "F.Mask" "F.Paste")
			(net "GND")
		)
		(pad "2" smd rect
			(at -0.40005 0 90)
			(size 0.4572 0.508)
			(layers "F.Cu" "F.Mask" "F.Paste")
			(net "LAN2_NC_SI_CLK_IN")
		)
	)
	(footprint ""
		(layer "F.Cu")
		(at 56.065166 -96.709992 90)
		(property "Reference" "R497"
			(at -54.98719 28.432252 90)
			(unlocked yes)
			(layer "F.SilkS")
			(effects
				(font
					(size 0.7874 0.5842)
					(thickness 0.1524)
				)
				(justify left)
			)
		)
		(property "Value" ""
			(at 0 0 90)
			(layer "F.Fab")
			(effects
				(font
					(size 1.27 1.27)
				)
			)
		)
		(duplicate_pad_numbers_are_jumpers no)
		(fp_line
			(start 0.7874 -0.4064)
			(end 0.7874 0.4064)
			(stroke
				(width 0.1524)
				(type default)
			)
			(layer "F.SilkS")
		)
		(fp_line
			(start -0.7874 -0.4064)
			(end 0.7874 -0.4064)
			(stroke
				(width 0.1524)
				(type default)
			)
			(layer "F.SilkS")
		)
		(fp_line
			(start 0.7874 0.4064)
			(end -0.7874 0.4064)
			(stroke
				(width 0.1524)
				(type default)
			)
			(layer "F.SilkS")
		)
		(fp_line
			(start -0.7874 0.4064)
			(end -0.7874 -0.4064)
			(stroke
				(width 0.1524)
				(type default)
			)
			(layer "F.SilkS")
		)
		(fp_poly
			(pts
				(xy -0.508 0.2794) (xy -0.508 0.2286) (xy -0.635 0.2286) (xy -0.635 -0.254) (xy -0.5334 -0.254)
				(xy -0.5334 -0.2794) (xy 0.5334 -0.2794) (xy 0.5334 -0.254) (xy 0.635 -0.254) (xy 0.635 0.254) (xy 0.5334 0.254)
				(xy 0.5334 0.2794)
			)
			(stroke
				(width 0)
				(type default)
			)
			(fill no)
			(layer "F.CrtYd")
		)
		(pad "1" smd rect
			(at 0.40005 0 90)
			(size 0.4572 0.508)
			(layers "F.Cu" "F.Mask" "F.Paste")
			(net "GND")
		)
		(pad "2" smd rect
			(at -0.40005 0 90)
			(size 0.4572 0.508)
			(layers "F.Cu" "F.Mask" "F.Paste")
			(net "PD_CPU_NODE1_DFX_GPIO_GRP0_0")
		)
	)
	(footprint ""
		(layer "F.Cu")
		(at 96.278954 -15.891764 90)
		(property "Reference" "R191"
			(at 0.643636 -0.886968 90)
			(unlocked yes)
			(layer "F.SilkS")
			(effects
				(font
					(size 0.7874 0.5842)
					(thickness 0.1524)
				)
				(justify left)
			)
		)
		(property "Value" ""
			(at 0 0 90)
			(layer "F.Fab")
			(effects
				(font
					(size 1.27 1.27)
				)
			)
		)
		(duplicate_pad_numbers_are_jumpers no)
		(fp_line
			(start 0.7874 -0.4064)
			(end 0.7874 0.4064)
			(stroke
				(width 0.1524)
				(type default)
			)
			(layer "F.SilkS")
		)
		(fp_line
			(start -0.7874 -0.4064)
			(end 0.7874 -0.4064)
			(stroke
				(width 0.1524)
				(type default)
			)
			(layer "F.SilkS")
		)
		(fp_line
			(start 0.7874 0.4064)
			(end -0.7874 0.4064)
			(stroke
				(width 0.1524)
				(type default)
			)
			(layer "F.SilkS")
		)
		(fp_line
			(start -0.7874 0.4064)
			(end -0.7874 -0.4064)
			(stroke
				(width 0.1524)
				(type default)
			)
			(layer "F.SilkS")
		)
		(fp_poly
			(pts
				(xy -0.508 0.2794) (xy -0.508 0.2286) (xy -0.635 0.2286) (xy -0.635 -0.254) (xy -0.5334 -0.254)
				(xy -0.5334 -0.2794) (xy 0.5334 -0.2794) (xy 0.5334 -0.254) (xy 0.635 -0.254) (xy 0.635 0.254) (xy 0.5334 0.254)
				(xy 0.5334 0.2794)
			)
			(stroke
				(width 0)
				(type default)
			)
			(fill no)
			(layer "F.CrtYd")
		)
		(pad "1" smd rect
			(at 0.40005 0 90)
			(size 0.4572 0.508)
			(layers "F.Cu" "F.Mask" "F.Paste")
			(net "LPC_CPU_NODE1_LAD1")
		)
		(pad "2" smd rect
			(at -0.40005 0 90)
			(size 0.4572 0.508)
			(layers "F.Cu" "F.Mask" "F.Paste")
			(net "LPC_CPU_TPM_LAD1")
		)
	)
	(footprint ""
		(layer "F.Cu")
		(at 70.289166 -96.709992 90)
		(property "Reference" "R67"
			(at -54.98719 28.333446 90)
			(unlocked yes)
			(layer "F.SilkS")
			(effects
				(font
					(size 0.7874 0.5842)
					(thickness 0.1524)
				)
				(justify left)
			)
		)
		(property "Value" ""
			(at 0 0 90)
			(layer "F.Fab")
			(effects
				(font
					(size 1.27 1.27)
				)
			)
		)
		(duplicate_pad_numbers_are_jumpers no)
		(fp_line
			(start 0.7874 -0.4064)
			(end 0.7874 0.4064)
			(stroke
				(width 0.1524)
				(type default)
			)
			(layer "F.SilkS")
		)
		(fp_line
			(start -0.7874 -0.4064)
			(end 0.7874 -0.4064)
			(stroke
				(width 0.1524)
				(type default)
			)
			(layer "F.SilkS")
		)
		(fp_line
			(start 0.7874 0.4064)
			(end -0.7874 0.4064)
			(stroke
				(width 0.1524)
				(type default)
			)
			(layer "F.SilkS")
		)
		(fp_line
			(start -0.7874 0.4064)
			(end -0.7874 -0.4064)
			(stroke
				(width 0.1524)
				(type default)
			)
			(layer "F.SilkS")
		)
		(fp_poly
			(pts
				(xy -0.508 0.2794) (xy -0.508 0.2286) (xy -0.635 0.2286) (xy -0.635 -0.254) (xy -0.5334 -0.254)
				(xy -0.5334 -0.2794) (xy 0.5334 -0.2794) (xy 0.5334 -0.254) (xy 0.635 -0.254) (xy 0.635 0.254) (xy 0.5334 0.254)
				(xy 0.5334 0.2794)
			)
			(stroke
				(width 0)
				(type default)
			)
			(fill no)
			(layer "F.CrtYd")
		)
		(pad "1" smd rect
			(at 0.40005 0 90)
			(size 0.4572 0.508)
			(layers "F.Cu" "F.Mask" "F.Paste")
			(net "SPC_CPU_NODE1_DTR_L")
		)
		(pad "2" smd rect
			(at -0.40005 0 90)
			(size 0.4572 0.508)
			(layers "F.Cu" "F.Mask" "F.Paste")
			(net "SPC_CPU_NODE1_DCD_L")
		)
	)
	(footprint ""
		(layer "F.Cu")
		(at 153.90876 -188.126624 90)
		(property "Reference" "C663"
			(at 5.519674 -3.189732 90)
			(unlocked yes)
			(layer "F.SilkS")
			(effects
				(font
					(size 0.7874 0.5842)
					(thickness 0.1524)
				)
				(justify left)
			)
		)
		(property "Value" ""
			(at 0 0 90)
			(layer "F.Fab")
			(effects
				(font
					(size 1.27 1.27)
				)
			)
		)
		(duplicate_pad_numbers_are_jumpers no)
		(fp_line
			(start 0.7874 -0.4064)
			(end 0.7874 0.4064)
			(stroke
				(width 0.1524)
				(type default)
			)
			(layer "F.SilkS")
		)
		(fp_line
			(start -0.7874 -0.4064)
			(end 0.7874 -0.4064)
			(stroke
				(width 0.1524)
				(type default)
			)
			(layer "F.SilkS")
		)
		(fp_line
			(start 0 0.381)
			(end 0 -0.381)
			(stroke
				(width 0.1524)
				(type default)
			)
			(layer "F.SilkS")
		)
		(fp_line
			(start 0.7874 0.4064)
			(end -0.7874 0.4064)
			(stroke
				(width 0.1524)
				(type default)
			)
			(layer "F.SilkS")
		)
		(fp_line
			(start -0.7874 0.4064)
			(end -0.7874 -0.4064)
			(stroke
				(width 0.1524)
				(type default)
			)
			(layer "F.SilkS")
		)
		(fp_poly
			(pts
				(xy -0.5334 0.254) (xy -0.635 0.254) (xy -0.635 0.2286) (xy -0.635 -0.254) (xy -0.5334 -0.254) (xy -0.5334 -0.2794)
				(xy 0.5334 -0.2794) (xy 0.5334 -0.254) (xy 0.635 -0.254) (xy 0.635 0.254) (xy 0.5334 0.254) (xy 0.5334 0.2794)
				(xy -0.508 0.2794) (xy -0.5334 0.2794)
			)
			(stroke
				(width 0)
				(type default)
			)
			(fill no)
			(layer "F.CrtYd")
		)
		(pad "1" smd rect
			(at 0.40005 0 90)
			(size 0.4572 0.508)
			(layers "F.Cu" "F.Mask" "F.Paste")
			(net "T12_NODE2_EN_R")
		)
		(pad "2" smd rect
			(at -0.40005 0 90)
			(size 0.4572 0.508)
			(layers "F.Cu" "F.Mask" "F.Paste")
			(net "GND")
		)
	)
	(footprint ""
		(layer "F.Cu")
		(at 157.971998 -142.93723 -90)
		(property "Reference" "R567"
			(at -1.23063 -0.17907 90)
			(unlocked yes)
			(layer "F.SilkS")
			(effects
				(font
					(size 0.7874 0.5842)
					(thickness 0.1524)
				)
				(justify left)
			)
		)
		(property "Value" ""
			(at 0 0 270)
			(layer "F.Fab")
			(effects
				(font
					(size 1.27 1.27)
				)
			)
		)
		(duplicate_pad_numbers_are_jumpers no)
		(fp_line
			(start -0.7874 0.4064)
			(end -0.7874 -0.4064)
			(stroke
				(width 0.1524)
				(type default)
			)
			(layer "F.SilkS")
		)
		(fp_line
			(start 0.7874 0.4064)
			(end -0.7874 0.4064)
			(stroke
				(width 0.1524)
				(type default)
			)
			(layer "F.SilkS")
		)
		(fp_line
			(start -0.7874 -0.4064)
			(end 0.7874 -0.4064)
			(stroke
				(width 0.1524)
				(type default)
			)
			(layer "F.SilkS")
		)
		(fp_line
			(start 0.7874 -0.4064)
			(end 0.7874 0.4064)
			(stroke
				(width 0.1524)
				(type default)
			)
			(layer "F.SilkS")
		)
		(fp_poly
			(pts
				(xy -0.508 0.2794) (xy -0.508 0.2286) (xy -0.635 0.2286) (xy -0.635 -0.254) (xy -0.5334 -0.254)
				(xy -0.5334 -0.2794) (xy 0.5334 -0.2794) (xy 0.5334 -0.254) (xy 0.635 -0.254) (xy 0.635 0.254) (xy 0.5334 0.254)
				(xy 0.5334 0.2794)
			)
			(stroke
				(width 0)
				(type default)
			)
			(fill no)
			(layer "F.CrtYd")
		)
		(pad "1" smd rect
			(at 0.40005 0 270)
			(size 0.4572 0.508)
			(layers "F.Cu" "F.Mask" "F.Paste")
			(net "P3V3_NODE1")
		)
		(pad "2" smd rect
			(at -0.40005 0 270)
			(size 0.4572 0.508)
			(layers "F.Cu" "F.Mask" "F.Paste")
			(net "PU_LAN2_TDI")
		)
	)
	(footprint ""
		(layer "F.Cu")
		(at 49.88814 -166.43985 90)
		(property "Reference" "R562"
			(at -130.36804 -3.432048 90)
			(unlocked yes)
			(layer "F.SilkS")
			(effects
				(font
					(size 0.7874 0.5842)
					(thickness 0.1524)
				)
				(justify left)
			)
		)
		(property "Value" ""
			(at 0 0 90)
			(layer "F.Fab")
			(effects
				(font
					(size 1.27 1.27)
				)
			)
		)
		(duplicate_pad_numbers_are_jumpers no)
		(fp_line
			(start 0.7874 -0.4064)
			(end 0.7874 0.4064)
			(stroke
				(width 0.1524)
				(type default)
			)
			(layer "F.SilkS")
		)
		(fp_line
			(start -0.7874 -0.4064)
			(end 0.7874 -0.4064)
			(stroke
				(width 0.1524)
				(type default)
			)
			(layer "F.SilkS")
		)
		(fp_line
			(start 0.7874 0.4064)
			(end -0.7874 0.4064)
			(stroke
				(width 0.1524)
				(type default)
			)
			(layer "F.SilkS")
		)
		(fp_line
			(start -0.7874 0.4064)
			(end -0.7874 -0.4064)
			(stroke
				(width 0.1524)
				(type default)
			)
			(layer "F.SilkS")
		)
		(fp_poly
			(pts
				(xy -0.508 0.2794) (xy -0.508 0.2286) (xy -0.635 0.2286) (xy -0.635 -0.254) (xy -0.5334 -0.254)
				(xy -0.5334 -0.2794) (xy 0.5334 -0.2794) (xy 0.5334 -0.254) (xy 0.635 -0.254) (xy 0.635 0.254) (xy 0.5334 0.254)
				(xy 0.5334 0.2794)
			)
			(stroke
				(width 0)
				(type default)
			)
			(fill no)
			(layer "F.CrtYd")
		)
		(pad "1" smd rect
			(at 0.40005 0 90)
			(size 0.4572 0.508)
			(layers "F.Cu" "F.Mask" "F.Paste")
			(net "SMB_PCH_SDA")
		)
		(pad "2" smd rect
			(at -0.40005 0 90)
			(size 0.4572 0.508)
			(layers "F.Cu" "F.Mask" "F.Paste")
			(net "SMB_LAN1_DAT")
		)
	)
	(footprint ""
		(layer "F.Cu")
		(at 79.963518 -91.027504 180)
		(property "Reference" "R163"
			(at 1.195578 -18.973546 0)
			(unlocked yes)
			(layer "F.SilkS")
			(effects
				(font
					(size 0.7874 0.5842)
					(thickness 0.1524)
				)
				(justify left)
			)
		)
		(property "Value" ""
			(at 0 0 180)
			(layer "F.Fab")
			(effects
				(font
					(size 1.27 1.27)
				)
			)
		)
		(duplicate_pad_numbers_are_jumpers no)
		(fp_line
			(start 0.7874 0.4064)
			(end -0.7874 0.4064)
			(stroke
				(width 0.1524)
				(type default)
			)
			(layer "F.SilkS")
		)
		(fp_line
			(start 0.7874 -0.4064)
			(end 0.7874 0.4064)
			(stroke
				(width 0.1524)
				(type default)
			)
			(layer "F.SilkS")
		)
		(fp_line
			(start -0.7874 0.4064)
			(end -0.7874 -0.4064)
			(stroke
				(width 0.1524)
				(type default)
			)
			(layer "F.SilkS")
		)
		(fp_line
			(start -0.7874 -0.4064)
			(end 0.7874 -0.4064)
			(stroke
				(width 0.1524)
				(type default)
			)
			(layer "F.SilkS")
		)
		(fp_poly
			(pts
				(xy -0.508 0.2794) (xy -0.508 0.2286) (xy -0.635 0.2286) (xy -0.635 -0.254) (xy -0.5334 -0.254)
				(xy -0.5334 -0.2794) (xy 0.5334 -0.2794) (xy 0.5334 -0.254) (xy 0.635 -0.254) (xy 0.635 0.254) (xy 0.5334 0.254)
				(xy 0.5334 0.2794)
			)
			(stroke
				(width 0)
				(type default)
			)
			(fill no)
			(layer "F.CrtYd")
		)
		(pad "1" smd rect
			(at 0.40005 0 180)
			(size 0.4572 0.508)
			(layers "F.Cu" "F.Mask" "F.Paste")
			(net "VR_CPU_NODE1_INTVRMEN")
		)
		(pad "2" smd rect
			(at -0.40005 0 180)
			(size 0.4572 0.508)
			(layers "F.Cu" "F.Mask" "F.Paste")
			(net "P3V3_RTC_NODE1")
		)
	)
	(footprint ""
		(layer "F.Cu")
		(at 44.625006 -182.898542 180)
		(property "Reference" "U93"
			(at -0.055118 5.057394 0)
			(unlocked yes)
			(layer "F.SilkS")
			(effects
				(font
					(size 0.7874 0.5842)
					(thickness 0.1524)
				)
			)
		)
		(property "Value" ""
			(at 0 0 180)
			(layer "F.Fab")
			(effects
				(font
					(size 1.27 1.27)
				)
			)
		)
		(duplicate_pad_numbers_are_jumpers no)
		(fp_line
			(start 1.651 1.905)
			(end -1.651 1.905)
			(stroke
				(width 0.1524)
				(type default)
			)
			(layer "F.SilkS")
		)
		(fp_line
			(start 1.651 -1.905)
			(end 1.651 1.905)
			(stroke
				(width 0.1524)
				(type default)
			)
			(layer "F.SilkS")
		)
		(fp_line
			(start -1.651 1.905)
			(end -1.651 -1.905)
			(stroke
				(width 0.1524)
				(type default)
			)
			(layer "F.SilkS")
		)
		(fp_line
			(start -1.651 -1.905)
			(end 1.651 -1.905)
			(stroke
				(width 0.1524)
				(type default)
			)
			(layer "F.SilkS")
		)
		(fp_poly
			(pts
				(xy -1.524 0.7112) (xy -1.524 1.7526) (xy -0.508 1.7526) (xy -0.508 0.6985) (xy 0.508 0.6985) (xy 0.508 1.7526)
				(xy 1.524 1.7526) (xy 1.524 0.6985) (xy 1.524 -0.6985) (xy 0.508 -0.6985) (xy 0.508 -1.7526) (xy -0.508 -1.7526)
				(xy -0.508 -0.6985) (xy -1.524 -0.6985) (xy -1.524 0.6985)
			)
			(stroke
				(width 0)
				(type default)
			)
			(fill no)
			(layer "F.CrtYd")
		)
		(fp_text user "D"
			(at 2.021586 -1.39192 0)
			(unlocked yes)
			(layer "F.SilkS")
			(effects
				(font
					(size 0.635 0.4064)
					(thickness 0.1524)
				)
			)
		)
		(fp_text user "S"
			(at 1.662176 2.46507 0)
			(unlocked yes)
			(layer "F.SilkS")
			(effects
				(font
					(size 0.635 0.4064)
					(thickness 0.1524)
				)
			)
		)
		(fp_text user "G"
			(at 0.580644 2.230374 0)
			(unlocked yes)
			(layer "F.SilkS")
			(effects
				(font
					(size 0.635 0.4064)
					(thickness 0.1524)
				)
			)
		)
		(pad "D" smd rect
			(at 0 -1.1176 180)
			(size 1.016 1.27)
			(layers "F.Cu" "F.Mask" "F.Paste")
			(net "P12V_AUX_EN")
		)
		(pad "G" smd rect
			(at -1.016 1.1176 180)
			(size 1.016 1.27)
			(layers "F.Cu" "F.Mask" "F.Paste")
			(net "MATE_N")
		)
		(pad "S" smd rect
			(at 1.016 1.1176 180)
			(size 1.016 1.27)
			(layers "F.Cu" "F.Mask" "F.Paste")
			(net "GND")
		)
	)
	(footprint ""
		(layer "F.Cu")
		(at 26.91892 -137.846308 180)
		(property "Reference" "C431"
			(at -2.42062 -0.05334 0)
			(unlocked yes)
			(layer "F.SilkS")
			(effects
				(font
					(size 0.7874 0.5842)
					(thickness 0.1524)
				)
				(justify left)
			)
		)
		(property "Value" ""
			(at 0 0 180)
			(layer "F.Fab")
			(effects
				(font
					(size 1.27 1.27)
				)
			)
		)
		(duplicate_pad_numbers_are_jumpers no)
		(fp_line
			(start 1.905 0.8636)
			(end -1.905 0.8636)
			(stroke
				(width 0.1524)
				(type default)
			)
			(layer "F.SilkS")
		)
		(fp_line
			(start 1.905 -0.8636)
			(end 1.905 0.8636)
			(stroke
				(width 0.1524)
				(type default)
			)
			(layer "F.SilkS")
		)
		(fp_line
			(start 0 0.8382)
			(end 0 -0.8382)
			(stroke
				(width 0.1524)
				(type default)
			)
			(layer "F.SilkS")
		)
		(fp_line
			(start -1.905 0.8636)
			(end -1.905 -0.8636)
			(stroke
				(width 0.1524)
				(type default)
			)
			(layer "F.SilkS")
		)
		(fp_line
			(start -1.905 -0.8636)
			(end 1.905 -0.8636)
			(stroke
				(width 0.1524)
				(type default)
			)
			(layer "F.SilkS")
		)
		(fp_rect
			(start -1.524 0.7366)
			(end 1.524 -0.7366)
			(stroke
				(width 0)
				(type default)
			)
			(fill no)
			(layer "F.CrtYd")
		)
		(pad "1" smd rect
			(at 0.94996 0 180)
			(size 1.1176 1.3716)
			(layers "F.Cu" "F.Mask" "F.Paste")
			(net "P1V9_LAN1")
		)
		(pad "2" smd rect
			(at -0.94996 0 180)
			(size 1.1176 1.3716)
			(layers "F.Cu" "F.Mask" "F.Paste")
			(net "GND")
		)
	)
	(footprint ""
		(layer "F.Cu")
		(at 137.65276 -185.205624 -90)
		(property "Reference" "R882"
			(at -4.768088 0.474472 90)
			(unlocked yes)
			(layer "F.SilkS")
			(effects
				(font
					(size 0.7874 0.5842)
					(thickness 0.1524)
				)
				(justify left)
			)
		)
		(property "Value" ""
			(at 0 0 270)
			(layer "F.Fab")
			(effects
				(font
					(size 1.27 1.27)
				)
			)
		)
		(duplicate_pad_numbers_are_jumpers no)
		(fp_line
			(start -0.7874 0.4064)
			(end -0.7874 -0.4064)
			(stroke
				(width 0.1524)
				(type default)
			)
			(layer "F.SilkS")
		)
		(fp_line
			(start 0.7874 0.4064)
			(end -0.7874 0.4064)
			(stroke
				(width 0.1524)
				(type default)
			)
			(layer "F.SilkS")
		)
		(fp_line
			(start -0.7874 -0.4064)
			(end 0.7874 -0.4064)
			(stroke
				(width 0.1524)
				(type default)
			)
			(layer "F.SilkS")
		)
		(fp_line
			(start 0.7874 -0.4064)
			(end 0.7874 0.4064)
			(stroke
				(width 0.1524)
				(type default)
			)
			(layer "F.SilkS")
		)
		(fp_poly
			(pts
				(xy -0.508 0.2794) (xy -0.508 0.2286) (xy -0.635 0.2286) (xy -0.635 -0.254) (xy -0.5334 -0.254)
				(xy -0.5334 -0.2794) (xy 0.5334 -0.2794) (xy 0.5334 -0.254) (xy 0.635 -0.254) (xy 0.635 0.254) (xy 0.5334 0.254)
				(xy 0.5334 0.2794)
			)
			(stroke
				(width 0)
				(type default)
			)
			(fill no)
			(layer "F.CrtYd")
		)
		(pad "1" smd rect
			(at 0.40005 0 270)
			(size 0.4572 0.508)
			(layers "F.Cu" "F.Mask" "F.Paste")
			(net "T10_NODE4_EN")
		)
		(pad "2" smd rect
			(at -0.40005 0 270)
			(size 0.4572 0.508)
			(layers "F.Cu" "F.Mask" "F.Paste")
			(net "T10_NODE4_EN_R")
		)
	)
	(footprint ""
		(layer "F.Cu")
		(at 152.579578 -70.203822 180)
		(property "Reference" "R504"
			(at 1.658366 2.26695 0)
			(unlocked yes)
			(layer "F.SilkS")
			(effects
				(font
					(size 0.7874 0.5842)
					(thickness 0.1524)
				)
				(justify left)
			)
		)
		(property "Value" ""
			(at 0 0 180)
			(layer "F.Fab")
			(effects
				(font
					(size 1.27 1.27)
				)
			)
		)
		(duplicate_pad_numbers_are_jumpers no)
		(fp_line
			(start 0.7874 0.4064)
			(end -0.7874 0.4064)
			(stroke
				(width 0.1524)
				(type default)
			)
			(layer "F.SilkS")
		)
		(fp_line
			(start 0.7874 -0.4064)
			(end 0.7874 0.4064)
			(stroke
				(width 0.1524)
				(type default)
			)
			(layer "F.SilkS")
		)
		(fp_line
			(start -0.7874 0.4064)
			(end -0.7874 -0.4064)
			(stroke
				(width 0.1524)
				(type default)
			)
			(layer "F.SilkS")
		)
		(fp_line
			(start -0.7874 -0.4064)
			(end 0.7874 -0.4064)
			(stroke
				(width 0.1524)
				(type default)
			)
			(layer "F.SilkS")
		)
		(fp_poly
			(pts
				(xy -0.508 0.2794) (xy -0.508 0.2286) (xy -0.635 0.2286) (xy -0.635 -0.254) (xy -0.5334 -0.254)
				(xy -0.5334 -0.2794) (xy 0.5334 -0.2794) (xy 0.5334 -0.254) (xy 0.635 -0.254) (xy 0.635 0.254) (xy 0.5334 0.254)
				(xy 0.5334 0.2794)
			)
			(stroke
				(width 0)
				(type default)
			)
			(fill no)
			(layer "F.CrtYd")
		)
		(pad "1" smd rect
			(at 0.40005 0 180)
			(size 0.4572 0.508)
			(layers "F.Cu" "F.Mask" "F.Paste")
			(net "SATA_NODE1_ISET")
		)
		(pad "2" smd rect
			(at -0.40005 0 180)
			(size 0.4572 0.508)
			(layers "F.Cu" "F.Mask" "F.Paste")
			(net "GND")
		)
	)
	(footprint ""
		(layer "F.Cu")
		(at 16.486124 -52.32908 -90)
		(property "Reference" "R638"
			(at 4.444492 -14.374114 90)
			(unlocked yes)
			(layer "F.SilkS")
			(effects
				(font
					(size 0.7874 0.5842)
					(thickness 0.1524)
				)
				(justify left)
			)
		)
		(property "Value" ""
			(at 0 0 270)
			(layer "F.Fab")
			(effects
				(font
					(size 1.27 1.27)
				)
			)
		)
		(duplicate_pad_numbers_are_jumpers no)
		(fp_line
			(start -0.7874 0.4064)
			(end -0.7874 -0.4064)
			(stroke
				(width 0.1524)
				(type default)
			)
			(layer "F.SilkS")
		)
		(fp_line
			(start 0.7874 0.4064)
			(end -0.7874 0.4064)
			(stroke
				(width 0.1524)
				(type default)
			)
			(layer "F.SilkS")
		)
		(fp_line
			(start -0.7874 -0.4064)
			(end 0.7874 -0.4064)
			(stroke
				(width 0.1524)
				(type default)
			)
			(layer "F.SilkS")
		)
		(fp_line
			(start 0.7874 -0.4064)
			(end 0.7874 0.4064)
			(stroke
				(width 0.1524)
				(type default)
			)
			(layer "F.SilkS")
		)
		(fp_poly
			(pts
				(xy -0.508 0.2794) (xy -0.508 0.2286) (xy -0.635 0.2286) (xy -0.635 -0.254) (xy -0.5334 -0.254)
				(xy -0.5334 -0.2794) (xy 0.5334 -0.2794) (xy 0.5334 -0.254) (xy 0.635 -0.254) (xy 0.635 0.254) (xy 0.5334 0.254)
				(xy 0.5334 0.2794)
			)
			(stroke
				(width 0)
				(type default)
			)
			(fill no)
			(layer "F.CrtYd")
		)
		(pad "1" smd rect
			(at 0.40005 0 270)
			(size 0.4572 0.508)
			(layers "F.Cu" "F.Mask" "F.Paste")
			(net "VGA_HSYNC")
		)
		(pad "2" smd rect
			(at -0.40005 0 270)
			(size 0.4572 0.508)
			(layers "F.Cu" "F.Mask" "F.Paste")
			(net "CRT_HSYNC")
		)
	)
	(footprint ""
		(layer "F.Cu")
		(at 155.350972 -33.459928 90)
		(property "Reference" "U51"
			(at -3.49377 5.493512 90)
			(unlocked yes)
			(layer "F.SilkS")
			(effects
				(font
					(size 0.7874 0.5842)
					(thickness 0.1524)
				)
				(justify left)
			)
		)
		(property "Value" ""
			(at 0 0 90)
			(layer "F.Fab")
			(effects
				(font
					(size 1.27 1.27)
				)
			)
		)
		(duplicate_pad_numbers_are_jumpers no)
		(fp_line
			(start 4.9022 -2.0066)
			(end 4.9022 2.0066)
			(stroke
				(width 0.1524)
				(type default)
			)
			(layer "F.SilkS")
		)
		(fp_line
			(start -4.9022 -2.0066)
			(end 4.9022 -2.0066)
			(stroke
				(width 0.1524)
				(type default)
			)
			(layer "F.SilkS")
		)
		(fp_line
			(start -4.9022 -0.5842)
			(end -4.9022 -2.0066)
			(stroke
				(width 0.1524)
				(type default)
			)
			(layer "F.SilkS")
		)
		(fp_line
			(start -4.318 0)
			(end -4.9022 -0.5842)
			(stroke
				(width 0.1524)
				(type default)
			)
			(layer "F.SilkS")
		)
		(fp_line
			(start -4.9022 0.5842)
			(end -4.318 0)
			(stroke
				(width 0.1524)
				(type default)
			)
			(layer "F.SilkS")
		)
		(fp_line
			(start 4.9022 2.0066)
			(end -4.9022 2.0066)
			(stroke
				(width 0.1524)
				(type default)
			)
			(layer "F.SilkS")
		)
		(fp_line
			(start -4.9022 2.0066)
			(end -4.9022 0.5842)
			(stroke
				(width 0.1524)
				(type default)
			)
			(layer "F.SilkS")
		)
		(fp_circle
			(center -4.318 1.524)
			(end -4.318 1.778)
			(stroke
				(width 0.1524)
				(type default)
			)
			(fill no)
			(layer "F.SilkS")
		)
		(fp_rect
			(start -4.9022 3.6703)
			(end 4.9022 -3.6703)
			(stroke
				(width 0)
				(type default)
			)
			(fill no)
			(layer "F.CrtYd")
		)
		(pad "1" smd rect
			(at -4.225036 2.921 90)
			(size 0.3556 1.4986)
			(layers "F.Cu" "F.Mask" "F.Paste")
			(net "N21624861")
		)
		(pad "2" smd rect
			(at -3.57505 2.921 90)
			(size 0.3556 1.4986)
			(layers "F.Cu" "F.Mask" "F.Paste")
			(net "N21624866")
		)
		(pad "3" smd rect
			(at -2.925064 2.921 90)
			(size 0.3556 1.4986)
			(layers "F.Cu" "F.Mask" "F.Paste")
			(net "N21624894")
		)
		(pad "4" smd rect
			(at -2.275078 2.921 90)
			(size 0.3556 1.4986)
			(layers "F.Cu" "F.Mask" "F.Paste")
			(net "UART_RX_P1_L")
		)
		(pad "5" smd rect
			(at -1.625092 2.921 90)
			(size 0.3556 1.4986)
			(layers "F.Cu" "F.Mask" "F.Paste")
			(net "UART_DSR_P1_L_N")
		)
		(pad "6" smd rect
			(at -0.975106 2.921 90)
			(size 0.3556 1.4986)
			(layers "F.Cu" "F.Mask" "F.Paste")
			(net "UART_CTS_P1_L_N")
		)
		(pad "7" smd rect
			(at -0.32512 2.921 90)
			(size 0.3556 1.4986)
			(layers "F.Cu" "F.Mask" "F.Paste")
			(net "N37284163")
		)
		(pad "8" smd rect
			(at 0.32512 2.921 90)
			(size 0.3556 1.4986)
			(layers "F.Cu" "F.Mask" "F.Paste")
			(net "N37284163")
		)
		(pad "9" smd rect
			(at 0.975106 2.921 90)
			(size 0.3556 1.4986)
			(layers "F.Cu" "F.Mask" "F.Paste")
			(net "UART_RTS_P1_L_N")
		)
		(pad "10" smd rect
			(at 1.625092 2.921 90)
			(size 0.3556 1.4986)
			(layers "F.Cu" "F.Mask" "F.Paste")
			(net "UART_TX_P1_L")
		)
		(pad "11" smd rect
			(at 2.275078 2.921 90)
			(size 0.3556 1.4986)
			(layers "F.Cu" "F.Mask" "F.Paste")
			(net "UART_DTR_P1_L_N")
		)
		(pad "12" smd rect
			(at 2.925064 2.921 90)
			(size 0.3556 1.4986)
			(layers "F.Cu" "F.Mask" "F.Paste")
			(net "UART_DTR_P1_N")
		)
		(pad "13" smd rect
			(at 3.57505 2.921 90)
			(size 0.3556 1.4986)
			(layers "F.Cu" "F.Mask" "F.Paste")
			(net "UART_TX_P1")
		)
		(pad "14" smd rect
			(at 4.225036 2.921 90)
			(size 0.3556 1.4986)
			(layers "F.Cu" "F.Mask" "F.Paste")
			(net "UART_RTS_P1_N")
		)
		(pad "15" smd rect
			(at 4.225036 -2.921 90)
			(size 0.3556 1.4986)
			(layers "F.Cu" "F.Mask" "F.Paste")
			(net "Net_503")
		)
		(pad "16" smd rect
			(at 3.57505 -2.921 90)
			(size 0.3556 1.4986)
			(layers "F.Cu" "F.Mask" "F.Paste")
			(net "Net_504")
		)
		(pad "17" smd rect
			(at 2.925064 -2.921 90)
			(size 0.3556 1.4986)
			(layers "F.Cu" "F.Mask" "F.Paste")
			(net "UART_CTS_P1_N")
		)
		(pad "18" smd rect
			(at 2.275078 -2.921 90)
			(size 0.3556 1.4986)
			(layers "F.Cu" "F.Mask" "F.Paste")
			(net "UART_DSR_P1_N")
		)
		(pad "19" smd rect
			(at 1.625092 -2.921 90)
			(size 0.3556 1.4986)
			(layers "F.Cu" "F.Mask" "F.Paste")
			(net "UART_RX_P1")
		)
		(pad "20" smd rect
			(at 0.975106 -2.921 90)
			(size 0.3556 1.4986)
			(layers "F.Cu" "F.Mask" "F.Paste")
			(net "Net_1849")
		)
		(pad "21" smd rect
			(at 0.32512 -2.921 90)
			(size 0.3556 1.4986)
			(layers "F.Cu" "F.Mask" "F.Paste")
			(net "Net_1848")
		)
		(pad "22" smd rect
			(at -0.32512 -2.921 90)
			(size 0.3556 1.4986)
			(layers "F.Cu" "F.Mask" "F.Paste")
			(net "N21624806")
		)
		(pad "23" smd rect
			(at -0.975106 -2.921 90)
			(size 0.3556 1.4986)
			(layers "F.Cu" "F.Mask" "F.Paste")
			(net "N21624804")
		)
		(pad "24" smd rect
			(at -1.625092 -2.921 90)
			(size 0.3556 1.4986)
			(layers "F.Cu" "F.Mask" "F.Paste")
			(net "N21624850")
		)
		(pad "25" smd rect
			(at -2.275078 -2.921 90)
			(size 0.3556 1.4986)
			(layers "F.Cu" "F.Mask" "F.Paste")
			(net "GND")
		)
		(pad "26" smd rect
			(at -2.925064 -2.921 90)
			(size 0.3556 1.4986)
			(layers "F.Cu" "F.Mask" "F.Paste")
			(net "P3V3_NODE1")
		)
		(pad "27" smd rect
			(at -3.57505 -2.921 90)
			(size 0.3556 1.4986)
			(layers "F.Cu" "F.Mask" "F.Paste")
			(net "N21624890")
		)
		(pad "28" smd rect
			(at -4.225036 -2.921 90)
			(size 0.3556 1.4986)
			(layers "F.Cu" "F.Mask" "F.Paste")
			(net "N21624848")
		)
	)
	(footprint ""
		(layer "F.Cu")
		(at 149.633178 -73.937622 90)
		(property "Reference" "C333"
			(at -0.780034 2.370074 90)
			(unlocked yes)
			(layer "F.SilkS")
			(effects
				(font
					(size 0.7874 0.5842)
					(thickness 0.1524)
				)
				(justify left)
			)
		)
		(property "Value" ""
			(at 0 0 90)
			(layer "F.Fab")
			(effects
				(font
					(size 1.27 1.27)
				)
			)
		)
		(duplicate_pad_numbers_are_jumpers no)
		(fp_line
			(start 0.7874 -0.4064)
			(end 0.7874 0.4064)
			(stroke
				(width 0.1524)
				(type default)
			)
			(layer "F.SilkS")
		)
		(fp_line
			(start -0.7874 -0.4064)
			(end 0.7874 -0.4064)
			(stroke
				(width 0.1524)
				(type default)
			)
			(layer "F.SilkS")
		)
		(fp_line
			(start 0 0.381)
			(end 0 -0.381)
			(stroke
				(width 0.1524)
				(type default)
			)
			(layer "F.SilkS")
		)
		(fp_line
			(start 0.7874 0.4064)
			(end -0.7874 0.4064)
			(stroke
				(width 0.1524)
				(type default)
			)
			(layer "F.SilkS")
		)
		(fp_line
			(start -0.7874 0.4064)
			(end -0.7874 -0.4064)
			(stroke
				(width 0.1524)
				(type default)
			)
			(layer "F.SilkS")
		)
		(fp_poly
			(pts
				(xy -0.5334 0.254) (xy -0.635 0.254) (xy -0.635 0.2286) (xy -0.635 -0.254) (xy -0.5334 -0.254) (xy -0.5334 -0.2794)
				(xy 0.5334 -0.2794) (xy 0.5334 -0.254) (xy 0.635 -0.254) (xy 0.635 0.254) (xy 0.5334 0.254) (xy 0.5334 0.2794)
				(xy -0.508 0.2794) (xy -0.5334 0.2794)
			)
			(stroke
				(width 0)
				(type default)
			)
			(fill no)
			(layer "F.CrtYd")
		)
		(pad "1" smd rect
			(at 0.40005 0 90)
			(size 0.4572 0.508)
			(layers "F.Cu" "F.Mask" "F.Paste")
			(net "P2E_CPU_SATA_NODE1_RX_DP")
		)
		(pad "2" smd rect
			(at -0.40005 0 90)
			(size 0.4572 0.508)
			(layers "F.Cu" "F.Mask" "F.Paste")
			(net "P2E_CPU_SATA_NODE1_RX_C_DP")
		)
	)
	(footprint ""
		(layer "F.Cu")
		(at 80.502252 -103.795576 90)
		(property "Reference" "R1099"
			(at -1.475486 -0.10033 0)
			(unlocked yes)
			(layer "F.SilkS")
			(effects
				(font
					(size 0.7874 0.5842)
					(thickness 0.1524)
				)
				(justify left)
			)
		)
		(property "Value" ""
			(at 0 0 90)
			(layer "F.Fab")
			(effects
				(font
					(size 1.27 1.27)
				)
			)
		)
		(duplicate_pad_numbers_are_jumpers no)
		(fp_line
			(start 0.7874 -0.4064)
			(end 0.7874 0.4064)
			(stroke
				(width 0.1524)
				(type default)
			)
			(layer "F.SilkS")
		)
		(fp_line
			(start -0.7874 -0.4064)
			(end 0.7874 -0.4064)
			(stroke
				(width 0.1524)
				(type default)
			)
			(layer "F.SilkS")
		)
		(fp_line
			(start 0.7874 0.4064)
			(end -0.7874 0.4064)
			(stroke
				(width 0.1524)
				(type default)
			)
			(layer "F.SilkS")
		)
		(fp_line
			(start -0.7874 0.4064)
			(end -0.7874 -0.4064)
			(stroke
				(width 0.1524)
				(type default)
			)
			(layer "F.SilkS")
		)
		(fp_poly
			(pts
				(xy -0.508 0.2794) (xy -0.508 0.2286) (xy -0.635 0.2286) (xy -0.635 -0.254) (xy -0.5334 -0.254)
				(xy -0.5334 -0.2794) (xy 0.5334 -0.2794) (xy 0.5334 -0.254) (xy 0.635 -0.254) (xy 0.635 0.254) (xy 0.5334 0.254)
				(xy 0.5334 0.2794)
			)
			(stroke
				(width 0)
				(type default)
			)
			(fill no)
			(layer "F.CrtYd")
		)
		(pad "1" smd rect
			(at 0.40005 0 90)
			(size 0.4572 0.508)
			(layers "F.Cu" "F.Mask" "F.Paste")
			(net "P12V_AUX")
		)
		(pad "2" smd rect
			(at -0.40005 0 90)
			(size 0.4572 0.508)
			(layers "F.Cu" "F.Mask" "F.Paste")
			(net "FM_CPLD_NODE1_P3V3_SUS_EN_LV")
		)
	)
	(footprint ""
		(layer "F.Cu")
		(at 20.921472 -74.207878 -90)
		(property "Reference" "C497"
			(at -1.699514 -0.002794 90)
			(unlocked yes)
			(layer "F.SilkS")
			(effects
				(font
					(size 0.7874 0.5842)
					(thickness 0.1524)
				)
				(justify left)
			)
		)
		(property "Value" ""
			(at 0 0 270)
			(layer "F.Fab")
			(effects
				(font
					(size 1.27 1.27)
				)
			)
		)
		(duplicate_pad_numbers_are_jumpers no)
		(fp_line
			(start -0.7874 0.4064)
			(end -0.7874 -0.4064)
			(stroke
				(width 0.1524)
				(type default)
			)
			(layer "F.SilkS")
		)
		(fp_line
			(start 0.7874 0.4064)
			(end -0.7874 0.4064)
			(stroke
				(width 0.1524)
				(type default)
			)
			(layer "F.SilkS")
		)
		(fp_line
			(start 0 0.381)
			(end 0 -0.381)
			(stroke
				(width 0.1524)
				(type default)
			)
			(layer "F.SilkS")
		)
		(fp_line
			(start -0.7874 -0.4064)
			(end 0.7874 -0.4064)
			(stroke
				(width 0.1524)
				(type default)
			)
			(layer "F.SilkS")
		)
		(fp_line
			(start 0.7874 -0.4064)
			(end 0.7874 0.4064)
			(stroke
				(width 0.1524)
				(type default)
			)
			(layer "F.SilkS")
		)
		(fp_poly
			(pts
				(xy -0.5334 0.254) (xy -0.635 0.254) (xy -0.635 0.2286) (xy -0.635 -0.254) (xy -0.5334 -0.254) (xy -0.5334 -0.2794)
				(xy 0.5334 -0.2794) (xy 0.5334 -0.254) (xy 0.635 -0.254) (xy 0.635 0.254) (xy 0.5334 0.254) (xy 0.5334 0.2794)
				(xy -0.508 0.2794) (xy -0.5334 0.2794)
			)
			(stroke
				(width 0)
				(type default)
			)
			(fill no)
			(layer "F.CrtYd")
		)
		(pad "1" smd rect
			(at 0.40005 0 270)
			(size 0.4572 0.508)
			(layers "F.Cu" "F.Mask" "F.Paste")
			(net "P5V_NODE1")
		)
		(pad "2" smd rect
			(at -0.40005 0 270)
			(size 0.4572 0.508)
			(layers "F.Cu" "F.Mask" "F.Paste")
			(net "GND")
		)
	)
	(footprint ""
		(layer "F.Cu")
		(at 47.649892 -112.875568 180)
		(property "Reference" "PC12"
			(at 1.286002 3.150108 0)
			(unlocked yes)
			(layer "F.SilkS")
			(effects
				(font
					(size 0.7874 0.5842)
					(thickness 0.1524)
				)
				(justify left)
			)
		)
		(property "Value" ""
			(at 0 0 180)
			(layer "F.Fab")
			(effects
				(font
					(size 1.27 1.27)
				)
			)
		)
		(duplicate_pad_numbers_are_jumpers no)
		(fp_line
			(start 0.7874 0.4064)
			(end -0.7874 0.4064)
			(stroke
				(width 0.1524)
				(type default)
			)
			(layer "F.SilkS")
		)
		(fp_line
			(start 0.7874 -0.4064)
			(end 0.7874 0.4064)
			(stroke
				(width 0.1524)
				(type default)
			)
			(layer "F.SilkS")
		)
		(fp_line
			(start 0 0.381)
			(end 0 -0.381)
			(stroke
				(width 0.1524)
				(type default)
			)
			(layer "F.SilkS")
		)
		(fp_line
			(start -0.7874 0.4064)
			(end -0.7874 -0.4064)
			(stroke
				(width 0.1524)
				(type default)
			)
			(layer "F.SilkS")
		)
		(fp_line
			(start -0.7874 -0.4064)
			(end 0.7874 -0.4064)
			(stroke
				(width 0.1524)
				(type default)
			)
			(layer "F.SilkS")
		)
		(fp_poly
			(pts
				(xy -0.5334 0.254) (xy -0.635 0.254) (xy -0.635 0.2286) (xy -0.635 -0.254) (xy -0.5334 -0.254) (xy -0.5334 -0.2794)
				(xy 0.5334 -0.2794) (xy 0.5334 -0.254) (xy 0.635 -0.254) (xy 0.635 0.254) (xy 0.5334 0.254) (xy 0.5334 0.2794)
				(xy -0.508 0.2794) (xy -0.5334 0.2794)
			)
			(stroke
				(width 0)
				(type default)
			)
			(fill no)
			(layer "F.CrtYd")
		)
		(pad "1" smd rect
			(at 0.40005 0 180)
			(size 0.4572 0.508)
			(layers "F.Cu" "F.Mask" "F.Paste")
			(net "P12V_AUX")
		)
		(pad "2" smd rect
			(at -0.40005 0 180)
			(size 0.4572 0.508)
			(layers "F.Cu" "F.Mask" "F.Paste")
			(net "GND")
		)
	)
	(footprint ""
		(layer "F.Cu")
		(at 82.614516 -104.569768 -90)
		(property "Reference" "Q32"
			(at 0.106426 -2.088896 90)
			(unlocked yes)
			(layer "F.SilkS")
			(effects
				(font
					(size 0.7874 0.5842)
					(thickness 0.1524)
				)
			)
		)
		(property "Value" ""
			(at 0 0 270)
			(layer "F.Fab")
			(effects
				(font
					(size 1.27 1.27)
				)
			)
		)
		(duplicate_pad_numbers_are_jumpers no)
		(fp_line
			(start -1.603248 1.500124)
			(end -1.603248 -1.500124)
			(stroke
				(width 0.1524)
				(type default)
			)
			(layer "F.SilkS")
		)
		(fp_line
			(start 1.603248 1.500124)
			(end -1.603248 1.500124)
			(stroke
				(width 0.1524)
				(type default)
			)
			(layer "F.SilkS")
		)
		(fp_line
			(start -1.603248 -1.500124)
			(end 1.603248 -1.500124)
			(stroke
				(width 0.1524)
				(type default)
			)
			(layer "F.SilkS")
		)
		(fp_line
			(start 1.603248 -1.500124)
			(end 1.603248 1.500124)
			(stroke
				(width 0.1524)
				(type default)
			)
			(layer "F.SilkS")
		)
		(fp_poly
			(pts
				(xy -0.700024 -1.500124) (xy -0.700024 -1.40716) (xy -1.507998 -1.40716) (xy -1.507998 -0.49276)
				(xy -0.700024 -0.49276) (xy -0.700024 0.47244) (xy -1.507998 0.47244) (xy -1.507998 1.41224) (xy -0.700024 1.41224)
				(xy -0.700024 1.500124) (xy 0.700024 1.500124) (xy 0.700024 0.47244) (xy 1.514602 0.47244) (xy 1.514602 -0.46736)
				(xy 0.700024 -0.46736) (xy 0.700024 -1.500124)
			)
			(stroke
				(width 0)
				(type default)
			)
			(fill no)
			(layer "F.CrtYd")
		)
		(fp_line
			(start -0.700024 1.500124)
			(end -0.700024 -1.500124)
			(stroke
				(width 0.1)
				(type default)
			)
			(layer "F.Fab")
		)
		(fp_line
			(start 0.700024 1.500124)
			(end -0.700024 1.500124)
			(stroke
				(width 0.1)
				(type default)
			)
			(layer "F.Fab")
		)
		(fp_line
			(start -0.700024 -1.500124)
			(end 0.700024 -1.500124)
			(stroke
				(width 0.1)
				(type default)
			)
			(layer "F.Fab")
		)
		(fp_line
			(start 0.700024 -1.500124)
			(end 0.700024 1.500124)
			(stroke
				(width 0.1)
				(type default)
			)
			(layer "F.Fab")
		)
		(fp_text user "S"
			(at -0.713486 1.863598 0)
			(unlocked yes)
			(layer "F.SilkS")
			(effects
				(font
					(size 0.635 0.4064)
					(thickness 0.1524)
				)
			)
		)
		(fp_text user "D"
			(at -2.051812 1.655826 0)
			(unlocked yes)
			(layer "F.SilkS")
			(effects
				(font
					(size 0.635 0.4064)
					(thickness 0.1524)
				)
			)
		)
		(fp_text user "G"
			(at 1.781556 -2.125218 0)
			(unlocked yes)
			(layer "F.SilkS")
			(effects
				(font
					(size 0.635 0.4064)
					(thickness 0.1524)
				)
			)
		)
		(fp_text user "S"
			(at -1.025906 2.0066 180)
			(unlocked yes)
			(layer "F.Fab")
			(effects
				(font
					(size 0.7874 0.5842)
					(thickness 0.000001)
				)
			)
		)
		(fp_text user "D"
			(at 2.098294 0.1016 180)
			(unlocked yes)
			(layer "F.Fab")
			(effects
				(font
					(size 0.7874 0.5842)
					(thickness 0.000001)
				)
			)
		)
		(fp_text user "G"
			(at -1.051306 -2.032 180)
			(unlocked yes)
			(layer "F.Fab")
			(effects
				(font
					(size 0.7874 0.5842)
					(thickness 0.000001)
				)
			)
		)
		(pad "D" smd rect
			(at 0.999998 0 180)
			(size 0.8128 0.9144)
			(layers "F.Cu" "F.Mask" "F.Paste")
			(net "FM_CPLD_NODE1_P3V3_SUS_EN_LV")
		)
		(pad "G" smd rect
			(at -0.999998 -0.94996 180)
			(size 0.8128 0.9144)
			(layers "F.Cu" "F.Mask" "F.Paste")
			(net "FM_CPLD_NODE1_P3V3_SUS_EN_G")
		)
		(pad "S" smd rect
			(at -0.999998 0.94996 180)
			(size 0.8128 0.9144)
			(layers "F.Cu" "F.Mask" "F.Paste")
			(net "FM_CPLD_NODE1_P3V3_SUS_EN")
		)
	)
	(footprint ""
		(layer "F.Cu")
		(at 94.211394 -185.790586)
		(property "Reference" "C678"
			(at -1.182878 -7.228586 0)
			(unlocked yes)
			(layer "F.SilkS")
			(effects
				(font
					(size 0.7874 0.5842)
					(thickness 0.1524)
				)
				(justify left)
			)
		)
		(property "Value" ""
			(at 0 0 0)
			(layer "F.Fab")
			(effects
				(font
					(size 1.27 1.27)
				)
			)
		)
		(duplicate_pad_numbers_are_jumpers no)
		(fp_line
			(start -0.7874 -0.4064)
			(end 0.7874 -0.4064)
			(stroke
				(width 0.1524)
				(type default)
			)
			(layer "F.SilkS")
		)
		(fp_line
			(start -0.7874 0.4064)
			(end -0.7874 -0.4064)
			(stroke
				(width 0.1524)
				(type default)
			)
			(layer "F.SilkS")
		)
		(fp_line
			(start 0 0.381)
			(end 0 -0.381)
			(stroke
				(width 0.1524)
				(type default)
			)
			(layer "F.SilkS")
		)
		(fp_line
			(start 0.7874 -0.4064)
			(end 0.7874 0.4064)
			(stroke
				(width 0.1524)
				(type default)
			)
			(layer "F.SilkS")
		)
		(fp_line
			(start 0.7874 0.4064)
			(end -0.7874 0.4064)
			(stroke
				(width 0.1524)
				(type default)
			)
			(layer "F.SilkS")
		)
		(fp_poly
			(pts
				(xy -0.5334 0.254) (xy -0.635 0.254) (xy -0.635 0.2286) (xy -0.635 -0.254) (xy -0.5334 -0.254) (xy -0.5334 -0.2794)
				(xy 0.5334 -0.2794) (xy 0.5334 -0.254) (xy 0.635 -0.254) (xy 0.635 0.254) (xy 0.5334 0.254) (xy 0.5334 0.2794)
				(xy -0.508 0.2794) (xy -0.5334 0.2794)
			)
			(stroke
				(width 0)
				(type default)
			)
			(fill no)
			(layer "F.CrtYd")
		)
		(pad "1" smd rect
			(at 0.40005 0)
			(size 0.4572 0.508)
			(layers "F.Cu" "F.Mask" "F.Paste")
			(net "UART_T5_NODE2_RXD")
		)
		(pad "2" smd rect
			(at -0.40005 0)
			(size 0.4572 0.508)
			(layers "F.Cu" "F.Mask" "F.Paste")
			(net "GND")
		)
	)
	(footprint ""
		(layer "F.Cu")
		(at 49.38776 -185.205624 90)
		(property "Reference" "R839"
			(at 4.006088 0.055372 90)
			(unlocked yes)
			(layer "F.SilkS")
			(effects
				(font
					(size 0.7874 0.5842)
					(thickness 0.1524)
				)
				(justify left)
			)
		)
		(property "Value" ""
			(at 0 0 90)
			(layer "F.Fab")
			(effects
				(font
					(size 1.27 1.27)
				)
			)
		)
		(duplicate_pad_numbers_are_jumpers no)
		(fp_line
			(start 0.7874 -0.4064)
			(end 0.7874 0.4064)
			(stroke
				(width 0.1524)
				(type default)
			)
			(layer "F.SilkS")
		)
		(fp_line
			(start -0.7874 -0.4064)
			(end 0.7874 -0.4064)
			(stroke
				(width 0.1524)
				(type default)
			)
			(layer "F.SilkS")
		)
		(fp_line
			(start 0.7874 0.4064)
			(end -0.7874 0.4064)
			(stroke
				(width 0.1524)
				(type default)
			)
			(layer "F.SilkS")
		)
		(fp_line
			(start -0.7874 0.4064)
			(end -0.7874 -0.4064)
			(stroke
				(width 0.1524)
				(type default)
			)
			(layer "F.SilkS")
		)
		(fp_poly
			(pts
				(xy -0.508 0.2794) (xy -0.508 0.2286) (xy -0.635 0.2286) (xy -0.635 -0.254) (xy -0.5334 -0.254)
				(xy -0.5334 -0.2794) (xy 0.5334 -0.2794) (xy 0.5334 -0.254) (xy 0.635 -0.254) (xy 0.635 0.254) (xy 0.5334 0.254)
				(xy 0.5334 0.2794)
			)
			(stroke
				(width 0)
				(type default)
			)
			(fill no)
			(layer "F.CrtYd")
		)
		(pad "1" smd rect
			(at 0.40005 0 90)
			(size 0.4572 0.508)
			(layers "F.Cu" "F.Mask" "F.Paste")
			(net "PSU4_AC_OK_R")
		)
		(pad "2" smd rect
			(at -0.40005 0 90)
			(size 0.4572 0.508)
			(layers "F.Cu" "F.Mask" "F.Paste")
			(net "PSU4_AC_OK")
		)
	)
	(footprint ""
		(layer "F.Cu")
		(at 116.398548 -138.065002)
		(property "Reference" "PC103"
			(at 2.059432 -4.505706 0)
			(unlocked yes)
			(layer "F.SilkS")
			(effects
				(font
					(size 0.7874 0.5842)
					(thickness 0.1524)
				)
				(justify left)
			)
		)
		(property "Value" ""
			(at 0 0 0)
			(layer "F.Fab")
			(effects
				(font
					(size 1.27 1.27)
				)
			)
		)
		(duplicate_pad_numbers_are_jumpers no)
		(fp_line
			(start -0.7874 -0.4064)
			(end 0.7874 -0.4064)
			(stroke
				(width 0.1524)
				(type default)
			)
			(layer "F.SilkS")
		)
		(fp_line
			(start -0.7874 0.4064)
			(end -0.7874 -0.4064)
			(stroke
				(width 0.1524)
				(type default)
			)
			(layer "F.SilkS")
		)
		(fp_line
			(start 0 0.381)
			(end 0 -0.381)
			(stroke
				(width 0.1524)
				(type default)
			)
			(layer "F.SilkS")
		)
		(fp_line
			(start 0.7874 -0.4064)
			(end 0.7874 0.4064)
			(stroke
				(width 0.1524)
				(type default)
			)
			(layer "F.SilkS")
		)
		(fp_line
			(start 0.7874 0.4064)
			(end -0.7874 0.4064)
			(stroke
				(width 0.1524)
				(type default)
			)
			(layer "F.SilkS")
		)
		(fp_poly
			(pts
				(xy -0.5334 0.254) (xy -0.635 0.254) (xy -0.635 0.2286) (xy -0.635 -0.254) (xy -0.5334 -0.254) (xy -0.5334 -0.2794)
				(xy 0.5334 -0.2794) (xy 0.5334 -0.254) (xy 0.635 -0.254) (xy 0.635 0.254) (xy 0.5334 0.254) (xy 0.5334 0.2794)
				(xy -0.508 0.2794) (xy -0.5334 0.2794)
			)
			(stroke
				(width 0)
				(type default)
			)
			(fill no)
			(layer "F.CrtYd")
		)
		(pad "1" smd rect
			(at 0.40005 0)
			(size 0.4572 0.508)
			(layers "F.Cu" "F.Mask" "F.Paste")
			(net "VR_PVCCP_NODE1_FB_RC")
		)
		(pad "2" smd rect
			(at -0.40005 0)
			(size 0.4572 0.508)
			(layers "F.Cu" "F.Mask" "F.Paste")
			(net "VR_PVCCP_NODE1_VSEN")
		)
	)
	(footprint ""
		(layer "F.Cu")
		(at 25.391872 -94.661228 90)
		(property "Reference" "C537"
			(at -1.12776 2.645664 90)
			(unlocked yes)
			(layer "F.SilkS")
			(effects
				(font
					(size 0.7874 0.5842)
					(thickness 0.1524)
				)
				(justify left)
			)
		)
		(property "Value" ""
			(at 0 0 90)
			(layer "F.Fab")
			(effects
				(font
					(size 1.27 1.27)
				)
			)
		)
		(duplicate_pad_numbers_are_jumpers no)
		(fp_line
			(start 0.7874 -0.4064)
			(end 0.7874 0.4064)
			(stroke
				(width 0.1524)
				(type default)
			)
			(layer "F.SilkS")
		)
		(fp_line
			(start -0.7874 -0.4064)
			(end 0.7874 -0.4064)
			(stroke
				(width 0.1524)
				(type default)
			)
			(layer "F.SilkS")
		)
		(fp_line
			(start 0 0.381)
			(end 0 -0.381)
			(stroke
				(width 0.1524)
				(type default)
			)
			(layer "F.SilkS")
		)
		(fp_line
			(start 0.7874 0.4064)
			(end -0.7874 0.4064)
			(stroke
				(width 0.1524)
				(type default)
			)
			(layer "F.SilkS")
		)
		(fp_line
			(start -0.7874 0.4064)
			(end -0.7874 -0.4064)
			(stroke
				(width 0.1524)
				(type default)
			)
			(layer "F.SilkS")
		)
		(fp_poly
			(pts
				(xy -0.5334 0.254) (xy -0.635 0.254) (xy -0.635 0.2286) (xy -0.635 -0.254) (xy -0.5334 -0.254) (xy -0.5334 -0.2794)
				(xy 0.5334 -0.2794) (xy 0.5334 -0.254) (xy 0.635 -0.254) (xy 0.635 0.254) (xy 0.5334 0.254) (xy 0.5334 0.2794)
				(xy -0.508 0.2794) (xy -0.5334 0.2794)
			)
			(stroke
				(width 0)
				(type default)
			)
			(fill no)
			(layer "F.CrtYd")
		)
		(pad "1" smd rect
			(at 0.40005 0 90)
			(size 0.4572 0.508)
			(layers "F.Cu" "F.Mask" "F.Paste")
			(net "P3V3_NODE1")
		)
		(pad "2" smd rect
			(at -0.40005 0 90)
			(size 0.4572 0.508)
			(layers "F.Cu" "F.Mask" "F.Paste")
			(net "GND")
		)
	)
	(footprint ""
		(layer "F.Cu")
		(at 142.478252 -26.320242 90)
		(property "Reference" "C483"
			(at -9.766808 3.98653 90)
			(unlocked yes)
			(layer "F.SilkS")
			(effects
				(font
					(size 0.7874 0.5842)
					(thickness 0.1524)
				)
			)
		)
		(property "Value" ""
			(at 0 0 90)
			(layer "F.Fab")
			(effects
				(font
					(size 1.27 1.27)
				)
			)
		)
		(duplicate_pad_numbers_are_jumpers no)
		(fp_line
			(start 1.2954 -0.5842)
			(end 1.2954 0.5842)
			(stroke
				(width 0.1524)
				(type default)
			)
			(layer "F.SilkS")
		)
		(fp_line
			(start 0 -0.5842)
			(end 0 0.5842)
			(stroke
				(width 0.1524)
				(type default)
			)
			(layer "F.SilkS")
		)
		(fp_line
			(start -1.2954 -0.5842)
			(end 1.2954 -0.5842)
			(stroke
				(width 0.1524)
				(type default)
			)
			(layer "F.SilkS")
		)
		(fp_line
			(start 1.2954 0.5842)
			(end -1.2954 0.5842)
			(stroke
				(width 0.1524)
				(type default)
			)
			(layer "F.SilkS")
		)
		(fp_line
			(start -1.2954 0.5842)
			(end -1.2954 -0.5842)
			(stroke
				(width 0.1524)
				(type default)
			)
			(layer "F.SilkS")
		)
		(fp_poly
			(pts
				(xy 0.8636 -0.4572) (xy 0.8636 -0.3556) (xy 1.143 -0.3556) (xy 1.143 0.3556) (xy 0.8636 0.3556)
				(xy 0.8636 0.4572) (xy -0.8636 0.4572) (xy -0.8636 0.3556) (xy -1.143 0.3556) (xy -1.143 -0.3556)
				(xy -0.8636 -0.3556) (xy -0.8636 -0.4572)
			)
			(stroke
				(width 0)
				(type default)
			)
			(fill no)
			(layer "F.CrtYd")
		)
		(fp_line
			(start 0.884936 -0.504952)
			(end 0.884936 0.504952)
			(stroke
				(width 0.1)
				(type default)
			)
			(layer "F.Fab")
		)
		(fp_line
			(start -0.884936 -0.504952)
			(end 0.884936 -0.504952)
			(stroke
				(width 0.1)
				(type default)
			)
			(layer "F.Fab")
		)
		(fp_line
			(start 0.884936 0.504952)
			(end -0.884936 0.504952)
			(stroke
				(width 0.1)
				(type default)
			)
			(layer "F.Fab")
		)
		(fp_line
			(start -0.884936 0.504952)
			(end -0.884936 -0.504952)
			(stroke
				(width 0.1)
				(type default)
			)
			(layer "F.Fab")
		)
		(pad "1" smd rect
			(at 0.7366 0 180)
			(size 0.7112 0.8128)
			(layers "F.Cu" "F.Mask" "F.Paste")
			(net "SIO_AVCC")
		)
		(pad "2" smd rect
			(at -0.7366 0 180)
			(size 0.7112 0.8128)
			(layers "F.Cu" "F.Mask" "F.Paste")
			(net "GNDA")
		)
	)
	(footprint ""
		(layer "F.Cu")
		(at 15.298166 -29.250132)
		(property "Reference" "C547"
			(at -1.003046 1.467104 0)
			(unlocked yes)
			(layer "F.SilkS")
			(effects
				(font
					(size 0.7874 0.5842)
					(thickness 0.1524)
				)
				(justify left)
			)
		)
		(property "Value" ""
			(at 0 0 0)
			(layer "F.Fab")
			(effects
				(font
					(size 1.27 1.27)
				)
			)
		)
		(duplicate_pad_numbers_are_jumpers no)
		(fp_line
			(start -0.7874 -0.4064)
			(end 0.7874 -0.4064)
			(stroke
				(width 0.1524)
				(type default)
			)
			(layer "F.SilkS")
		)
		(fp_line
			(start -0.7874 0.4064)
			(end -0.7874 -0.4064)
			(stroke
				(width 0.1524)
				(type default)
			)
			(layer "F.SilkS")
		)
		(fp_line
			(start 0 0.381)
			(end 0 -0.381)
			(stroke
				(width 0.1524)
				(type default)
			)
			(layer "F.SilkS")
		)
		(fp_line
			(start 0.7874 -0.4064)
			(end 0.7874 0.4064)
			(stroke
				(width 0.1524)
				(type default)
			)
			(layer "F.SilkS")
		)
		(fp_line
			(start 0.7874 0.4064)
			(end -0.7874 0.4064)
			(stroke
				(width 0.1524)
				(type default)
			)
			(layer "F.SilkS")
		)
		(fp_poly
			(pts
				(xy -0.5334 0.254) (xy -0.635 0.254) (xy -0.635 0.2286) (xy -0.635 -0.254) (xy -0.5334 -0.254) (xy -0.5334 -0.2794)
				(xy 0.5334 -0.2794) (xy 0.5334 -0.254) (xy 0.635 -0.254) (xy 0.635 0.254) (xy 0.5334 0.254) (xy 0.5334 0.2794)
				(xy -0.508 0.2794) (xy -0.5334 0.2794)
			)
			(stroke
				(width 0)
				(type default)
			)
			(fill no)
			(layer "F.CrtYd")
		)
		(pad "1" smd rect
			(at 0.40005 0)
			(size 0.4572 0.508)
			(layers "F.Cu" "F.Mask" "F.Paste")
			(net "N54251527")
		)
		(pad "2" smd rect
			(at -0.40005 0)
			(size 0.4572 0.508)
			(layers "F.Cu" "F.Mask" "F.Paste")
			(net "N54251529")
		)
	)
	(footprint ""
		(layer "F.Cu")
		(at 83.98256 -80.683608 -90)
		(property "Reference" "C90"
			(at 17.592294 -1.189482 90)
			(unlocked yes)
			(layer "F.SilkS")
			(effects
				(font
					(size 0.7874 0.5842)
					(thickness 0.1524)
				)
				(justify left)
			)
		)
		(property "Value" ""
			(at 0 0 270)
			(layer "F.Fab")
			(effects
				(font
					(size 1.27 1.27)
				)
			)
		)
		(duplicate_pad_numbers_are_jumpers no)
		(fp_line
			(start -0.7874 0.4064)
			(end -0.7874 -0.4064)
			(stroke
				(width 0.1524)
				(type default)
			)
			(layer "F.SilkS")
		)
		(fp_line
			(start 0.7874 0.4064)
			(end -0.7874 0.4064)
			(stroke
				(width 0.1524)
				(type default)
			)
			(layer "F.SilkS")
		)
		(fp_line
			(start 0 0.381)
			(end 0 -0.381)
			(stroke
				(width 0.1524)
				(type default)
			)
			(layer "F.SilkS")
		)
		(fp_line
			(start -0.7874 -0.4064)
			(end 0.7874 -0.4064)
			(stroke
				(width 0.1524)
				(type default)
			)
			(layer "F.SilkS")
		)
		(fp_line
			(start 0.7874 -0.4064)
			(end 0.7874 0.4064)
			(stroke
				(width 0.1524)
				(type default)
			)
			(layer "F.SilkS")
		)
		(fp_poly
			(pts
				(xy -0.5334 0.254) (xy -0.635 0.254) (xy -0.635 0.2286) (xy -0.635 -0.254) (xy -0.5334 -0.254) (xy -0.5334 -0.2794)
				(xy 0.5334 -0.2794) (xy 0.5334 -0.254) (xy 0.635 -0.254) (xy 0.635 0.254) (xy 0.5334 0.254) (xy 0.5334 0.2794)
				(xy -0.508 0.2794) (xy -0.5334 0.2794)
			)
			(stroke
				(width 0)
				(type default)
			)
			(fill no)
			(layer "F.CrtYd")
		)
		(pad "1" smd rect
			(at 0.40005 0 270)
			(size 0.4572 0.508)
			(layers "F.Cu" "F.Mask" "F.Paste")
			(net "PV_VCCP_NODE1")
		)
		(pad "2" smd rect
			(at -0.40005 0 270)
			(size 0.4572 0.508)
			(layers "F.Cu" "F.Mask" "F.Paste")
			(net "GND")
		)
	)
	(footprint ""
		(layer "F.Cu")
		(at 60.071508 -111.743744 180)
		(property "Reference" "PC18"
			(at 1.989582 -7.189978 0)
			(unlocked yes)
			(layer "F.SilkS")
			(effects
				(font
					(size 0.7874 0.5842)
					(thickness 0.1524)
				)
				(justify left)
			)
		)
		(property "Value" ""
			(at 0 0 180)
			(layer "F.Fab")
			(effects
				(font
					(size 1.27 1.27)
				)
			)
		)
		(duplicate_pad_numbers_are_jumpers no)
		(fp_line
			(start 0.7874 0.4064)
			(end -0.7874 0.4064)
			(stroke
				(width 0.1524)
				(type default)
			)
			(layer "F.SilkS")
		)
		(fp_line
			(start 0.7874 -0.4064)
			(end 0.7874 0.4064)
			(stroke
				(width 0.1524)
				(type default)
			)
			(layer "F.SilkS")
		)
		(fp_line
			(start 0 0.381)
			(end 0 -0.381)
			(stroke
				(width 0.1524)
				(type default)
			)
			(layer "F.SilkS")
		)
		(fp_line
			(start -0.7874 0.4064)
			(end -0.7874 -0.4064)
			(stroke
				(width 0.1524)
				(type default)
			)
			(layer "F.SilkS")
		)
		(fp_line
			(start -0.7874 -0.4064)
			(end 0.7874 -0.4064)
			(stroke
				(width 0.1524)
				(type default)
			)
			(layer "F.SilkS")
		)
		(fp_poly
			(pts
				(xy -0.5334 0.254) (xy -0.635 0.254) (xy -0.635 0.2286) (xy -0.635 -0.254) (xy -0.5334 -0.254) (xy -0.5334 -0.2794)
				(xy 0.5334 -0.2794) (xy 0.5334 -0.254) (xy 0.635 -0.254) (xy 0.635 0.254) (xy 0.5334 0.254) (xy 0.5334 0.2794)
				(xy -0.508 0.2794) (xy -0.5334 0.2794)
			)
			(stroke
				(width 0)
				(type default)
			)
			(fill no)
			(layer "F.CrtYd")
		)
		(pad "1" smd rect
			(at 0.40005 0 180)
			(size 0.4572 0.508)
			(layers "F.Cu" "F.Mask" "F.Paste")
			(net "P3V3_STB_NODE1")
		)
		(pad "2" smd rect
			(at -0.40005 0 180)
			(size 0.4572 0.508)
			(layers "F.Cu" "F.Mask" "F.Paste")
			(net "GND")
		)
	)
	(footprint ""
		(layer "F.Cu")
		(at 112.320578 -160.17748 90)
		(property "Reference" "R1283"
			(at 0.676148 1.209802 0)
			(unlocked yes)
			(layer "F.SilkS")
			(effects
				(font
					(size 0.635 0.4064)
					(thickness 0.1524)
				)
				(justify left)
			)
		)
		(property "Value" ""
			(at 0 0 90)
			(layer "F.Fab")
			(effects
				(font
					(size 1.27 1.27)
				)
			)
		)
		(duplicate_pad_numbers_are_jumpers no)
		(fp_line
			(start 0.7874 -0.4064)
			(end 0.7874 0.4064)
			(stroke
				(width 0.1524)
				(type default)
			)
			(layer "F.SilkS")
		)
		(fp_line
			(start -0.7874 -0.4064)
			(end 0.7874 -0.4064)
			(stroke
				(width 0.1524)
				(type default)
			)
			(layer "F.SilkS")
		)
		(fp_line
			(start 0.7874 0.4064)
			(end -0.7874 0.4064)
			(stroke
				(width 0.1524)
				(type default)
			)
			(layer "F.SilkS")
		)
		(fp_line
			(start -0.7874 0.4064)
			(end -0.7874 -0.4064)
			(stroke
				(width 0.1524)
				(type default)
			)
			(layer "F.SilkS")
		)
		(fp_poly
			(pts
				(xy -0.508 0.2794) (xy -0.508 0.2286) (xy -0.635 0.2286) (xy -0.635 -0.254) (xy -0.5334 -0.254)
				(xy -0.5334 -0.2794) (xy 0.5334 -0.2794) (xy 0.5334 -0.254) (xy 0.635 -0.254) (xy 0.635 0.254) (xy 0.5334 0.254)
				(xy 0.5334 0.2794)
			)
			(stroke
				(width 0)
				(type default)
			)
			(fill no)
			(layer "F.CrtYd")
		)
		(pad "1" smd rect
			(at 0.40005 0 90)
			(size 0.4572 0.508)
			(layers "F.Cu" "F.Mask" "F.Paste")
			(net "P5V_NODE1")
		)
		(pad "2" smd rect
			(at -0.40005 0 90)
			(size 0.4572 0.508)
			(layers "F.Cu" "F.Mask" "F.Paste")
			(net "PMBUS2_EN")
		)
	)
	(footprint ""
		(layer "F.Cu")
		(at 122.66676 -188.126624 90)
		(property "Reference" "C632"
			(at 4.912868 -0.284988 90)
			(unlocked yes)
			(layer "F.SilkS")
			(effects
				(font
					(size 0.7874 0.5842)
					(thickness 0.1524)
				)
				(justify left)
			)
		)
		(property "Value" ""
			(at 0 0 90)
			(layer "F.Fab")
			(effects
				(font
					(size 1.27 1.27)
				)
			)
		)
		(duplicate_pad_numbers_are_jumpers no)
		(fp_line
			(start 0.7874 -0.4064)
			(end 0.7874 0.4064)
			(stroke
				(width 0.1524)
				(type default)
			)
			(layer "F.SilkS")
		)
		(fp_line
			(start -0.7874 -0.4064)
			(end 0.7874 -0.4064)
			(stroke
				(width 0.1524)
				(type default)
			)
			(layer "F.SilkS")
		)
		(fp_line
			(start 0 0.381)
			(end 0 -0.381)
			(stroke
				(width 0.1524)
				(type default)
			)
			(layer "F.SilkS")
		)
		(fp_line
			(start 0.7874 0.4064)
			(end -0.7874 0.4064)
			(stroke
				(width 0.1524)
				(type default)
			)
			(layer "F.SilkS")
		)
		(fp_line
			(start -0.7874 0.4064)
			(end -0.7874 -0.4064)
			(stroke
				(width 0.1524)
				(type default)
			)
			(layer "F.SilkS")
		)
		(fp_poly
			(pts
				(xy -0.5334 0.254) (xy -0.635 0.254) (xy -0.635 0.2286) (xy -0.635 -0.254) (xy -0.5334 -0.254) (xy -0.5334 -0.2794)
				(xy 0.5334 -0.2794) (xy 0.5334 -0.254) (xy 0.635 -0.254) (xy 0.635 0.254) (xy 0.5334 0.254) (xy 0.5334 0.2794)
				(xy -0.508 0.2794) (xy -0.5334 0.2794)
			)
			(stroke
				(width 0)
				(type default)
			)
			(fill no)
			(layer "F.CrtYd")
		)
		(pad "1" smd rect
			(at 0.40005 0 90)
			(size 0.4572 0.508)
			(layers "F.Cu" "F.Mask" "F.Paste")
			(net "T8_NODE4_EN_R")
		)
		(pad "2" smd rect
			(at -0.40005 0 90)
			(size 0.4572 0.508)
			(layers "F.Cu" "F.Mask" "F.Paste")
			(net "GND")
		)
	)
	(footprint ""
		(layer "F.Cu")
		(at 81.39176 -185.205624 -90)
		(property "Reference" "R898"
			(at -4.198112 1.795272 90)
			(unlocked yes)
			(layer "F.SilkS")
			(effects
				(font
					(size 0.7874 0.5842)
					(thickness 0.1524)
				)
				(justify left)
			)
		)
		(property "Value" ""
			(at 0 0 270)
			(layer "F.Fab")
			(effects
				(font
					(size 1.27 1.27)
				)
			)
		)
		(duplicate_pad_numbers_are_jumpers no)
		(fp_line
			(start -0.7874 0.4064)
			(end -0.7874 -0.4064)
			(stroke
				(width 0.1524)
				(type default)
			)
			(layer "F.SilkS")
		)
		(fp_line
			(start 0.7874 0.4064)
			(end -0.7874 0.4064)
			(stroke
				(width 0.1524)
				(type default)
			)
			(layer "F.SilkS")
		)
		(fp_line
			(start -0.7874 -0.4064)
			(end 0.7874 -0.4064)
			(stroke
				(width 0.1524)
				(type default)
			)
			(layer "F.SilkS")
		)
		(fp_line
			(start 0.7874 -0.4064)
			(end 0.7874 0.4064)
			(stroke
				(width 0.1524)
				(type default)
			)
			(layer "F.SilkS")
		)
		(fp_poly
			(pts
				(xy -0.508 0.2794) (xy -0.508 0.2286) (xy -0.635 0.2286) (xy -0.635 -0.254) (xy -0.5334 -0.254)
				(xy -0.5334 -0.2794) (xy 0.5334 -0.2794) (xy 0.5334 -0.254) (xy 0.635 -0.254) (xy 0.635 0.254) (xy 0.5334 0.254)
				(xy 0.5334 0.2794)
			)
			(stroke
				(width 0)
				(type default)
			)
			(fill no)
			(layer "F.CrtYd")
		)
		(pad "1" smd rect
			(at 0.40005 0 270)
			(size 0.4572 0.508)
			(layers "F.Cu" "F.Mask" "F.Paste")
			(net "T4_NODE2_EN")
		)
		(pad "2" smd rect
			(at -0.40005 0 270)
			(size 0.4572 0.508)
			(layers "F.Cu" "F.Mask" "F.Paste")
			(net "T4_NODE2_EN_R")
		)
	)
	(footprint ""
		(layer "F.Cu")
		(at 176.666398 -37.991034)
		(property "Reference" "C557"
			(at -4.146042 0.705612 0)
			(unlocked yes)
			(layer "F.SilkS")
			(effects
				(font
					(size 0.7874 0.5842)
					(thickness 0.1524)
				)
				(justify left)
			)
		)
		(property "Value" ""
			(at 0 0 0)
			(layer "F.Fab")
			(effects
				(font
					(size 1.27 1.27)
				)
			)
		)
		(duplicate_pad_numbers_are_jumpers no)
		(fp_line
			(start -0.7874 -0.4064)
			(end 0.7874 -0.4064)
			(stroke
				(width 0.1524)
				(type default)
			)
			(layer "F.SilkS")
		)
		(fp_line
			(start -0.7874 0.4064)
			(end -0.7874 -0.4064)
			(stroke
				(width 0.1524)
				(type default)
			)
			(layer "F.SilkS")
		)
		(fp_line
			(start 0 0.381)
			(end 0 -0.381)
			(stroke
				(width 0.1524)
				(type default)
			)
			(layer "F.SilkS")
		)
		(fp_line
			(start 0.7874 -0.4064)
			(end 0.7874 0.4064)
			(stroke
				(width 0.1524)
				(type default)
			)
			(layer "F.SilkS")
		)
		(fp_line
			(start 0.7874 0.4064)
			(end -0.7874 0.4064)
			(stroke
				(width 0.1524)
				(type default)
			)
			(layer "F.SilkS")
		)
		(fp_poly
			(pts
				(xy -0.5334 0.254) (xy -0.635 0.254) (xy -0.635 0.2286) (xy -0.635 -0.254) (xy -0.5334 -0.254) (xy -0.5334 -0.2794)
				(xy 0.5334 -0.2794) (xy 0.5334 -0.254) (xy 0.635 -0.254) (xy 0.635 0.254) (xy 0.5334 0.254) (xy 0.5334 0.2794)
				(xy -0.508 0.2794) (xy -0.5334 0.2794)
			)
			(stroke
				(width 0)
				(type default)
			)
			(fill no)
			(layer "F.CrtYd")
		)
		(pad "1" smd rect
			(at 0.40005 0)
			(size 0.4572 0.508)
			(layers "F.Cu" "F.Mask" "F.Paste")
			(net "USBPWR_P0")
		)
		(pad "2" smd rect
			(at -0.40005 0)
			(size 0.4572 0.508)
			(layers "F.Cu" "F.Mask" "F.Paste")
			(net "GND")
		)
	)
	(footprint ""
		(layer "F.Cu")
		(at 171.852336 -131.92125 180)
		(property "Reference" "R93"
			(at 1.965452 8.565896 0)
			(unlocked yes)
			(layer "F.SilkS")
			(effects
				(font
					(size 0.7874 0.5842)
					(thickness 0.1524)
				)
				(justify left)
			)
		)
		(property "Value" ""
			(at 0 0 180)
			(layer "F.Fab")
			(effects
				(font
					(size 1.27 1.27)
				)
			)
		)
		(duplicate_pad_numbers_are_jumpers no)
		(fp_line
			(start 0.7874 0.4064)
			(end -0.7874 0.4064)
			(stroke
				(width 0.1524)
				(type default)
			)
			(layer "F.SilkS")
		)
		(fp_line
			(start 0.7874 -0.4064)
			(end 0.7874 0.4064)
			(stroke
				(width 0.1524)
				(type default)
			)
			(layer "F.SilkS")
		)
		(fp_line
			(start -0.7874 0.4064)
			(end -0.7874 -0.4064)
			(stroke
				(width 0.1524)
				(type default)
			)
			(layer "F.SilkS")
		)
		(fp_line
			(start -0.7874 -0.4064)
			(end 0.7874 -0.4064)
			(stroke
				(width 0.1524)
				(type default)
			)
			(layer "F.SilkS")
		)
		(fp_poly
			(pts
				(xy -0.508 0.2794) (xy -0.508 0.2286) (xy -0.635 0.2286) (xy -0.635 -0.254) (xy -0.5334 -0.254)
				(xy -0.5334 -0.2794) (xy 0.5334 -0.2794) (xy 0.5334 -0.254) (xy 0.635 -0.254) (xy 0.635 0.254) (xy 0.5334 0.254)
				(xy 0.5334 0.2794)
			)
			(stroke
				(width 0)
				(type default)
			)
			(fill no)
			(layer "F.CrtYd")
		)
		(pad "1" smd rect
			(at 0.40005 0 180)
			(size 0.4572 0.508)
			(layers "F.Cu" "F.Mask" "F.Paste")
			(net "H_CPU_NODE1_THRMTRIP_L")
		)
		(pad "2" smd rect
			(at -0.40005 0 180)
			(size 0.4572 0.508)
			(layers "F.Cu" "F.Mask" "F.Paste")
			(net "N41777073")
		)
	)
	(footprint ""
		(layer "F.Cu")
		(at 149.508972 -33.586928 180)
		(property "Reference" "R650"
			(at 1.179576 3.705352 0)
			(unlocked yes)
			(layer "F.SilkS")
			(effects
				(font
					(size 0.7874 0.5842)
					(thickness 0.1524)
				)
				(justify left)
			)
		)
		(property "Value" ""
			(at 0 0 180)
			(layer "F.Fab")
			(effects
				(font
					(size 1.27 1.27)
				)
			)
		)
		(duplicate_pad_numbers_are_jumpers no)
		(fp_line
			(start 0.7874 0.4064)
			(end -0.7874 0.4064)
			(stroke
				(width 0.1524)
				(type default)
			)
			(layer "F.SilkS")
		)
		(fp_line
			(start 0.7874 -0.4064)
			(end 0.7874 0.4064)
			(stroke
				(width 0.1524)
				(type default)
			)
			(layer "F.SilkS")
		)
		(fp_line
			(start -0.7874 0.4064)
			(end -0.7874 -0.4064)
			(stroke
				(width 0.1524)
				(type default)
			)
			(layer "F.SilkS")
		)
		(fp_line
			(start -0.7874 -0.4064)
			(end 0.7874 -0.4064)
			(stroke
				(width 0.1524)
				(type default)
			)
			(layer "F.SilkS")
		)
		(fp_poly
			(pts
				(xy -0.508 0.2794) (xy -0.508 0.2286) (xy -0.635 0.2286) (xy -0.635 -0.254) (xy -0.5334 -0.254)
				(xy -0.5334 -0.2794) (xy 0.5334 -0.2794) (xy 0.5334 -0.254) (xy 0.635 -0.254) (xy 0.635 0.254) (xy 0.5334 0.254)
				(xy 0.5334 0.2794)
			)
			(stroke
				(width 0)
				(type default)
			)
			(fill no)
			(layer "F.CrtYd")
		)
		(pad "1" smd rect
			(at 0.40005 0 180)
			(size 0.4572 0.508)
			(layers "F.Cu" "F.Mask" "F.Paste")
			(net "P3V3_NODE1")
		)
		(pad "2" smd rect
			(at -0.40005 0 180)
			(size 0.4572 0.508)
			(layers "F.Cu" "F.Mask" "F.Paste")
			(net "N21624806")
		)
	)
	(footprint ""
		(layer "F.Cu")
		(at 184.3786 -179.7812)
		(property "Reference" "R1318"
			(at 9.3218 17.19707 0)
			(unlocked yes)
			(layer "F.SilkS")
			(effects
				(font
					(size 0.7874 0.5842)
					(thickness 0.1524)
				)
				(justify left)
			)
		)
		(property "Value" ""
			(at 0 0 0)
			(layer "F.Fab")
			(effects
				(font
					(size 1.27 1.27)
				)
			)
		)
		(duplicate_pad_numbers_are_jumpers no)
		(fp_line
			(start -0.7874 -0.4064)
			(end 0.7874 -0.4064)
			(stroke
				(width 0.1524)
				(type default)
			)
			(layer "F.SilkS")
		)
		(fp_line
			(start -0.7874 0.4064)
			(end -0.7874 -0.4064)
			(stroke
				(width 0.1524)
				(type default)
			)
			(layer "F.SilkS")
		)
		(fp_line
			(start 0.7874 -0.4064)
			(end 0.7874 0.4064)
			(stroke
				(width 0.1524)
				(type default)
			)
			(layer "F.SilkS")
		)
		(fp_line
			(start 0.7874 0.4064)
			(end -0.7874 0.4064)
			(stroke
				(width 0.1524)
				(type default)
			)
			(layer "F.SilkS")
		)
		(fp_poly
			(pts
				(xy -0.508 0.2794) (xy -0.508 0.2286) (xy -0.635 0.2286) (xy -0.635 -0.254) (xy -0.5334 -0.254)
				(xy -0.5334 -0.2794) (xy 0.5334 -0.2794) (xy 0.5334 -0.254) (xy 0.635 -0.254) (xy 0.635 0.254) (xy 0.5334 0.254)
				(xy 0.5334 0.2794)
			)
			(stroke
				(width 0)
				(type default)
			)
			(fill no)
			(layer "F.CrtYd")
		)
		(pad "1" smd rect
			(at 0.40005 0)
			(size 0.4572 0.508)
			(layers "F.Cu" "F.Mask" "F.Paste")
			(net "POWER_SW3_PWR_CTR_12V")
		)
		(pad "2" smd rect
			(at -0.40005 0)
			(size 0.4572 0.508)
			(layers "F.Cu" "F.Mask" "F.Paste")
			(net "POWER_SW3_PWR_CTR_12V_R")
		)
	)
	(footprint ""
		(layer "F.Cu")
		(at 108.390944 -162.73272 180)
		(property "Reference" "R646"
			(at -86.581996 -70.245732 0)
			(unlocked yes)
			(layer "F.SilkS")
			(effects
				(font
					(size 0.7874 0.5842)
					(thickness 0.1524)
				)
				(justify left)
			)
		)
		(property "Value" ""
			(at 0 0 180)
			(layer "F.Fab")
			(effects
				(font
					(size 1.27 1.27)
				)
			)
		)
		(duplicate_pad_numbers_are_jumpers no)
		(fp_line
			(start 0.7874 0.4064)
			(end -0.7874 0.4064)
			(stroke
				(width 0.1524)
				(type default)
			)
			(layer "F.SilkS")
		)
		(fp_line
			(start 0.7874 -0.4064)
			(end 0.7874 0.4064)
			(stroke
				(width 0.1524)
				(type default)
			)
			(layer "F.SilkS")
		)
		(fp_line
			(start -0.7874 0.4064)
			(end -0.7874 -0.4064)
			(stroke
				(width 0.1524)
				(type default)
			)
			(layer "F.SilkS")
		)
		(fp_line
			(start -0.7874 -0.4064)
			(end 0.7874 -0.4064)
			(stroke
				(width 0.1524)
				(type default)
			)
			(layer "F.SilkS")
		)
		(fp_poly
			(pts
				(xy -0.508 0.2794) (xy -0.508 0.2286) (xy -0.635 0.2286) (xy -0.635 -0.254) (xy -0.5334 -0.254)
				(xy -0.5334 -0.2794) (xy 0.5334 -0.2794) (xy 0.5334 -0.254) (xy 0.635 -0.254) (xy 0.635 0.254) (xy 0.5334 0.254)
				(xy 0.5334 0.2794)
			)
			(stroke
				(width 0)
				(type default)
			)
			(fill no)
			(layer "F.CrtYd")
		)
		(pad "1" smd rect
			(at 0.40005 0 180)
			(size 0.4572 0.508)
			(layers "F.Cu" "F.Mask" "F.Paste")
			(net "I2C_PSU2_SCL")
		)
		(pad "2" smd rect
			(at -0.40005 0 180)
			(size 0.4572 0.508)
			(layers "F.Cu" "F.Mask" "F.Paste")
			(net "I2C_PSU2_SCL_MOS")
		)
	)
	(footprint ""
		(layer "F.Cu")
		(at 190.173102 -28.98775 90)
		(property "Reference" "FS3"
			(at -0.15367 1.844802 90)
			(unlocked yes)
			(layer "F.SilkS")
			(effects
				(font
					(size 0.7874 0.5842)
					(thickness 0.1524)
				)
				(justify left)
			)
		)
		(property "Value" ""
			(at 0 0 90)
			(layer "F.Fab")
			(effects
				(font
					(size 1.27 1.27)
				)
			)
		)
		(duplicate_pad_numbers_are_jumpers no)
		(fp_line
			(start 3.550412 -1.050036)
			(end 3.550412 1.050036)
			(stroke
				(width 0.1524)
				(type default)
			)
			(layer "F.SilkS")
		)
		(fp_line
			(start -0.650494 -1.050036)
			(end 3.550412 -1.050036)
			(stroke
				(width 0.1524)
				(type default)
			)
			(layer "F.SilkS")
		)
		(fp_line
			(start 3.550412 1.050036)
			(end -0.650494 1.050036)
			(stroke
				(width 0.1524)
				(type default)
			)
			(layer "F.SilkS")
		)
		(fp_line
			(start -0.650494 1.050036)
			(end -0.650494 -1.050036)
			(stroke
				(width 0.1524)
				(type default)
			)
			(layer "F.SilkS")
		)
		(fp_poly
			(pts
				(xy 3.228086 -0.9652) (xy 3.228086 -1.100074) (xy -0.327914 -1.100074) (xy -0.327914 -0.9652) (xy -0.556514 -0.9652)
				(xy -0.556514 0.9652) (xy -0.327914 0.9652) (xy -0.327914 1.100074) (xy 3.228086 1.100074) (xy 3.228086 0.9652)
				(xy 3.456686 0.9652) (xy 3.456686 -0.9652)
			)
			(stroke
				(width 0)
				(type default)
			)
			(fill no)
			(layer "F.CrtYd")
		)
		(fp_text user "1"
			(at -1.177036 -0.36449 90)
			(unlocked yes)
			(layer "F.SilkS")
			(effects
				(font
					(size 0.635 0.4064)
					(thickness 0.1524)
				)
				(justify left)
			)
		)
		(fp_text user "2"
			(at 3.635248 2.086864 0)
			(unlocked yes)
			(layer "F.SilkS")
			(effects
				(font
					(size 0.635 0.4064)
					(thickness 0.1524)
				)
				(justify left)
			)
		)
		(pad "1" smd rect
			(at 0 0 90)
			(size 1.016 1.8034)
			(layers "F.Cu" "F.Mask" "F.Paste")
			(net "P5V_NODE1")
		)
		(pad "2" smd rect
			(at 2.899918 0 90)
			(size 1.016 1.8034)
			(layers "F.Cu" "F.Mask" "F.Paste")
			(net "USBPWR_P0")
		)
	)
	(footprint ""
		(layer "F.Cu")
		(at 19.72564 -131.344416 180)
		(property "Reference" "PR26"
			(at -1.49352 0.232156 0)
			(unlocked yes)
			(layer "F.SilkS")
			(effects
				(font
					(size 0.7874 0.5842)
					(thickness 0.1524)
				)
				(justify left)
			)
		)
		(property "Value" ""
			(at 0 0 180)
			(layer "F.Fab")
			(effects
				(font
					(size 1.27 1.27)
				)
			)
		)
		(duplicate_pad_numbers_are_jumpers no)
		(fp_line
			(start 0.7874 0.4064)
			(end -0.7874 0.4064)
			(stroke
				(width 0.1524)
				(type default)
			)
			(layer "F.SilkS")
		)
		(fp_line
			(start 0.7874 -0.4064)
			(end 0.7874 0.4064)
			(stroke
				(width 0.1524)
				(type default)
			)
			(layer "F.SilkS")
		)
		(fp_line
			(start -0.7874 0.4064)
			(end -0.7874 -0.4064)
			(stroke
				(width 0.1524)
				(type default)
			)
			(layer "F.SilkS")
		)
		(fp_line
			(start -0.7874 -0.4064)
			(end 0.7874 -0.4064)
			(stroke
				(width 0.1524)
				(type default)
			)
			(layer "F.SilkS")
		)
		(fp_poly
			(pts
				(xy -0.508 0.2794) (xy -0.508 0.2286) (xy -0.635 0.2286) (xy -0.635 -0.254) (xy -0.5334 -0.254)
				(xy -0.5334 -0.2794) (xy 0.5334 -0.2794) (xy 0.5334 -0.254) (xy 0.635 -0.254) (xy 0.635 0.254) (xy 0.5334 0.254)
				(xy 0.5334 0.2794)
			)
			(stroke
				(width 0)
				(type default)
			)
			(fill no)
			(layer "F.CrtYd")
		)
		(pad "1" smd rect
			(at 0.40005 0 180)
			(size 0.4572 0.508)
			(layers "F.Cu" "F.Mask" "F.Paste")
			(net "P1V05_NODE1_MODE")
		)
		(pad "2" smd rect
			(at -0.40005 0 180)
			(size 0.4572 0.508)
			(layers "F.Cu" "F.Mask" "F.Paste")
			(net "GND")
		)
	)
	(footprint ""
		(layer "F.Cu")
		(at 185.817764 -115.367562 90)
		(property "Reference" "R1027"
			(at -4.22275 -0.987806 0)
			(unlocked yes)
			(layer "F.SilkS")
			(effects
				(font
					(size 0.7874 0.5842)
					(thickness 0.1524)
				)
				(justify left)
			)
		)
		(property "Value" ""
			(at 0 0 90)
			(layer "F.Fab")
			(effects
				(font
					(size 1.27 1.27)
				)
			)
		)
		(duplicate_pad_numbers_are_jumpers no)
		(fp_line
			(start 0.7874 -0.4064)
			(end 0.7874 0.4064)
			(stroke
				(width 0.1524)
				(type default)
			)
			(layer "F.SilkS")
		)
		(fp_line
			(start -0.7874 -0.4064)
			(end 0.7874 -0.4064)
			(stroke
				(width 0.1524)
				(type default)
			)
			(layer "F.SilkS")
		)
		(fp_line
			(start 0.7874 0.4064)
			(end -0.7874 0.4064)
			(stroke
				(width 0.1524)
				(type default)
			)
			(layer "F.SilkS")
		)
		(fp_line
			(start -0.7874 0.4064)
			(end -0.7874 -0.4064)
			(stroke
				(width 0.1524)
				(type default)
			)
			(layer "F.SilkS")
		)
		(fp_poly
			(pts
				(xy -0.508 0.2794) (xy -0.508 0.2286) (xy -0.635 0.2286) (xy -0.635 -0.254) (xy -0.5334 -0.254)
				(xy -0.5334 -0.2794) (xy 0.5334 -0.2794) (xy 0.5334 -0.254) (xy 0.635 -0.254) (xy 0.635 0.254) (xy 0.5334 0.254)
				(xy 0.5334 0.2794)
			)
			(stroke
				(width 0)
				(type default)
			)
			(fill no)
			(layer "F.CrtYd")
		)
		(pad "1" smd rect
			(at 0.40005 0 90)
			(size 0.4572 0.508)
			(layers "F.Cu" "F.Mask" "F.Paste")
			(net "PWRGD_NODE1_P12V_PG")
		)
		(pad "2" smd rect
			(at -0.40005 0 90)
			(size 0.4572 0.508)
			(layers "F.Cu" "F.Mask" "F.Paste")
			(net "PWRGD_NODE1_P12V_PG_R")
		)
	)
	(footprint ""
		(layer "F.Cu")
		(at 160.054798 -161.370518 90)
		(property "Reference" "R574"
			(at -8.066278 17.651476 90)
			(unlocked yes)
			(layer "F.SilkS")
			(effects
				(font
					(size 0.7874 0.5842)
					(thickness 0.1524)
				)
				(justify left)
			)
		)
		(property "Value" ""
			(at 0 0 90)
			(layer "F.Fab")
			(effects
				(font
					(size 1.27 1.27)
				)
			)
		)
		(duplicate_pad_numbers_are_jumpers no)
		(fp_line
			(start 0.7874 -0.4064)
			(end 0.7874 0.4064)
			(stroke
				(width 0.1524)
				(type default)
			)
			(layer "F.SilkS")
		)
		(fp_line
			(start -0.7874 -0.4064)
			(end 0.7874 -0.4064)
			(stroke
				(width 0.1524)
				(type default)
			)
			(layer "F.SilkS")
		)
		(fp_line
			(start 0.7874 0.4064)
			(end -0.7874 0.4064)
			(stroke
				(width 0.1524)
				(type default)
			)
			(layer "F.SilkS")
		)
		(fp_line
			(start -0.7874 0.4064)
			(end -0.7874 -0.4064)
			(stroke
				(width 0.1524)
				(type default)
			)
			(layer "F.SilkS")
		)
		(fp_poly
			(pts
				(xy -0.508 0.2794) (xy -0.508 0.2286) (xy -0.635 0.2286) (xy -0.635 -0.254) (xy -0.5334 -0.254)
				(xy -0.5334 -0.2794) (xy 0.5334 -0.2794) (xy 0.5334 -0.254) (xy 0.635 -0.254) (xy 0.635 0.254) (xy 0.5334 0.254)
				(xy 0.5334 0.2794)
			)
			(stroke
				(width 0)
				(type default)
			)
			(fill no)
			(layer "F.CrtYd")
		)
		(pad "1" smd rect
			(at 0.40005 0 90)
			(size 0.4572 0.508)
			(layers "F.Cu" "F.Mask" "F.Paste")
			(net "P3V3_NODE1")
		)
		(pad "2" smd rect
			(at -0.40005 0 90)
			(size 0.4572 0.508)
			(layers "F.Cu" "F.Mask" "F.Paste")
			(net "LAN2_NC_SI_TDX0")
		)
	)
	(footprint ""
		(layer "F.Cu")
		(at 63.832486 -121.044462 -90)
		(property "Reference" "R327"
			(at 6.142736 -8.268716 90)
			(unlocked yes)
			(layer "F.SilkS")
			(effects
				(font
					(size 0.7874 0.5842)
					(thickness 0.1524)
				)
				(justify left)
			)
		)
		(property "Value" ""
			(at 0 0 270)
			(layer "F.Fab")
			(effects
				(font
					(size 1.27 1.27)
				)
			)
		)
		(duplicate_pad_numbers_are_jumpers no)
		(fp_line
			(start -0.7874 0.4064)
			(end -0.7874 -0.4064)
			(stroke
				(width 0.1524)
				(type default)
			)
			(layer "F.SilkS")
		)
		(fp_line
			(start 0.7874 0.4064)
			(end -0.7874 0.4064)
			(stroke
				(width 0.1524)
				(type default)
			)
			(layer "F.SilkS")
		)
		(fp_line
			(start -0.7874 -0.4064)
			(end 0.7874 -0.4064)
			(stroke
				(width 0.1524)
				(type default)
			)
			(layer "F.SilkS")
		)
		(fp_line
			(start 0.7874 -0.4064)
			(end 0.7874 0.4064)
			(stroke
				(width 0.1524)
				(type default)
			)
			(layer "F.SilkS")
		)
		(fp_poly
			(pts
				(xy -0.508 0.2794) (xy -0.508 0.2286) (xy -0.635 0.2286) (xy -0.635 -0.254) (xy -0.5334 -0.254)
				(xy -0.5334 -0.2794) (xy 0.5334 -0.2794) (xy 0.5334 -0.254) (xy 0.635 -0.254) (xy 0.635 0.254) (xy 0.5334 0.254)
				(xy 0.5334 0.2794)
			)
			(stroke
				(width 0)
				(type default)
			)
			(fill no)
			(layer "F.CrtYd")
		)
		(pad "1" smd rect
			(at 0.40005 0 270)
			(size 0.4572 0.508)
			(layers "F.Cu" "F.Mask" "F.Paste")
			(net "P3V3_NODE1")
		)
		(pad "2" smd rect
			(at -0.40005 0 270)
			(size 0.4572 0.508)
			(layers "F.Cu" "F.Mask" "F.Paste")
			(net "BMC_ROMA11")
		)
	)
	(footprint ""
		(layer "F.Cu")
		(at 171.685458 -12.474194 90)
		(property "Reference" "R1200"
			(at -0.981202 2.072132 90)
			(unlocked yes)
			(layer "F.SilkS")
			(effects
				(font
					(size 0.7874 0.5842)
					(thickness 0.1524)
				)
				(justify left)
			)
		)
		(property "Value" ""
			(at 0 0 90)
			(layer "F.Fab")
			(effects
				(font
					(size 1.27 1.27)
				)
			)
		)
		(duplicate_pad_numbers_are_jumpers no)
		(fp_line
			(start 0.7874 -0.4064)
			(end 0.7874 0.4064)
			(stroke
				(width 0.1524)
				(type default)
			)
			(layer "F.SilkS")
		)
		(fp_line
			(start -0.7874 -0.4064)
			(end 0.7874 -0.4064)
			(stroke
				(width 0.1524)
				(type default)
			)
			(layer "F.SilkS")
		)
		(fp_line
			(start 0.7874 0.4064)
			(end -0.7874 0.4064)
			(stroke
				(width 0.1524)
				(type default)
			)
			(layer "F.SilkS")
		)
		(fp_line
			(start -0.7874 0.4064)
			(end -0.7874 -0.4064)
			(stroke
				(width 0.1524)
				(type default)
			)
			(layer "F.SilkS")
		)
		(fp_poly
			(pts
				(xy -0.508 0.2794) (xy -0.508 0.2286) (xy -0.635 0.2286) (xy -0.635 -0.254) (xy -0.5334 -0.254)
				(xy -0.5334 -0.2794) (xy 0.5334 -0.2794) (xy 0.5334 -0.254) (xy 0.635 -0.254) (xy 0.635 0.254) (xy 0.5334 0.254)
				(xy 0.5334 0.2794)
			)
			(stroke
				(width 0)
				(type default)
			)
			(fill no)
			(layer "F.CrtYd")
		)
		(pad "1" smd rect
			(at 0.40005 0 90)
			(size 0.4572 0.508)
			(layers "F.Cu" "F.Mask" "F.Paste")
			(net "SIO_JTAG_CPLD3_TCK")
		)
		(pad "2" smd rect
			(at -0.40005 0 90)
			(size 0.4572 0.508)
			(layers "F.Cu" "F.Mask" "F.Paste")
			(net "JTAG_CPLD3_TCK")
		)
	)
	(footprint ""
		(layer "F.Cu")
		(at 82.563462 -153.762456 180)
		(property "Reference" "PR4"
			(at -1.147318 -0.315468 0)
			(unlocked yes)
			(layer "F.SilkS")
			(effects
				(font
					(size 0.7874 0.5842)
					(thickness 0.1524)
				)
				(justify left)
			)
		)
		(property "Value" ""
			(at 0 0 180)
			(layer "F.Fab")
			(effects
				(font
					(size 1.27 1.27)
				)
			)
		)
		(duplicate_pad_numbers_are_jumpers no)
		(fp_line
			(start 0.7874 0.4064)
			(end -0.7874 0.4064)
			(stroke
				(width 0.1524)
				(type default)
			)
			(layer "F.SilkS")
		)
		(fp_line
			(start 0.7874 -0.4064)
			(end 0.7874 0.4064)
			(stroke
				(width 0.1524)
				(type default)
			)
			(layer "F.SilkS")
		)
		(fp_line
			(start -0.7874 0.4064)
			(end -0.7874 -0.4064)
			(stroke
				(width 0.1524)
				(type default)
			)
			(layer "F.SilkS")
		)
		(fp_line
			(start -0.7874 -0.4064)
			(end 0.7874 -0.4064)
			(stroke
				(width 0.1524)
				(type default)
			)
			(layer "F.SilkS")
		)
		(fp_poly
			(pts
				(xy -0.508 0.2794) (xy -0.508 0.2286) (xy -0.635 0.2286) (xy -0.635 -0.254) (xy -0.5334 -0.254)
				(xy -0.5334 -0.2794) (xy 0.5334 -0.2794) (xy 0.5334 -0.254) (xy 0.635 -0.254) (xy 0.635 0.254) (xy 0.5334 0.254)
				(xy 0.5334 0.2794)
			)
			(stroke
				(width 0)
				(type default)
			)
			(fill no)
			(layer "F.CrtYd")
		)
		(pad "1" smd rect
			(at 0.40005 0 180)
			(size 0.4572 0.508)
			(layers "F.Cu" "F.Mask" "F.Paste")
			(net "P5V_STB_NODE1_FB")
		)
		(pad "2" smd rect
			(at -0.40005 0 180)
			(size 0.4572 0.508)
			(layers "F.Cu" "F.Mask" "F.Paste")
			(net "GND")
		)
	)
	(footprint ""
		(layer "F.Cu")
		(at 184.7596 -176.4792 180)
		(property "Reference" "R1314"
			(at -9.9568 -17.45107 0)
			(unlocked yes)
			(layer "F.SilkS")
			(effects
				(font
					(size 0.7874 0.5842)
					(thickness 0.1524)
				)
				(justify left)
			)
		)
		(property "Value" ""
			(at 0 0 180)
			(layer "F.Fab")
			(effects
				(font
					(size 1.27 1.27)
				)
			)
		)
		(duplicate_pad_numbers_are_jumpers no)
		(fp_line
			(start 0.7874 0.4064)
			(end -0.7874 0.4064)
			(stroke
				(width 0.1524)
				(type default)
			)
			(layer "F.SilkS")
		)
		(fp_line
			(start 0.7874 -0.4064)
			(end 0.7874 0.4064)
			(stroke
				(width 0.1524)
				(type default)
			)
			(layer "F.SilkS")
		)
		(fp_line
			(start -0.7874 0.4064)
			(end -0.7874 -0.4064)
			(stroke
				(width 0.1524)
				(type default)
			)
			(layer "F.SilkS")
		)
		(fp_line
			(start -0.7874 -0.4064)
			(end 0.7874 -0.4064)
			(stroke
				(width 0.1524)
				(type default)
			)
			(layer "F.SilkS")
		)
		(fp_poly
			(pts
				(xy -0.508 0.2794) (xy -0.508 0.2286) (xy -0.635 0.2286) (xy -0.635 -0.254) (xy -0.5334 -0.254)
				(xy -0.5334 -0.2794) (xy 0.5334 -0.2794) (xy 0.5334 -0.254) (xy 0.635 -0.254) (xy 0.635 0.254) (xy 0.5334 0.254)
				(xy 0.5334 0.2794)
			)
			(stroke
				(width 0)
				(type default)
			)
			(fill no)
			(layer "F.CrtYd")
		)
		(pad "1" smd rect
			(at 0.40005 0 180)
			(size 0.4572 0.508)
			(layers "F.Cu" "F.Mask" "F.Paste")
			(net "POWER_SW2_PWR_CTR_12V")
		)
		(pad "2" smd rect
			(at -0.40005 0 180)
			(size 0.4572 0.508)
			(layers "F.Cu" "F.Mask" "F.Paste")
			(net "POWER_SW2_PWR_CTR_12V_R")
		)
	)
	(footprint ""
		(layer "F.Cu")
		(at 142.22476 -188.126624 90)
		(property "Reference" "C765"
			(at 5.519674 -0.636016 90)
			(unlocked yes)
			(layer "F.SilkS")
			(effects
				(font
					(size 0.7874 0.5842)
					(thickness 0.1524)
				)
				(justify left)
			)
		)
		(property "Value" ""
			(at 0 0 90)
			(layer "F.Fab")
			(effects
				(font
					(size 1.27 1.27)
				)
			)
		)
		(duplicate_pad_numbers_are_jumpers no)
		(fp_line
			(start 0.7874 -0.4064)
			(end 0.7874 0.4064)
			(stroke
				(width 0.1524)
				(type default)
			)
			(layer "F.SilkS")
		)
		(fp_line
			(start -0.7874 -0.4064)
			(end 0.7874 -0.4064)
			(stroke
				(width 0.1524)
				(type default)
			)
			(layer "F.SilkS")
		)
		(fp_line
			(start 0 0.381)
			(end 0 -0.381)
			(stroke
				(width 0.1524)
				(type default)
			)
			(layer "F.SilkS")
		)
		(fp_line
			(start 0.7874 0.4064)
			(end -0.7874 0.4064)
			(stroke
				(width 0.1524)
				(type default)
			)
			(layer "F.SilkS")
		)
		(fp_line
			(start -0.7874 0.4064)
			(end -0.7874 -0.4064)
			(stroke
				(width 0.1524)
				(type default)
			)
			(layer "F.SilkS")
		)
		(fp_poly
			(pts
				(xy -0.5334 0.254) (xy -0.635 0.254) (xy -0.635 0.2286) (xy -0.635 -0.254) (xy -0.5334 -0.254) (xy -0.5334 -0.2794)
				(xy 0.5334 -0.2794) (xy 0.5334 -0.254) (xy 0.635 -0.254) (xy 0.635 0.254) (xy 0.5334 0.254) (xy 0.5334 0.2794)
				(xy -0.508 0.2794) (xy -0.5334 0.2794)
			)
			(stroke
				(width 0)
				(type default)
			)
			(fill no)
			(layer "F.CrtYd")
		)
		(pad "1" smd rect
			(at 0.40005 0 90)
			(size 0.4572 0.508)
			(layers "F.Cu" "F.Mask" "F.Paste")
			(net "UART_T12_NODE4_TXD_R")
		)
		(pad "2" smd rect
			(at -0.40005 0 90)
			(size 0.4572 0.508)
			(layers "F.Cu" "F.Mask" "F.Paste")
			(net "GND")
		)
	)
	(footprint ""
		(layer "F.Cu")
		(at 10.566146 -11.613896 -90)
		(property "Reference" "R216"
			(at 0.984758 4.681982 90)
			(unlocked yes)
			(layer "F.SilkS")
			(effects
				(font
					(size 0.7874 0.5842)
					(thickness 0.1524)
				)
				(justify left)
			)
		)
		(property "Value" ""
			(at 0 0 270)
			(layer "F.Fab")
			(effects
				(font
					(size 1.27 1.27)
				)
			)
		)
		(duplicate_pad_numbers_are_jumpers no)
		(fp_line
			(start -0.7874 0.4064)
			(end -0.7874 -0.4064)
			(stroke
				(width 0.1524)
				(type default)
			)
			(layer "F.SilkS")
		)
		(fp_line
			(start 0.7874 0.4064)
			(end -0.7874 0.4064)
			(stroke
				(width 0.1524)
				(type default)
			)
			(layer "F.SilkS")
		)
		(fp_line
			(start -0.7874 -0.4064)
			(end 0.7874 -0.4064)
			(stroke
				(width 0.1524)
				(type default)
			)
			(layer "F.SilkS")
		)
		(fp_line
			(start 0.7874 -0.4064)
			(end 0.7874 0.4064)
			(stroke
				(width 0.1524)
				(type default)
			)
			(layer "F.SilkS")
		)
		(fp_poly
			(pts
				(xy -0.508 0.2794) (xy -0.508 0.2286) (xy -0.635 0.2286) (xy -0.635 -0.254) (xy -0.5334 -0.254)
				(xy -0.5334 -0.2794) (xy 0.5334 -0.2794) (xy 0.5334 -0.254) (xy 0.635 -0.254) (xy 0.635 0.254) (xy 0.5334 0.254)
				(xy 0.5334 0.2794)
			)
			(stroke
				(width 0)
				(type default)
			)
			(fill no)
			(layer "F.CrtYd")
		)
		(pad "1" smd rect
			(at 0.40005 0 270)
			(size 0.4572 0.508)
			(layers "F.Cu" "F.Mask" "F.Paste")
			(net "PV_VDDR_NODE1_VREF_R")
		)
		(pad "2" smd rect
			(at -0.40005 0 270)
			(size 0.4572 0.508)
			(layers "F.Cu" "F.Mask" "F.Paste")
			(net "PV_VDDR_NODE1_VREF_LM321")
		)
	)
	(footprint ""
		(layer "F.Cu")
		(at 118.37797 -25.081738 180)
		(property "Reference" "C855"
			(at 0.43688 -2.01168 0)
			(unlocked yes)
			(layer "F.SilkS")
			(effects
				(font
					(size 0.7874 0.5842)
					(thickness 0.1524)
				)
				(justify left)
			)
		)
		(property "Value" ""
			(at 0 0 180)
			(layer "F.Fab")
			(effects
				(font
					(size 1.27 1.27)
				)
			)
		)
		(duplicate_pad_numbers_are_jumpers no)
		(fp_line
			(start 0.7874 0.4064)
			(end -0.7874 0.4064)
			(stroke
				(width 0.1524)
				(type default)
			)
			(layer "F.SilkS")
		)
		(fp_line
			(start 0.7874 -0.4064)
			(end 0.7874 0.4064)
			(stroke
				(width 0.1524)
				(type default)
			)
			(layer "F.SilkS")
		)
		(fp_line
			(start 0 0.381)
			(end 0 -0.381)
			(stroke
				(width 0.1524)
				(type default)
			)
			(layer "F.SilkS")
		)
		(fp_line
			(start -0.7874 0.4064)
			(end -0.7874 -0.4064)
			(stroke
				(width 0.1524)
				(type default)
			)
			(layer "F.SilkS")
		)
		(fp_line
			(start -0.7874 -0.4064)
			(end 0.7874 -0.4064)
			(stroke
				(width 0.1524)
				(type default)
			)
			(layer "F.SilkS")
		)
		(fp_poly
			(pts
				(xy -0.5334 0.254) (xy -0.635 0.254) (xy -0.635 0.2286) (xy -0.635 -0.254) (xy -0.5334 -0.254) (xy -0.5334 -0.2794)
				(xy 0.5334 -0.2794) (xy 0.5334 -0.254) (xy 0.635 -0.254) (xy 0.635 0.254) (xy 0.5334 0.254) (xy 0.5334 0.2794)
				(xy -0.508 0.2794) (xy -0.5334 0.2794)
			)
			(stroke
				(width 0)
				(type default)
			)
			(fill no)
			(layer "F.CrtYd")
		)
		(pad "1" smd rect
			(at 0.40005 0 180)
			(size 0.4572 0.508)
			(layers "F.Cu" "F.Mask" "F.Paste")
			(net "PV_VTT_DDR_NODE1_REFIN")
		)
		(pad "2" smd rect
			(at -0.40005 0 180)
			(size 0.4572 0.508)
			(layers "F.Cu" "F.Mask" "F.Paste")
			(net "GND")
		)
	)
	(footprint ""
		(layer "F.Cu")
		(at 167.80764 -188.19749 -90)
		(property "Reference" "R841"
			(at -0.95631 0.21717 90)
			(unlocked yes)
			(layer "F.SilkS")
			(effects
				(font
					(size 0.7874 0.5842)
					(thickness 0.1524)
				)
				(justify left)
			)
		)
		(property "Value" ""
			(at 0 0 270)
			(layer "F.Fab")
			(effects
				(font
					(size 1.27 1.27)
				)
			)
		)
		(duplicate_pad_numbers_are_jumpers no)
		(fp_line
			(start -0.7874 0.4064)
			(end -0.7874 -0.4064)
			(stroke
				(width 0.1524)
				(type default)
			)
			(layer "F.SilkS")
		)
		(fp_line
			(start 0.7874 0.4064)
			(end -0.7874 0.4064)
			(stroke
				(width 0.1524)
				(type default)
			)
			(layer "F.SilkS")
		)
		(fp_line
			(start -0.7874 -0.4064)
			(end 0.7874 -0.4064)
			(stroke
				(width 0.1524)
				(type default)
			)
			(layer "F.SilkS")
		)
		(fp_line
			(start 0.7874 -0.4064)
			(end 0.7874 0.4064)
			(stroke
				(width 0.1524)
				(type default)
			)
			(layer "F.SilkS")
		)
		(fp_poly
			(pts
				(xy -0.508 0.2794) (xy -0.508 0.2286) (xy -0.635 0.2286) (xy -0.635 -0.254) (xy -0.5334 -0.254)
				(xy -0.5334 -0.2794) (xy 0.5334 -0.2794) (xy 0.5334 -0.254) (xy 0.635 -0.254) (xy 0.635 0.254) (xy 0.5334 0.254)
				(xy 0.5334 0.2794)
			)
			(stroke
				(width 0)
				(type default)
			)
			(fill no)
			(layer "F.CrtYd")
		)
		(pad "1" smd rect
			(at 0.40005 0 270)
			(size 0.4572 0.508)
			(layers "F.Cu" "F.Mask" "F.Paste")
			(net "I2C_PDB_SCL")
		)
		(pad "2" smd rect
			(at -0.40005 0 270)
			(size 0.4572 0.508)
			(layers "F.Cu" "F.Mask" "F.Paste")
			(net "I2C_PDB_R_SCL")
		)
	)
	(footprint ""
		(layer "F.Cu")
		(at 94.451932 -174.306992)
		(property "Reference" "R754"
			(at 86.67369 74.174096 0)
			(unlocked yes)
			(layer "F.SilkS")
			(effects
				(font
					(size 0.7874 0.5842)
					(thickness 0.1524)
				)
				(justify left)
			)
		)
		(property "Value" ""
			(at 0 0 0)
			(layer "F.Fab")
			(effects
				(font
					(size 1.27 1.27)
				)
			)
		)
		(duplicate_pad_numbers_are_jumpers no)
		(fp_line
			(start -0.7874 -0.4064)
			(end 0.7874 -0.4064)
			(stroke
				(width 0.1524)
				(type default)
			)
			(layer "F.SilkS")
		)
		(fp_line
			(start -0.7874 0.4064)
			(end -0.7874 -0.4064)
			(stroke
				(width 0.1524)
				(type default)
			)
			(layer "F.SilkS")
		)
		(fp_line
			(start 0.7874 -0.4064)
			(end 0.7874 0.4064)
			(stroke
				(width 0.1524)
				(type default)
			)
			(layer "F.SilkS")
		)
		(fp_line
			(start 0.7874 0.4064)
			(end -0.7874 0.4064)
			(stroke
				(width 0.1524)
				(type default)
			)
			(layer "F.SilkS")
		)
		(fp_poly
			(pts
				(xy -0.508 0.2794) (xy -0.508 0.2286) (xy -0.635 0.2286) (xy -0.635 -0.254) (xy -0.5334 -0.254)
				(xy -0.5334 -0.2794) (xy 0.5334 -0.2794) (xy 0.5334 -0.254) (xy 0.635 -0.254) (xy 0.635 0.254) (xy 0.5334 0.254)
				(xy 0.5334 0.2794)
			)
			(stroke
				(width 0)
				(type default)
			)
			(fill no)
			(layer "F.CrtYd")
		)
		(pad "1" smd rect
			(at 0.40005 0)
			(size 0.4572 0.508)
			(layers "F.Cu" "F.Mask" "F.Paste")
			(net "N21698906")
		)
		(pad "2" smd rect
			(at -0.40005 0)
			(size 0.4572 0.508)
			(layers "F.Cu" "F.Mask" "F.Paste")
			(net "GND")
		)
	)
	(footprint ""
		(layer "F.Cu")
		(at 82.408014 -74.724006 -90)
		(property "Reference" "R113"
			(at 16.256508 -1.86055 90)
			(unlocked yes)
			(layer "F.SilkS")
			(effects
				(font
					(size 0.7874 0.5842)
					(thickness 0.1524)
				)
				(justify left)
			)
		)
		(property "Value" ""
			(at 0 0 270)
			(layer "F.Fab")
			(effects
				(font
					(size 1.27 1.27)
				)
			)
		)
		(duplicate_pad_numbers_are_jumpers no)
		(fp_line
			(start -0.7874 0.4064)
			(end -0.7874 -0.4064)
			(stroke
				(width 0.1524)
				(type default)
			)
			(layer "F.SilkS")
		)
		(fp_line
			(start 0.7874 0.4064)
			(end -0.7874 0.4064)
			(stroke
				(width 0.1524)
				(type default)
			)
			(layer "F.SilkS")
		)
		(fp_line
			(start -0.7874 -0.4064)
			(end 0.7874 -0.4064)
			(stroke
				(width 0.1524)
				(type default)
			)
			(layer "F.SilkS")
		)
		(fp_line
			(start 0.7874 -0.4064)
			(end 0.7874 0.4064)
			(stroke
				(width 0.1524)
				(type default)
			)
			(layer "F.SilkS")
		)
		(fp_poly
			(pts
				(xy -0.508 0.2794) (xy -0.508 0.2286) (xy -0.635 0.2286) (xy -0.635 -0.254) (xy -0.5334 -0.254)
				(xy -0.5334 -0.2794) (xy 0.5334 -0.2794) (xy 0.5334 -0.254) (xy 0.635 -0.254) (xy 0.635 0.254) (xy 0.5334 0.254)
				(xy 0.5334 0.2794)
			)
			(stroke
				(width 0)
				(type default)
			)
			(fill no)
			(layer "F.CrtYd")
		)
		(pad "1" smd rect
			(at 0.40005 0 270)
			(size 0.4572 0.508)
			(layers "F.Cu" "F.Mask" "F.Paste")
			(net "XDP_CPU_NODE1_PREQ_L")
		)
		(pad "2" smd rect
			(at -0.40005 0 270)
			(size 0.4572 0.508)
			(layers "F.Cu" "F.Mask" "F.Paste")
			(net "P1V05_NODE1")
		)
	)
	(footprint ""
		(layer "F.Cu")
		(at 24.032718 -149.117558 180)
		(property "Reference" "R564"
			(at 0.035306 1.198626 0)
			(unlocked yes)
			(layer "F.SilkS")
			(effects
				(font
					(size 0.7874 0.5842)
					(thickness 0.1524)
				)
			)
		)
		(property "Value" ""
			(at 0 0 180)
			(layer "F.Fab")
			(effects
				(font
					(size 1.27 1.27)
				)
			)
		)
		(duplicate_pad_numbers_are_jumpers no)
		(fp_line
			(start 1.2954 0.5842)
			(end -1.2954 0.5842)
			(stroke
				(width 0.1524)
				(type default)
			)
			(layer "F.SilkS")
		)
		(fp_line
			(start 1.2954 -0.5842)
			(end 1.2954 0.5842)
			(stroke
				(width 0.1524)
				(type default)
			)
			(layer "F.SilkS")
		)
		(fp_line
			(start -1.2954 0.5842)
			(end -1.2954 -0.5842)
			(stroke
				(width 0.1524)
				(type default)
			)
			(layer "F.SilkS")
		)
		(fp_line
			(start -1.2954 -0.5842)
			(end 1.2954 -0.5842)
			(stroke
				(width 0.1524)
				(type default)
			)
			(layer "F.SilkS")
		)
		(fp_poly
			(pts
				(xy 1.143 -0.3556) (xy 1.143 0.3556) (xy 0.8636 0.3556) (xy 0.8636 0.4572) (xy -0.8636 0.4572) (xy -0.8636 0.4318)
				(xy -0.8636 0.3556) (xy -1.143 0.3556) (xy -1.143 -0.3556) (xy -0.8636 -0.3556) (xy -0.8636 -0.4572)
				(xy 0.8636 -0.4572) (xy 0.8636 -0.3556)
			)
			(stroke
				(width 0)
				(type default)
			)
			(fill no)
			(layer "F.CrtYd")
		)
		(pad "1" smd rect
			(at 0.7366 0 270)
			(size 0.7112 0.8128)
			(layers "F.Cu" "F.Mask" "F.Paste")
			(net "P3V3_NODE1")
		)
		(pad "2" smd rect
			(at -0.7366 0 270)
			(size 0.7112 0.8128)
			(layers "F.Cu" "F.Mask" "F.Paste")
			(net "LAN1_CTRL_P1V9")
		)
	)
	(footprint ""
		(layer "F.Cu")
		(at 182.430674 -145.204942 -90)
		(property "Reference" "R594"
			(at -0.189738 2.185162 90)
			(unlocked yes)
			(layer "F.SilkS")
			(effects
				(font
					(size 0.7874 0.5842)
					(thickness 0.1524)
				)
			)
		)
		(property "Value" ""
			(at 0 0 270)
			(layer "F.Fab")
			(effects
				(font
					(size 1.27 1.27)
				)
			)
		)
		(duplicate_pad_numbers_are_jumpers no)
		(fp_line
			(start -1.2954 0.5842)
			(end -1.2954 -0.5842)
			(stroke
				(width 0.1524)
				(type default)
			)
			(layer "F.SilkS")
		)
		(fp_line
			(start 1.2954 0.5842)
			(end -1.2954 0.5842)
			(stroke
				(width 0.1524)
				(type default)
			)
			(layer "F.SilkS")
		)
		(fp_line
			(start -1.2954 -0.5842)
			(end 1.2954 -0.5842)
			(stroke
				(width 0.1524)
				(type default)
			)
			(layer "F.SilkS")
		)
		(fp_line
			(start 1.2954 -0.5842)
			(end 1.2954 0.5842)
			(stroke
				(width 0.1524)
				(type default)
			)
			(layer "F.SilkS")
		)
		(fp_poly
			(pts
				(xy 1.143 -0.3556) (xy 1.143 0.3556) (xy 0.8636 0.3556) (xy 0.8636 0.4572) (xy -0.8636 0.4572) (xy -0.8636 0.4318)
				(xy -0.8636 0.3556) (xy -1.143 0.3556) (xy -1.143 -0.3556) (xy -0.8636 -0.3556) (xy -0.8636 -0.4572)
				(xy 0.8636 -0.4572) (xy 0.8636 -0.3556)
			)
			(stroke
				(width 0)
				(type default)
			)
			(fill no)
			(layer "F.CrtYd")
		)
		(pad "1" smd rect
			(at 0.7366 0)
			(size 0.7112 0.8128)
			(layers "F.Cu" "F.Mask" "F.Paste")
			(net "P3V3_NODE1")
		)
		(pad "2" smd rect
			(at -0.7366 0)
			(size 0.7112 0.8128)
			(layers "F.Cu" "F.Mask" "F.Paste")
			(net "LAN2_CTRL_P1V9")
		)
	)
	(footprint ""
		(layer "F.Cu")
		(at 76.81976 -188.126624 90)
		(property "Reference" "C698"
			(at 4.548886 -1.419098 90)
			(unlocked yes)
			(layer "F.SilkS")
			(effects
				(font
					(size 0.7874 0.5842)
					(thickness 0.1524)
				)
				(justify left)
			)
		)
		(property "Value" ""
			(at 0 0 90)
			(layer "F.Fab")
			(effects
				(font
					(size 1.27 1.27)
				)
			)
		)
		(duplicate_pad_numbers_are_jumpers no)
		(fp_line
			(start 0.7874 -0.4064)
			(end 0.7874 0.4064)
			(stroke
				(width 0.1524)
				(type default)
			)
			(layer "F.SilkS")
		)
		(fp_line
			(start -0.7874 -0.4064)
			(end 0.7874 -0.4064)
			(stroke
				(width 0.1524)
				(type default)
			)
			(layer "F.SilkS")
		)
		(fp_line
			(start 0 0.381)
			(end 0 -0.381)
			(stroke
				(width 0.1524)
				(type default)
			)
			(layer "F.SilkS")
		)
		(fp_line
			(start 0.7874 0.4064)
			(end -0.7874 0.4064)
			(stroke
				(width 0.1524)
				(type default)
			)
			(layer "F.SilkS")
		)
		(fp_line
			(start -0.7874 0.4064)
			(end -0.7874 -0.4064)
			(stroke
				(width 0.1524)
				(type default)
			)
			(layer "F.SilkS")
		)
		(fp_poly
			(pts
				(xy -0.5334 0.254) (xy -0.635 0.254) (xy -0.635 0.2286) (xy -0.635 -0.254) (xy -0.5334 -0.254) (xy -0.5334 -0.2794)
				(xy 0.5334 -0.2794) (xy 0.5334 -0.254) (xy 0.635 -0.254) (xy 0.635 0.254) (xy 0.5334 0.254) (xy 0.5334 0.2794)
				(xy -0.508 0.2794) (xy -0.5334 0.2794)
			)
			(stroke
				(width 0)
				(type default)
			)
			(fill no)
			(layer "F.CrtYd")
		)
		(pad "1" smd rect
			(at 0.40005 0 90)
			(size 0.4572 0.508)
			(layers "F.Cu" "F.Mask" "F.Paste")
			(net "UART_T4_NODE1_TXD_R")
		)
		(pad "2" smd rect
			(at -0.40005 0 90)
			(size 0.4572 0.508)
			(layers "F.Cu" "F.Mask" "F.Paste")
			(net "GND")
		)
	)
	(footprint ""
		(layer "F.Cu")
		(at 75.474068 -94.131892 -90)
		(property "Reference" "R160"
			(at 55.53329 -24.083264 90)
			(unlocked yes)
			(layer "F.SilkS")
			(effects
				(font
					(size 0.7874 0.5842)
					(thickness 0.1524)
				)
				(justify left)
			)
		)
		(property "Value" ""
			(at 0 0 270)
			(layer "F.Fab")
			(effects
				(font
					(size 1.27 1.27)
				)
			)
		)
		(duplicate_pad_numbers_are_jumpers no)
		(fp_line
			(start -0.7874 0.4064)
			(end -0.7874 -0.4064)
			(stroke
				(width 0.1524)
				(type default)
			)
			(layer "F.SilkS")
		)
		(fp_line
			(start 0.7874 0.4064)
			(end -0.7874 0.4064)
			(stroke
				(width 0.1524)
				(type default)
			)
			(layer "F.SilkS")
		)
		(fp_line
			(start -0.7874 -0.4064)
			(end 0.7874 -0.4064)
			(stroke
				(width 0.1524)
				(type default)
			)
			(layer "F.SilkS")
		)
		(fp_line
			(start 0.7874 -0.4064)
			(end 0.7874 0.4064)
			(stroke
				(width 0.1524)
				(type default)
			)
			(layer "F.SilkS")
		)
		(fp_poly
			(pts
				(xy -0.508 0.2794) (xy -0.508 0.2286) (xy -0.635 0.2286) (xy -0.635 -0.254) (xy -0.5334 -0.254)
				(xy -0.5334 -0.2794) (xy 0.5334 -0.2794) (xy 0.5334 -0.254) (xy 0.635 -0.254) (xy 0.635 0.254) (xy 0.5334 0.254)
				(xy 0.5334 0.2794)
			)
			(stroke
				(width 0)
				(type default)
			)
			(fill no)
			(layer "F.CrtYd")
		)
		(pad "1" smd rect
			(at 0.40005 0 270)
			(size 0.4572 0.508)
			(layers "F.Cu" "F.Mask" "F.Paste")
			(net "PD_CPU_NODE1_NODE_ID")
		)
		(pad "2" smd rect
			(at -0.40005 0 270)
			(size 0.4572 0.508)
			(layers "F.Cu" "F.Mask" "F.Paste")
			(net "GND")
		)
	)
	(footprint ""
		(layer "F.Cu")
		(at 40.350186 -20.94992 90)
		(property "Reference" "J2"
			(at -2.420874 10.237724 0)
			(unlocked yes)
			(layer "F.SilkS")
			(effects
				(font
					(size 0.7874 0.5842)
					(thickness 0.1524)
				)
				(justify left)
			)
		)
		(property "Value" ""
			(at 0 0 90)
			(layer "F.Fab")
			(effects
				(font
					(size 1.27 1.27)
				)
			)
		)
		(duplicate_pad_numbers_are_jumpers no)
		(fp_line
			(start 25.150064 -5.850128)
			(end 18.628614 -5.695188)
			(stroke
				(width 0.1524)
				(type default)
			)
			(layer "F.SilkS")
		)
		(fp_line
			(start 13.5763 -5.575046)
			(end 4.100068 -5.350002)
			(stroke
				(width 0.1524)
				(type default)
			)
			(layer "F.SilkS")
		)
		(fp_line
			(start 4.100068 -5.350002)
			(end -0.750062 -5.350002)
			(stroke
				(width 0.1524)
				(type default)
			)
			(layer "F.SilkS")
		)
		(fp_line
			(start -0.750062 -5.350002)
			(end -0.750062 -0.328676)
			(stroke
				(width 0.1524)
				(type default)
			)
			(layer "F.SilkS")
		)
		(fp_line
			(start 25.150064 -0.40005)
			(end 25.150064 -5.850128)
			(stroke
				(width 0.1524)
				(type default)
			)
			(layer "F.SilkS")
		)
		(fp_line
			(start 7.549896 -0.40005)
			(end 25.150064 -0.40005)
			(stroke
				(width 0.1524)
				(type default)
			)
			(layer "F.SilkS")
		)
		(fp_line
			(start 7.549896 -0.049276)
			(end 7.549896 -0.40005)
			(stroke
				(width 0.1524)
				(type default)
			)
			(layer "F.SilkS")
		)
		(fp_line
			(start -0.750062 21.362924)
			(end -0.750062 23.648924)
			(stroke
				(width 0.1524)
				(type default)
			)
			(layer "F.SilkS")
		)
		(fp_line
			(start 7.549896 23.953724)
			(end 7.549896 21.616924)
			(stroke
				(width 0.1524)
				(type default)
			)
			(layer "F.SilkS")
		)
		(fp_line
			(start -0.750062 63.349124)
			(end -0.750062 68.650104)
			(stroke
				(width 0.1524)
				(type default)
			)
			(layer "F.SilkS")
		)
		(fp_line
			(start 25.150064 63.699898)
			(end 7.549896 63.699898)
			(stroke
				(width 0.1524)
				(type default)
			)
			(layer "F.SilkS")
		)
		(fp_line
			(start 7.549896 63.699898)
			(end 7.549896 63.628524)
			(stroke
				(width 0.1524)
				(type default)
			)
			(layer "F.SilkS")
		)
		(fp_line
			(start -0.750062 68.650104)
			(end 13.371322 68.922646)
			(stroke
				(width 0.1524)
				(type default)
			)
			(layer "F.SilkS")
		)
		(fp_line
			(start 18.630138 69.024246)
			(end 25.150064 69.149976)
			(stroke
				(width 0.1524)
				(type default)
			)
			(layer "F.SilkS")
		)
		(fp_line
			(start 25.150064 69.149976)
			(end 25.150064 63.699898)
			(stroke
				(width 0.1524)
				(type default)
			)
			(layer "F.SilkS")
		)
		(fp_poly
			(pts
				(xy -2.074672 -0.534416) (xy -3.090672 -1.042416) (xy -3.090672 -0.026416)
			)
			(stroke
				(width 0)
				(type default)
			)
			(fill yes)
			(layer "F.SilkS")
		)
		(fp_poly
			(pts
				(arc
					(start 4.938268 65.049908)
					(mid 3.261868 65.049908)
					(end 4.938268 65.049908)
				)
			)
			(stroke
				(width 0)
				(type default)
			)
			(fill no)
			(layer "B.CrtYd")
		)
		(fp_poly
			(pts
				(arc
					(start 5.179822 -1.75006)
					(mid 3.020314 -1.75006)
					(end 5.179822 -1.75006)
				)
			)
			(stroke
				(width 0)
				(type default)
			)
			(fill no)
			(layer "B.CrtYd")
		)
		(fp_poly
			(pts
				(xy 4.100068 -5.350002) (xy -0.750062 -5.350002) (xy -0.750062 -0.252476) (xy -1.081532 -0.252476)
				(xy -1.081532 21.248624) (xy -0.750062 21.248624) (xy -0.750062 23.750524) (xy -1.081532 23.750524)
				(xy -1.081532 63.247524) (xy -0.750062 63.247524) (xy -0.750062 68.650104) (xy 13.688568 68.928742)
				(xy 13.688568 71.464424) (xy 13.701268 71.464424) (xy 18.501868 71.464424) (xy 18.501868 69.021706)
				(xy 25.150064 69.149976) (xy 25.150064 63.699898) (xy 7.549896 63.699898) (xy 7.549896 63.552324)
				(xy 9.281668 63.552324) (xy 9.281668 24.055324) (xy 7.549896 24.055324) (xy 7.549896 21.553424)
				(xy 9.281668 21.553424) (xy 9.281668 21.540724) (xy 9.281668 0.052324) (xy 7.549896 0.052324) (xy 7.549896 -0.40005)
				(xy 25.150064 -0.40005) (xy 25.150064 -5.850128) (xy 18.501868 -5.69214) (xy 18.501868 -8.164576)
				(xy 13.688314 -8.164576) (xy 13.688314 -5.57784)
			)
			(stroke
				(width 0)
				(type default)
			)
			(fill no)
			(layer "F.CrtYd")
		)
		(fp_line
			(start 25.150064 -5.850128)
			(end 4.100068 -5.350002)
			(stroke
				(width 0.1)
				(type default)
			)
			(layer "F.Fab")
		)
		(fp_line
			(start 4.100068 -5.350002)
			(end -0.750062 -5.350002)
			(stroke
				(width 0.1)
				(type default)
			)
			(layer "F.Fab")
		)
		(fp_line
			(start -0.750062 -5.350002)
			(end -0.750062 68.650104)
			(stroke
				(width 0.1)
				(type default)
			)
			(layer "F.Fab")
		)
		(fp_line
			(start 25.150064 -0.40005)
			(end 25.150064 -5.850128)
			(stroke
				(width 0.1)
				(type default)
			)
			(layer "F.Fab")
		)
		(fp_line
			(start 7.549896 -0.40005)
			(end 25.150064 -0.40005)
			(stroke
				(width 0.1)
				(type default)
			)
			(layer "F.Fab")
		)
		(fp_line
			(start 25.150064 63.699898)
			(end 7.549896 63.699898)
			(stroke
				(width 0.1)
				(type default)
			)
			(layer "F.Fab")
		)
		(fp_line
			(start 7.549896 63.699898)
			(end 7.549896 -0.40005)
			(stroke
				(width 0.1)
				(type default)
			)
			(layer "F.Fab")
		)
		(fp_line
			(start -0.750062 68.650104)
			(end 25.150064 69.149976)
			(stroke
				(width 0.1)
				(type default)
			)
			(layer "F.Fab")
		)
		(fp_line
			(start 25.150064 69.149976)
			(end 25.150064 63.699898)
			(stroke
				(width 0.1)
				(type default)
			)
			(layer "F.Fab")
		)
		(fp_poly
			(pts
				(xy -1.132332 0.001524) (xy -2.148332 -0.506476) (xy -2.148332 0.509524)
			)
			(stroke
				(width 0)
				(type default)
			)
			(fill yes)
			(layer "F.Fab")
		)
		(fp_text user "1"
			(at -1.51257 -0.776986 0)
			(unlocked yes)
			(layer "F.SilkS")
			(effects
				(font
					(size 0.635 0.4064)
					(thickness 0.1524)
				)
				(justify left)
			)
		)
		(fp_text user "2"
			(at 10.262108 0.040132 0)
			(unlocked yes)
			(layer "F.SilkS")
			(effects
				(font
					(size 0.7874 0.5842)
					(thickness 0.1524)
				)
				(justify left)
			)
		)
		(fp_text user "71"
			(at -1.848866 20.04314 0)
			(unlocked yes)
			(layer "F.SilkS")
			(effects
				(font
					(size 0.635 0.4064)
					(thickness 0.1524)
				)
				(justify left)
			)
		)
		(fp_text user "72"
			(at 9.945624 20.613624 0)
			(unlocked yes)
			(layer "F.SilkS")
			(effects
				(font
					(size 0.635 0.4064)
					(thickness 0.1524)
				)
				(justify left)
			)
		)
		(fp_text user "74"
			(at 10.147046 23.238714 0)
			(unlocked yes)
			(layer "F.SilkS")
			(effects
				(font
					(size 0.635 0.4064)
					(thickness 0.1524)
				)
				(justify left)
			)
		)
		(fp_text user "73"
			(at -1.912366 23.438612 0)
			(unlocked yes)
			(layer "F.SilkS")
			(effects
				(font
					(size 0.635 0.4064)
					(thickness 0.1524)
				)
				(justify left)
			)
		)
		(fp_text user "204"
			(at 10.475722 60.459366 0)
			(unlocked yes)
			(layer "F.SilkS")
			(effects
				(font
					(size 0.635 0.4064)
					(thickness 0.1524)
				)
				(justify left)
			)
		)
		(fp_text user "203"
			(at -1.53797 66.21907 0)
			(unlocked yes)
			(layer "F.SilkS")
			(effects
				(font
					(size 0.635 0.4064)
					(thickness 0.1524)
				)
				(justify left)
			)
		)
		(fp_text user "1"
			(at -1.489202 -0.862076 0)
			(unlocked yes)
			(layer "F.Fab")
			(effects
				(font
					(size 0.7874 0.5842)
					(thickness 0.000001)
				)
				(justify left)
			)
		)
		(fp_text user "2"
			(at 9.762998 0.026924 0)
			(unlocked yes)
			(layer "F.Fab")
			(effects
				(font
					(size 0.7874 0.5842)
					(thickness 0.000001)
				)
				(justify left)
			)
		)
		(fp_text user "71"
			(at -1.743202 20.321524 0)
			(unlocked yes)
			(layer "F.Fab")
			(effects
				(font
					(size 0.7874 0.5842)
					(thickness 0.000001)
				)
				(justify left)
			)
		)
		(fp_text user "72"
			(at 9.839198 20.550124 0)
			(unlocked yes)
			(layer "F.Fab")
			(effects
				(font
					(size 0.7874 0.5842)
					(thickness 0.000001)
				)
				(justify left)
			)
		)
		(fp_text user "73"
			(at -1.768602 23.267924 0)
			(unlocked yes)
			(layer "F.Fab")
			(effects
				(font
					(size 0.7874 0.5842)
					(thickness 0.000001)
				)
				(justify left)
			)
		)
		(fp_text user "74"
			(at 9.762998 23.547324 0)
			(unlocked yes)
			(layer "F.Fab")
			(effects
				(font
					(size 0.7874 0.5842)
					(thickness 0.000001)
				)
				(justify left)
			)
		)
		(fp_text user "203"
			(at -1.540002 63.171324 0)
			(unlocked yes)
			(layer "F.Fab")
			(effects
				(font
					(size 0.7874 0.5842)
					(thickness 0.000001)
				)
				(justify left)
			)
		)
		(fp_text user "204"
			(at 9.513824 63.194438 90)
			(unlocked yes)
			(layer "F.Fab")
			(effects
				(font
					(size 0.7874 0.5842)
					(thickness 0.000001)
				)
				(justify left)
			)
		)
		(pad "" np_thru_hole circle
			(at 4.100068 -1.75006 90)
			(size 1.651 1.651)
			(drill 1.651)
			(layers "*.Cu" "*.Mask")
			(clearance 0.381)
			(thermal_gap 0.381)
		)
		(pad "" np_thru_hole circle
			(at 4.100068 65.049908 90)
			(size 1.1684 1.1684)
			(drill 1.1684)
			(layers "*.Cu" "*.Mask")
			(clearance 0.381)
			(thermal_gap 0.381)
		)
		(pad "1" smd rect
			(at 0 0)
			(size 0.381 2.0574)
			(layers "F.Cu" "F.Mask" "F.Paste")
			(net "P1V5_NODE1_DDR3_VREF0_D")
		)
		(pad "2" smd rect
			(at 8.199882 0.299974)
			(size 0.381 2.0574)
			(layers "F.Cu" "F.Mask" "F.Paste")
			(net "GND")
		)
		(pad "3" smd rect
			(at 0 0.599948)
			(size 0.381 2.0574)
			(layers "F.Cu" "F.Mask" "F.Paste")
			(net "GND")
		)
		(pad "4" smd rect
			(at 8.199882 0.899922)
			(size 0.381 2.0574)
			(layers "F.Cu" "F.Mask" "F.Paste")
			(net "M1_DQ_NODE1_DQ4")
		)
		(pad "5" smd rect
			(at 0 1.199896)
			(size 0.381 2.0574)
			(layers "F.Cu" "F.Mask" "F.Paste")
			(net "M1_DQ_NODE1_DQ0")
		)
		(pad "6" smd rect
			(at 8.199882 1.500124)
			(size 0.381 2.0574)
			(layers "F.Cu" "F.Mask" "F.Paste")
			(net "M1_DQ_NODE1_DQ5")
		)
		(pad "7" smd rect
			(at 0 1.800098)
			(size 0.381 2.0574)
			(layers "F.Cu" "F.Mask" "F.Paste")
			(net "M1_DQ_NODE1_DQ1")
		)
		(pad "8" smd rect
			(at 8.199882 2.100072)
			(size 0.381 2.0574)
			(layers "F.Cu" "F.Mask" "F.Paste")
			(net "GND")
		)
		(pad "9" smd rect
			(at 0 2.400046)
			(size 0.381 2.0574)
			(layers "F.Cu" "F.Mask" "F.Paste")
			(net "GND")
		)
		(pad "10" smd rect
			(at 8.199882 2.70002)
			(size 0.381 2.0574)
			(layers "F.Cu" "F.Mask" "F.Paste")
			(net "M_DDR3_NODE1_DQS0N")
		)
		(pad "11" smd rect
			(at 0 2.999994)
			(size 0.381 2.0574)
			(layers "F.Cu" "F.Mask" "F.Paste")
			(net "PD_NODE1_DM0")
		)
		(pad "12" smd rect
			(at 8.199882 3.299968)
			(size 0.381 2.0574)
			(layers "F.Cu" "F.Mask" "F.Paste")
			(net "M_DDR3_NODE1_DQS0P")
		)
		(pad "13" smd rect
			(at 0 3.599942)
			(size 0.381 2.0574)
			(layers "F.Cu" "F.Mask" "F.Paste")
			(net "M1_DQ_NODE1_DQ2")
		)
		(pad "14" smd rect
			(at 8.199882 3.899916)
			(size 0.381 2.0574)
			(layers "F.Cu" "F.Mask" "F.Paste")
			(net "GND")
		)
		(pad "15" smd rect
			(at 0 4.19989)
			(size 0.381 2.0574)
			(layers "F.Cu" "F.Mask" "F.Paste")
			(net "M1_DQ_NODE1_DQ3")
		)
		(pad "16" smd rect
			(at 8.199882 4.500118)
			(size 0.381 2.0574)
			(layers "F.Cu" "F.Mask" "F.Paste")
			(net "M1_DQ_NODE1_DQ6")
		)
		(pad "17" smd rect
			(at 0 4.800092)
			(size 0.381 2.0574)
			(layers "F.Cu" "F.Mask" "F.Paste")
			(net "GND")
		)
		(pad "18" smd rect
			(at 8.199882 5.100066)
			(size 0.381 2.0574)
			(layers "F.Cu" "F.Mask" "F.Paste")
			(net "M1_DQ_NODE1_DQ7")
		)
		(pad "19" smd rect
			(at 0 5.40004)
			(size 0.381 2.0574)
			(layers "F.Cu" "F.Mask" "F.Paste")
			(net "M1_DQ_NODE1_DQ8")
		)
		(pad "20" smd rect
			(at 8.199882 5.700014)
			(size 0.381 2.0574)
			(layers "F.Cu" "F.Mask" "F.Paste")
			(net "GND")
		)
		(pad "21" smd rect
			(at 0 5.999988)
			(size 0.381 2.0574)
			(layers "F.Cu" "F.Mask" "F.Paste")
			(net "M1_DQ_NODE1_DQ9")
		)
		(pad "22" smd rect
			(at 8.199882 6.299962)
			(size 0.381 2.0574)
			(layers "F.Cu" "F.Mask" "F.Paste")
			(net "M1_DQ_NODE1_DQ12")
		)
		(pad "23" smd rect
			(at 0 6.599936)
			(size 0.381 2.0574)
			(layers "F.Cu" "F.Mask" "F.Paste")
			(net "GND")
		)
		(pad "24" smd rect
			(at 8.199882 6.89991)
			(size 0.381 2.0574)
			(layers "F.Cu" "F.Mask" "F.Paste")
			(net "M1_DQ_NODE1_DQ13")
		)
		(pad "25" smd rect
			(at 0 7.199884)
			(size 0.381 2.0574)
			(layers "F.Cu" "F.Mask" "F.Paste")
			(net "M_DDR3_NODE1_DQS1N")
		)
		(pad "26" smd rect
			(at 8.199882 7.500112)
			(size 0.381 2.0574)
			(layers "F.Cu" "F.Mask" "F.Paste")
			(net "GND")
		)
		(pad "27" smd rect
			(at 0 7.800086)
			(size 0.381 2.0574)
			(layers "F.Cu" "F.Mask" "F.Paste")
			(net "M_DDR3_NODE1_DQS1P")
		)
		(pad "28" smd rect
			(at 8.199882 8.10006)
			(size 0.381 2.0574)
			(layers "F.Cu" "F.Mask" "F.Paste")
			(net "PD_NODE1_DM1")
		)
		(pad "29" smd rect
			(at 0 8.400034)
			(size 0.381 2.0574)
			(layers "F.Cu" "F.Mask" "F.Paste")
			(net "GND")
		)
		(pad "30" smd rect
			(at 8.199882 8.700008)
			(size 0.381 2.0574)
			(layers "F.Cu" "F.Mask" "F.Paste")
			(net "M_NODE1_DIMM_RST_L")
		)
		(pad "31" smd rect
			(at 0 8.999982)
			(size 0.381 2.0574)
			(layers "F.Cu" "F.Mask" "F.Paste")
			(net "M1_DQ_NODE1_DQ10")
		)
		(pad "32" smd rect
			(at 8.199882 9.299956)
			(size 0.381 2.0574)
			(layers "F.Cu" "F.Mask" "F.Paste")
			(net "GND")
		)
		(pad "33" smd rect
			(at 0 9.59993)
			(size 0.381 2.0574)
			(layers "F.Cu" "F.Mask" "F.Paste")
			(net "M1_DQ_NODE1_DQ11")
		)
		(pad "34" smd rect
			(at 8.199882 9.899904)
			(size 0.381 2.0574)
			(layers "F.Cu" "F.Mask" "F.Paste")
			(net "M1_DQ_NODE1_DQ14")
		)
		(pad "35" smd rect
			(at 0 10.199878)
			(size 0.381 2.0574)
			(layers "F.Cu" "F.Mask" "F.Paste")
			(net "GND")
		)
		(pad "36" smd rect
			(at 8.199882 10.500106)
			(size 0.381 2.0574)
			(layers "F.Cu" "F.Mask" "F.Paste")
			(net "M1_DQ_NODE1_DQ15")
		)
		(pad "37" smd rect
			(at 0 10.80008)
			(size 0.381 2.0574)
			(layers "F.Cu" "F.Mask" "F.Paste")
			(net "M1_DQ_NODE1_DQ16")
		)
		(pad "38" smd rect
			(at 8.199882 11.100054)
			(size 0.381 2.0574)
			(layers "F.Cu" "F.Mask" "F.Paste")
			(net "GND")
		)
		(pad "39" smd rect
			(at 0 11.400028)
			(size 0.381 2.0574)
			(layers "F.Cu" "F.Mask" "F.Paste")
			(net "M1_DQ_NODE1_DQ17")
		)
		(pad "40" smd rect
			(at 8.199882 11.700002)
			(size 0.381 2.0574)
			(layers "F.Cu" "F.Mask" "F.Paste")
			(net "M1_DQ_NODE1_DQ20")
		)
		(pad "41" smd rect
			(at 0 11.999976)
			(size 0.381 2.0574)
			(layers "F.Cu" "F.Mask" "F.Paste")
			(net "GND")
		)
		(pad "42" smd rect
			(at 8.199882 12.29995)
			(size 0.381 2.0574)
			(layers "F.Cu" "F.Mask" "F.Paste")
			(net "M1_DQ_NODE1_DQ21")
		)
		(pad "43" smd rect
			(at 0 12.599924)
			(size 0.381 2.0574)
			(layers "F.Cu" "F.Mask" "F.Paste")
			(net "M_DDR3_NODE1_DQS2N")
		)
		(pad "44" smd rect
			(at 8.199882 12.899898)
			(size 0.381 2.0574)
			(layers "F.Cu" "F.Mask" "F.Paste")
			(net "PD_NODE1_DM2")
		)
		(pad "45" smd rect
			(at 0 13.199872)
			(size 0.381 2.0574)
			(layers "F.Cu" "F.Mask" "F.Paste")
			(net "M_DDR3_NODE1_DQS2P")
		)
		(pad "46" smd rect
			(at 8.199882 13.5001)
			(size 0.381 2.0574)
			(layers "F.Cu" "F.Mask" "F.Paste")
			(net "GND")
		)
		(pad "47" smd rect
			(at 0 13.800074)
			(size 0.381 2.0574)
			(layers "F.Cu" "F.Mask" "F.Paste")
			(net "GND")
		)
		(pad "48" smd rect
			(at 8.199882 14.100048)
			(size 0.381 2.0574)
			(layers "F.Cu" "F.Mask" "F.Paste")
			(net "M1_DQ_NODE1_DQ22")
		)
		(pad "49" smd rect
			(at 0 14.400022)
			(size 0.381 2.0574)
			(layers "F.Cu" "F.Mask" "F.Paste")
			(net "M1_DQ_NODE1_DQ18")
		)
		(pad "50" smd rect
			(at 8.199882 14.699996)
			(size 0.381 2.0574)
			(layers "F.Cu" "F.Mask" "F.Paste")
			(net "M1_DQ_NODE1_DQ23")
		)
		(pad "51" smd rect
			(at 0 14.99997)
			(size 0.381 2.0574)
			(layers "F.Cu" "F.Mask" "F.Paste")
			(net "M1_DQ_NODE1_DQ19")
		)
		(pad "52" smd rect
			(at 8.199882 15.299944)
			(size 0.381 2.0574)
			(layers "F.Cu" "F.Mask" "F.Paste")
			(net "GND")
		)
		(pad "53" smd rect
			(at 0 15.599918)
			(size 0.381 2.0574)
			(layers "F.Cu" "F.Mask" "F.Paste")
			(net "GND")
		)
		(pad "54" smd rect
			(at 8.199882 15.899892)
			(size 0.381 2.0574)
			(layers "F.Cu" "F.Mask" "F.Paste")
			(net "M1_DQ_NODE1_DQ28")
		)
		(pad "55" smd rect
			(at 0 16.20012)
			(size 0.381 2.0574)
			(layers "F.Cu" "F.Mask" "F.Paste")
			(net "M1_DQ_NODE1_DQ24")
		)
		(pad "56" smd rect
			(at 8.199882 16.500094)
			(size 0.381 2.0574)
			(layers "F.Cu" "F.Mask" "F.Paste")
			(net "M1_DQ_NODE1_DQ29")
		)
		(pad "57" smd rect
			(at 0 16.800068)
			(size 0.381 2.0574)
			(layers "F.Cu" "F.Mask" "F.Paste")
			(net "M1_DQ_NODE1_DQ25")
		)
		(pad "58" smd rect
			(at 8.199882 17.100042)
			(size 0.381 2.0574)
			(layers "F.Cu" "F.Mask" "F.Paste")
			(net "GND")
		)
		(pad "59" smd rect
			(at 0 17.400016)
			(size 0.381 2.0574)
			(layers "F.Cu" "F.Mask" "F.Paste")
			(net "PD_NODE1_DM3")
		)
		(pad "60" smd rect
			(at 8.199882 17.69999)
			(size 0.381 2.0574)
			(layers "F.Cu" "F.Mask" "F.Paste")
			(net "M_DDR3_NODE1_DQS3N")
		)
		(pad "61" smd rect
			(at 0 17.999964)
			(size 0.381 2.0574)
			(layers "F.Cu" "F.Mask" "F.Paste")
			(net "GND")
		)
		(pad "62" smd rect
			(at 8.199882 18.299938)
			(size 0.381 2.0574)
			(layers "F.Cu" "F.Mask" "F.Paste")
			(net "M_DDR3_NODE1_DQS3P")
		)
		(pad "63" smd rect
			(at 0 18.599912)
			(size 0.381 2.0574)
			(layers "F.Cu" "F.Mask" "F.Paste")
			(net "M1_DQ_NODE1_DQ26")
		)
		(pad "64" smd rect
			(at 8.199882 18.899886)
			(size 0.381 2.0574)
			(layers "F.Cu" "F.Mask" "F.Paste")
			(net "GND")
		)
		(pad "65" smd rect
			(at 0 19.200114)
			(size 0.381 2.0574)
			(layers "F.Cu" "F.Mask" "F.Paste")
			(net "M1_DQ_NODE1_DQ27")
		)
		(pad "66" smd rect
			(at 8.199882 19.500088)
			(size 0.381 2.0574)
			(layers "F.Cu" "F.Mask" "F.Paste")
			(net "M1_DQ_NODE1_DQ30")
		)
		(pad "67" smd rect
			(at 0 19.800062)
			(size 0.381 2.0574)
			(layers "F.Cu" "F.Mask" "F.Paste")
			(net "GND")
		)
		(pad "68" smd rect
			(at 8.199882 20.100036)
			(size 0.381 2.0574)
			(layers "F.Cu" "F.Mask" "F.Paste")
			(net "M1_DQ_NODE1_DQ31")
		)
		(pad "69" smd rect
			(at 0 20.40001)
			(size 0.381 2.0574)
			(layers "F.Cu" "F.Mask" "F.Paste")
			(net "M_DDR3_NODE1_ECC0")
		)
		(pad "70" smd rect
			(at 8.199882 20.699984)
			(size 0.381 2.0574)
			(layers "F.Cu" "F.Mask" "F.Paste")
			(net "GND")
		)
		(pad "71" smd rect
			(at 0 20.999958)
			(size 0.381 2.0574)
			(layers "F.Cu" "F.Mask" "F.Paste")
			(net "M_DDR3_NODE1_ECC1")
		)
		(pad "72" smd rect
			(at 8.199882 21.299932)
			(size 0.381 2.0574)
			(layers "F.Cu" "F.Mask" "F.Paste")
			(net "M_DDR3_NODE1_ECC4")
		)
		(pad "73" smd rect
			(at 0 23.999952)
			(size 0.381 2.0574)
			(layers "F.Cu" "F.Mask" "F.Paste")
			(net "GND")
		)
		(pad "74" smd rect
			(at 8.199882 24.299926)
			(size 0.381 2.0574)
			(layers "F.Cu" "F.Mask" "F.Paste")
			(net "M_DDR3_NODE1_ECC5")
		)
		(pad "75" smd rect
			(at 0 24.5999)
			(size 0.381 2.0574)
			(layers "F.Cu" "F.Mask" "F.Paste")
			(net "M_DDR3_NODE1_DQSECCN")
		)
		(pad "76" smd rect
			(at 8.199882 24.900128)
			(size 0.381 2.0574)
			(layers "F.Cu" "F.Mask" "F.Paste")
			(net "PD_NODE1_DM8")
		)
		(pad "77" smd rect
			(at 0 25.200102)
			(size 0.381 2.0574)
			(layers "F.Cu" "F.Mask" "F.Paste")
			(net "M_DDR3_NODE1_DQSECCP")
		)
		(pad "78" smd rect
			(at 8.199882 25.500076)
			(size 0.381 2.0574)
			(layers "F.Cu" "F.Mask" "F.Paste")
			(net "GND")
		)
		(pad "79" smd rect
			(at 0 25.80005)
			(size 0.381 2.0574)
			(layers "F.Cu" "F.Mask" "F.Paste")
			(net "GND")
		)
		(pad "80" smd rect
			(at 8.199882 26.100024)
			(size 0.381 2.0574)
			(layers "F.Cu" "F.Mask" "F.Paste")
			(net "M_DDR3_NODE1_ECC6")
		)
		(pad "81" smd rect
			(at 0 26.399998)
			(size 0.381 2.0574)
			(layers "F.Cu" "F.Mask" "F.Paste")
			(net "M_DDR3_NODE1_ECC2")
		)
		(pad "82" smd rect
			(at 8.199882 26.699972)
			(size 0.381 2.0574)
			(layers "F.Cu" "F.Mask" "F.Paste")
			(net "M_DDR3_NODE1_ECC7")
		)
		(pad "83" smd rect
			(at 0 26.999946)
			(size 0.381 2.0574)
			(layers "F.Cu" "F.Mask" "F.Paste")
			(net "M_DDR3_NODE1_ECC3")
		)
		(pad "84" smd rect
			(at 8.199882 27.29992)
			(size 0.381 2.0574)
			(layers "F.Cu" "F.Mask" "F.Paste")
			(net "P1V5_NODE1_DDR3_VREF_A_A")
		)
		(pad "85" smd rect
			(at 0 27.599894)
			(size 0.381 2.0574)
			(layers "F.Cu" "F.Mask" "F.Paste")
			(net "PV_VDDR_NODE1")
		)
		(pad "86" smd rect
			(at 8.199882 27.900122)
			(size 0.381 2.0574)
			(layers "F.Cu" "F.Mask" "F.Paste")
			(net "PV_VDDR_NODE1")
		)
		(pad "87" smd rect
			(at 0 28.200096)
			(size 0.381 2.0574)
			(layers "F.Cu" "F.Mask" "F.Paste")
			(net "M_DDR3_NODE1_CKE0")
		)
		(pad "88" smd rect
			(at 8.199882 28.50007)
			(size 0.381 2.0574)
			(layers "F.Cu" "F.Mask" "F.Paste")
			(net "M_DDR3_NODE1_MA15")
		)
		(pad "89" smd rect
			(at 0 28.800044)
			(size 0.381 2.0574)
			(layers "F.Cu" "F.Mask" "F.Paste")
			(net "M_DDR3_NODE1_CKE1")
		)
		(pad "90" smd rect
			(at 8.199882 29.100018)
			(size 0.381 2.0574)
			(layers "F.Cu" "F.Mask" "F.Paste")
			(net "M_DDR3_NODE1_MA14")
		)
		(pad "91" smd rect
			(at 0 29.399992)
			(size 0.381 2.0574)
			(layers "F.Cu" "F.Mask" "F.Paste")
			(net "M_DDR3_NODE1_BS2")
		)
		(pad "92" smd rect
			(at 8.199882 29.699966)
			(size 0.381 2.0574)
			(layers "F.Cu" "F.Mask" "F.Paste")
			(net "M_DDR3_NODE1_MA9")
		)
		(pad "93" smd rect
			(at 0 29.99994)
			(size 0.381 2.0574)
			(layers "F.Cu" "F.Mask" "F.Paste")
			(net "PV_VDDR_NODE1")
		)
		(pad "94" smd rect
			(at 8.199882 30.299914)
			(size 0.381 2.0574)
			(layers "F.Cu" "F.Mask" "F.Paste")
			(net "PV_VDDR_NODE1")
		)
		(pad "95" smd rect
			(at 0 30.599888)
			(size 0.381 2.0574)
			(layers "F.Cu" "F.Mask" "F.Paste")
			(net "M_DDR3_NODE1_MA12")
		)
		(pad "96" smd rect
			(at 8.199882 30.900116)
			(size 0.381 2.0574)
			(layers "F.Cu" "F.Mask" "F.Paste")
			(net "M_DDR3_NODE1_MA11")
		)
		(pad "97" smd rect
			(at 0 31.20009)
			(size 0.381 2.0574)
			(layers "F.Cu" "F.Mask" "F.Paste")
			(net "M_DDR3_NODE1_MA8")
		)
		(pad "98" smd rect
			(at 8.199882 31.500064)
			(size 0.381 2.0574)
			(layers "F.Cu" "F.Mask" "F.Paste")
			(net "M_DDR3_NODE1_MA7")
		)
		(pad "99" smd rect
			(at 0 31.800038)
			(size 0.381 2.0574)
			(layers "F.Cu" "F.Mask" "F.Paste")
			(net "M_DDR3_NODE1_MA5")
		)
		(pad "100" smd rect
			(at 8.199882 32.100012)
			(size 0.381 2.0574)
			(layers "F.Cu" "F.Mask" "F.Paste")
			(net "M_DDR3_NODE1_MA6")
		)
		(pad "101" smd rect
			(at 0 32.399986)
			(size 0.381 2.0574)
			(layers "F.Cu" "F.Mask" "F.Paste")
			(net "PV_VDDR_NODE1")
		)
		(pad "102" smd rect
			(at 8.199882 32.69996)
			(size 0.381 2.0574)
			(layers "F.Cu" "F.Mask" "F.Paste")
			(net "PV_VDDR_NODE1")
		)
		(pad "103" smd rect
			(at 0 32.999934)
			(size 0.381 2.0574)
			(layers "F.Cu" "F.Mask" "F.Paste")
			(net "M_DDR3_NODE1_MA3")
		)
		(pad "104" smd rect
			(at 8.199882 33.299908)
			(size 0.381 2.0574)
			(layers "F.Cu" "F.Mask" "F.Paste")
			(net "M_DDR3_NODE1_MA4")
		)
		(pad "105" smd rect
			(at 0 33.599882)
			(size 0.381 2.0574)
			(layers "F.Cu" "F.Mask" "F.Paste")
			(net "M_DDR3_NODE1_MA1")
		)
		(pad "106" smd rect
			(at 8.199882 33.90011)
			(size 0.381 2.0574)
			(layers "F.Cu" "F.Mask" "F.Paste")
			(net "M_DDR3_NODE1_MA2")
		)
		(pad "107" smd rect
			(at 0 34.200084)
			(size 0.381 2.0574)
			(layers "F.Cu" "F.Mask" "F.Paste")
			(net "M_DDR3_NODE1_MA0")
		)
		(pad "108" smd rect
			(at 8.199882 34.500058)
			(size 0.381 2.0574)
			(layers "F.Cu" "F.Mask" "F.Paste")
			(net "M_DDR3_NODE1_BS1")
		)
		(pad "109" smd rect
			(at 0 34.800032)
			(size 0.381 2.0574)
			(layers "F.Cu" "F.Mask" "F.Paste")
			(net "PV_VDDR_NODE1")
		)
		(pad "110" smd rect
			(at 8.199882 35.100006)
			(size 0.381 2.0574)
			(layers "F.Cu" "F.Mask" "F.Paste")
			(net "PV_VDDR_NODE1")
		)
		(pad "111" smd rect
			(at 0 35.39998)
			(size 0.381 2.0574)
			(layers "F.Cu" "F.Mask" "F.Paste")
			(net "M_DDR3_NODE1_CK0P")
		)
		(pad "112" smd rect
			(at 8.199882 35.699954)
			(size 0.381 2.0574)
			(layers "F.Cu" "F.Mask" "F.Paste")
			(net "M_DDR3_NODE1_CK1P")
		)
		(pad "113" smd rect
			(at 0 35.999928)
			(size 0.381 2.0574)
			(layers "F.Cu" "F.Mask" "F.Paste")
			(net "M_DDR3_NODE1_CK0N")
		)
		(pad "114" smd rect
			(at 8.199882 36.299902)
			(size 0.381 2.0574)
			(layers "F.Cu" "F.Mask" "F.Paste")
			(net "M_DDR3_NODE1_CK1N")
		)
		(pad "115" smd rect
			(at 0 36.599876)
			(size 0.381 2.0574)
			(layers "F.Cu" "F.Mask" "F.Paste")
			(net "PV_VDDR_NODE1")
		)
		(pad "116" smd rect
			(at 8.199882 36.900104)
			(size 0.381 2.0574)
			(layers "F.Cu" "F.Mask" "F.Paste")
			(net "PV_VDDR_NODE1")
		)
		(pad "117" smd rect
			(at 0 37.200078)
			(size 0.381 2.0574)
			(layers "F.Cu" "F.Mask" "F.Paste")
			(net "M_DDR3_NODE1_MA10")
		)
		(pad "118" smd rect
			(at 8.199882 37.500052)
			(size 0.381 2.0574)
			(layers "F.Cu" "F.Mask" "F.Paste")
			(net "TP_DDR3_NODE1_CS3_L")
		)
		(pad "119" smd rect
			(at 0 37.800026)
			(size 0.381 2.0574)
			(layers "F.Cu" "F.Mask" "F.Paste")
			(net "M_DDR3_NODE1_BS0")
		)
		(pad "120" smd rect
			(at 8.199882 38.1)
			(size 0.381 2.0574)
			(layers "F.Cu" "F.Mask" "F.Paste")
			(net "TP_DDR3_NODE1_CS2_L")
		)
		(pad "121" smd rect
			(at 0 38.399974)
			(size 0.381 2.0574)
			(layers "F.Cu" "F.Mask" "F.Paste")
			(net "M_DDR3_NODE1_WE_L")
		)
		(pad "122" smd rect
			(at 8.199882 38.699948)
			(size 0.381 2.0574)
			(layers "F.Cu" "F.Mask" "F.Paste")
			(net "M_DDR3_NODE1_RAS_L")
		)
		(pad "123" smd rect
			(at 0 38.999922)
			(size 0.381 2.0574)
			(layers "F.Cu" "F.Mask" "F.Paste")
			(net "PV_VDDR_NODE1")
		)
		(pad "124" smd rect
			(at 8.199882 39.299896)
			(size 0.381 2.0574)
			(layers "F.Cu" "F.Mask" "F.Paste")
			(net "PV_VDDR_NODE1")
		)
		(pad "125" smd rect
			(at 0 39.600124)
			(size 0.381 2.0574)
			(layers "F.Cu" "F.Mask" "F.Paste")
			(net "M_DDR3_NODE1_CAS_L")
		)
		(pad "126" smd rect
			(at 8.199882 39.900098)
			(size 0.381 2.0574)
			(layers "F.Cu" "F.Mask" "F.Paste")
			(net "M_DDR3_NODE1_ODT0")
		)
		(pad "127" smd rect
			(at 0 40.200072)
			(size 0.381 2.0574)
			(layers "F.Cu" "F.Mask" "F.Paste")
			(net "M_DDR3_NODE1_CS0_L")
		)
		(pad "128" smd rect
			(at 8.199882 40.500046)
			(size 0.381 2.0574)
			(layers "F.Cu" "F.Mask" "F.Paste")
			(net "M_DDR3_NODE1_ODT1")
		)
		(pad "129" smd rect
			(at 0 40.80002)
			(size 0.381 2.0574)
			(layers "F.Cu" "F.Mask" "F.Paste")
			(net "M_DDR3_NODE1_CS1_L")
		)
		(pad "130" smd rect
			(at 8.199882 41.099994)
			(size 0.381 2.0574)
			(layers "F.Cu" "F.Mask" "F.Paste")
			(net "M_DDR3_NODE1_MA13")
		)
		(pad "131" smd rect
			(at 0 41.399968)
			(size 0.381 2.0574)
			(layers "F.Cu" "F.Mask" "F.Paste")
			(net "PV_VDDR_NODE1")
		)
		(pad "132" smd rect
			(at 8.199882 41.699942)
			(size 0.381 2.0574)
			(layers "F.Cu" "F.Mask" "F.Paste")
			(net "PV_VDDR_NODE1")
		)
		(pad "133" smd rect
			(at 0 41.999916)
			(size 0.381 2.0574)
			(layers "F.Cu" "F.Mask" "F.Paste")
			(net "M1_DQ_NODE1_DQ32")
		)
		(pad "134" smd rect
			(at 8.199882 42.29989)
			(size 0.381 2.0574)
			(layers "F.Cu" "F.Mask" "F.Paste")
			(net "M1_DQ_NODE1_DQ36")
		)
		(pad "135" smd rect
			(at 0 42.600118)
			(size 0.381 2.0574)
			(layers "F.Cu" "F.Mask" "F.Paste")
			(net "M1_DQ_NODE1_DQ33")
		)
		(pad "136" smd rect
			(at 8.199882 42.900092)
			(size 0.381 2.0574)
			(layers "F.Cu" "F.Mask" "F.Paste")
			(net "M1_DQ_NODE1_DQ37")
		)
		(pad "137" smd rect
			(at 0 43.200066)
			(size 0.381 2.0574)
			(layers "F.Cu" "F.Mask" "F.Paste")
			(net "GND")
		)
		(pad "138" smd rect
			(at 8.199882 43.50004)
			(size 0.381 2.0574)
			(layers "F.Cu" "F.Mask" "F.Paste")
			(net "GND")
		)
		(pad "139" smd rect
			(at 0 43.800014)
			(size 0.381 2.0574)
			(layers "F.Cu" "F.Mask" "F.Paste")
			(net "M_DDR3_NODE1_DQS4N")
		)
		(pad "140" smd rect
			(at 8.199882 44.099988)
			(size 0.381 2.0574)
			(layers "F.Cu" "F.Mask" "F.Paste")
			(net "PD_NODE1_DM4")
		)
		(pad "141" smd rect
			(at 0 44.399962)
			(size 0.381 2.0574)
			(layers "F.Cu" "F.Mask" "F.Paste")
			(net "M_DDR3_NODE1_DQS4P")
		)
		(pad "142" smd rect
			(at 8.199882 44.699936)
			(size 0.381 2.0574)
			(layers "F.Cu" "F.Mask" "F.Paste")
			(net "M1_DQ_NODE1_DQ38")
		)
		(pad "143" smd rect
			(at 0 44.99991)
			(size 0.381 2.0574)
			(layers "F.Cu" "F.Mask" "F.Paste")
			(net "GND")
		)
		(pad "144" smd rect
			(at 8.199882 45.299884)
			(size 0.381 2.0574)
			(layers "F.Cu" "F.Mask" "F.Paste")
			(net "M1_DQ_NODE1_DQ39")
		)
		(pad "145" smd rect
			(at 0 45.600112)
			(size 0.381 2.0574)
			(layers "F.Cu" "F.Mask" "F.Paste")
			(net "M1_DQ_NODE1_DQ34")
		)
		(pad "146" smd rect
			(at 8.199882 45.900086)
			(size 0.381 2.0574)
			(layers "F.Cu" "F.Mask" "F.Paste")
			(net "GND")
		)
		(pad "147" smd rect
			(at 0 46.20006)
			(size 0.381 2.0574)
			(layers "F.Cu" "F.Mask" "F.Paste")
			(net "M1_DQ_NODE1_DQ35")
		)
		(pad "148" smd rect
			(at 8.199882 46.500034)
			(size 0.381 2.0574)
			(layers "F.Cu" "F.Mask" "F.Paste")
			(net "M1_DQ_NODE1_DQ44")
		)
		(pad "149" smd rect
			(at 0 46.800008)
			(size 0.381 2.0574)
			(layers "F.Cu" "F.Mask" "F.Paste")
			(net "GND")
		)
		(pad "150" smd rect
			(at 8.199882 47.099982)
			(size 0.381 2.0574)
			(layers "F.Cu" "F.Mask" "F.Paste")
			(net "M1_DQ_NODE1_DQ45")
		)
		(pad "151" smd rect
			(at 0 47.399956)
			(size 0.381 2.0574)
			(layers "F.Cu" "F.Mask" "F.Paste")
			(net "M1_DQ_NODE1_DQ40")
		)
		(pad "152" smd rect
			(at 8.199882 47.69993)
			(size 0.381 2.0574)
			(layers "F.Cu" "F.Mask" "F.Paste")
			(net "GND")
		)
		(pad "153" smd rect
			(at 0 47.999904)
			(size 0.381 2.0574)
			(layers "F.Cu" "F.Mask" "F.Paste")
			(net "M1_DQ_NODE1_DQ41")
		)
		(pad "154" smd rect
			(at 8.199882 48.299878)
			(size 0.381 2.0574)
			(layers "F.Cu" "F.Mask" "F.Paste")
			(net "M_DDR3_NODE1_DQS5N")
		)
		(pad "155" smd rect
			(at 0 48.600106)
			(size 0.381 2.0574)
			(layers "F.Cu" "F.Mask" "F.Paste")
			(net "GND")
		)
		(pad "156" smd rect
			(at 8.199882 48.90008)
			(size 0.381 2.0574)
			(layers "F.Cu" "F.Mask" "F.Paste")
			(net "M_DDR3_NODE1_DQS5P")
		)
		(pad "157" smd rect
			(at 0 49.200054)
			(size 0.381 2.0574)
			(layers "F.Cu" "F.Mask" "F.Paste")
			(net "PD_NODE1_DM5")
		)
		(pad "158" smd rect
			(at 8.199882 49.500028)
			(size 0.381 2.0574)
			(layers "F.Cu" "F.Mask" "F.Paste")
			(net "GND")
		)
		(pad "159" smd rect
			(at 0 49.800002)
			(size 0.381 2.0574)
			(layers "F.Cu" "F.Mask" "F.Paste")
			(net "M1_DQ_NODE1_DQ42")
		)
		(pad "160" smd rect
			(at 8.199882 50.099976)
			(size 0.381 2.0574)
			(layers "F.Cu" "F.Mask" "F.Paste")
			(net "M1_DQ_NODE1_DQ46")
		)
		(pad "161" smd rect
			(at 0 50.39995)
			(size 0.381 2.0574)
			(layers "F.Cu" "F.Mask" "F.Paste")
			(net "M1_DQ_NODE1_DQ43")
		)
		(pad "162" smd rect
			(at 8.199882 50.699924)
			(size 0.381 2.0574)
			(layers "F.Cu" "F.Mask" "F.Paste")
			(net "M1_DQ_NODE1_DQ47")
		)
		(pad "163" smd rect
			(at 0 50.999898)
			(size 0.381 2.0574)
			(layers "F.Cu" "F.Mask" "F.Paste")
			(net "GND")
		)
		(pad "164" smd rect
			(at 8.199882 51.299872)
			(size 0.381 2.0574)
			(layers "F.Cu" "F.Mask" "F.Paste")
			(net "GND")
		)
		(pad "165" smd rect
			(at 0 51.6001)
			(size 0.381 2.0574)
			(layers "F.Cu" "F.Mask" "F.Paste")
			(net "M1_DQ_NODE1_DQ48")
		)
		(pad "166" smd rect
			(at 8.199882 51.900074)
			(size 0.381 2.0574)
			(layers "F.Cu" "F.Mask" "F.Paste")
			(net "M1_DQ_NODE1_DQ52")
		)
		(pad "167" smd rect
			(at 0 52.200048)
			(size 0.381 2.0574)
			(layers "F.Cu" "F.Mask" "F.Paste")
			(net "M1_DQ_NODE1_DQ49")
		)
		(pad "168" smd rect
			(at 8.199882 52.500022)
			(size 0.381 2.0574)
			(layers "F.Cu" "F.Mask" "F.Paste")
			(net "M1_DQ_NODE1_DQ53")
		)
		(pad "169" smd rect
			(at 0 52.799996)
			(size 0.381 2.0574)
			(layers "F.Cu" "F.Mask" "F.Paste")
			(net "GND")
		)
		(pad "170" smd rect
			(at 8.199882 53.09997)
			(size 0.381 2.0574)
			(layers "F.Cu" "F.Mask" "F.Paste")
			(net "GND")
		)
		(pad "171" smd rect
			(at 0 53.399944)
			(size 0.381 2.0574)
			(layers "F.Cu" "F.Mask" "F.Paste")
			(net "M_DDR3_NODE1_DQS6N")
		)
		(pad "172" smd rect
			(at 8.199882 53.699918)
			(size 0.381 2.0574)
			(layers "F.Cu" "F.Mask" "F.Paste")
			(net "PD_NODE1_DM6")
		)
		(pad "173" smd rect
			(at 0 53.999892)
			(size 0.381 2.0574)
			(layers "F.Cu" "F.Mask" "F.Paste")
			(net "M_DDR3_NODE1_DQS6P")
		)
		(pad "174" smd rect
			(at 8.199882 54.30012)
			(size 0.381 2.0574)
			(layers "F.Cu" "F.Mask" "F.Paste")
			(net "M1_DQ_NODE1_DQ54")
		)
		(pad "175" smd rect
			(at 0 54.600094)
			(size 0.381 2.0574)
			(layers "F.Cu" "F.Mask" "F.Paste")
			(net "GND")
		)
		(pad "176" smd rect
			(at 8.199882 54.900068)
			(size 0.381 2.0574)
			(layers "F.Cu" "F.Mask" "F.Paste")
			(net "M1_DQ_NODE1_DQ55")
		)
		(pad "177" smd rect
			(at 0 55.200042)
			(size 0.381 2.0574)
			(layers "F.Cu" "F.Mask" "F.Paste")
			(net "M1_DQ_NODE1_DQ50")
		)
		(pad "178" smd rect
			(at 8.199882 55.500016)
			(size 0.381 2.0574)
			(layers "F.Cu" "F.Mask" "F.Paste")
			(net "GND")
		)
		(pad "179" smd rect
			(at 0 55.79999)
			(size 0.381 2.0574)
			(layers "F.Cu" "F.Mask" "F.Paste")
			(net "M1_DQ_NODE1_DQ51")
		)
		(pad "180" smd rect
			(at 8.199882 56.099964)
			(size 0.381 2.0574)
			(layers "F.Cu" "F.Mask" "F.Paste")
			(net "M1_DQ_NODE1_DQ60")
		)
		(pad "181" smd rect
			(at 0 56.399938)
			(size 0.381 2.0574)
			(layers "F.Cu" "F.Mask" "F.Paste")
			(net "GND")
		)
		(pad "182" smd rect
			(at 8.199882 56.699912)
			(size 0.381 2.0574)
			(layers "F.Cu" "F.Mask" "F.Paste")
			(net "M1_DQ_NODE1_DQ61")
		)
		(pad "183" smd rect
			(at 0 56.999886)
			(size 0.381 2.0574)
			(layers "F.Cu" "F.Mask" "F.Paste")
			(net "M1_DQ_NODE1_DQ56")
		)
		(pad "184" smd rect
			(at 8.199882 57.300114)
			(size 0.381 2.0574)
			(layers "F.Cu" "F.Mask" "F.Paste")
			(net "GND")
		)
		(pad "185" smd rect
			(at 0 57.600088)
			(size 0.381 2.0574)
			(layers "F.Cu" "F.Mask" "F.Paste")
			(net "M1_DQ_NODE1_DQ57")
		)
		(pad "186" smd rect
			(at 8.199882 57.900062)
			(size 0.381 2.0574)
			(layers "F.Cu" "F.Mask" "F.Paste")
			(net "M_DDR3_NODE1_DQS7N")
		)
		(pad "187" smd rect
			(at 0 58.200036)
			(size 0.381 2.0574)
			(layers "F.Cu" "F.Mask" "F.Paste")
			(net "GND")
		)
		(pad "188" smd rect
			(at 8.199882 58.50001)
			(size 0.381 2.0574)
			(layers "F.Cu" "F.Mask" "F.Paste")
			(net "M_DDR3_NODE1_DQS7P")
		)
		(pad "189" smd rect
			(at 0 58.799984)
			(size 0.381 2.0574)
			(layers "F.Cu" "F.Mask" "F.Paste")
			(net "PD_NODE1_DM7")
		)
		(pad "190" smd rect
			(at 8.199882 59.099958)
			(size 0.381 2.0574)
			(layers "F.Cu" "F.Mask" "F.Paste")
			(net "GND")
		)
		(pad "191" smd rect
			(at 0 59.399932)
			(size 0.381 2.0574)
			(layers "F.Cu" "F.Mask" "F.Paste")
			(net "M1_DQ_NODE1_DQ58")
		)
		(pad "192" smd rect
			(at 8.199882 59.699906)
			(size 0.381 2.0574)
			(layers "F.Cu" "F.Mask" "F.Paste")
			(net "M1_DQ_NODE1_DQ62")
		)
		(pad "193" smd rect
			(at 0 59.99988)
			(size 0.381 2.0574)
			(layers "F.Cu" "F.Mask" "F.Paste")
			(net "M1_DQ_NODE1_DQ59")
		)
		(pad "194" smd rect
			(at 8.199882 60.300108)
			(size 0.381 2.0574)
			(layers "F.Cu" "F.Mask" "F.Paste")
			(net "M1_DQ_NODE1_DQ63")
		)
		(pad "195" smd rect
			(at 0 60.600082)
			(size 0.381 2.0574)
			(layers "F.Cu" "F.Mask" "F.Paste")
			(net "GND")
		)
		(pad "196" smd rect
			(at 8.199882 60.900056)
			(size 0.381 2.0574)
			(layers "F.Cu" "F.Mask" "F.Paste")
			(net "GND")
		)
		(pad "197" smd rect
			(at 0 61.20003)
			(size 0.381 2.0574)
			(layers "F.Cu" "F.Mask" "F.Paste")
			(net "GND")
		)
		(pad "198" smd rect
			(at 8.199882 61.500004)
			(size 0.381 2.0574)
			(layers "F.Cu" "F.Mask" "F.Paste")
			(net "TP_NODE1_ERR_OUT_DIMM0")
		)
		(pad "199" smd rect
			(at 0 61.799978)
			(size 0.381 2.0574)
			(layers "F.Cu" "F.Mask" "F.Paste")
			(net "P3V3_NODE1")
		)
		(pad "200" smd rect
			(at 8.199882 62.099952)
			(size 0.381 2.0574)
			(layers "F.Cu" "F.Mask" "F.Paste")
			(net "SMB_DIMM_NODE1_DAT")
		)
		(pad "201" smd rect
			(at 0 62.399926)
			(size 0.381 2.0574)
			(layers "F.Cu" "F.Mask" "F.Paste")
			(net "GND")
		)
		(pad "202" smd rect
			(at 8.199882 62.6999)
			(size 0.381 2.0574)
			(layers "F.Cu" "F.Mask" "F.Paste")
			(net "SMB_DIMM_NODE1_CLK")
		)
		(pad "203" smd rect
			(at 0 63.000128)
			(size 0.381 2.0574)
			(layers "F.Cu" "F.Mask" "F.Paste")
			(net "PV_VTT_DDR_NODE1")
		)
		(pad "204" smd rect
			(at 8.199882 63.300102)
			(size 0.381 2.0574)
			(layers "F.Cu" "F.Mask" "F.Paste")
			(net "PV_VTT_DDR_NODE1")
		)
		(pad "G1" smd rect
			(at 16.100044 -5.80009)
			(size 4.6228 4.699)
			(layers "F.Cu" "F.Mask" "F.Paste")
			(net "GND")
		)
		(pad "G2" smd rect
			(at 16.100044 69.099938)
			(size 4.6228 4.699)
			(layers "F.Cu" "F.Mask" "F.Paste")
			(net "GND")
		)
		(zone
			(layers "F.Cu" "B.Cu" "In1.Cu" "In2.Cu" "In3.Cu" "In4.Cu" "In5.Cu" "In6.Cu"
				"In7.Cu" "In8.Cu"
			)
			(hatch none 0.5)
			(connect_pads
				(clearance 0)
			)
			(min_thickness 0.25)
			(keepout
				(tracks not_allowed)
				(vias allowed)
				(pads allowed)
				(copperpour not_allowed)
				(footprints allowed)
			)
			(placement
				(enabled no)
				(sheetname "")
			)
			(fill
				(thermal_gap 0.5)
				(thermal_bridge_width 0.5)
				(island_removal_mode 0)
			)
			(polygon
				(pts
					(arc
						(start 105.400094 -26.040588)
						(mid 105.400094 -24.059388)
						(end 105.400094 -26.040588)
					)
				)
			)
		)
		(zone
			(layers "F.Cu" "B.Cu" "In1.Cu" "In2.Cu" "In3.Cu" "In4.Cu" "In5.Cu" "In6.Cu"
				"In7.Cu" "In8.Cu"
			)
			(hatch none 0.5)
			(connect_pads
				(clearance 0)
			)
			(min_thickness 0.25)
			(keepout
				(tracks not_allowed)
				(vias allowed)
				(pads allowed)
				(copperpour not_allowed)
				(footprints allowed)
			)
			(placement
				(enabled no)
				(sheetname "")
			)
			(fill
				(thermal_gap 0.5)
				(thermal_bridge_width 0.5)
				(island_removal_mode 0)
			)
			(polygon
				(pts
					(arc
						(start 38.600126 -26.282142)
						(mid 38.600126 -23.817834)
						(end 38.600126 -26.282142)
					)
				)
			)
		)
	)
	(footprint ""
		(layer "F.Cu")
		(at 108.67263 -164.1094)
		(property "Reference" "R759"
			(at 86.51875 69.344032 0)
			(unlocked yes)
			(layer "F.SilkS")
			(effects
				(font
					(size 0.7874 0.5842)
					(thickness 0.1524)
				)
				(justify left)
			)
		)
		(property "Value" ""
			(at 0 0 0)
			(layer "F.Fab")
			(effects
				(font
					(size 1.27 1.27)
				)
			)
		)
		(duplicate_pad_numbers_are_jumpers no)
		(fp_line
			(start -0.7874 -0.4064)
			(end 0.7874 -0.4064)
			(stroke
				(width 0.1524)
				(type default)
			)
			(layer "F.SilkS")
		)
		(fp_line
			(start -0.7874 0.4064)
			(end -0.7874 -0.4064)
			(stroke
				(width 0.1524)
				(type default)
			)
			(layer "F.SilkS")
		)
		(fp_line
			(start 0.7874 -0.4064)
			(end 0.7874 0.4064)
			(stroke
				(width 0.1524)
				(type default)
			)
			(layer "F.SilkS")
		)
		(fp_line
			(start 0.7874 0.4064)
			(end -0.7874 0.4064)
			(stroke
				(width 0.1524)
				(type default)
			)
			(layer "F.SilkS")
		)
		(fp_poly
			(pts
				(xy -0.508 0.2794) (xy -0.508 0.2286) (xy -0.635 0.2286) (xy -0.635 -0.254) (xy -0.5334 -0.254)
				(xy -0.5334 -0.2794) (xy 0.5334 -0.2794) (xy 0.5334 -0.254) (xy 0.635 -0.254) (xy 0.635 0.254) (xy 0.5334 0.254)
				(xy 0.5334 0.2794)
			)
			(stroke
				(width 0)
				(type default)
			)
			(fill no)
			(layer "F.CrtYd")
		)
		(pad "1" smd rect
			(at 0.40005 0)
			(size 0.4572 0.508)
			(layers "F.Cu" "F.Mask" "F.Paste")
			(net "TMP05_FUNC1")
		)
		(pad "2" smd rect
			(at -0.40005 0)
			(size 0.4572 0.508)
			(layers "F.Cu" "F.Mask" "F.Paste")
			(net "P3V3_NODE1")
		)
	)
	(footprint ""
		(layer "F.Cu")
		(at 27.438604 -123.262644 -90)
		(property "Reference" "R1233"
			(at 4.09702 1.30175 90)
			(unlocked yes)
			(layer "F.SilkS")
			(effects
				(font
					(size 0.7874 0.5842)
					(thickness 0.1524)
				)
				(justify left)
			)
		)
		(property "Value" ""
			(at 0 0 270)
			(layer "F.Fab")
			(effects
				(font
					(size 1.27 1.27)
				)
			)
		)
		(duplicate_pad_numbers_are_jumpers no)
		(fp_line
			(start -0.7874 0.4064)
			(end -0.7874 -0.4064)
			(stroke
				(width 0.1524)
				(type default)
			)
			(layer "F.SilkS")
		)
		(fp_line
			(start 0.7874 0.4064)
			(end -0.7874 0.4064)
			(stroke
				(width 0.1524)
				(type default)
			)
			(layer "F.SilkS")
		)
		(fp_line
			(start -0.7874 -0.4064)
			(end 0.7874 -0.4064)
			(stroke
				(width 0.1524)
				(type default)
			)
			(layer "F.SilkS")
		)
		(fp_line
			(start 0.7874 -0.4064)
			(end 0.7874 0.4064)
			(stroke
				(width 0.1524)
				(type default)
			)
			(layer "F.SilkS")
		)
		(fp_poly
			(pts
				(xy -0.508 0.2794) (xy -0.508 0.2286) (xy -0.635 0.2286) (xy -0.635 -0.254) (xy -0.5334 -0.254)
				(xy -0.5334 -0.2794) (xy 0.5334 -0.2794) (xy 0.5334 -0.254) (xy 0.635 -0.254) (xy 0.635 0.254) (xy 0.5334 0.254)
				(xy 0.5334 0.2794)
			)
			(stroke
				(width 0)
				(type default)
			)
			(fill no)
			(layer "F.CrtYd")
		)
		(pad "1" smd rect
			(at 0.40005 0 270)
			(size 0.4572 0.508)
			(layers "F.Cu" "F.Mask" "F.Paste")
			(net "GND")
		)
		(pad "2" smd rect
			(at -0.40005 0 270)
			(size 0.4572 0.508)
			(layers "F.Cu" "F.Mask" "F.Paste")
			(net "FM_CPLD_NODE1_P1V538_BMC_EN")
		)
	)
	(footprint ""
		(layer "F.Cu")
		(at 72.500998 -10.893044 180)
		(property "Reference" "PC43"
			(at -2.883154 -0.431038 0)
			(unlocked yes)
			(layer "F.SilkS")
			(effects
				(font
					(size 0.7874 0.5842)
					(thickness 0.1524)
				)
				(justify left)
			)
		)
		(property "Value" ""
			(at 0 0 180)
			(layer "F.Fab")
			(effects
				(font
					(size 1.27 1.27)
				)
			)
		)
		(duplicate_pad_numbers_are_jumpers no)
		(fp_line
			(start 2.2098 0.9398)
			(end -2.2098 0.9398)
			(stroke
				(width 0.1524)
				(type default)
			)
			(layer "F.SilkS")
		)
		(fp_line
			(start 2.2098 -0.9398)
			(end 2.2098 0.9398)
			(stroke
				(width 0.1524)
				(type default)
			)
			(layer "F.SilkS")
		)
		(fp_line
			(start 0 -0.9398)
			(end 0 0.9398)
			(stroke
				(width 0.1524)
				(type default)
			)
			(layer "F.SilkS")
		)
		(fp_line
			(start -2.2098 0.9398)
			(end -2.2098 -0.9398)
			(stroke
				(width 0.1524)
				(type default)
			)
			(layer "F.SilkS")
		)
		(fp_line
			(start -2.2098 -0.9398)
			(end 2.2098 -0.9398)
			(stroke
				(width 0.1524)
				(type default)
			)
			(layer "F.SilkS")
		)
		(fp_poly
			(pts
				(xy -1.6764 0.889) (xy -1.6764 0.7874) (xy -2.0574 0.7874) (xy -2.0574 -0.7874) (xy -1.6764 -0.7874)
				(xy -1.6764 -0.9398) (xy 1.6764 -0.9398) (xy 1.6764 -0.7874) (xy 2.0574 -0.7874) (xy 2.0574 0.7874)
				(xy 1.6764 0.7874) (xy 1.6764 0.9398) (xy -1.6764 0.9398)
			)
			(stroke
				(width 0)
				(type default)
			)
			(fill no)
			(layer "F.CrtYd")
		)
		(fp_line
			(start 1.700022 0.899922)
			(end -1.700022 0.899922)
			(stroke
				(width 0.1)
				(type default)
			)
			(layer "F.Fab")
		)
		(fp_line
			(start 1.700022 -0.899922)
			(end 1.700022 0.899922)
			(stroke
				(width 0.1)
				(type default)
			)
			(layer "F.Fab")
		)
		(fp_line
			(start -1.700022 0.899922)
			(end -1.700022 -0.899922)
			(stroke
				(width 0.1)
				(type default)
			)
			(layer "F.Fab")
		)
		(fp_line
			(start -1.700022 -0.899922)
			(end 1.700022 -0.899922)
			(stroke
				(width 0.1)
				(type default)
			)
			(layer "F.Fab")
		)
		(pad "1" smd rect
			(at 1.4732 0 180)
			(size 1.1684 1.5748)
			(layers "F.Cu" "F.Mask" "F.Paste")
			(net "P12V_AUX")
		)
		(pad "2" smd rect
			(at -1.4732 0 180)
			(size 1.1684 1.5748)
			(layers "F.Cu" "F.Mask" "F.Paste")
			(net "GND")
		)
	)
	(footprint ""
		(layer "F.Cu")
		(at 185.817764 -113.548922 90)
		(property "Reference" "R1029"
			(at -3.457448 -0.987806 0)
			(unlocked yes)
			(layer "F.SilkS")
			(effects
				(font
					(size 0.7874 0.5842)
					(thickness 0.1524)
				)
				(justify left)
			)
		)
		(property "Value" ""
			(at 0 0 90)
			(layer "F.Fab")
			(effects
				(font
					(size 1.27 1.27)
				)
			)
		)
		(duplicate_pad_numbers_are_jumpers no)
		(fp_line
			(start 0.7874 -0.4064)
			(end 0.7874 0.4064)
			(stroke
				(width 0.1524)
				(type default)
			)
			(layer "F.SilkS")
		)
		(fp_line
			(start -0.7874 -0.4064)
			(end 0.7874 -0.4064)
			(stroke
				(width 0.1524)
				(type default)
			)
			(layer "F.SilkS")
		)
		(fp_line
			(start 0.7874 0.4064)
			(end -0.7874 0.4064)
			(stroke
				(width 0.1524)
				(type default)
			)
			(layer "F.SilkS")
		)
		(fp_line
			(start -0.7874 0.4064)
			(end -0.7874 -0.4064)
			(stroke
				(width 0.1524)
				(type default)
			)
			(layer "F.SilkS")
		)
		(fp_poly
			(pts
				(xy -0.508 0.2794) (xy -0.508 0.2286) (xy -0.635 0.2286) (xy -0.635 -0.254) (xy -0.5334 -0.254)
				(xy -0.5334 -0.2794) (xy 0.5334 -0.2794) (xy 0.5334 -0.254) (xy 0.635 -0.254) (xy 0.635 0.254) (xy 0.5334 0.254)
				(xy 0.5334 0.2794)
			)
			(stroke
				(width 0)
				(type default)
			)
			(fill no)
			(layer "F.CrtYd")
		)
		(pad "1" smd rect
			(at 0.40005 0 90)
			(size 0.4572 0.508)
			(layers "F.Cu" "F.Mask" "F.Paste")
			(net "PWRGD_NODE1_P12V_PG_R")
		)
		(pad "2" smd rect
			(at -0.40005 0 90)
			(size 0.4572 0.508)
			(layers "F.Cu" "F.Mask" "F.Paste")
			(net "GND")
		)
	)
	(footprint ""
		(layer "F.Cu")
		(at 36.203128 -11.393678)
		(property "Reference" "PU7"
			(at -7.701788 1.185164 0)
			(unlocked yes)
			(layer "F.SilkS")
			(effects
				(font
					(size 0.7874 0.5842)
					(thickness 0.1524)
				)
			)
		)
		(property "Value" ""
			(at 0 0 0)
			(layer "F.Fab")
			(effects
				(font
					(size 1.27 1.27)
				)
			)
		)
		(duplicate_pad_numbers_are_jumpers no)
		(fp_line
			(start 0.3302 -0.0762)
			(end 0.7112 -0.4572)
			(stroke
				(width 0.1524)
				(type default)
			)
			(layer "F.SilkS")
		)
		(fp_line
			(start 0.3302 0.0254)
			(end 0.3302 -0.0762)
			(stroke
				(width 0.1524)
				(type default)
			)
			(layer "F.SilkS")
		)
		(fp_line
			(start 0.3302 2.159)
			(end 0.3302 2.6416)
			(stroke
				(width 0.1524)
				(type default)
			)
			(layer "F.SilkS")
		)
		(fp_line
			(start 0.3302 2.6416)
			(end 0.8128 2.6416)
			(stroke
				(width 0.1524)
				(type default)
			)
			(layer "F.SilkS")
		)
		(fp_line
			(start 0.7112 -0.4572)
			(end 0.8128 -0.4572)
			(stroke
				(width 0.1524)
				(type default)
			)
			(layer "F.SilkS")
		)
		(fp_line
			(start 2.9718 -0.4572)
			(end 3.429 -0.4572)
			(stroke
				(width 0.1524)
				(type default)
			)
			(layer "F.SilkS")
		)
		(fp_line
			(start 3.429 -0.4572)
			(end 3.429 0.0254)
			(stroke
				(width 0.1524)
				(type default)
			)
			(layer "F.SilkS")
		)
		(fp_line
			(start 3.429 2.1844)
			(end 3.429 2.6416)
			(stroke
				(width 0.1524)
				(type default)
			)
			(layer "F.SilkS")
		)
		(fp_line
			(start 3.429 2.6416)
			(end 2.9464 2.6416)
			(stroke
				(width 0.1524)
				(type default)
			)
			(layer "F.SilkS")
		)
		(fp_poly
			(pts
				(xy -0.85852 0.480568) (xy -0.85852 -0.144272) (xy -0.3048 0.183896)
			)
			(stroke
				(width 0)
				(type default)
			)
			(fill yes)
			(layer "F.SilkS")
		)
		(fp_poly
			(pts
				(xy 3.429508 2.642108) (xy 3.429508 2.0828) (xy 3.429508 2.032) (xy 3.937 2.032) (xy 3.937 0.1524)
				(xy 3.429508 0.1524) (xy 3.429508 0.127) (xy 3.429508 0.1016) (xy 3.429508 -0.457708) (xy 2.8702 -0.457708)
				(xy 2.8194 -0.457708) (xy 2.8194 -0.9652) (xy 0.9398 -0.9652) (xy 0.9398 -0.457708) (xy 0.889 -0.457708)
				(xy 0.329692 -0.457708) (xy 0.329692 0.1016) (xy 0.3302 0.1016) (xy 0.3302 0.1524) (xy -0.1778 0.1524)
				(xy -0.1778 2.032) (xy 0.329692 2.032) (xy 0.329692 2.0828) (xy 0.329692 2.642108) (xy 0.889 2.642108)
				(xy 0.9398 2.642108) (xy 0.9398 3.1496) (xy 2.8194 3.1496) (xy 2.8194 2.6416) (xy 3.0226 2.6416)
				(xy 3.0226 2.642108)
			)
			(stroke
				(width 0)
				(type default)
			)
			(fill no)
			(layer "F.CrtYd")
		)
		(fp_line
			(start 0.329692 -0.457708)
			(end 3.429508 -0.457708)
			(stroke
				(width 0.1)
				(type default)
			)
			(layer "F.Fab")
		)
		(fp_line
			(start 0.329692 2.642108)
			(end 0.329692 -0.457708)
			(stroke
				(width 0.1)
				(type default)
			)
			(layer "F.Fab")
		)
		(fp_line
			(start 3.429508 -0.457708)
			(end 3.429508 2.642108)
			(stroke
				(width 0.1)
				(type default)
			)
			(layer "F.Fab")
		)
		(fp_line
			(start 3.429508 2.642108)
			(end 0.329692 2.642108)
			(stroke
				(width 0.1)
				(type default)
			)
			(layer "F.Fab")
		)
		(fp_poly
			(pts
				(xy -0.96266 0.54102) (xy -0.96266 -0.08382) (xy -0.40894 0.244348)
			)
			(stroke
				(width 0)
				(type default)
			)
			(fill yes)
			(layer "F.Fab")
		)
		(fp_text user "1"
			(at -0.656082 -0.602488 0)
			(unlocked yes)
			(layer "F.SilkS")
			(effects
				(font
					(size 0.635 0.4064)
					(thickness 0.1524)
				)
			)
		)
		(fp_text user "5"
			(at -0.567944 1.704594 0)
			(unlocked yes)
			(layer "F.SilkS")
			(effects
				(font
					(size 0.635 0.4064)
					(thickness 0.1524)
				)
			)
		)
		(fp_text user "20"
			(at 0.205486 -1.008634 0)
			(unlocked yes)
			(layer "F.SilkS")
			(effects
				(font
					(size 0.635 0.4064)
					(thickness 0.1524)
				)
			)
		)
		(fp_text user "6"
			(at 0.713486 3.44043 0)
			(unlocked yes)
			(layer "F.SilkS")
			(effects
				(font
					(size 0.635 0.4064)
					(thickness 0.1524)
				)
			)
		)
		(fp_text user "16"
			(at 3.052572 -1.465834 0)
			(unlocked yes)
			(layer "F.SilkS")
			(effects
				(font
					(size 0.635 0.4064)
					(thickness 0.1524)
				)
			)
		)
		(fp_text user "10"
			(at 3.209798 3.577336 0)
			(unlocked yes)
			(layer "F.SilkS")
			(effects
				(font
					(size 0.635 0.4064)
					(thickness 0.1524)
				)
			)
		)
		(fp_text user "11"
			(at 4.30403 2.916428 0)
			(unlocked yes)
			(layer "F.SilkS")
			(effects
				(font
					(size 0.635 0.4064)
					(thickness 0.1524)
				)
			)
		)
		(fp_text user "15"
			(at 4.442714 -0.169164 0)
			(unlocked yes)
			(layer "F.SilkS")
			(effects
				(font
					(size 0.635 0.4064)
					(thickness 0.1524)
				)
			)
		)
		(fp_text user "1"
			(at -0.332232 0.064516 0)
			(unlocked yes)
			(layer "F.Fab")
			(effects
				(font
					(size 0.7874 0.5842)
					(thickness 0.000001)
				)
			)
		)
		(fp_text user "5"
			(at -0.230632 2.655316 0)
			(unlocked yes)
			(layer "F.Fab")
			(effects
				(font
					(size 0.7874 0.5842)
					(thickness 0.000001)
				)
			)
		)
		(fp_text user "20"
			(at 0.2032 -0.91313 0)
			(unlocked yes)
			(layer "F.Fab")
			(effects
				(font
					(size 0.7874 0.5842)
					(thickness 0.000001)
				)
			)
		)
		(fp_text user "6"
			(at 0.963168 3.645916 0)
			(unlocked yes)
			(layer "F.Fab")
			(effects
				(font
					(size 0.7874 0.5842)
					(thickness 0.000001)
				)
			)
		)
		(fp_text user "10"
			(at 2.944622 3.595116 0)
			(unlocked yes)
			(layer "F.Fab")
			(effects
				(font
					(size 0.7874 0.5842)
					(thickness 0.000001)
				)
			)
		)
		(fp_text user "16"
			(at 3.429 -0.98933 0)
			(unlocked yes)
			(layer "F.Fab")
			(effects
				(font
					(size 0.7874 0.5842)
					(thickness 0.000001)
				)
			)
		)
		(fp_text user "11"
			(at 4.6228 2.69367 0)
			(unlocked yes)
			(layer "F.Fab")
			(effects
				(font
					(size 0.7874 0.5842)
					(thickness 0.000001)
				)
			)
		)
		(fp_text user "15"
			(at 4.646422 0.115316 0)
			(unlocked yes)
			(layer "F.Fab")
			(effects
				(font
					(size 0.7874 0.5842)
					(thickness 0.000001)
				)
			)
		)
		(pad "1" smd rect
			(at 0.316738 0.2921 270)
			(size 0.1778 0.9144)
			(layers "F.Cu" "F.Mask" "F.Paste")
			(net "VSENSE_PV_VDDR_NODE1_N")
		)
		(pad "2" smd rect
			(at 0.316738 0.69215 270)
			(size 0.1778 0.9144)
			(layers "F.Cu" "F.Mask" "F.Paste")
			(net "PV_VDDR_NODE1_V1")
		)
		(pad "3" smd rect
			(at 0.316738 1.0922 270)
			(size 0.1778 0.9144)
			(layers "F.Cu" "F.Mask" "F.Paste")
			(net "PV_VDDR_NODE1_V1")
		)
		(pad "4" smd rect
			(at 0.316738 1.49225 270)
			(size 0.1778 0.9144)
			(layers "F.Cu" "F.Mask" "F.Paste")
			(net "PV_VDDR_NODE1_V1")
		)
		(pad "5" smd rect
			(at 0.316738 1.8923 270)
			(size 0.1778 0.9144)
			(layers "F.Cu" "F.Mask" "F.Paste")
			(net "PV_VDDR_NODE1_V0")
		)
		(pad "6" smd rect
			(at 1.0795 2.655062)
			(size 0.1778 0.9144)
			(layers "F.Cu" "F.Mask" "F.Paste")
			(net "PV_VDDR_NODE1_VREF")
		)
		(pad "7" smd rect
			(at 1.47955 2.655062)
			(size 0.1778 0.9144)
			(layers "F.Cu" "F.Mask" "F.Paste")
			(net "PWRGD_NODE1_PVDDR_STB_PG")
		)
		(pad "8" smd rect
			(at 1.8796 2.655062)
			(size 0.1778 0.9144)
			(layers "F.Cu" "F.Mask" "F.Paste")
			(net "PV_VDDR_NODE1_VID0")
		)
		(pad "9" smd rect
			(at 2.27965 2.655062)
			(size 0.1778 0.9144)
			(layers "F.Cu" "F.Mask" "F.Paste")
			(net "PV_VDDR_NODE1_VID1")
		)
		(pad "10" smd rect
			(at 2.6797 2.655062)
			(size 0.1778 0.9144)
			(layers "F.Cu" "F.Mask" "F.Paste")
			(net "PV_VDDR_NODE1_EN")
		)
		(pad "11" smd rect
			(at 3.442462 1.8923 270)
			(size 0.1778 0.9144)
			(layers "F.Cu" "F.Mask" "F.Paste")
			(net "SW_PV_VDDR_NODE1_BT")
		)
		(pad "12" smd rect
			(at 3.442462 1.49225 270)
			(size 0.1778 0.9144)
			(layers "F.Cu" "F.Mask" "F.Paste")
			(net "SW_PV_VDDR_NODE1_PH")
		)
		(pad "13" smd rect
			(at 3.442462 1.0922 270)
			(size 0.1778 0.9144)
			(layers "F.Cu" "F.Mask" "F.Paste")
			(net "SW_PV_VDDR_NODE1_DRVH")
		)
		(pad "14" smd rect
			(at 3.442462 0.69215 270)
			(size 0.1778 0.9144)
			(layers "F.Cu" "F.Mask" "F.Paste")
			(net "SW_PV_VDDR_NODE1_DRVL")
		)
		(pad "15" smd rect
			(at 3.442462 0.2921 270)
			(size 0.1778 0.9144)
			(layers "F.Cu" "F.Mask" "F.Paste")
			(net "P5V_STB_NODE1")
		)
		(pad "16" smd rect
			(at 2.6797 -0.470662)
			(size 0.1778 0.9144)
			(layers "F.Cu" "F.Mask" "F.Paste")
			(net "PV_VDDR_NODE1_MODE")
		)
		(pad "17" smd rect
			(at 2.27965 -0.470662)
			(size 0.1778 0.9144)
			(layers "F.Cu" "F.Mask" "F.Paste")
			(net "GND")
		)
		(pad "18" smd rect
			(at 1.8796 -0.470662)
			(size 0.1778 0.9144)
			(layers "F.Cu" "F.Mask" "F.Paste")
			(net "PV_VDDR_NODE1_TRIP")
		)
		(pad "19" smd rect
			(at 1.47955 -0.470662)
			(size 0.1778 0.9144)
			(layers "F.Cu" "F.Mask" "F.Paste")
			(net "PV_VDDR_NODE1_SLEW")
		)
		(pad "20" smd rect
			(at 1.0795 -0.470662)
			(size 0.1778 0.9144)
			(layers "F.Cu" "F.Mask" "F.Paste")
			(net "VSENSE_PV_VDDR_NODE1_P")
		)
		(pad "TH" smd rect
			(at 1.8796 1.0922 90)
			(size 1.8034 1.8034)
			(layers "F.Cu" "F.Mask" "F.Paste")
			(net "GND")
		)
		(zone
			(layer "F.Cu")
			(hatch none 0.5)
			(connect_pads
				(clearance 0)
			)
			(min_thickness 0.25)
			(keepout
				(tracks allowed)
				(vias not_allowed)
				(pads allowed)
				(copperpour not_allowed)
				(footprints allowed)
			)
			(placement
				(enabled no)
				(sheetname "")
			)
			(fill
				(thermal_gap 0.5)
				(thermal_bridge_width 0.5)
				(island_removal_mode 0)
			)
			(polygon
				(pts
					(xy 37.039804 -9.272778) (xy 37.116004 -9.272778) (xy 37.116004 -11.330178) (xy 37.039804 -11.330178)
				)
			)
		)
		(zone
			(layer "F.Cu")
			(hatch none 0.5)
			(connect_pads
				(clearance 0)
			)
			(min_thickness 0.25)
			(keepout
				(tracks not_allowed)
				(vias allowed)
				(pads allowed)
				(copperpour not_allowed)
				(footprints allowed)
			)
			(placement
				(enabled no)
				(sheetname "")
			)
			(fill
				(thermal_gap 0.5)
				(thermal_bridge_width 0.5)
				(island_removal_mode 0)
			)
			(polygon
				(pts
					(xy 37.039804 -9.272778) (xy 37.116004 -9.272778) (xy 37.116004 -11.330178) (xy 37.039804 -11.330178)
				)
			)
		)
		(zone
			(layer "F.Cu")
			(hatch none 0.5)
			(connect_pads
				(clearance 0)
			)
			(min_thickness 0.25)
			(keepout
				(tracks not_allowed)
				(vias allowed)
				(pads allowed)
				(copperpour not_allowed)
				(footprints allowed)
			)
			(placement
				(enabled no)
				(sheetname "")
			)
			(fill
				(thermal_gap 0.5)
				(thermal_bridge_width 0.5)
				(island_removal_mode 0)
			)
			(polygon
				(pts
					(xy 37.116004 -11.253978) (xy 39.122604 -11.253978) (xy 39.122604 -11.330178) (xy 37.116004 -11.330178)
				)
			)
		)
		(zone
			(layer "F.Cu")
			(hatch none 0.5)
			(connect_pads
				(clearance 0)
			)
			(min_thickness 0.25)
			(keepout
				(tracks allowed)
				(vias not_allowed)
				(pads allowed)
				(copperpour not_allowed)
				(footprints allowed)
			)
			(placement
				(enabled no)
				(sheetname "")
			)
			(fill
				(thermal_gap 0.5)
				(thermal_bridge_width 0.5)
				(island_removal_mode 0)
			)
			(polygon
				(pts
					(xy 37.116004 -11.253978) (xy 39.122604 -11.253978) (xy 39.122604 -11.330178) (xy 37.116004 -11.330178)
				)
			)
		)
		(zone
			(layer "F.Cu")
			(hatch none 0.5)
			(connect_pads
				(clearance 0)
			)
			(min_thickness 0.25)
			(keepout
				(tracks not_allowed)
				(vias allowed)
				(pads allowed)
				(copperpour not_allowed)
				(footprints allowed)
			)
			(placement
				(enabled no)
				(sheetname "")
			)
			(fill
				(thermal_gap 0.5)
				(thermal_bridge_width 0.5)
				(island_removal_mode 0)
			)
			(polygon
				(pts
					(xy 37.116004 -9.272778) (xy 39.046404 -9.272778) (xy 39.046404 -9.348978) (xy 37.116004 -9.348978)
				)
			)
		)
		(zone
			(layer "F.Cu")
			(hatch none 0.5)
			(connect_pads
				(clearance 0)
			)
			(min_thickness 0.25)
			(keepout
				(tracks allowed)
				(vias not_allowed)
				(pads allowed)
				(copperpour not_allowed)
				(footprints allowed)
			)
			(placement
				(enabled no)
				(sheetname "")
			)
			(fill
				(thermal_gap 0.5)
				(thermal_bridge_width 0.5)
				(island_removal_mode 0)
			)
			(polygon
				(pts
					(xy 39.046404 -11.253978) (xy 39.122604 -11.253978) (xy 39.122604 -9.272778) (xy 39.046404 -9.272778)
				)
			)
		)
		(zone
			(layer "F.Cu")
			(hatch none 0.5)
			(connect_pads
				(clearance 0)
			)
			(min_thickness 0.25)
			(keepout
				(tracks allowed)
				(vias not_allowed)
				(pads allowed)
				(copperpour not_allowed)
				(footprints allowed)
			)
			(placement
				(enabled no)
				(sheetname "")
			)
			(fill
				(thermal_gap 0.5)
				(thermal_bridge_width 0.5)
				(island_removal_mode 0)
			)
			(polygon
				(pts
					(xy 39.046404 -9.348978) (xy 37.116004 -9.348978) (xy 37.116004 -9.272778) (xy 39.046404 -9.272778)
				)
			)
		)
		(zone
			(layer "F.Cu")
			(hatch none 0.5)
			(connect_pads
				(clearance 0)
			)
			(min_thickness 0.25)
			(keepout
				(tracks not_allowed)
				(vias allowed)
				(pads allowed)
				(copperpour not_allowed)
				(footprints allowed)
			)
			(placement
				(enabled no)
				(sheetname "")
			)
			(fill
				(thermal_gap 0.5)
				(thermal_bridge_width 0.5)
				(island_removal_mode 0)
			)
			(polygon
				(pts
					(xy 39.046404 -9.272778) (xy 39.122604 -9.272778) (xy 39.122604 -11.253978) (xy 39.046404 -11.253978)
				)
			)
		)
	)
	(footprint ""
		(layer "F.Cu")
		(at 163.687252 -90.14079 180)
		(property "Reference" "C367"
			(at 0.675386 -2.384044 0)
			(unlocked yes)
			(layer "F.SilkS")
			(effects
				(font
					(size 0.7874 0.5842)
					(thickness 0.1524)
				)
				(justify left)
			)
		)
		(property "Value" ""
			(at 0 0 180)
			(layer "F.Fab")
			(effects
				(font
					(size 1.27 1.27)
				)
			)
		)
		(duplicate_pad_numbers_are_jumpers no)
		(fp_line
			(start 0.7874 0.4064)
			(end -0.7874 0.4064)
			(stroke
				(width 0.1524)
				(type default)
			)
			(layer "F.SilkS")
		)
		(fp_line
			(start 0.7874 -0.4064)
			(end 0.7874 0.4064)
			(stroke
				(width 0.1524)
				(type default)
			)
			(layer "F.SilkS")
		)
		(fp_line
			(start 0 0.381)
			(end 0 -0.381)
			(stroke
				(width 0.1524)
				(type default)
			)
			(layer "F.SilkS")
		)
		(fp_line
			(start -0.7874 0.4064)
			(end -0.7874 -0.4064)
			(stroke
				(width 0.1524)
				(type default)
			)
			(layer "F.SilkS")
		)
		(fp_line
			(start -0.7874 -0.4064)
			(end 0.7874 -0.4064)
			(stroke
				(width 0.1524)
				(type default)
			)
			(layer "F.SilkS")
		)
		(fp_poly
			(pts
				(xy -0.5334 0.254) (xy -0.635 0.254) (xy -0.635 0.2286) (xy -0.635 -0.254) (xy -0.5334 -0.254) (xy -0.5334 -0.2794)
				(xy 0.5334 -0.2794) (xy 0.5334 -0.254) (xy 0.635 -0.254) (xy 0.635 0.254) (xy 0.5334 0.254) (xy 0.5334 0.2794)
				(xy -0.508 0.2794) (xy -0.5334 0.2794)
			)
			(stroke
				(width 0)
				(type default)
			)
			(fill no)
			(layer "F.CrtYd")
		)
		(pad "1" smd rect
			(at 0.40005 0 180)
			(size 0.4572 0.508)
			(layers "F.Cu" "F.Mask" "F.Paste")
			(net "P3V3_NODE1")
		)
		(pad "2" smd rect
			(at -0.40005 0 180)
			(size 0.4572 0.508)
			(layers "F.Cu" "F.Mask" "F.Paste")
			(net "GND")
		)
	)
	(footprint ""
		(layer "F.Cu")
		(at 141.708886 -51.476656 90)
		(property "Reference" "R1017"
			(at 16.324326 30.435042 90)
			(unlocked yes)
			(layer "F.SilkS")
			(effects
				(font
					(size 0.7874 0.5842)
					(thickness 0.1524)
				)
				(justify left)
			)
		)
		(property "Value" ""
			(at 0 0 90)
			(layer "F.Fab")
			(effects
				(font
					(size 1.27 1.27)
				)
			)
		)
		(duplicate_pad_numbers_are_jumpers no)
		(fp_line
			(start 0.7874 -0.4064)
			(end 0.7874 0.4064)
			(stroke
				(width 0.1524)
				(type default)
			)
			(layer "F.SilkS")
		)
		(fp_line
			(start -0.7874 -0.4064)
			(end 0.7874 -0.4064)
			(stroke
				(width 0.1524)
				(type default)
			)
			(layer "F.SilkS")
		)
		(fp_line
			(start 0.7874 0.4064)
			(end -0.7874 0.4064)
			(stroke
				(width 0.1524)
				(type default)
			)
			(layer "F.SilkS")
		)
		(fp_line
			(start -0.7874 0.4064)
			(end -0.7874 -0.4064)
			(stroke
				(width 0.1524)
				(type default)
			)
			(layer "F.SilkS")
		)
		(fp_poly
			(pts
				(xy -0.508 0.2794) (xy -0.508 0.2286) (xy -0.635 0.2286) (xy -0.635 -0.254) (xy -0.5334 -0.254)
				(xy -0.5334 -0.2794) (xy 0.5334 -0.2794) (xy 0.5334 -0.254) (xy 0.635 -0.254) (xy 0.635 0.254) (xy 0.5334 0.254)
				(xy 0.5334 0.2794)
			)
			(stroke
				(width 0)
				(type default)
			)
			(fill no)
			(layer "F.CrtYd")
		)
		(pad "1" smd rect
			(at 0.40005 0 90)
			(size 0.4572 0.508)
			(layers "F.Cu" "F.Mask" "F.Paste")
			(net "P5V_NODE1")
		)
		(pad "2" smd rect
			(at -0.40005 0 90)
			(size 0.4572 0.508)
			(layers "F.Cu" "F.Mask" "F.Paste")
			(net "UART_RTS_P2_N")
		)
	)
	(footprint ""
		(layer "F.Cu")
		(at 187.55614 -123.860306)
		(property "Reference" "R1033"
			(at 5.48386 18.984976 0)
			(unlocked yes)
			(layer "F.SilkS")
			(effects
				(font
					(size 0.7874 0.5842)
					(thickness 0.1524)
				)
				(justify left)
			)
		)
		(property "Value" ""
			(at 0 0 0)
			(layer "F.Fab")
			(effects
				(font
					(size 1.27 1.27)
				)
			)
		)
		(duplicate_pad_numbers_are_jumpers no)
		(fp_line
			(start -0.7874 -0.4064)
			(end 0.7874 -0.4064)
			(stroke
				(width 0.1524)
				(type default)
			)
			(layer "F.SilkS")
		)
		(fp_line
			(start -0.7874 0.4064)
			(end -0.7874 -0.4064)
			(stroke
				(width 0.1524)
				(type default)
			)
			(layer "F.SilkS")
		)
		(fp_line
			(start 0.7874 -0.4064)
			(end 0.7874 0.4064)
			(stroke
				(width 0.1524)
				(type default)
			)
			(layer "F.SilkS")
		)
		(fp_line
			(start 0.7874 0.4064)
			(end -0.7874 0.4064)
			(stroke
				(width 0.1524)
				(type default)
			)
			(layer "F.SilkS")
		)
		(fp_poly
			(pts
				(xy -0.508 0.2794) (xy -0.508 0.2286) (xy -0.635 0.2286) (xy -0.635 -0.254) (xy -0.5334 -0.254)
				(xy -0.5334 -0.2794) (xy 0.5334 -0.2794) (xy 0.5334 -0.254) (xy 0.635 -0.254) (xy 0.635 0.254) (xy 0.5334 0.254)
				(xy 0.5334 0.2794)
			)
			(stroke
				(width 0)
				(type default)
			)
			(fill no)
			(layer "F.CrtYd")
		)
		(pad "1" smd rect
			(at 0.40005 0)
			(size 0.4572 0.508)
			(layers "F.Cu" "F.Mask" "F.Paste")
			(net "GND")
		)
		(pad "2" smd rect
			(at -0.40005 0)
			(size 0.4572 0.508)
			(layers "F.Cu" "F.Mask" "F.Paste")
			(net "JTAG_CPLD1_TCK")
		)
	)
	(footprint ""
		(layer "F.Cu")
		(at 130.08864 -54.10835 90)
		(property "Reference" "C538"
			(at -1.27635 1.10363 90)
			(unlocked yes)
			(layer "F.SilkS")
			(effects
				(font
					(size 0.7874 0.5842)
					(thickness 0.1524)
				)
				(justify left)
			)
		)
		(property "Value" ""
			(at 0 0 90)
			(layer "F.Fab")
			(effects
				(font
					(size 1.27 1.27)
				)
			)
		)
		(duplicate_pad_numbers_are_jumpers no)
		(fp_line
			(start 0.7874 -0.4064)
			(end 0.7874 0.4064)
			(stroke
				(width 0.1524)
				(type default)
			)
			(layer "F.SilkS")
		)
		(fp_line
			(start -0.7874 -0.4064)
			(end 0.7874 -0.4064)
			(stroke
				(width 0.1524)
				(type default)
			)
			(layer "F.SilkS")
		)
		(fp_line
			(start 0 0.381)
			(end 0 -0.381)
			(stroke
				(width 0.1524)
				(type default)
			)
			(layer "F.SilkS")
		)
		(fp_line
			(start 0.7874 0.4064)
			(end -0.7874 0.4064)
			(stroke
				(width 0.1524)
				(type default)
			)
			(layer "F.SilkS")
		)
		(fp_line
			(start -0.7874 0.4064)
			(end -0.7874 -0.4064)
			(stroke
				(width 0.1524)
				(type default)
			)
			(layer "F.SilkS")
		)
		(fp_poly
			(pts
				(xy -0.5334 0.254) (xy -0.635 0.254) (xy -0.635 0.2286) (xy -0.635 -0.254) (xy -0.5334 -0.254) (xy -0.5334 -0.2794)
				(xy 0.5334 -0.2794) (xy 0.5334 -0.254) (xy 0.635 -0.254) (xy 0.635 0.254) (xy 0.5334 0.254) (xy 0.5334 0.2794)
				(xy -0.508 0.2794) (xy -0.5334 0.2794)
			)
			(stroke
				(width 0)
				(type default)
			)
			(fill no)
			(layer "F.CrtYd")
		)
		(pad "1" smd rect
			(at 0.40005 0 90)
			(size 0.4572 0.508)
			(layers "F.Cu" "F.Mask" "F.Paste")
			(net "P3V3_NODE1")
		)
		(pad "2" smd rect
			(at -0.40005 0 90)
			(size 0.4572 0.508)
			(layers "F.Cu" "F.Mask" "F.Paste")
			(net "GND")
		)
	)
	(footprint ""
		(layer "F.Cu")
		(at 51.906932 -98.929698 180)
		(property "Reference" "U9"
			(at 4.570222 -1.766824 0)
			(unlocked yes)
			(layer "F.SilkS")
			(effects
				(font
					(size 0.7874 0.5842)
					(thickness 0.1524)
				)
				(justify left)
			)
		)
		(property "Value" ""
			(at 0 0 180)
			(layer "F.Fab")
			(effects
				(font
					(size 1.27 1.27)
				)
			)
		)
		(duplicate_pad_numbers_are_jumpers no)
		(fp_line
			(start 4.040886 1.294892)
			(end 4.929886 1.294892)
			(stroke
				(width 0.1524)
				(type default)
			)
			(layer "F.SilkS")
		)
		(fp_line
			(start 3.81 3.024886)
			(end 3.81 2.25679)
			(stroke
				(width 0.1524)
				(type default)
			)
			(layer "F.SilkS")
		)
		(fp_line
			(start 3.81 -0.306832)
			(end 3.81 -1.074928)
			(stroke
				(width 0.1524)
				(type default)
			)
			(layer "F.SilkS")
		)
		(fp_line
			(start 3.81 -1.074928)
			(end 3.038602 -1.074928)
			(stroke
				(width 0.1524)
				(type default)
			)
			(layer "F.SilkS")
		)
		(fp_line
			(start 3.033776 3.024886)
			(end 3.81 3.024886)
			(stroke
				(width 0.1524)
				(type default)
			)
			(layer "F.SilkS")
		)
		(fp_line
			(start 1.429512 -1.350518)
			(end 1.429512 -1.858518)
			(stroke
				(width 0.1524)
				(type default)
			)
			(layer "F.SilkS")
		)
		(fp_line
			(start 0.778256 3.277108)
			(end 0.778256 3.785108)
			(stroke
				(width 0.1524)
				(type default)
			)
			(layer "F.SilkS")
		)
		(fp_line
			(start 0.483108 -1.074928)
			(end -0.290068 -1.074928)
			(stroke
				(width 0.1524)
				(type default)
			)
			(layer "F.SilkS")
		)
		(fp_line
			(start -0.290068 3.024886)
			(end 0.487934 3.024886)
			(stroke
				(width 0.1524)
				(type default)
			)
			(layer "F.SilkS")
		)
		(fp_line
			(start -0.290068 2.25044)
			(end -0.290068 3.024886)
			(stroke
				(width 0.1524)
				(type default)
			)
			(layer "F.SilkS")
		)
		(fp_line
			(start -0.290068 -1.074928)
			(end -0.290068 -0.309372)
			(stroke
				(width 0.1524)
				(type default)
			)
			(layer "F.SilkS")
		)
		(fp_poly
			(pts
				(xy -1.237742 -0.381) (xy -1.237742 0.381) (xy -0.475742 0)
			)
			(stroke
				(width 0)
				(type default)
			)
			(fill yes)
			(layer "F.SilkS")
		)
		(fp_poly
			(pts
				(xy 0.543814 3.141472) (xy 0.543814 3.024886) (xy -0.290068 3.024886) (xy -0.290068 2.191258) (xy -0.4064 2.191258)
				(xy -0.4064 -0.2413) (xy -0.290068 -0.2413) (xy -0.290068 -1.074928) (xy 0.543814 -1.074928) (xy 0.543814 -1.191514)
				(xy 2.976372 -1.191514) (xy 2.976372 -1.074928) (xy 3.81 -1.074928) (xy 3.81 -0.2413) (xy 3.926332 -0.2413)
				(xy 3.926332 2.191258) (xy 3.81 2.191258) (xy 3.81 3.024886) (xy 2.976372 3.024886) (xy 2.976372 3.141472)
			)
			(stroke
				(width 0)
				(type default)
			)
			(fill no)
			(layer "F.CrtYd")
		)
		(fp_line
			(start 4.040886 1.294892)
			(end 4.929886 1.294892)
			(stroke
				(width 0.1)
				(type default)
			)
			(layer "F.Fab")
		)
		(fp_line
			(start 3.81 3.024886)
			(end 3.81 -1.074928)
			(stroke
				(width 0.1)
				(type default)
			)
			(layer "F.Fab")
		)
		(fp_line
			(start 3.81 -1.074928)
			(end -0.290068 -1.074928)
			(stroke
				(width 0.1)
				(type default)
			)
			(layer "F.Fab")
		)
		(fp_line
			(start 1.429512 -1.350518)
			(end 1.429512 -1.858518)
			(stroke
				(width 0.1)
				(type default)
			)
			(layer "F.Fab")
		)
		(fp_line
			(start 0.778256 3.277108)
			(end 0.778256 3.785108)
			(stroke
				(width 0.1)
				(type default)
			)
			(layer "F.Fab")
		)
		(fp_line
			(start -0.290068 3.024886)
			(end 3.81 3.024886)
			(stroke
				(width 0.1)
				(type default)
			)
			(layer "F.Fab")
		)
		(fp_line
			(start -0.290068 -1.074928)
			(end -0.290068 3.024886)
			(stroke
				(width 0.1)
				(type default)
			)
			(layer "F.Fab")
		)
		(fp_poly
			(pts
				(xy -1.237742 -0.381) (xy -1.237742 0.381) (xy -0.475742 0)
			)
			(stroke
				(width 0)
				(type default)
			)
			(fill yes)
			(layer "F.Fab")
		)
		(fp_text user "12"
			(at 4.454652 -0.15621 0)
			(unlocked yes)
			(layer "F.SilkS")
			(effects
				(font
					(size 0.635 0.4064)
					(thickness 0.1524)
				)
			)
		)
		(fp_text user "9"
			(at 4.168902 2.082546 0)
			(unlocked yes)
			(layer "F.SilkS")
			(effects
				(font
					(size 0.635 0.4064)
					(thickness 0.1524)
				)
			)
		)
		(fp_text user "8"
			(at 3.358134 3.519678 0)
			(unlocked yes)
			(layer "F.SilkS")
			(effects
				(font
					(size 0.635 0.4064)
					(thickness 0.1524)
				)
			)
		)
		(fp_text user "13"
			(at 2.740914 -1.63957 0)
			(unlocked yes)
			(layer "F.SilkS")
			(effects
				(font
					(size 0.635 0.4064)
					(thickness 0.1524)
				)
			)
		)
		(fp_text user "16"
			(at 0.686308 -1.648714 0)
			(unlocked yes)
			(layer "F.SilkS")
			(effects
				(font
					(size 0.635 0.4064)
					(thickness 0.1524)
				)
			)
		)
		(fp_text user "5"
			(at 0.262636 3.556508 0)
			(unlocked yes)
			(layer "F.SilkS")
			(effects
				(font
					(size 0.635 0.4064)
					(thickness 0.1524)
				)
			)
		)
		(fp_text user "1"
			(at -0.589788 -0.693674 0)
			(unlocked yes)
			(layer "F.SilkS")
			(effects
				(font
					(size 0.635 0.4064)
					(thickness 0.1524)
				)
			)
		)
		(fp_text user "4"
			(at -0.686308 1.815338 0)
			(unlocked yes)
			(layer "F.SilkS")
			(effects
				(font
					(size 0.635 0.4064)
					(thickness 0.1524)
				)
			)
		)
		(fp_text user "12"
			(at 4.38023 -0.706882 270)
			(unlocked yes)
			(layer "F.Fab")
			(effects
				(font
					(size 0.635 0.4064)
					(thickness 0.000001)
				)
			)
		)
		(fp_text user "9"
			(at 4.309872 2.62128 270)
			(unlocked yes)
			(layer "F.Fab")
			(effects
				(font
					(size 0.635 0.4064)
					(thickness 0.000001)
				)
			)
		)
		(fp_text user "13"
			(at 3.370326 -1.593596 180)
			(unlocked yes)
			(layer "F.Fab")
			(effects
				(font
					(size 0.635 0.4064)
					(thickness 0.000001)
				)
			)
		)
		(fp_text user "8"
			(at 3.368802 3.51155 180)
			(unlocked yes)
			(layer "F.Fab")
			(effects
				(font
					(size 0.635 0.4064)
					(thickness 0.000001)
				)
			)
		)
		(fp_text user "5"
			(at 0.093472 3.53695 180)
			(unlocked yes)
			(layer "F.Fab")
			(effects
				(font
					(size 0.635 0.4064)
					(thickness 0.000001)
				)
			)
		)
		(fp_text user "16"
			(at 0.0127 -1.600454 180)
			(unlocked yes)
			(layer "F.Fab")
			(effects
				(font
					(size 0.635 0.4064)
					(thickness 0.000001)
				)
			)
		)
		(fp_text user "4"
			(at -0.736854 2.692146 270)
			(unlocked yes)
			(layer "F.Fab")
			(effects
				(font
					(size 0.635 0.4064)
					(thickness 0.000001)
				)
			)
		)
		(fp_text user "1"
			(at -0.769112 -0.660146 270)
			(unlocked yes)
			(layer "F.Fab")
			(effects
				(font
					(size 0.635 0.4064)
					(thickness 0.000001)
				)
			)
		)
		(pad "1" smd oval
			(at 0 0 270)
			(size 0.381 0.7112)
			(layers "F.Cu" "F.Mask" "F.Paste")
			(net "A_CPU0_NODE1_THERMDA")
		)
		(pad "2" smd oval
			(at 0 0.649986 270)
			(size 0.381 0.7112)
			(layers "F.Cu" "F.Mask" "F.Paste")
			(net "A_CPU0_NODE1_THERMDC")
		)
		(pad "3" smd oval
			(at 0 1.299972 270)
			(size 0.381 0.7112)
			(layers "F.Cu" "F.Mask" "F.Paste")
			(net "A_CPU1_NODE1_THERMDA")
		)
		(pad "4" smd oval
			(at 0 1.949958 270)
			(size 0.381 0.7112)
			(layers "F.Cu" "F.Mask" "F.Paste")
			(net "A_CPU1_NODE1_THERMDC")
		)
		(pad "5" smd oval
			(at 0.785114 2.735072 180)
			(size 0.381 0.7112)
			(layers "F.Cu" "F.Mask" "F.Paste")
			(net "PU_EMC1428_NODE1_TRIP")
		)
		(pad "6" smd oval
			(at 1.4351 2.735072 180)
			(size 0.381 0.7112)
			(layers "F.Cu" "F.Mask" "F.Paste")
			(net "PU_TEMP1_NODE1_SYS_SHDN_L")
		)
		(pad "7" smd oval
			(at 2.085086 2.735072 180)
			(size 0.381 0.7112)
			(layers "F.Cu" "F.Mask" "F.Paste")
			(net "SMB_TEMP1_NODE1_ALERT_R_L")
		)
		(pad "8" smd oval
			(at 2.735072 2.735072 180)
			(size 0.381 0.7112)
			(layers "F.Cu" "F.Mask" "F.Paste")
			(net "GND")
		)
		(pad "9" smd oval
			(at 3.519932 1.949958 270)
			(size 0.381 0.7112)
			(layers "F.Cu" "F.Mask" "F.Paste")
			(net "A_SOC_NODE1_THERMDC")
		)
		(pad "10" smd oval
			(at 3.519932 1.299972 270)
			(size 0.381 0.7112)
			(layers "F.Cu" "F.Mask" "F.Paste")
			(net "A_SOC_NODE1_THERMDA")
		)
		(pad "11" smd oval
			(at 3.519932 0.649986 270)
			(size 0.381 0.7112)
			(layers "F.Cu" "F.Mask" "F.Paste")
			(net "SMB_MUX_CPU_ICS_NODE1_DAT")
		)
		(pad "12" smd oval
			(at 3.519932 0 270)
			(size 0.381 0.7112)
			(layers "F.Cu" "F.Mask" "F.Paste")
			(net "SMB_MUX_CPU_ICS_NODE1_CLK")
		)
		(pad "13" smd oval
			(at 2.735072 -0.785114 180)
			(size 0.381 0.7112)
			(layers "F.Cu" "F.Mask" "F.Paste")
			(net "TP_TEMP1_NODE1_3")
		)
		(pad "14" smd oval
			(at 2.085086 -0.785114 180)
			(size 0.381 0.7112)
			(layers "F.Cu" "F.Mask" "F.Paste")
			(net "TP_TEMP1_NODE1_2")
		)
		(pad "15" smd oval
			(at 1.4351 -0.785114 180)
			(size 0.381 0.7112)
			(layers "F.Cu" "F.Mask" "F.Paste")
			(net "TP_TEMP1_NODE1_1")
		)
		(pad "16" smd oval
			(at 0.785114 -0.785114 180)
			(size 0.381 0.7112)
			(layers "F.Cu" "F.Mask" "F.Paste")
			(net "P3V3_NODE1")
		)
		(pad "TH" smd rect
			(at 1.759966 0.975106 180)
			(size 2.1082 2.1082)
			(layers "F.Cu" "F.Mask" "F.Paste")
			(net "GND")
		)
		(zone
			(layer "F.Cu")
			(hatch none 0.5)
			(connect_pads
				(clearance 0)
			)
			(min_thickness 0.25)
			(keepout
				(tracks allowed)
				(vias not_allowed)
				(pads allowed)
				(copperpour not_allowed)
				(footprints allowed)
			)
			(placement
				(enabled no)
				(sheetname "")
			)
			(fill
				(thermal_gap 0.5)
				(thermal_bridge_width 0.5)
				(island_removal_mode 0)
			)
			(polygon
				(pts
					(xy 51.500532 -101.25837) (xy 51.500532 -98.550984) (xy 51.251866 -98.550984) (xy 51.251866 -101.009704)
					(xy 49.042066 -101.009704) (xy 49.042066 -98.799904) (xy 51.237134 -98.799904) (xy 51.237134 -98.550984)
					(xy 48.7934 -98.550984) (xy 48.7934 -101.25837)
				)
			)
		)
		(zone
			(layer "F.Cu")
			(hatch none 0.5)
			(connect_pads
				(clearance 0)
			)
			(min_thickness 0.25)
			(keepout
				(tracks not_allowed)
				(vias allowed)
				(pads allowed)
				(copperpour not_allowed)
				(footprints allowed)
			)
			(placement
				(enabled no)
				(sheetname "")
			)
			(fill
				(thermal_gap 0.5)
				(thermal_bridge_width 0.5)
				(island_removal_mode 0)
			)
			(polygon
				(pts
					(xy 51.500532 -101.25837) (xy 51.500532 -98.550984) (xy 51.251866 -98.550984) (xy 51.251866 -101.009704)
					(xy 49.042066 -101.009704) (xy 49.042066 -98.799904) (xy 51.237134 -98.799904) (xy 51.237134 -98.550984)
					(xy 48.7934 -98.550984) (xy 48.7934 -101.25837)
				)
			)
		)
	)
	(footprint ""
		(layer "F.Cu")
		(at 45.532802 -145.829782 -90)
		(property "Reference" "R544"
			(at 0.88646 6.618732 90)
			(unlocked yes)
			(layer "F.SilkS")
			(effects
				(font
					(size 0.7874 0.5842)
					(thickness 0.1524)
				)
				(justify left)
			)
		)
		(property "Value" ""
			(at 0 0 270)
			(layer "F.Fab")
			(effects
				(font
					(size 1.27 1.27)
				)
			)
		)
		(duplicate_pad_numbers_are_jumpers no)
		(fp_line
			(start -0.7874 0.4064)
			(end -0.7874 -0.4064)
			(stroke
				(width 0.1524)
				(type default)
			)
			(layer "F.SilkS")
		)
		(fp_line
			(start 0.7874 0.4064)
			(end -0.7874 0.4064)
			(stroke
				(width 0.1524)
				(type default)
			)
			(layer "F.SilkS")
		)
		(fp_line
			(start -0.7874 -0.4064)
			(end 0.7874 -0.4064)
			(stroke
				(width 0.1524)
				(type default)
			)
			(layer "F.SilkS")
		)
		(fp_line
			(start 0.7874 -0.4064)
			(end 0.7874 0.4064)
			(stroke
				(width 0.1524)
				(type default)
			)
			(layer "F.SilkS")
		)
		(fp_poly
			(pts
				(xy -0.508 0.2794) (xy -0.508 0.2286) (xy -0.635 0.2286) (xy -0.635 -0.254) (xy -0.5334 -0.254)
				(xy -0.5334 -0.2794) (xy 0.5334 -0.2794) (xy 0.5334 -0.254) (xy 0.635 -0.254) (xy 0.635 0.254) (xy 0.5334 0.254)
				(xy 0.5334 0.2794)
			)
			(stroke
				(width 0)
				(type default)
			)
			(fill no)
			(layer "F.CrtYd")
		)
		(pad "1" smd rect
			(at 0.40005 0 270)
			(size 0.4572 0.508)
			(layers "F.Cu" "F.Mask" "F.Paste")
			(net "P3V3_NODE1")
		)
		(pad "2" smd rect
			(at -0.40005 0 270)
			(size 0.4572 0.508)
			(layers "F.Cu" "F.Mask" "F.Paste")
			(net "LAN1_NC_SI_TDX0")
		)
	)
	(footprint ""
		(layer "F.Cu")
		(at 129.1082 -50.8762 -90)
		(property "Reference" "R1161"
			(at -16.891 -30.83687 90)
			(unlocked yes)
			(layer "F.SilkS")
			(effects
				(font
					(size 0.7874 0.5842)
					(thickness 0.1524)
				)
				(justify left)
			)
		)
		(property "Value" ""
			(at 0 0 270)
			(layer "F.Fab")
			(effects
				(font
					(size 1.27 1.27)
				)
			)
		)
		(duplicate_pad_numbers_are_jumpers no)
		(fp_line
			(start -0.7874 0.4064)
			(end -0.7874 -0.4064)
			(stroke
				(width 0.1524)
				(type default)
			)
			(layer "F.SilkS")
		)
		(fp_line
			(start 0.7874 0.4064)
			(end -0.7874 0.4064)
			(stroke
				(width 0.1524)
				(type default)
			)
			(layer "F.SilkS")
		)
		(fp_line
			(start -0.7874 -0.4064)
			(end 0.7874 -0.4064)
			(stroke
				(width 0.1524)
				(type default)
			)
			(layer "F.SilkS")
		)
		(fp_line
			(start 0.7874 -0.4064)
			(end 0.7874 0.4064)
			(stroke
				(width 0.1524)
				(type default)
			)
			(layer "F.SilkS")
		)
		(fp_poly
			(pts
				(xy -0.508 0.2794) (xy -0.508 0.2286) (xy -0.635 0.2286) (xy -0.635 -0.254) (xy -0.5334 -0.254)
				(xy -0.5334 -0.2794) (xy 0.5334 -0.2794) (xy 0.5334 -0.254) (xy 0.635 -0.254) (xy 0.635 0.254) (xy 0.5334 0.254)
				(xy 0.5334 0.2794)
			)
			(stroke
				(width 0)
				(type default)
			)
			(fill no)
			(layer "F.CrtYd")
		)
		(pad "1" smd rect
			(at 0.40005 0 270)
			(size 0.4572 0.508)
			(layers "F.Cu" "F.Mask" "F.Paste")
			(net "UART_TX_P4_R")
		)
		(pad "2" smd rect
			(at -0.40005 0 270)
			(size 0.4572 0.508)
			(layers "F.Cu" "F.Mask" "F.Paste")
			(net "UART_TX_P4_BUF")
		)
	)
	(footprint ""
		(layer "F.Cu")
		(at 57.38876 -185.205624 90)
		(property "Reference" "C712"
			(at 4.006088 -0.154178 90)
			(unlocked yes)
			(layer "F.SilkS")
			(effects
				(font
					(size 0.7874 0.5842)
					(thickness 0.1524)
				)
				(justify left)
			)
		)
		(property "Value" ""
			(at 0 0 90)
			(layer "F.Fab")
			(effects
				(font
					(size 1.27 1.27)
				)
			)
		)
		(duplicate_pad_numbers_are_jumpers no)
		(fp_line
			(start 0.7874 -0.4064)
			(end 0.7874 0.4064)
			(stroke
				(width 0.1524)
				(type default)
			)
			(layer "F.SilkS")
		)
		(fp_line
			(start -0.7874 -0.4064)
			(end 0.7874 -0.4064)
			(stroke
				(width 0.1524)
				(type default)
			)
			(layer "F.SilkS")
		)
		(fp_line
			(start 0 0.381)
			(end 0 -0.381)
			(stroke
				(width 0.1524)
				(type default)
			)
			(layer "F.SilkS")
		)
		(fp_line
			(start 0.7874 0.4064)
			(end -0.7874 0.4064)
			(stroke
				(width 0.1524)
				(type default)
			)
			(layer "F.SilkS")
		)
		(fp_line
			(start -0.7874 0.4064)
			(end -0.7874 -0.4064)
			(stroke
				(width 0.1524)
				(type default)
			)
			(layer "F.SilkS")
		)
		(fp_poly
			(pts
				(xy -0.5334 0.254) (xy -0.635 0.254) (xy -0.635 0.2286) (xy -0.635 -0.254) (xy -0.5334 -0.254) (xy -0.5334 -0.2794)
				(xy 0.5334 -0.2794) (xy 0.5334 -0.254) (xy 0.635 -0.254) (xy 0.635 0.254) (xy 0.5334 0.254) (xy 0.5334 0.2794)
				(xy -0.508 0.2794) (xy -0.5334 0.2794)
			)
			(stroke
				(width 0)
				(type default)
			)
			(fill no)
			(layer "F.CrtYd")
		)
		(pad "1" smd rect
			(at 0.40005 0 90)
			(size 0.4572 0.508)
			(layers "F.Cu" "F.Mask" "F.Paste")
			(net "UART_T2_NODE4_RXD")
		)
		(pad "2" smd rect
			(at -0.40005 0 90)
			(size 0.4572 0.508)
			(layers "F.Cu" "F.Mask" "F.Paste")
			(net "GND")
		)
	)
	(footprint ""
		(layer "F.Cu")
		(at 62.161166 -96.709992 90)
		(property "Reference" "R57"
			(at -54.98719 28.524962 90)
			(unlocked yes)
			(layer "F.SilkS")
			(effects
				(font
					(size 0.7874 0.5842)
					(thickness 0.1524)
				)
				(justify left)
			)
		)
		(property "Value" ""
			(at 0 0 90)
			(layer "F.Fab")
			(effects
				(font
					(size 1.27 1.27)
				)
			)
		)
		(duplicate_pad_numbers_are_jumpers no)
		(fp_line
			(start 0.7874 -0.4064)
			(end 0.7874 0.4064)
			(stroke
				(width 0.1524)
				(type default)
			)
			(layer "F.SilkS")
		)
		(fp_line
			(start -0.7874 -0.4064)
			(end 0.7874 -0.4064)
			(stroke
				(width 0.1524)
				(type default)
			)
			(layer "F.SilkS")
		)
		(fp_line
			(start 0.7874 0.4064)
			(end -0.7874 0.4064)
			(stroke
				(width 0.1524)
				(type default)
			)
			(layer "F.SilkS")
		)
		(fp_line
			(start -0.7874 0.4064)
			(end -0.7874 -0.4064)
			(stroke
				(width 0.1524)
				(type default)
			)
			(layer "F.SilkS")
		)
		(fp_poly
			(pts
				(xy -0.508 0.2794) (xy -0.508 0.2286) (xy -0.635 0.2286) (xy -0.635 -0.254) (xy -0.5334 -0.254)
				(xy -0.5334 -0.2794) (xy 0.5334 -0.2794) (xy 0.5334 -0.254) (xy 0.635 -0.254) (xy 0.635 0.254) (xy 0.5334 0.254)
				(xy 0.5334 0.2794)
			)
			(stroke
				(width 0)
				(type default)
			)
			(fill no)
			(layer "F.CrtYd")
		)
		(pad "1" smd rect
			(at 0.40005 0 90)
			(size 0.4572 0.508)
			(layers "F.Cu" "F.Mask" "F.Paste")
			(net "SPI_CPU_NODE1_CS0_L")
		)
		(pad "2" smd rect
			(at -0.40005 0 90)
			(size 0.4572 0.508)
			(layers "F.Cu" "F.Mask" "F.Paste")
			(net "SPI_CPU_NODE1_CS0_R_L")
		)
	)
	(footprint ""
		(layer "F.Cu")
		(at 40.177974 -4.07035 90)
		(property "Reference" "PC31"
			(at -3.490722 -12.492482 90)
			(unlocked yes)
			(layer "F.SilkS")
			(effects
				(font
					(size 0.7874 0.5842)
					(thickness 0.1524)
				)
				(justify left)
			)
		)
		(property "Value" ""
			(at 0 0 90)
			(layer "F.Fab")
			(effects
				(font
					(size 1.27 1.27)
				)
			)
		)
		(duplicate_pad_numbers_are_jumpers no)
		(fp_line
			(start 0.7874 -0.4064)
			(end 0.7874 0.4064)
			(stroke
				(width 0.1524)
				(type default)
			)
			(layer "F.SilkS")
		)
		(fp_line
			(start -0.7874 -0.4064)
			(end 0.7874 -0.4064)
			(stroke
				(width 0.1524)
				(type default)
			)
			(layer "F.SilkS")
		)
		(fp_line
			(start 0 0.381)
			(end 0 -0.381)
			(stroke
				(width 0.1524)
				(type default)
			)
			(layer "F.SilkS")
		)
		(fp_line
			(start 0.7874 0.4064)
			(end -0.7874 0.4064)
			(stroke
				(width 0.1524)
				(type default)
			)
			(layer "F.SilkS")
		)
		(fp_line
			(start -0.7874 0.4064)
			(end -0.7874 -0.4064)
			(stroke
				(width 0.1524)
				(type default)
			)
			(layer "F.SilkS")
		)
		(fp_poly
			(pts
				(xy -0.5334 0.254) (xy -0.635 0.254) (xy -0.635 0.2286) (xy -0.635 -0.254) (xy -0.5334 -0.254) (xy -0.5334 -0.2794)
				(xy 0.5334 -0.2794) (xy 0.5334 -0.254) (xy 0.635 -0.254) (xy 0.635 0.254) (xy 0.5334 0.254) (xy 0.5334 0.2794)
				(xy -0.508 0.2794) (xy -0.5334 0.2794)
			)
			(stroke
				(width 0)
				(type default)
			)
			(fill no)
			(layer "F.CrtYd")
		)
		(pad "1" smd rect
			(at 0.40005 0 90)
			(size 0.4572 0.508)
			(layers "F.Cu" "F.Mask" "F.Paste")
			(net "FM_CPLD_NODE1_PVDDR_STB_EN")
		)
		(pad "2" smd rect
			(at -0.40005 0 90)
			(size 0.4572 0.508)
			(layers "F.Cu" "F.Mask" "F.Paste")
			(net "GND")
		)
	)
	(footprint ""
		(layer "F.Cu")
		(at 99.938078 -150.328122)
		(property "Reference" "PC32"
			(at -1.988566 2.731008 0)
			(unlocked yes)
			(layer "F.SilkS")
			(effects
				(font
					(size 0.7874 0.5842)
					(thickness 0.1524)
				)
				(justify left)
			)
		)
		(property "Value" ""
			(at 0 0 0)
			(layer "F.Fab")
			(effects
				(font
					(size 1.27 1.27)
				)
			)
		)
		(duplicate_pad_numbers_are_jumpers no)
		(fp_line
			(start -2.2098 -0.9398)
			(end 2.2098 -0.9398)
			(stroke
				(width 0.1524)
				(type default)
			)
			(layer "F.SilkS")
		)
		(fp_line
			(start -2.2098 0.9398)
			(end -2.2098 -0.9398)
			(stroke
				(width 0.1524)
				(type default)
			)
			(layer "F.SilkS")
		)
		(fp_line
			(start 0 -0.9398)
			(end 0 0.9398)
			(stroke
				(width 0.1524)
				(type default)
			)
			(layer "F.SilkS")
		)
		(fp_line
			(start 2.2098 -0.9398)
			(end 2.2098 0.9398)
			(stroke
				(width 0.1524)
				(type default)
			)
			(layer "F.SilkS")
		)
		(fp_line
			(start 2.2098 0.9398)
			(end -2.2098 0.9398)
			(stroke
				(width 0.1524)
				(type default)
			)
			(layer "F.SilkS")
		)
		(fp_poly
			(pts
				(xy -1.6764 0.889) (xy -1.6764 0.7874) (xy -2.0574 0.7874) (xy -2.0574 -0.7874) (xy -1.6764 -0.7874)
				(xy -1.6764 -0.9398) (xy 1.6764 -0.9398) (xy 1.6764 -0.7874) (xy 2.0574 -0.7874) (xy 2.0574 0.7874)
				(xy 1.6764 0.7874) (xy 1.6764 0.9398) (xy -1.6764 0.9398)
			)
			(stroke
				(width 0)
				(type default)
			)
			(fill no)
			(layer "F.CrtYd")
		)
		(fp_line
			(start -1.700022 -0.899922)
			(end 1.700022 -0.899922)
			(stroke
				(width 0.1)
				(type default)
			)
			(layer "F.Fab")
		)
		(fp_line
			(start -1.700022 0.899922)
			(end -1.700022 -0.899922)
			(stroke
				(width 0.1)
				(type default)
			)
			(layer "F.Fab")
		)
		(fp_line
			(start 1.700022 -0.899922)
			(end 1.700022 0.899922)
			(stroke
				(width 0.1)
				(type default)
			)
			(layer "F.Fab")
		)
		(fp_line
			(start 1.700022 0.899922)
			(end -1.700022 0.899922)
			(stroke
				(width 0.1)
				(type default)
			)
			(layer "F.Fab")
		)
		(pad "1" smd rect
			(at 1.4732 0)
			(size 1.1684 1.5748)
			(layers "F.Cu" "F.Mask" "F.Paste")
			(net "P12V_AUX")
		)
		(pad "2" smd rect
			(at -1.4732 0)
			(size 1.1684 1.5748)
			(layers "F.Cu" "F.Mask" "F.Paste")
			(net "GND")
		)
	)
	(footprint ""
		(layer "F.Cu")
		(at 36.707572 -74.418698 180)
		(property "Reference" "R150"
			(at 5.396484 -0.103124 0)
			(unlocked yes)
			(layer "F.SilkS")
			(effects
				(font
					(size 0.7874 0.5842)
					(thickness 0.1524)
				)
				(justify left)
			)
		)
		(property "Value" ""
			(at 0 0 180)
			(layer "F.Fab")
			(effects
				(font
					(size 1.27 1.27)
				)
			)
		)
		(duplicate_pad_numbers_are_jumpers no)
		(fp_line
			(start 0.7874 0.4064)
			(end -0.7874 0.4064)
			(stroke
				(width 0.1524)
				(type default)
			)
			(layer "F.SilkS")
		)
		(fp_line
			(start 0.7874 -0.4064)
			(end 0.7874 0.4064)
			(stroke
				(width 0.1524)
				(type default)
			)
			(layer "F.SilkS")
		)
		(fp_line
			(start -0.7874 0.4064)
			(end -0.7874 -0.4064)
			(stroke
				(width 0.1524)
				(type default)
			)
			(layer "F.SilkS")
		)
		(fp_line
			(start -0.7874 -0.4064)
			(end 0.7874 -0.4064)
			(stroke
				(width 0.1524)
				(type default)
			)
			(layer "F.SilkS")
		)
		(fp_poly
			(pts
				(xy -0.508 0.2794) (xy -0.508 0.2286) (xy -0.635 0.2286) (xy -0.635 -0.254) (xy -0.5334 -0.254)
				(xy -0.5334 -0.2794) (xy 0.5334 -0.2794) (xy 0.5334 -0.254) (xy 0.635 -0.254) (xy 0.635 0.254) (xy 0.5334 0.254)
				(xy 0.5334 0.2794)
			)
			(stroke
				(width 0)
				(type default)
			)
			(fill no)
			(layer "F.CrtYd")
		)
		(pad "1" smd rect
			(at 0.40005 0 180)
			(size 0.4572 0.508)
			(layers "F.Cu" "F.Mask" "F.Paste")
			(net "P1V5_NODE1")
		)
		(pad "2" smd rect
			(at -0.40005 0 180)
			(size 0.4572 0.508)
			(layers "F.Cu" "F.Mask" "F.Paste")
			(net "P1V5_NODE1_AJ21")
		)
	)
	(footprint ""
		(layer "F.Cu")
		(at 108.31576 -185.205624 -90)
		(property "Reference" "R893"
			(at -4.768088 -0.724408 90)
			(unlocked yes)
			(layer "F.SilkS")
			(effects
				(font
					(size 0.7874 0.5842)
					(thickness 0.1524)
				)
				(justify left)
			)
		)
		(property "Value" ""
			(at 0 0 270)
			(layer "F.Fab")
			(effects
				(font
					(size 1.27 1.27)
				)
			)
		)
		(duplicate_pad_numbers_are_jumpers no)
		(fp_line
			(start -0.7874 0.4064)
			(end -0.7874 -0.4064)
			(stroke
				(width 0.1524)
				(type default)
			)
			(layer "F.SilkS")
		)
		(fp_line
			(start 0.7874 0.4064)
			(end -0.7874 0.4064)
			(stroke
				(width 0.1524)
				(type default)
			)
			(layer "F.SilkS")
		)
		(fp_line
			(start -0.7874 -0.4064)
			(end 0.7874 -0.4064)
			(stroke
				(width 0.1524)
				(type default)
			)
			(layer "F.SilkS")
		)
		(fp_line
			(start 0.7874 -0.4064)
			(end 0.7874 0.4064)
			(stroke
				(width 0.1524)
				(type default)
			)
			(layer "F.SilkS")
		)
		(fp_poly
			(pts
				(xy -0.508 0.2794) (xy -0.508 0.2286) (xy -0.635 0.2286) (xy -0.635 -0.254) (xy -0.5334 -0.254)
				(xy -0.5334 -0.2794) (xy 0.5334 -0.2794) (xy 0.5334 -0.254) (xy 0.635 -0.254) (xy 0.635 0.254) (xy 0.5334 0.254)
				(xy 0.5334 0.2794)
			)
			(stroke
				(width 0)
				(type default)
			)
			(fill no)
			(layer "F.CrtYd")
		)
		(pad "1" smd rect
			(at 0.40005 0 270)
			(size 0.4572 0.508)
			(layers "F.Cu" "F.Mask" "F.Paste")
			(net "T6_NODE4_EN")
		)
		(pad "2" smd rect
			(at -0.40005 0 270)
			(size 0.4572 0.508)
			(layers "F.Cu" "F.Mask" "F.Paste")
			(net "T6_NODE4_EN_R")
		)
	)
	(footprint ""
		(layer "F.Cu")
		(at 125.735588 -181.503828 180)
		(property "Reference" "R721"
			(at -1.520444 -1.289304 0)
			(unlocked yes)
			(layer "F.SilkS")
			(effects
				(font
					(size 0.7874 0.5842)
					(thickness 0.1524)
				)
				(justify left)
			)
		)
		(property "Value" ""
			(at 0 0 180)
			(layer "F.Fab")
			(effects
				(font
					(size 1.27 1.27)
				)
			)
		)
		(duplicate_pad_numbers_are_jumpers no)
		(fp_line
			(start 0.7874 0.4064)
			(end -0.7874 0.4064)
			(stroke
				(width 0.1524)
				(type default)
			)
			(layer "F.SilkS")
		)
		(fp_line
			(start 0.7874 -0.4064)
			(end 0.7874 0.4064)
			(stroke
				(width 0.1524)
				(type default)
			)
			(layer "F.SilkS")
		)
		(fp_line
			(start -0.7874 0.4064)
			(end -0.7874 -0.4064)
			(stroke
				(width 0.1524)
				(type default)
			)
			(layer "F.SilkS")
		)
		(fp_line
			(start -0.7874 -0.4064)
			(end 0.7874 -0.4064)
			(stroke
				(width 0.1524)
				(type default)
			)
			(layer "F.SilkS")
		)
		(fp_poly
			(pts
				(xy -0.508 0.2794) (xy -0.508 0.2286) (xy -0.635 0.2286) (xy -0.635 -0.254) (xy -0.5334 -0.254)
				(xy -0.5334 -0.2794) (xy 0.5334 -0.2794) (xy 0.5334 -0.254) (xy 0.635 -0.254) (xy 0.635 0.254) (xy 0.5334 0.254)
				(xy 0.5334 0.2794)
			)
			(stroke
				(width 0)
				(type default)
			)
			(fill no)
			(layer "F.CrtYd")
		)
		(pad "1" smd rect
			(at 0.40005 0 180)
			(size 0.4572 0.508)
			(layers "F.Cu" "F.Mask" "F.Paste")
			(net "T7_NODE2_EN")
		)
		(pad "2" smd rect
			(at -0.40005 0 180)
			(size 0.4572 0.508)
			(layers "F.Cu" "F.Mask" "F.Paste")
			(net "P5V_NODE1")
		)
	)
	(footprint ""
		(layer "F.Cu")
		(at 136.310878 -51.45151 -90)
		(property "Reference" "R1157"
			(at -16.29029 -30.644592 90)
			(unlocked yes)
			(layer "F.SilkS")
			(effects
				(font
					(size 0.7874 0.5842)
					(thickness 0.1524)
				)
				(justify left)
			)
		)
		(property "Value" ""
			(at 0 0 270)
			(layer "F.Fab")
			(effects
				(font
					(size 1.27 1.27)
				)
			)
		)
		(duplicate_pad_numbers_are_jumpers no)
		(fp_line
			(start -0.7874 0.4064)
			(end -0.7874 -0.4064)
			(stroke
				(width 0.1524)
				(type default)
			)
			(layer "F.SilkS")
		)
		(fp_line
			(start 0.7874 0.4064)
			(end -0.7874 0.4064)
			(stroke
				(width 0.1524)
				(type default)
			)
			(layer "F.SilkS")
		)
		(fp_line
			(start -0.7874 -0.4064)
			(end 0.7874 -0.4064)
			(stroke
				(width 0.1524)
				(type default)
			)
			(layer "F.SilkS")
		)
		(fp_line
			(start 0.7874 -0.4064)
			(end 0.7874 0.4064)
			(stroke
				(width 0.1524)
				(type default)
			)
			(layer "F.SilkS")
		)
		(fp_poly
			(pts
				(xy -0.508 0.2794) (xy -0.508 0.2286) (xy -0.635 0.2286) (xy -0.635 -0.254) (xy -0.5334 -0.254)
				(xy -0.5334 -0.2794) (xy 0.5334 -0.2794) (xy 0.5334 -0.254) (xy 0.635 -0.254) (xy 0.635 0.254) (xy 0.5334 0.254)
				(xy 0.5334 0.2794)
			)
			(stroke
				(width 0)
				(type default)
			)
			(fill no)
			(layer "F.CrtYd")
		)
		(pad "1" smd rect
			(at 0.40005 0 270)
			(size 0.4572 0.508)
			(layers "F.Cu" "F.Mask" "F.Paste")
			(net "UART_RTS_P3_R_N")
		)
		(pad "2" smd rect
			(at -0.40005 0 270)
			(size 0.4572 0.508)
			(layers "F.Cu" "F.Mask" "F.Paste")
			(net "UART_RTS_P3_N")
		)
	)
	(footprint ""
		(layer "F.Cu")
		(at 85.411818 -145.059908 -90)
		(property "Reference" "C837"
			(at 1.701038 -2.218944 90)
			(unlocked yes)
			(layer "F.SilkS")
			(effects
				(font
					(size 0.7874 0.5842)
					(thickness 0.1524)
				)
				(justify left)
			)
		)
		(property "Value" ""
			(at 0 0 270)
			(layer "F.Fab")
			(effects
				(font
					(size 1.27 1.27)
				)
			)
		)
		(duplicate_pad_numbers_are_jumpers no)
		(fp_line
			(start -0.7874 0.4064)
			(end -0.7874 -0.4064)
			(stroke
				(width 0.1524)
				(type default)
			)
			(layer "F.SilkS")
		)
		(fp_line
			(start 0.7874 0.4064)
			(end -0.7874 0.4064)
			(stroke
				(width 0.1524)
				(type default)
			)
			(layer "F.SilkS")
		)
		(fp_line
			(start 0 0.381)
			(end 0 -0.381)
			(stroke
				(width 0.1524)
				(type default)
			)
			(layer "F.SilkS")
		)
		(fp_line
			(start -0.7874 -0.4064)
			(end 0.7874 -0.4064)
			(stroke
				(width 0.1524)
				(type default)
			)
			(layer "F.SilkS")
		)
		(fp_line
			(start 0.7874 -0.4064)
			(end 0.7874 0.4064)
			(stroke
				(width 0.1524)
				(type default)
			)
			(layer "F.SilkS")
		)
		(fp_poly
			(pts
				(xy -0.5334 0.254) (xy -0.635 0.254) (xy -0.635 0.2286) (xy -0.635 -0.254) (xy -0.5334 -0.254) (xy -0.5334 -0.2794)
				(xy 0.5334 -0.2794) (xy 0.5334 -0.254) (xy 0.635 -0.254) (xy 0.635 0.254) (xy 0.5334 0.254) (xy 0.5334 0.2794)
				(xy -0.508 0.2794) (xy -0.5334 0.2794)
			)
			(stroke
				(width 0)
				(type default)
			)
			(fill no)
			(layer "F.CrtYd")
		)
		(pad "1" smd rect
			(at 0.40005 0 270)
			(size 0.4572 0.508)
			(layers "F.Cu" "F.Mask" "F.Paste")
			(net "FM_CPLD_NODE1_P1V26_BMC_EN")
		)
		(pad "2" smd rect
			(at -0.40005 0 270)
			(size 0.4572 0.508)
			(layers "F.Cu" "F.Mask" "F.Paste")
			(net "GND")
		)
	)
	(footprint ""
		(layer "F.Cu")
		(at 51.310286 -120.460262)
		(property "Reference" "C246"
			(at -7.234428 0.25146 0)
			(unlocked yes)
			(layer "F.SilkS")
			(effects
				(font
					(size 0.7874 0.5842)
					(thickness 0.1524)
				)
				(justify left)
			)
		)
		(property "Value" ""
			(at 0 0 0)
			(layer "F.Fab")
			(effects
				(font
					(size 1.27 1.27)
				)
			)
		)
		(duplicate_pad_numbers_are_jumpers no)
		(fp_line
			(start -0.7874 -0.4064)
			(end 0.7874 -0.4064)
			(stroke
				(width 0.1524)
				(type default)
			)
			(layer "F.SilkS")
		)
		(fp_line
			(start -0.7874 0.4064)
			(end -0.7874 -0.4064)
			(stroke
				(width 0.1524)
				(type default)
			)
			(layer "F.SilkS")
		)
		(fp_line
			(start 0 0.381)
			(end 0 -0.381)
			(stroke
				(width 0.1524)
				(type default)
			)
			(layer "F.SilkS")
		)
		(fp_line
			(start 0.7874 -0.4064)
			(end 0.7874 0.4064)
			(stroke
				(width 0.1524)
				(type default)
			)
			(layer "F.SilkS")
		)
		(fp_line
			(start 0.7874 0.4064)
			(end -0.7874 0.4064)
			(stroke
				(width 0.1524)
				(type default)
			)
			(layer "F.SilkS")
		)
		(fp_poly
			(pts
				(xy -0.5334 0.254) (xy -0.635 0.254) (xy -0.635 0.2286) (xy -0.635 -0.254) (xy -0.5334 -0.254) (xy -0.5334 -0.2794)
				(xy 0.5334 -0.2794) (xy 0.5334 -0.254) (xy 0.635 -0.254) (xy 0.635 0.254) (xy 0.5334 0.254) (xy 0.5334 0.2794)
				(xy -0.508 0.2794) (xy -0.5334 0.2794)
			)
			(stroke
				(width 0)
				(type default)
			)
			(fill no)
			(layer "F.CrtYd")
		)
		(pad "1" smd rect
			(at 0.40005 0)
			(size 0.4572 0.508)
			(layers "F.Cu" "F.Mask" "F.Paste")
			(net "BMC_NODE1_OSC1_VDD")
		)
		(pad "2" smd rect
			(at -0.40005 0)
			(size 0.4572 0.508)
			(layers "F.Cu" "F.Mask" "F.Paste")
			(net "GND")
		)
	)
	(footprint ""
		(layer "F.Cu")
		(at 125.735588 -179.471828 180)
		(property "Reference" "R723"
			(at -1.39446 2.707132 0)
			(unlocked yes)
			(layer "F.SilkS")
			(effects
				(font
					(size 0.7874 0.5842)
					(thickness 0.1524)
				)
				(justify left)
			)
		)
		(property "Value" ""
			(at 0 0 180)
			(layer "F.Fab")
			(effects
				(font
					(size 1.27 1.27)
				)
			)
		)
		(duplicate_pad_numbers_are_jumpers no)
		(fp_line
			(start 0.7874 0.4064)
			(end -0.7874 0.4064)
			(stroke
				(width 0.1524)
				(type default)
			)
			(layer "F.SilkS")
		)
		(fp_line
			(start 0.7874 -0.4064)
			(end 0.7874 0.4064)
			(stroke
				(width 0.1524)
				(type default)
			)
			(layer "F.SilkS")
		)
		(fp_line
			(start -0.7874 0.4064)
			(end -0.7874 -0.4064)
			(stroke
				(width 0.1524)
				(type default)
			)
			(layer "F.SilkS")
		)
		(fp_line
			(start -0.7874 -0.4064)
			(end 0.7874 -0.4064)
			(stroke
				(width 0.1524)
				(type default)
			)
			(layer "F.SilkS")
		)
		(fp_poly
			(pts
				(xy -0.508 0.2794) (xy -0.508 0.2286) (xy -0.635 0.2286) (xy -0.635 -0.254) (xy -0.5334 -0.254)
				(xy -0.5334 -0.2794) (xy 0.5334 -0.2794) (xy 0.5334 -0.254) (xy 0.635 -0.254) (xy 0.635 0.254) (xy 0.5334 0.254)
				(xy 0.5334 0.2794)
			)
			(stroke
				(width 0)
				(type default)
			)
			(fill no)
			(layer "F.CrtYd")
		)
		(pad "1" smd rect
			(at 0.40005 0 180)
			(size 0.4572 0.508)
			(layers "F.Cu" "F.Mask" "F.Paste")
			(net "T7_NODE4_EN")
		)
		(pad "2" smd rect
			(at -0.40005 0 180)
			(size 0.4572 0.508)
			(layers "F.Cu" "F.Mask" "F.Paste")
			(net "P5V_NODE1")
		)
	)
	(footprint ""
		(layer "F.Cu")
		(at 65.672462 -110.333028 90)
		(property "Reference" "Q38"
			(at 0.121666 -2.182876 90)
			(unlocked yes)
			(layer "F.SilkS")
			(effects
				(font
					(size 0.7874 0.5842)
					(thickness 0.1524)
				)
			)
		)
		(property "Value" ""
			(at 0 0 90)
			(layer "F.Fab")
			(effects
				(font
					(size 1.27 1.27)
				)
			)
		)
		(duplicate_pad_numbers_are_jumpers no)
		(fp_line
			(start 1.603248 -1.500124)
			(end 1.603248 1.500124)
			(stroke
				(width 0.1524)
				(type default)
			)
			(layer "F.SilkS")
		)
		(fp_line
			(start -1.603248 -1.500124)
			(end 1.603248 -1.500124)
			(stroke
				(width 0.1524)
				(type default)
			)
			(layer "F.SilkS")
		)
		(fp_line
			(start 1.603248 1.500124)
			(end -1.603248 1.500124)
			(stroke
				(width 0.1524)
				(type default)
			)
			(layer "F.SilkS")
		)
		(fp_line
			(start -1.603248 1.500124)
			(end -1.603248 -1.500124)
			(stroke
				(width 0.1524)
				(type default)
			)
			(layer "F.SilkS")
		)
		(fp_poly
			(pts
				(xy -0.700024 -1.500124) (xy -0.700024 -1.40716) (xy -1.507998 -1.40716) (xy -1.507998 -0.49276)
				(xy -0.700024 -0.49276) (xy -0.700024 0.47244) (xy -1.507998 0.47244) (xy -1.507998 1.41224) (xy -0.700024 1.41224)
				(xy -0.700024 1.500124) (xy 0.700024 1.500124) (xy 0.700024 0.47244) (xy 1.514602 0.47244) (xy 1.514602 -0.46736)
				(xy 0.700024 -0.46736) (xy 0.700024 -1.500124)
			)
			(stroke
				(width 0)
				(type default)
			)
			(fill no)
			(layer "F.CrtYd")
		)
		(fp_line
			(start 0.700024 -1.500124)
			(end 0.700024 1.500124)
			(stroke
				(width 0.1)
				(type default)
			)
			(layer "F.Fab")
		)
		(fp_line
			(start -0.700024 -1.500124)
			(end 0.700024 -1.500124)
			(stroke
				(width 0.1)
				(type default)
			)
			(layer "F.Fab")
		)
		(fp_line
			(start 0.700024 1.500124)
			(end -0.700024 1.500124)
			(stroke
				(width 0.1)
				(type default)
			)
			(layer "F.Fab")
		)
		(fp_line
			(start -0.700024 1.500124)
			(end -0.700024 -1.500124)
			(stroke
				(width 0.1)
				(type default)
			)
			(layer "F.Fab")
		)
		(fp_text user "G"
			(at -2.637536 -2.028444 90)
			(unlocked yes)
			(layer "F.SilkS")
			(effects
				(font
					(size 0.635 0.4064)
					(thickness 0.1524)
				)
			)
		)
		(fp_text user "D"
			(at 2.188464 1.273556 90)
			(unlocked yes)
			(layer "F.SilkS")
			(effects
				(font
					(size 0.635 0.4064)
					(thickness 0.1524)
				)
			)
		)
		(fp_text user "S"
			(at -2.256536 2.416556 90)
			(unlocked yes)
			(layer "F.SilkS")
			(effects
				(font
					(size 0.635 0.4064)
					(thickness 0.1524)
				)
			)
		)
		(fp_text user "G"
			(at -1.051306 -2.032 0)
			(unlocked yes)
			(layer "F.Fab")
			(effects
				(font
					(size 0.7874 0.5842)
					(thickness 0.000001)
				)
			)
		)
		(fp_text user "D"
			(at 2.098294 0.1016 0)
			(unlocked yes)
			(layer "F.Fab")
			(effects
				(font
					(size 0.7874 0.5842)
					(thickness 0.000001)
				)
			)
		)
		(fp_text user "S"
			(at -1.025906 2.0066 0)
			(unlocked yes)
			(layer "F.Fab")
			(effects
				(font
					(size 0.7874 0.5842)
					(thickness 0.000001)
				)
			)
		)
		(pad "D" smd rect
			(at 0.999998 0)
			(size 0.8128 0.9144)
			(layers "F.Cu" "F.Mask" "F.Paste")
			(net "FM_CPLD_NODE1_P1V8_EN_LV")
		)
		(pad "G" smd rect
			(at -0.999998 -0.94996)
			(size 0.8128 0.9144)
			(layers "F.Cu" "F.Mask" "F.Paste")
			(net "FM_CPLD_NODE1_P1V8_EN_G")
		)
		(pad "S" smd rect
			(at -0.999998 0.94996)
			(size 0.8128 0.9144)
			(layers "F.Cu" "F.Mask" "F.Paste")
			(net "FM_CPLD_NODE1_P1V8_EN")
		)
	)
	(footprint ""
		(layer "F.Cu")
		(at 34.990786 -173.4185 90)
		(property "Reference" "R1023"
			(at -7.980172 -2.986786 0)
			(unlocked yes)
			(layer "F.SilkS")
			(effects
				(font
					(size 0.7874 0.5842)
					(thickness 0.1524)
				)
				(justify left)
			)
		)
		(property "Value" ""
			(at 0 0 90)
			(layer "F.Fab")
			(effects
				(font
					(size 1.27 1.27)
				)
			)
		)
		(duplicate_pad_numbers_are_jumpers no)
		(fp_line
			(start 0.7874 -0.4064)
			(end 0.7874 0.4064)
			(stroke
				(width 0.1524)
				(type default)
			)
			(layer "F.SilkS")
		)
		(fp_line
			(start -0.7874 -0.4064)
			(end 0.7874 -0.4064)
			(stroke
				(width 0.1524)
				(type default)
			)
			(layer "F.SilkS")
		)
		(fp_line
			(start 0.7874 0.4064)
			(end -0.7874 0.4064)
			(stroke
				(width 0.1524)
				(type default)
			)
			(layer "F.SilkS")
		)
		(fp_line
			(start -0.7874 0.4064)
			(end -0.7874 -0.4064)
			(stroke
				(width 0.1524)
				(type default)
			)
			(layer "F.SilkS")
		)
		(fp_poly
			(pts
				(xy -0.508 0.2794) (xy -0.508 0.2286) (xy -0.635 0.2286) (xy -0.635 -0.254) (xy -0.5334 -0.254)
				(xy -0.5334 -0.2794) (xy 0.5334 -0.2794) (xy 0.5334 -0.254) (xy 0.635 -0.254) (xy 0.635 0.254) (xy 0.5334 0.254)
				(xy 0.5334 0.2794)
			)
			(stroke
				(width 0)
				(type default)
			)
			(fill no)
			(layer "F.CrtYd")
		)
		(pad "1" smd rect
			(at 0.40005 0 90)
			(size 0.4572 0.508)
			(layers "F.Cu" "F.Mask" "F.Paste")
			(net "SMB_BMC_NODE1_HSC_ALERT_L")
		)
		(pad "2" smd rect
			(at -0.40005 0 90)
			(size 0.4572 0.508)
			(layers "F.Cu" "F.Mask" "F.Paste")
			(net "P3V3_SUS_NODE1")
		)
	)
	(footprint ""
		(layer "F.Cu")
		(at 120.85193 -70.425818)
		(property "Reference" "U3"
			(at -1.069594 -2.505202 0)
			(unlocked yes)
			(layer "F.SilkS")
			(effects
				(font
					(size 0.7874 0.5842)
					(thickness 0.1524)
				)
			)
		)
		(property "Value" ""
			(at 0 0 0)
			(layer "F.Fab")
			(effects
				(font
					(size 1.27 1.27)
				)
			)
		)
		(duplicate_pad_numbers_are_jumpers no)
		(fp_line
			(start -1.651 -1.905)
			(end 1.651 -1.905)
			(stroke
				(width 0.1524)
				(type default)
			)
			(layer "F.SilkS")
		)
		(fp_line
			(start -1.651 1.905)
			(end -1.651 -1.905)
			(stroke
				(width 0.1524)
				(type default)
			)
			(layer "F.SilkS")
		)
		(fp_line
			(start 1.651 -1.905)
			(end 1.651 1.905)
			(stroke
				(width 0.1524)
				(type default)
			)
			(layer "F.SilkS")
		)
		(fp_line
			(start 1.651 1.905)
			(end -1.651 1.905)
			(stroke
				(width 0.1524)
				(type default)
			)
			(layer "F.SilkS")
		)
		(fp_poly
			(pts
				(xy -1.524 0.7112) (xy -1.524 1.7526) (xy -0.508 1.7526) (xy -0.508 0.6985) (xy 0.508 0.6985) (xy 0.508 1.7526)
				(xy 1.524 1.7526) (xy 1.524 0.6985) (xy 1.524 -0.6985) (xy 0.508 -0.6985) (xy 0.508 -1.7526) (xy -0.508 -1.7526)
				(xy -0.508 -0.6985) (xy -1.524 -0.6985) (xy -1.524 0.6985)
			)
			(stroke
				(width 0)
				(type default)
			)
			(fill no)
			(layer "F.CrtYd")
		)
		(fp_text user "1"
			(at -2.094484 0.8509 0)
			(unlocked yes)
			(layer "F.SilkS")
			(effects
				(font
					(size 0.635 0.4064)
					(thickness 0.1524)
				)
			)
		)
		(fp_text user "3"
			(at 1.08204 -2.361946 0)
			(unlocked yes)
			(layer "F.SilkS")
			(effects
				(font
					(size 0.635 0.4064)
					(thickness 0.1524)
				)
			)
		)
		(fp_text user "2"
			(at 2.131822 2.203704 0)
			(unlocked yes)
			(layer "F.SilkS")
			(effects
				(font
					(size 0.635 0.4064)
					(thickness 0.1524)
				)
			)
		)
		(pad "1" smd rect
			(at -1.016 1.1176)
			(size 1.016 1.27)
			(layers "F.Cu" "F.Mask" "F.Paste")
			(net "P3V3_STB_NODE1")
		)
		(pad "2" smd rect
			(at 1.016 1.1176)
			(size 1.016 1.27)
			(layers "F.Cu" "F.Mask" "F.Paste")
			(net "P3V0_BAT_NODE1_R")
		)
		(pad "3" smd rect
			(at 0 -1.1176)
			(size 1.016 1.27)
			(layers "F.Cu" "F.Mask" "F.Paste")
			(net "P3V3_RTC_NODE1")
		)
	)
	(footprint ""
		(layer "F.Cu")
		(at 23.84171 -110.729522 180)
		(property "Reference" "PC68"
			(at -2.97815 2.097532 0)
			(unlocked yes)
			(layer "F.SilkS")
			(effects
				(font
					(size 0.7874 0.5842)
					(thickness 0.1524)
				)
				(justify left)
			)
		)
		(property "Value" ""
			(at 0 0 180)
			(layer "F.Fab")
			(effects
				(font
					(size 1.27 1.27)
				)
			)
		)
		(duplicate_pad_numbers_are_jumpers no)
		(fp_line
			(start 1.905 0.8636)
			(end -1.905 0.8636)
			(stroke
				(width 0.1524)
				(type default)
			)
			(layer "F.SilkS")
		)
		(fp_line
			(start 1.905 -0.8636)
			(end 1.905 0.8636)
			(stroke
				(width 0.1524)
				(type default)
			)
			(layer "F.SilkS")
		)
		(fp_line
			(start 0 0.837946)
			(end 0 -0.837946)
			(stroke
				(width 0.1524)
				(type default)
			)
			(layer "F.SilkS")
		)
		(fp_line
			(start -1.905 0.8636)
			(end -1.905 -0.8636)
			(stroke
				(width 0.1524)
				(type default)
			)
			(layer "F.SilkS")
		)
		(fp_line
			(start -1.905 -0.8636)
			(end 1.905 -0.8636)
			(stroke
				(width 0.1524)
				(type default)
			)
			(layer "F.SilkS")
		)
		(fp_rect
			(start -1.524 0.7366)
			(end 1.524 -0.7366)
			(stroke
				(width 0)
				(type default)
			)
			(fill no)
			(layer "F.CrtYd")
		)
		(pad "1" smd rect
			(at 0.94996 0 180)
			(size 1.1176 1.3716)
			(layers "F.Cu" "F.Mask" "F.Paste")
			(net "P1V05_NODE1")
		)
		(pad "2" smd rect
			(at -0.94996 0 180)
			(size 1.1176 1.3716)
			(layers "F.Cu" "F.Mask" "F.Paste")
			(net "GND")
		)
	)
	(footprint ""
		(layer "F.Cu")
		(at 8.19658 -154.13736 -90)
		(property "Reference" "R1299"
			(at 5.109464 -8.876792 90)
			(unlocked yes)
			(layer "F.SilkS")
			(effects
				(font
					(size 0.7874 0.5842)
					(thickness 0.1524)
				)
				(justify left)
			)
		)
		(property "Value" ""
			(at 0 0 270)
			(layer "F.Fab")
			(effects
				(font
					(size 1.27 1.27)
				)
			)
		)
		(duplicate_pad_numbers_are_jumpers no)
		(fp_line
			(start -0.7874 0.4064)
			(end -0.7874 -0.4064)
			(stroke
				(width 0.1524)
				(type default)
			)
			(layer "F.SilkS")
		)
		(fp_line
			(start 0.7874 0.4064)
			(end -0.7874 0.4064)
			(stroke
				(width 0.1524)
				(type default)
			)
			(layer "F.SilkS")
		)
		(fp_line
			(start -0.7874 -0.4064)
			(end 0.7874 -0.4064)
			(stroke
				(width 0.1524)
				(type default)
			)
			(layer "F.SilkS")
		)
		(fp_line
			(start 0.7874 -0.4064)
			(end 0.7874 0.4064)
			(stroke
				(width 0.1524)
				(type default)
			)
			(layer "F.SilkS")
		)
		(fp_poly
			(pts
				(xy -0.508 0.2794) (xy -0.508 0.2286) (xy -0.635 0.2286) (xy -0.635 -0.254) (xy -0.5334 -0.254)
				(xy -0.5334 -0.2794) (xy 0.5334 -0.2794) (xy 0.5334 -0.254) (xy 0.635 -0.254) (xy 0.635 0.254) (xy 0.5334 0.254)
				(xy 0.5334 0.2794)
			)
			(stroke
				(width 0)
				(type default)
			)
			(fill no)
			(layer "F.CrtYd")
		)
		(pad "1" smd rect
			(at 0.40005 0 270)
			(size 0.4572 0.508)
			(layers "F.Cu" "F.Mask" "F.Paste")
			(net "P3V3_NODE1")
		)
		(pad "2" smd rect
			(at -0.40005 0 270)
			(size 0.4572 0.508)
			(layers "F.Cu" "F.Mask" "F.Paste")
			(net "N54258474")
		)
	)
	(footprint ""
		(layer "F.Cu")
		(at 31.122112 -169.072052)
		(property "Reference" "R1251"
			(at -3.05562 6.778752 0)
			(unlocked yes)
			(layer "F.SilkS")
			(effects
				(font
					(size 0.7874 0.5842)
					(thickness 0.1524)
				)
				(justify left)
			)
		)
		(property "Value" ""
			(at 0 0 0)
			(layer "F.Fab")
			(effects
				(font
					(size 1.27 1.27)
				)
			)
		)
		(duplicate_pad_numbers_are_jumpers no)
		(fp_line
			(start -0.7874 -0.4064)
			(end 0.7874 -0.4064)
			(stroke
				(width 0.1524)
				(type default)
			)
			(layer "F.SilkS")
		)
		(fp_line
			(start -0.7874 0.4064)
			(end -0.7874 -0.4064)
			(stroke
				(width 0.1524)
				(type default)
			)
			(layer "F.SilkS")
		)
		(fp_line
			(start 0.7874 -0.4064)
			(end 0.7874 0.4064)
			(stroke
				(width 0.1524)
				(type default)
			)
			(layer "F.SilkS")
		)
		(fp_line
			(start 0.7874 0.4064)
			(end -0.7874 0.4064)
			(stroke
				(width 0.1524)
				(type default)
			)
			(layer "F.SilkS")
		)
		(fp_poly
			(pts
				(xy -0.508 0.2794) (xy -0.508 0.2286) (xy -0.635 0.2286) (xy -0.635 -0.254) (xy -0.5334 -0.254)
				(xy -0.5334 -0.2794) (xy 0.5334 -0.2794) (xy 0.5334 -0.254) (xy 0.635 -0.254) (xy 0.635 0.254) (xy 0.5334 0.254)
				(xy 0.5334 0.2794)
			)
			(stroke
				(width 0)
				(type default)
			)
			(fill no)
			(layer "F.CrtYd")
		)
		(pad "1" smd rect
			(at 0.40005 0)
			(size 0.4572 0.508)
			(layers "F.Cu" "F.Mask" "F.Paste")
			(net "CM_PWR_CTL_IN_R")
		)
		(pad "2" smd rect
			(at -0.40005 0)
			(size 0.4572 0.508)
			(layers "F.Cu" "F.Mask" "F.Paste")
			(net "GND")
		)
	)
	(footprint ""
		(layer "F.Cu")
		(at 71.10476 -188.126624 -90)
		(property "Reference" "R950"
			(at -4.548886 0.908558 90)
			(unlocked yes)
			(layer "F.SilkS")
			(effects
				(font
					(size 0.7874 0.5842)
					(thickness 0.1524)
				)
				(justify left)
			)
		)
		(property "Value" ""
			(at 0 0 270)
			(layer "F.Fab")
			(effects
				(font
					(size 1.27 1.27)
				)
			)
		)
		(duplicate_pad_numbers_are_jumpers no)
		(fp_line
			(start -0.7874 0.4064)
			(end -0.7874 -0.4064)
			(stroke
				(width 0.1524)
				(type default)
			)
			(layer "F.SilkS")
		)
		(fp_line
			(start 0.7874 0.4064)
			(end -0.7874 0.4064)
			(stroke
				(width 0.1524)
				(type default)
			)
			(layer "F.SilkS")
		)
		(fp_line
			(start -0.7874 -0.4064)
			(end 0.7874 -0.4064)
			(stroke
				(width 0.1524)
				(type default)
			)
			(layer "F.SilkS")
		)
		(fp_line
			(start 0.7874 -0.4064)
			(end 0.7874 0.4064)
			(stroke
				(width 0.1524)
				(type default)
			)
			(layer "F.SilkS")
		)
		(fp_poly
			(pts
				(xy -0.508 0.2794) (xy -0.508 0.2286) (xy -0.635 0.2286) (xy -0.635 -0.254) (xy -0.5334 -0.254)
				(xy -0.5334 -0.2794) (xy 0.5334 -0.2794) (xy 0.5334 -0.254) (xy 0.635 -0.254) (xy 0.635 0.254) (xy 0.5334 0.254)
				(xy 0.5334 0.2794)
			)
			(stroke
				(width 0)
				(type default)
			)
			(fill no)
			(layer "F.CrtYd")
		)
		(pad "1" smd rect
			(at 0.40005 0 270)
			(size 0.4572 0.508)
			(layers "F.Cu" "F.Mask" "F.Paste")
			(net "UART_T4_NODE4_RXD")
		)
		(pad "2" smd rect
			(at -0.40005 0 270)
			(size 0.4572 0.508)
			(layers "F.Cu" "F.Mask" "F.Paste")
			(net "UART_T4_NODE4_RXD_R")
		)
	)
	(footprint ""
		(layer "F.Cu")
		(at 155.685998 -142.93723 -90)
		(property "Reference" "R568"
			(at -1.23063 -0.43307 90)
			(unlocked yes)
			(layer "F.SilkS")
			(effects
				(font
					(size 0.7874 0.5842)
					(thickness 0.1524)
				)
				(justify left)
			)
		)
		(property "Value" ""
			(at 0 0 270)
			(layer "F.Fab")
			(effects
				(font
					(size 1.27 1.27)
				)
			)
		)
		(duplicate_pad_numbers_are_jumpers no)
		(fp_line
			(start -0.7874 0.4064)
			(end -0.7874 -0.4064)
			(stroke
				(width 0.1524)
				(type default)
			)
			(layer "F.SilkS")
		)
		(fp_line
			(start 0.7874 0.4064)
			(end -0.7874 0.4064)
			(stroke
				(width 0.1524)
				(type default)
			)
			(layer "F.SilkS")
		)
		(fp_line
			(start -0.7874 -0.4064)
			(end 0.7874 -0.4064)
			(stroke
				(width 0.1524)
				(type default)
			)
			(layer "F.SilkS")
		)
		(fp_line
			(start 0.7874 -0.4064)
			(end 0.7874 0.4064)
			(stroke
				(width 0.1524)
				(type default)
			)
			(layer "F.SilkS")
		)
		(fp_poly
			(pts
				(xy -0.508 0.2794) (xy -0.508 0.2286) (xy -0.635 0.2286) (xy -0.635 -0.254) (xy -0.5334 -0.254)
				(xy -0.5334 -0.2794) (xy 0.5334 -0.2794) (xy 0.5334 -0.254) (xy 0.635 -0.254) (xy 0.635 0.254) (xy 0.5334 0.254)
				(xy 0.5334 0.2794)
			)
			(stroke
				(width 0)
				(type default)
			)
			(fill no)
			(layer "F.CrtYd")
		)
		(pad "1" smd rect
			(at 0.40005 0 270)
			(size 0.4572 0.508)
			(layers "F.Cu" "F.Mask" "F.Paste")
			(net "P3V3_NODE1")
		)
		(pad "2" smd rect
			(at -0.40005 0 270)
			(size 0.4572 0.508)
			(layers "F.Cu" "F.Mask" "F.Paste")
			(net "PU_LAN2_TMS")
		)
	)
	(footprint ""
		(layer "F.Cu")
		(at 76.490068 -94.131892 -90)
		(property "Reference" "R157"
			(at 55.53329 -24.083264 90)
			(unlocked yes)
			(layer "F.SilkS")
			(effects
				(font
					(size 0.7874 0.5842)
					(thickness 0.1524)
				)
				(justify left)
			)
		)
		(property "Value" ""
			(at 0 0 270)
			(layer "F.Fab")
			(effects
				(font
					(size 1.27 1.27)
				)
			)
		)
		(duplicate_pad_numbers_are_jumpers no)
		(fp_line
			(start -0.7874 0.4064)
			(end -0.7874 -0.4064)
			(stroke
				(width 0.1524)
				(type default)
			)
			(layer "F.SilkS")
		)
		(fp_line
			(start 0.7874 0.4064)
			(end -0.7874 0.4064)
			(stroke
				(width 0.1524)
				(type default)
			)
			(layer "F.SilkS")
		)
		(fp_line
			(start -0.7874 -0.4064)
			(end 0.7874 -0.4064)
			(stroke
				(width 0.1524)
				(type default)
			)
			(layer "F.SilkS")
		)
		(fp_line
			(start 0.7874 -0.4064)
			(end 0.7874 0.4064)
			(stroke
				(width 0.1524)
				(type default)
			)
			(layer "F.SilkS")
		)
		(fp_poly
			(pts
				(xy -0.508 0.2794) (xy -0.508 0.2286) (xy -0.635 0.2286) (xy -0.635 -0.254) (xy -0.5334 -0.254)
				(xy -0.5334 -0.2794) (xy 0.5334 -0.2794) (xy 0.5334 -0.254) (xy 0.635 -0.254) (xy 0.635 0.254) (xy 0.5334 0.254)
				(xy 0.5334 0.2794)
			)
			(stroke
				(width 0)
				(type default)
			)
			(fill no)
			(layer "F.CrtYd")
		)
		(pad "1" smd rect
			(at 0.40005 0 270)
			(size 0.4572 0.508)
			(layers "F.Cu" "F.Mask" "F.Paste")
			(net "PD_CPU_NODE1_NODE_ID")
		)
		(pad "2" smd rect
			(at -0.40005 0 270)
			(size 0.4572 0.508)
			(layers "F.Cu" "F.Mask" "F.Paste")
			(net "P3V3_NODE1")
		)
	)
	(footprint ""
		(layer "F.Cu")
		(at 76.419456 -150.293578)
		(property "Reference" "PC1"
			(at -1.18999 1.655826 0)
			(unlocked yes)
			(layer "F.SilkS")
			(effects
				(font
					(size 0.7874 0.5842)
					(thickness 0.1524)
				)
				(justify left)
			)
		)
		(property "Value" ""
			(at 0 0 0)
			(layer "F.Fab")
			(effects
				(font
					(size 1.27 1.27)
				)
			)
		)
		(duplicate_pad_numbers_are_jumpers no)
		(fp_line
			(start -2.2098 -0.9398)
			(end 2.2098 -0.9398)
			(stroke
				(width 0.1524)
				(type default)
			)
			(layer "F.SilkS")
		)
		(fp_line
			(start -2.2098 0.9398)
			(end -2.2098 -0.9398)
			(stroke
				(width 0.1524)
				(type default)
			)
			(layer "F.SilkS")
		)
		(fp_line
			(start 0 -0.9398)
			(end 0 0.9398)
			(stroke
				(width 0.1524)
				(type default)
			)
			(layer "F.SilkS")
		)
		(fp_line
			(start 2.2098 -0.9398)
			(end 2.2098 0.9398)
			(stroke
				(width 0.1524)
				(type default)
			)
			(layer "F.SilkS")
		)
		(fp_line
			(start 2.2098 0.9398)
			(end -2.2098 0.9398)
			(stroke
				(width 0.1524)
				(type default)
			)
			(layer "F.SilkS")
		)
		(fp_poly
			(pts
				(xy -1.6764 0.889) (xy -1.6764 0.7874) (xy -2.0574 0.7874) (xy -2.0574 -0.7874) (xy -1.6764 -0.7874)
				(xy -1.6764 -0.9398) (xy 1.6764 -0.9398) (xy 1.6764 -0.7874) (xy 2.0574 -0.7874) (xy 2.0574 0.7874)
				(xy 1.6764 0.7874) (xy 1.6764 0.9398) (xy -1.6764 0.9398)
			)
			(stroke
				(width 0)
				(type default)
			)
			(fill no)
			(layer "F.CrtYd")
		)
		(fp_line
			(start -1.700022 -0.899922)
			(end 1.700022 -0.899922)
			(stroke
				(width 0.1)
				(type default)
			)
			(layer "F.Fab")
		)
		(fp_line
			(start -1.700022 0.899922)
			(end -1.700022 -0.899922)
			(stroke
				(width 0.1)
				(type default)
			)
			(layer "F.Fab")
		)
		(fp_line
			(start 1.700022 -0.899922)
			(end 1.700022 0.899922)
			(stroke
				(width 0.1)
				(type default)
			)
			(layer "F.Fab")
		)
		(fp_line
			(start 1.700022 0.899922)
			(end -1.700022 0.899922)
			(stroke
				(width 0.1)
				(type default)
			)
			(layer "F.Fab")
		)
		(pad "1" smd rect
			(at 1.4732 0)
			(size 1.1684 1.5748)
			(layers "F.Cu" "F.Mask" "F.Paste")
			(net "P12V_AUX")
		)
		(pad "2" smd rect
			(at -1.4732 0)
			(size 1.1684 1.5748)
			(layers "F.Cu" "F.Mask" "F.Paste")
			(net "GND")
		)
	)
	(footprint ""
		(layer "F.Cu")
		(at 133.71576 -110.783624 -90)
		(property "Reference" "R17"
			(at 5.84835 -0.882142 90)
			(unlocked yes)
			(layer "F.SilkS")
			(effects
				(font
					(size 0.7874 0.5842)
					(thickness 0.1524)
				)
				(justify left)
			)
		)
		(property "Value" ""
			(at 0 0 270)
			(layer "F.Fab")
			(effects
				(font
					(size 1.27 1.27)
				)
			)
		)
		(duplicate_pad_numbers_are_jumpers no)
		(fp_line
			(start -0.7874 0.4064)
			(end -0.7874 -0.4064)
			(stroke
				(width 0.1524)
				(type default)
			)
			(layer "F.SilkS")
		)
		(fp_line
			(start 0.7874 0.4064)
			(end -0.7874 0.4064)
			(stroke
				(width 0.1524)
				(type default)
			)
			(layer "F.SilkS")
		)
		(fp_line
			(start -0.7874 -0.4064)
			(end 0.7874 -0.4064)
			(stroke
				(width 0.1524)
				(type default)
			)
			(layer "F.SilkS")
		)
		(fp_line
			(start 0.7874 -0.4064)
			(end 0.7874 0.4064)
			(stroke
				(width 0.1524)
				(type default)
			)
			(layer "F.SilkS")
		)
		(fp_poly
			(pts
				(xy -0.508 0.2794) (xy -0.508 0.2286) (xy -0.635 0.2286) (xy -0.635 -0.254) (xy -0.5334 -0.254)
				(xy -0.5334 -0.2794) (xy 0.5334 -0.2794) (xy 0.5334 -0.254) (xy 0.635 -0.254) (xy 0.635 0.254) (xy 0.5334 0.254)
				(xy 0.5334 0.2794)
			)
			(stroke
				(width 0)
				(type default)
			)
			(fill no)
			(layer "F.CrtYd")
		)
		(pad "1" smd rect
			(at 0.40005 0 270)
			(size 0.4572 0.508)
			(layers "F.Cu" "F.Mask" "F.Paste")
			(net "GND")
		)
		(pad "2" smd rect
			(at -0.40005 0 270)
			(size 0.4572 0.508)
			(layers "F.Cu" "F.Mask" "F.Paste")
			(net "CLP_ITP_EN_NODE1")
		)
	)
	(footprint ""
		(layer "F.Cu")
		(at 67.924934 -2.944114 -90)
		(property "Reference" "PR18"
			(at 2.74828 2.869184 90)
			(unlocked yes)
			(layer "F.SilkS")
			(effects
				(font
					(size 0.7874 0.5842)
					(thickness 0.1524)
				)
				(justify left)
			)
		)
		(property "Value" ""
			(at 0 0 270)
			(layer "F.Fab")
			(effects
				(font
					(size 1.27 1.27)
				)
			)
		)
		(duplicate_pad_numbers_are_jumpers no)
		(fp_line
			(start -0.7874 0.4064)
			(end -0.7874 -0.4064)
			(stroke
				(width 0.1524)
				(type default)
			)
			(layer "F.SilkS")
		)
		(fp_line
			(start 0.7874 0.4064)
			(end -0.7874 0.4064)
			(stroke
				(width 0.1524)
				(type default)
			)
			(layer "F.SilkS")
		)
		(fp_line
			(start -0.7874 -0.4064)
			(end 0.7874 -0.4064)
			(stroke
				(width 0.1524)
				(type default)
			)
			(layer "F.SilkS")
		)
		(fp_line
			(start 0.7874 -0.4064)
			(end 0.7874 0.4064)
			(stroke
				(width 0.1524)
				(type default)
			)
			(layer "F.SilkS")
		)
		(fp_poly
			(pts
				(xy -0.508 0.2794) (xy -0.508 0.2286) (xy -0.635 0.2286) (xy -0.635 -0.254) (xy -0.5334 -0.254)
				(xy -0.5334 -0.2794) (xy 0.5334 -0.2794) (xy 0.5334 -0.254) (xy 0.635 -0.254) (xy 0.635 0.254) (xy 0.5334 0.254)
				(xy 0.5334 0.2794)
			)
			(stroke
				(width 0)
				(type default)
			)
			(fill no)
			(layer "F.CrtYd")
		)
		(pad "1" smd rect
			(at 0.40005 0 270)
			(size 0.4572 0.508)
			(layers "F.Cu" "F.Mask" "F.Paste")
			(net "P3V3_NODE1_VREG5")
		)
		(pad "2" smd rect
			(at -0.40005 0 270)
			(size 0.4572 0.508)
			(layers "F.Cu" "F.Mask" "F.Paste")
			(net "PWRGD_NODE1_P3V3_PG")
		)
	)
	(footprint ""
		(layer "F.Cu")
		(at 77.138022 -17.664176 90)
		(property "Reference" "C176"
			(at -3.058414 5.652262 90)
			(unlocked yes)
			(layer "F.SilkS")
			(effects
				(font
					(size 0.7874 0.5842)
					(thickness 0.1524)
				)
			)
		)
		(property "Value" ""
			(at 0 0 90)
			(layer "F.Fab")
			(effects
				(font
					(size 1.27 1.27)
				)
			)
		)
		(duplicate_pad_numbers_are_jumpers no)
		(fp_line
			(start 1.2954 -0.5842)
			(end 1.2954 0.5842)
			(stroke
				(width 0.1524)
				(type default)
			)
			(layer "F.SilkS")
		)
		(fp_line
			(start 0 -0.5842)
			(end 0 0.5842)
			(stroke
				(width 0.1524)
				(type default)
			)
			(layer "F.SilkS")
		)
		(fp_line
			(start -1.2954 -0.5842)
			(end 1.2954 -0.5842)
			(stroke
				(width 0.1524)
				(type default)
			)
			(layer "F.SilkS")
		)
		(fp_line
			(start 1.2954 0.5842)
			(end -1.2954 0.5842)
			(stroke
				(width 0.1524)
				(type default)
			)
			(layer "F.SilkS")
		)
		(fp_line
			(start -1.2954 0.5842)
			(end -1.2954 -0.5842)
			(stroke
				(width 0.1524)
				(type default)
			)
			(layer "F.SilkS")
		)
		(fp_poly
			(pts
				(xy 0.8636 -0.4572) (xy 0.8636 -0.3556) (xy 1.143 -0.3556) (xy 1.143 0.3556) (xy 0.8636 0.3556)
				(xy 0.8636 0.4572) (xy -0.8636 0.4572) (xy -0.8636 0.3556) (xy -1.143 0.3556) (xy -1.143 -0.3556)
				(xy -0.8636 -0.3556) (xy -0.8636 -0.4572)
			)
			(stroke
				(width 0)
				(type default)
			)
			(fill no)
			(layer "F.CrtYd")
		)
		(fp_line
			(start 0.884936 -0.504952)
			(end 0.884936 0.504952)
			(stroke
				(width 0.1)
				(type default)
			)
			(layer "F.Fab")
		)
		(fp_line
			(start -0.884936 -0.504952)
			(end 0.884936 -0.504952)
			(stroke
				(width 0.1)
				(type default)
			)
			(layer "F.Fab")
		)
		(fp_line
			(start 0.884936 0.504952)
			(end -0.884936 0.504952)
			(stroke
				(width 0.1)
				(type default)
			)
			(layer "F.Fab")
		)
		(fp_line
			(start -0.884936 0.504952)
			(end -0.884936 -0.504952)
			(stroke
				(width 0.1)
				(type default)
			)
			(layer "F.Fab")
		)
		(pad "1" smd rect
			(at 0.7366 0 180)
			(size 0.7112 0.8128)
			(layers "F.Cu" "F.Mask" "F.Paste")
			(net "PV_VDDR_NODE1")
		)
		(pad "2" smd rect
			(at -0.7366 0 180)
			(size 0.7112 0.8128)
			(layers "F.Cu" "F.Mask" "F.Paste")
			(net "GND")
		)
	)
	(footprint ""
		(layer "F.Cu")
		(at 171.151042 -139.383008)
		(property "Reference" "R1066"
			(at -2.911094 -9.79932 0)
			(unlocked yes)
			(layer "F.SilkS")
			(effects
				(font
					(size 0.7874 0.5842)
					(thickness 0.1524)
				)
				(justify left)
			)
		)
		(property "Value" ""
			(at 0 0 0)
			(layer "F.Fab")
			(effects
				(font
					(size 1.27 1.27)
				)
			)
		)
		(duplicate_pad_numbers_are_jumpers no)
		(fp_line
			(start -0.7874 -0.4064)
			(end 0.7874 -0.4064)
			(stroke
				(width 0.1524)
				(type default)
			)
			(layer "F.SilkS")
		)
		(fp_line
			(start -0.7874 0.4064)
			(end -0.7874 -0.4064)
			(stroke
				(width 0.1524)
				(type default)
			)
			(layer "F.SilkS")
		)
		(fp_line
			(start 0.7874 -0.4064)
			(end 0.7874 0.4064)
			(stroke
				(width 0.1524)
				(type default)
			)
			(layer "F.SilkS")
		)
		(fp_line
			(start 0.7874 0.4064)
			(end -0.7874 0.4064)
			(stroke
				(width 0.1524)
				(type default)
			)
			(layer "F.SilkS")
		)
		(fp_poly
			(pts
				(xy -0.508 0.2794) (xy -0.508 0.2286) (xy -0.635 0.2286) (xy -0.635 -0.254) (xy -0.5334 -0.254)
				(xy -0.5334 -0.2794) (xy 0.5334 -0.2794) (xy 0.5334 -0.254) (xy 0.635 -0.254) (xy 0.635 0.254) (xy 0.5334 0.254)
				(xy 0.5334 0.2794)
			)
			(stroke
				(width 0)
				(type default)
			)
			(fill no)
			(layer "F.CrtYd")
		)
		(pad "1" smd rect
			(at 0.40005 0)
			(size 0.4572 0.508)
			(layers "F.Cu" "F.Mask" "F.Paste")
			(net "PWR_BTN_NODE1_C_L")
		)
		(pad "2" smd rect
			(at -0.40005 0)
			(size 0.4572 0.508)
			(layers "F.Cu" "F.Mask" "F.Paste")
			(net "FM_CPLD_NODE1_PWR_BTN_L")
		)
	)
	(footprint ""
		(layer "F.Cu")
		(at 108.72724 -142.414498 90)
		(property "Reference" "PR64"
			(at 1.927352 0.092964 90)
			(unlocked yes)
			(layer "F.SilkS")
			(effects
				(font
					(size 0.635 0.4064)
					(thickness 0.1524)
				)
				(justify left)
			)
		)
		(property "Value" ""
			(at 0 0 90)
			(layer "F.Fab")
			(effects
				(font
					(size 1.27 1.27)
				)
			)
		)
		(duplicate_pad_numbers_are_jumpers no)
		(fp_line
			(start 0.7874 -0.4064)
			(end 0.7874 0.4064)
			(stroke
				(width 0.1524)
				(type default)
			)
			(layer "F.SilkS")
		)
		(fp_line
			(start -0.7874 -0.4064)
			(end 0.7874 -0.4064)
			(stroke
				(width 0.1524)
				(type default)
			)
			(layer "F.SilkS")
		)
		(fp_line
			(start 0.7874 0.4064)
			(end -0.7874 0.4064)
			(stroke
				(width 0.1524)
				(type default)
			)
			(layer "F.SilkS")
		)
		(fp_line
			(start -0.7874 0.4064)
			(end -0.7874 -0.4064)
			(stroke
				(width 0.1524)
				(type default)
			)
			(layer "F.SilkS")
		)
		(fp_poly
			(pts
				(xy -0.508 0.2794) (xy -0.508 0.2286) (xy -0.635 0.2286) (xy -0.635 -0.254) (xy -0.5334 -0.254)
				(xy -0.5334 -0.2794) (xy 0.5334 -0.2794) (xy 0.5334 -0.254) (xy 0.635 -0.254) (xy 0.635 0.254) (xy 0.5334 0.254)
				(xy 0.5334 0.2794)
			)
			(stroke
				(width 0)
				(type default)
			)
			(fill no)
			(layer "F.CrtYd")
		)
		(pad "1" smd rect
			(at 0.40005 0 90)
			(size 0.4572 0.508)
			(layers "F.Cu" "F.Mask" "F.Paste")
			(net "VR_PVCCP_NODE1_VCC")
		)
		(pad "2" smd rect
			(at -0.40005 0 90)
			(size 0.4572 0.508)
			(layers "F.Cu" "F.Mask" "F.Paste")
			(net "VR_PVCCP_NODE1_ICCMAX")
		)
	)
	(footprint ""
		(layer "F.Cu")
		(at 159.652208 -74.318114)
		(property "Reference" "C851"
			(at -3.902456 -2.80289 0)
			(unlocked yes)
			(layer "F.SilkS")
			(effects
				(font
					(size 0.7874 0.5842)
					(thickness 0.1524)
				)
				(justify left)
			)
		)
		(property "Value" ""
			(at 0 0 0)
			(layer "F.Fab")
			(effects
				(font
					(size 1.27 1.27)
				)
			)
		)
		(duplicate_pad_numbers_are_jumpers no)
		(fp_line
			(start -0.7874 -0.4064)
			(end 0.7874 -0.4064)
			(stroke
				(width 0.1524)
				(type default)
			)
			(layer "F.SilkS")
		)
		(fp_line
			(start -0.7874 0.4064)
			(end -0.7874 -0.4064)
			(stroke
				(width 0.1524)
				(type default)
			)
			(layer "F.SilkS")
		)
		(fp_line
			(start 0 0.381)
			(end 0 -0.381)
			(stroke
				(width 0.1524)
				(type default)
			)
			(layer "F.SilkS")
		)
		(fp_line
			(start 0.7874 -0.4064)
			(end 0.7874 0.4064)
			(stroke
				(width 0.1524)
				(type default)
			)
			(layer "F.SilkS")
		)
		(fp_line
			(start 0.7874 0.4064)
			(end -0.7874 0.4064)
			(stroke
				(width 0.1524)
				(type default)
			)
			(layer "F.SilkS")
		)
		(fp_poly
			(pts
				(xy -0.5334 0.254) (xy -0.635 0.254) (xy -0.635 0.2286) (xy -0.635 -0.254) (xy -0.5334 -0.254) (xy -0.5334 -0.2794)
				(xy 0.5334 -0.2794) (xy 0.5334 -0.254) (xy 0.635 -0.254) (xy 0.635 0.254) (xy 0.5334 0.254) (xy 0.5334 0.2794)
				(xy -0.508 0.2794) (xy -0.5334 0.2794)
			)
			(stroke
				(width 0)
				(type default)
			)
			(fill no)
			(layer "F.CrtYd")
		)
		(pad "1" smd rect
			(at 0.40005 0)
			(size 0.4572 0.508)
			(layers "F.Cu" "F.Mask" "F.Paste")
			(net "P1V0_ADJ")
		)
		(pad "2" smd rect
			(at -0.40005 0)
			(size 0.4572 0.508)
			(layers "F.Cu" "F.Mask" "F.Paste")
			(net "P1V0_ADJ_S")
		)
	)
	(footprint ""
		(layer "F.Cu")
		(at 111.74476 -188.126624 90)
		(property "Reference" "C647"
			(at 5.151882 1.617472 90)
			(unlocked yes)
			(layer "F.SilkS")
			(effects
				(font
					(size 0.7874 0.5842)
					(thickness 0.1524)
				)
				(justify left)
			)
		)
		(property "Value" ""
			(at 0 0 90)
			(layer "F.Fab")
			(effects
				(font
					(size 1.27 1.27)
				)
			)
		)
		(duplicate_pad_numbers_are_jumpers no)
		(fp_line
			(start 0.7874 -0.4064)
			(end 0.7874 0.4064)
			(stroke
				(width 0.1524)
				(type default)
			)
			(layer "F.SilkS")
		)
		(fp_line
			(start -0.7874 -0.4064)
			(end 0.7874 -0.4064)
			(stroke
				(width 0.1524)
				(type default)
			)
			(layer "F.SilkS")
		)
		(fp_line
			(start 0 0.381)
			(end 0 -0.381)
			(stroke
				(width 0.1524)
				(type default)
			)
			(layer "F.SilkS")
		)
		(fp_line
			(start 0.7874 0.4064)
			(end -0.7874 0.4064)
			(stroke
				(width 0.1524)
				(type default)
			)
			(layer "F.SilkS")
		)
		(fp_line
			(start -0.7874 0.4064)
			(end -0.7874 -0.4064)
			(stroke
				(width 0.1524)
				(type default)
			)
			(layer "F.SilkS")
		)
		(fp_poly
			(pts
				(xy -0.5334 0.254) (xy -0.635 0.254) (xy -0.635 0.2286) (xy -0.635 -0.254) (xy -0.5334 -0.254) (xy -0.5334 -0.2794)
				(xy 0.5334 -0.2794) (xy 0.5334 -0.254) (xy 0.635 -0.254) (xy 0.635 0.254) (xy 0.5334 0.254) (xy 0.5334 0.2794)
				(xy -0.508 0.2794) (xy -0.5334 0.2794)
			)
			(stroke
				(width 0)
				(type default)
			)
			(fill no)
			(layer "F.CrtYd")
		)
		(pad "1" smd rect
			(at 0.40005 0 90)
			(size 0.4572 0.508)
			(layers "F.Cu" "F.Mask" "F.Paste")
			(net "T6_NODE1_EN_R")
		)
		(pad "2" smd rect
			(at -0.40005 0 90)
			(size 0.4572 0.508)
			(layers "F.Cu" "F.Mask" "F.Paste")
			(net "GND")
		)
	)
	(footprint ""
		(layer "F.Cu")
		(at 123.301252 -137.03935 180)
		(property "Reference" "R281"
			(at 0.967232 -1.41986 0)
			(unlocked yes)
			(layer "F.SilkS")
			(effects
				(font
					(size 0.7874 0.5842)
					(thickness 0.1524)
				)
				(justify left)
			)
		)
		(property "Value" ""
			(at 0 0 180)
			(layer "F.Fab")
			(effects
				(font
					(size 1.27 1.27)
				)
			)
		)
		(duplicate_pad_numbers_are_jumpers no)
		(fp_line
			(start 0.7874 0.4064)
			(end -0.7874 0.4064)
			(stroke
				(width 0.1524)
				(type default)
			)
			(layer "F.SilkS")
		)
		(fp_line
			(start 0.7874 -0.4064)
			(end 0.7874 0.4064)
			(stroke
				(width 0.1524)
				(type default)
			)
			(layer "F.SilkS")
		)
		(fp_line
			(start -0.7874 0.4064)
			(end -0.7874 -0.4064)
			(stroke
				(width 0.1524)
				(type default)
			)
			(layer "F.SilkS")
		)
		(fp_line
			(start -0.7874 -0.4064)
			(end 0.7874 -0.4064)
			(stroke
				(width 0.1524)
				(type default)
			)
			(layer "F.SilkS")
		)
		(fp_poly
			(pts
				(xy -0.508 0.2794) (xy -0.508 0.2286) (xy -0.635 0.2286) (xy -0.635 -0.254) (xy -0.5334 -0.254)
				(xy -0.5334 -0.2794) (xy 0.5334 -0.2794) (xy 0.5334 -0.254) (xy 0.635 -0.254) (xy 0.635 0.254) (xy 0.5334 0.254)
				(xy 0.5334 0.2794)
			)
			(stroke
				(width 0)
				(type default)
			)
			(fill no)
			(layer "F.CrtYd")
		)
		(pad "1" smd rect
			(at 0.40005 0 180)
			(size 0.4572 0.508)
			(layers "F.Cu" "F.Mask" "F.Paste")
			(net "P3V3_NODE1")
		)
		(pad "2" smd rect
			(at -0.40005 0 180)
			(size 0.4572 0.508)
			(layers "F.Cu" "F.Mask" "F.Paste")
			(net "PE_SW_BMC_PERST_L")
		)
	)
	(footprint ""
		(layer "F.Cu")
		(at 159.351726 -76.74102 90)
		(property "Reference" "PC29"
			(at 2.55778 -3.601974 0)
			(unlocked yes)
			(layer "F.SilkS")
			(effects
				(font
					(size 0.7874 0.5842)
					(thickness 0.1524)
				)
				(justify left)
			)
		)
		(property "Value" ""
			(at 0 0 90)
			(layer "F.Fab")
			(effects
				(font
					(size 1.27 1.27)
				)
			)
		)
		(duplicate_pad_numbers_are_jumpers no)
		(fp_line
			(start 0.7874 -0.4064)
			(end 0.7874 0.4064)
			(stroke
				(width 0.1524)
				(type default)
			)
			(layer "F.SilkS")
		)
		(fp_line
			(start -0.7874 -0.4064)
			(end 0.7874 -0.4064)
			(stroke
				(width 0.1524)
				(type default)
			)
			(layer "F.SilkS")
		)
		(fp_line
			(start 0 0.381)
			(end 0 -0.381)
			(stroke
				(width 0.1524)
				(type default)
			)
			(layer "F.SilkS")
		)
		(fp_line
			(start 0.7874 0.4064)
			(end -0.7874 0.4064)
			(stroke
				(width 0.1524)
				(type default)
			)
			(layer "F.SilkS")
		)
		(fp_line
			(start -0.7874 0.4064)
			(end -0.7874 -0.4064)
			(stroke
				(width 0.1524)
				(type default)
			)
			(layer "F.SilkS")
		)
		(fp_poly
			(pts
				(xy -0.5334 0.254) (xy -0.635 0.254) (xy -0.635 0.2286) (xy -0.635 -0.254) (xy -0.5334 -0.254) (xy -0.5334 -0.2794)
				(xy 0.5334 -0.2794) (xy 0.5334 -0.254) (xy 0.635 -0.254) (xy 0.635 0.254) (xy 0.5334 0.254) (xy 0.5334 0.2794)
				(xy -0.508 0.2794) (xy -0.5334 0.2794)
			)
			(stroke
				(width 0)
				(type default)
			)
			(fill no)
			(layer "F.CrtYd")
		)
		(pad "1" smd rect
			(at 0.40005 0 90)
			(size 0.4572 0.508)
			(layers "F.Cu" "F.Mask" "F.Paste")
			(net "P1V0_NODE1")
		)
		(pad "2" smd rect
			(at -0.40005 0 90)
			(size 0.4572 0.508)
			(layers "F.Cu" "F.Mask" "F.Paste")
			(net "GND")
		)
	)
	(footprint ""
		(layer "F.Cu")
		(at 59.931808 -149.689058)
		(property "Reference" "R314"
			(at -29.640276 -6.737096 0)
			(unlocked yes)
			(layer "F.SilkS")
			(effects
				(font
					(size 0.7874 0.5842)
					(thickness 0.1524)
				)
			)
		)
		(property "Value" ""
			(at 0 0 0)
			(layer "F.Fab")
			(effects
				(font
					(size 1.27 1.27)
				)
			)
		)
		(duplicate_pad_numbers_are_jumpers no)
		(fp_line
			(start -1.2954 -0.5842)
			(end 1.2954 -0.5842)
			(stroke
				(width 0.1524)
				(type default)
			)
			(layer "F.SilkS")
		)
		(fp_line
			(start -1.2954 0.5842)
			(end -1.2954 -0.5842)
			(stroke
				(width 0.1524)
				(type default)
			)
			(layer "F.SilkS")
		)
		(fp_line
			(start 1.2954 -0.5842)
			(end 1.2954 0.5842)
			(stroke
				(width 0.1524)
				(type default)
			)
			(layer "F.SilkS")
		)
		(fp_line
			(start 1.2954 0.5842)
			(end -1.2954 0.5842)
			(stroke
				(width 0.1524)
				(type default)
			)
			(layer "F.SilkS")
		)
		(fp_poly
			(pts
				(xy 1.143 -0.3556) (xy 1.143 0.3556) (xy 0.8636 0.3556) (xy 0.8636 0.4572) (xy -0.8636 0.4572) (xy -0.8636 0.4318)
				(xy -0.8636 0.3556) (xy -1.143 0.3556) (xy -1.143 -0.3556) (xy -0.8636 -0.3556) (xy -0.8636 -0.4572)
				(xy 0.8636 -0.4572) (xy 0.8636 -0.3556)
			)
			(stroke
				(width 0)
				(type default)
			)
			(fill no)
			(layer "F.CrtYd")
		)
		(pad "1" smd rect
			(at 0.7366 0 90)
			(size 0.7112 0.8128)
			(layers "F.Cu" "F.Mask" "F.Paste")
			(net "BMC_NODE1_DACAV33")
		)
		(pad "2" smd rect
			(at -0.7366 0 90)
			(size 0.7112 0.8128)
			(layers "F.Cu" "F.Mask" "F.Paste")
			(net "P3V3_NODE1")
		)
	)
	(footprint ""
		(layer "F.Cu")
		(at 85.96376 -185.205624 -90)
		(property "Reference" "R954"
			(at -4.198112 2.082292 90)
			(unlocked yes)
			(layer "F.SilkS")
			(effects
				(font
					(size 0.7874 0.5842)
					(thickness 0.1524)
				)
				(justify left)
			)
		)
		(property "Value" ""
			(at 0 0 270)
			(layer "F.Fab")
			(effects
				(font
					(size 1.27 1.27)
				)
			)
		)
		(duplicate_pad_numbers_are_jumpers no)
		(fp_line
			(start -0.7874 0.4064)
			(end -0.7874 -0.4064)
			(stroke
				(width 0.1524)
				(type default)
			)
			(layer "F.SilkS")
		)
		(fp_line
			(start 0.7874 0.4064)
			(end -0.7874 0.4064)
			(stroke
				(width 0.1524)
				(type default)
			)
			(layer "F.SilkS")
		)
		(fp_line
			(start -0.7874 -0.4064)
			(end 0.7874 -0.4064)
			(stroke
				(width 0.1524)
				(type default)
			)
			(layer "F.SilkS")
		)
		(fp_line
			(start 0.7874 -0.4064)
			(end 0.7874 0.4064)
			(stroke
				(width 0.1524)
				(type default)
			)
			(layer "F.SilkS")
		)
		(fp_poly
			(pts
				(xy -0.508 0.2794) (xy -0.508 0.2286) (xy -0.635 0.2286) (xy -0.635 -0.254) (xy -0.5334 -0.254)
				(xy -0.5334 -0.2794) (xy 0.5334 -0.2794) (xy 0.5334 -0.254) (xy 0.635 -0.254) (xy 0.635 0.254) (xy 0.5334 0.254)
				(xy 0.5334 0.2794)
			)
			(stroke
				(width 0)
				(type default)
			)
			(fill no)
			(layer "F.CrtYd")
		)
		(pad "1" smd rect
			(at 0.40005 0 270)
			(size 0.4572 0.508)
			(layers "F.Cu" "F.Mask" "F.Paste")
			(net "UART_T6_NODE4_TXD")
		)
		(pad "2" smd rect
			(at -0.40005 0 270)
			(size 0.4572 0.508)
			(layers "F.Cu" "F.Mask" "F.Paste")
			(net "UART_T6_NODE4_TXD_R")
		)
	)
	(footprint ""
		(layer "F.Cu")
		(at 118.72976 -179.363624 -90)
		(property "Reference" "D17"
			(at -3.294126 -5.75691 90)
			(unlocked yes)
			(layer "F.SilkS")
			(effects
				(font
					(size 0.635 0.4064)
					(thickness 0.1524)
				)
				(justify left)
			)
		)
		(property "Value" ""
			(at 0 0 270)
			(layer "F.Fab")
			(effects
				(font
					(size 1.27 1.27)
				)
			)
		)
		(duplicate_pad_numbers_are_jumpers no)
		(fp_line
			(start -1.3208 0.5588)
			(end -1.3208 -0.5588)
			(stroke
				(width 0.1524)
				(type default)
			)
			(layer "F.SilkS")
		)
		(fp_line
			(start 1.3208 0.5588)
			(end -1.3208 0.5588)
			(stroke
				(width 0.1524)
				(type default)
			)
			(layer "F.SilkS")
		)
		(fp_line
			(start 1.6256 0.5588)
			(end 1.6256 -0.5588)
			(stroke
				(width 0.1524)
				(type default)
			)
			(layer "F.SilkS")
		)
		(fp_line
			(start 1.778 0.5588)
			(end 1.3208 0.5588)
			(stroke
				(width 0.1524)
				(type default)
			)
			(layer "F.SilkS")
		)
		(fp_line
			(start -1.3208 -0.5588)
			(end 1.3208 -0.5588)
			(stroke
				(width 0.1524)
				(type default)
			)
			(layer "F.SilkS")
		)
		(fp_line
			(start 1.3208 -0.5588)
			(end 1.3208 0.5588)
			(stroke
				(width 0.1524)
				(type default)
			)
			(layer "F.SilkS")
		)
		(fp_line
			(start 1.4732 -0.5588)
			(end 1.4732 0.5588)
			(stroke
				(width 0.1524)
				(type default)
			)
			(layer "F.SilkS")
		)
		(fp_line
			(start 1.778 -0.5588)
			(end 1.778 0.5588)
			(stroke
				(width 0.1524)
				(type default)
			)
			(layer "F.SilkS")
		)
		(fp_line
			(start 1.778 -0.5588)
			(end 1.3208 -0.5588)
			(stroke
				(width 0.1524)
				(type default)
			)
			(layer "F.SilkS")
		)
		(fp_rect
			(start -1.1684 0.508)
			(end 1.1684 -0.508)
			(stroke
				(width 0)
				(type default)
			)
			(fill no)
			(layer "F.CrtYd")
		)
		(pad "A" smd rect
			(at -0.750062 0 270)
			(size 0.8128 0.8128)
			(layers "F.Cu" "F.Mask" "F.Paste")
			(net "UART_SW_S2_N")
		)
		(pad "C" smd rect
			(at 0.750062 0 270)
			(size 0.8128 0.8128)
			(layers "F.Cu" "F.Mask" "F.Paste")
			(net "N31328107")
		)
	)
	(footprint ""
		(layer "F.Cu")
		(at 112.179354 -135.306054 -90)
		(property "Reference" "PR68"
			(at -1.955546 -6.042152 90)
			(unlocked yes)
			(layer "F.SilkS")
			(effects
				(font
					(size 0.635 0.4064)
					(thickness 0.1524)
				)
				(justify left)
			)
		)
		(property "Value" ""
			(at 0 0 270)
			(layer "F.Fab")
			(effects
				(font
					(size 1.27 1.27)
				)
			)
		)
		(duplicate_pad_numbers_are_jumpers no)
		(fp_line
			(start -0.7874 0.4064)
			(end -0.7874 -0.4064)
			(stroke
				(width 0.1524)
				(type default)
			)
			(layer "F.SilkS")
		)
		(fp_line
			(start 0.7874 0.4064)
			(end -0.7874 0.4064)
			(stroke
				(width 0.1524)
				(type default)
			)
			(layer "F.SilkS")
		)
		(fp_line
			(start -0.7874 -0.4064)
			(end 0.7874 -0.4064)
			(stroke
				(width 0.1524)
				(type default)
			)
			(layer "F.SilkS")
		)
		(fp_line
			(start 0.7874 -0.4064)
			(end 0.7874 0.4064)
			(stroke
				(width 0.1524)
				(type default)
			)
			(layer "F.SilkS")
		)
		(fp_poly
			(pts
				(xy -0.508 0.2794) (xy -0.508 0.2286) (xy -0.635 0.2286) (xy -0.635 -0.254) (xy -0.5334 -0.254)
				(xy -0.5334 -0.2794) (xy 0.5334 -0.2794) (xy 0.5334 -0.254) (xy 0.635 -0.254) (xy 0.635 0.254) (xy 0.5334 0.254)
				(xy 0.5334 0.2794)
			)
			(stroke
				(width 0)
				(type default)
			)
			(fill no)
			(layer "F.CrtYd")
		)
		(pad "1" smd rect
			(at 0.40005 0 270)
			(size 0.4572 0.508)
			(layers "F.Cu" "F.Mask" "F.Paste")
			(net "VR_PVCCP_NODE1_COMP")
		)
		(pad "2" smd rect
			(at -0.40005 0 270)
			(size 0.4572 0.508)
			(layers "F.Cu" "F.Mask" "F.Paste")
			(net "VR_PVCCP_NODE1_FB")
		)
	)
	(footprint ""
		(layer "F.Cu")
		(at 78.90256 -80.683608 -90)
		(property "Reference" "C85"
			(at 17.592294 -1.189482 90)
			(unlocked yes)
			(layer "F.SilkS")
			(effects
				(font
					(size 0.7874 0.5842)
					(thickness 0.1524)
				)
				(justify left)
			)
		)
		(property "Value" ""
			(at 0 0 270)
			(layer "F.Fab")
			(effects
				(font
					(size 1.27 1.27)
				)
			)
		)
		(duplicate_pad_numbers_are_jumpers no)
		(fp_line
			(start -0.7874 0.4064)
			(end -0.7874 -0.4064)
			(stroke
				(width 0.1524)
				(type default)
			)
			(layer "F.SilkS")
		)
		(fp_line
			(start 0.7874 0.4064)
			(end -0.7874 0.4064)
			(stroke
				(width 0.1524)
				(type default)
			)
			(layer "F.SilkS")
		)
		(fp_line
			(start 0 0.381)
			(end 0 -0.381)
			(stroke
				(width 0.1524)
				(type default)
			)
			(layer "F.SilkS")
		)
		(fp_line
			(start -0.7874 -0.4064)
			(end 0.7874 -0.4064)
			(stroke
				(width 0.1524)
				(type default)
			)
			(layer "F.SilkS")
		)
		(fp_line
			(start 0.7874 -0.4064)
			(end 0.7874 0.4064)
			(stroke
				(width 0.1524)
				(type default)
			)
			(layer "F.SilkS")
		)
		(fp_poly
			(pts
				(xy -0.5334 0.254) (xy -0.635 0.254) (xy -0.635 0.2286) (xy -0.635 -0.254) (xy -0.5334 -0.254) (xy -0.5334 -0.2794)
				(xy 0.5334 -0.2794) (xy 0.5334 -0.254) (xy 0.635 -0.254) (xy 0.635 0.254) (xy 0.5334 0.254) (xy 0.5334 0.2794)
				(xy -0.508 0.2794) (xy -0.5334 0.2794)
			)
			(stroke
				(width 0)
				(type default)
			)
			(fill no)
			(layer "F.CrtYd")
		)
		(pad "1" smd rect
			(at 0.40005 0 270)
			(size 0.4572 0.508)
			(layers "F.Cu" "F.Mask" "F.Paste")
			(net "PV_VCCP_NODE1")
		)
		(pad "2" smd rect
			(at -0.40005 0 270)
			(size 0.4572 0.508)
			(layers "F.Cu" "F.Mask" "F.Paste")
			(net "GND")
		)
	)
	(footprint ""
		(layer "F.Cu")
		(at 163.712652 -88.84539)
		(property "Reference" "R529"
			(at -0.668274 2.090928 0)
			(unlocked yes)
			(layer "F.SilkS")
			(effects
				(font
					(size 0.7874 0.5842)
					(thickness 0.1524)
				)
				(justify left)
			)
		)
		(property "Value" ""
			(at 0 0 0)
			(layer "F.Fab")
			(effects
				(font
					(size 1.27 1.27)
				)
			)
		)
		(duplicate_pad_numbers_are_jumpers no)
		(fp_line
			(start -0.7874 -0.4064)
			(end 0.7874 -0.4064)
			(stroke
				(width 0.1524)
				(type default)
			)
			(layer "F.SilkS")
		)
		(fp_line
			(start -0.7874 0.4064)
			(end -0.7874 -0.4064)
			(stroke
				(width 0.1524)
				(type default)
			)
			(layer "F.SilkS")
		)
		(fp_line
			(start 0.7874 -0.4064)
			(end 0.7874 0.4064)
			(stroke
				(width 0.1524)
				(type default)
			)
			(layer "F.SilkS")
		)
		(fp_line
			(start 0.7874 0.4064)
			(end -0.7874 0.4064)
			(stroke
				(width 0.1524)
				(type default)
			)
			(layer "F.SilkS")
		)
		(fp_poly
			(pts
				(xy -0.508 0.2794) (xy -0.508 0.2286) (xy -0.635 0.2286) (xy -0.635 -0.254) (xy -0.5334 -0.254)
				(xy -0.5334 -0.2794) (xy 0.5334 -0.2794) (xy 0.5334 -0.254) (xy 0.635 -0.254) (xy 0.635 0.254) (xy 0.5334 0.254)
				(xy 0.5334 0.2794)
			)
			(stroke
				(width 0)
				(type default)
			)
			(fill no)
			(layer "F.CrtYd")
		)
		(pad "1" smd rect
			(at 0.40005 0)
			(size 0.4572 0.508)
			(layers "F.Cu" "F.Mask" "F.Paste")
			(net "P3V3_NODE1")
		)
		(pad "2" smd rect
			(at -0.40005 0)
			(size 0.4572 0.508)
			(layers "F.Cu" "F.Mask" "F.Paste")
			(net "SPI_USB_NODE1_HOLD_L")
		)
	)
	(footprint ""
		(layer "F.Cu")
		(at 144.738852 -146.20875)
		(property "Reference" "R308"
			(at -0.526288 18.560288 0)
			(unlocked yes)
			(layer "F.SilkS")
			(effects
				(font
					(size 0.7874 0.5842)
					(thickness 0.1524)
				)
				(justify left)
			)
		)
		(property "Value" ""
			(at 0 0 0)
			(layer "F.Fab")
			(effects
				(font
					(size 1.27 1.27)
				)
			)
		)
		(duplicate_pad_numbers_are_jumpers no)
		(fp_line
			(start -0.7874 -0.4064)
			(end 0.7874 -0.4064)
			(stroke
				(width 0.1524)
				(type default)
			)
			(layer "F.SilkS")
		)
		(fp_line
			(start -0.7874 0.4064)
			(end -0.7874 -0.4064)
			(stroke
				(width 0.1524)
				(type default)
			)
			(layer "F.SilkS")
		)
		(fp_line
			(start 0.7874 -0.4064)
			(end 0.7874 0.4064)
			(stroke
				(width 0.1524)
				(type default)
			)
			(layer "F.SilkS")
		)
		(fp_line
			(start 0.7874 0.4064)
			(end -0.7874 0.4064)
			(stroke
				(width 0.1524)
				(type default)
			)
			(layer "F.SilkS")
		)
		(fp_poly
			(pts
				(xy -0.508 0.2794) (xy -0.508 0.2286) (xy -0.635 0.2286) (xy -0.635 -0.254) (xy -0.5334 -0.254)
				(xy -0.5334 -0.2794) (xy 0.5334 -0.2794) (xy 0.5334 -0.254) (xy 0.635 -0.254) (xy 0.635 0.254) (xy 0.5334 0.254)
				(xy 0.5334 0.2794)
			)
			(stroke
				(width 0)
				(type default)
			)
			(fill no)
			(layer "F.CrtYd")
		)
		(pad "1" smd rect
			(at 0.40005 0)
			(size 0.4572 0.508)
			(layers "F.Cu" "F.Mask" "F.Paste")
			(net "GND")
		)
		(pad "2" smd rect
			(at -0.40005 0)
			(size 0.4572 0.508)
			(layers "F.Cu" "F.Mask" "F.Paste")
			(net "PCIE_SW_GPIO5")
		)
	)
	(footprint ""
		(layer "F.Cu")
		(at -11.397488 -191.641222 -90)
		(property "Reference" "J25"
			(at 2.96672 1.84277 90)
			(unlocked yes)
			(layer "F.SilkS")
			(effects
				(font
					(size 0.7874 0.5842)
					(thickness 0.1524)
				)
				(justify left)
			)
		)
		(property "Value" ""
			(at 0 0 270)
			(layer "F.Fab")
			(effects
				(font
					(size 1.27 1.27)
				)
			)
		)
		(duplicate_pad_numbers_are_jumpers no)
		(fp_circle
			(center 0 0)
			(end 0 -0.635)
			(stroke
				(width 0.05)
				(type default)
			)
			(fill no)
			(layer "Edge.Cuts")
		)
		(fp_circle
			(center 4.064 0)
			(end 4.064 -0.635)
			(stroke
				(width 0.05)
				(type default)
			)
			(fill no)
			(layer "Edge.Cuts")
		)
		(fp_circle
			(center 0 -4.572)
			(end 0 -5.207)
			(stroke
				(width 0.05)
				(type default)
			)
			(fill no)
			(layer "Edge.Cuts")
		)
		(fp_circle
			(center 4.064 -4.572)
			(end 4.064 -5.207)
			(stroke
				(width 0.05)
				(type default)
			)
			(fill no)
			(layer "Edge.Cuts")
		)
		(fp_rect
			(start -1.27 1.27)
			(end 5.334 -5.842)
			(stroke
				(width 0)
				(type default)
			)
			(fill no)
			(layer "F.CrtYd")
		)
		(pad "" np_thru_hole circle
			(at 0 -4.572 270)
			(size 0.254 0.254)
			(drill 1.27)
			(layers "*.Cu" "*.Mask")
			(clearance 0.889)
			(thermal_gap 0.889)
		)
		(pad "" np_thru_hole circle
			(at 0 0 270)
			(size 0.254 0.254)
			(drill 1.27)
			(layers "*.Cu" "*.Mask")
			(clearance 0.889)
			(thermal_gap 0.889)
		)
		(pad "" np_thru_hole circle
			(at 4.064 -4.572 270)
			(size 0.254 0.254)
			(drill 1.27)
			(layers "*.Cu" "*.Mask")
			(clearance 0.889)
			(thermal_gap 0.889)
		)
		(pad "" np_thru_hole circle
			(at 4.064 0 270)
			(size 0.254 0.254)
			(drill 1.27)
			(layers "*.Cu" "*.Mask")
			(clearance 0.889)
			(thermal_gap 0.889)
		)
		(pad "1" thru_hole custom
			(at 1.397 -2.286)
			(size 0.266741 0.266741)
			(drill 0.254)
			(layers "*.Cu" "*.Mask")
			(remove_unused_layers no)
			(net "GND")
			(options
				(clearance outline)
				(anchor circle)
			)
			(primitives
				(gr_poly
					(pts
						(xy -0.979932 0.5334)
						(arc
							(start -0.979932 -0.078994)
							(mid -0.925932 -0.48038)
							(end -0.527812 -0.4064)
						)
						(arc
							(start -0.234188 -0.4064)
							(mid 0 -0.53341)
							(end 0.234188 -0.4064)
						)
						(arc
							(start 0.527812 -0.4064)
							(mid 0.925878 -0.480305)
							(end 0.979932 -0.078994)
						)
						(xy 0.979932 0.5334) (xy 0.548132 0.5334) (xy 0.548132 0.1016) (xy -0.548132 0.1016) (xy -0.548132 0.5334)
					)
					(width 0)
					(fill yes)
				)
			)
			(padstack
				(mode front_inner_back)
				(layer "Inner"
					(shape custom)
					(size 0.139735 0.139735)
					(options
						(anchor circle)
					)
					(primitives
						(gr_poly
							(pts
								(arc
									(start 0.26035 0.1016)
									(mid 0 0.279472)
									(end -0.26035 0.1016)
								)
								(arc
									(start -0.50165 0.1016)
									(mid -1.041472 0)
									(end -0.50165 -0.1016)
								)
								(arc
									(start -0.26035 -0.1016)
									(mid 0 -0.279472)
									(end 0.26035 -0.1016)
								)
								(arc
									(start 0.50165 -0.1016)
									(mid 1.041472 0)
									(end 0.50165 0.1016)
								)
							)
							(width 0)
							(fill yes)
						)
					)
				)
				(layer "B.Cu"
					(shape custom)
					(size 0.139735 0.139735)
					(options
						(anchor circle)
					)
					(primitives
						(gr_poly
							(pts
								(arc
									(start 0.26035 0.1016)
									(mid 0 0.279472)
									(end -0.26035 0.1016)
								)
								(arc
									(start -0.50165 0.1016)
									(mid -1.041472 0)
									(end -0.50165 -0.1016)
								)
								(arc
									(start -0.26035 -0.1016)
									(mid 0 -0.279472)
									(end 0.26035 -0.1016)
								)
								(arc
									(start 0.50165 -0.1016)
									(mid 1.041472 0)
									(end 0.50165 0.1016)
								)
							)
							(width 0)
							(fill yes)
						)
					)
				)
			)
		)
		(pad "2" smd rect
			(at 2.032 -2.060956 270)
			(size 0.3048 0.2032)
			(layers "F.Cu" "F.Mask" "F.Paste")
			(net "IN3_85OHM")
		)
		(pad "3" smd rect
			(at 2.032 -2.511044 270)
			(size 0.3048 0.2032)
			(layers "F.Cu" "F.Mask" "F.Paste")
			(net "IN3_85OHM")
		)
		(zone
			(layers "F.Cu" "B.Cu" "In1.Cu" "In2.Cu" "In3.Cu" "In4.Cu" "In5.Cu" "In6.Cu"
				"In7.Cu" "In8.Cu"
			)
			(hatch none 0.5)
			(connect_pads
				(clearance 0)
			)
			(min_thickness 0.25)
			(keepout
				(tracks not_allowed)
				(vias allowed)
				(pads allowed)
				(copperpour not_allowed)
				(footprints allowed)
			)
			(placement
				(enabled no)
				(sheetname "")
			)
			(fill
				(thermal_gap 0.5)
				(thermal_bridge_width 0.5)
				(island_removal_mode 0)
			)
			(polygon
				(pts
					(arc
						(start -11.397488 -190.752222)
						(mid -11.397488 -192.530222)
						(end -11.397488 -190.752222)
					)
				)
			)
		)
		(zone
			(layers "F.Cu" "B.Cu" "In1.Cu" "In2.Cu" "In3.Cu" "In4.Cu" "In5.Cu" "In6.Cu"
				"In7.Cu" "In8.Cu"
			)
			(hatch none 0.5)
			(connect_pads
				(clearance 0)
			)
			(min_thickness 0.25)
			(keepout
				(tracks not_allowed)
				(vias allowed)
				(pads allowed)
				(copperpour not_allowed)
				(footprints allowed)
			)
			(placement
				(enabled no)
				(sheetname "")
			)
			(fill
				(thermal_gap 0.5)
				(thermal_bridge_width 0.5)
				(island_removal_mode 0)
			)
			(polygon
				(pts
					(arc
						(start -11.397488 -186.688222)
						(mid -11.397488 -188.466222)
						(end -11.397488 -186.688222)
					)
				)
			)
		)
		(zone
			(layers "F.Cu" "B.Cu" "In1.Cu" "In2.Cu" "In3.Cu" "In4.Cu" "In5.Cu" "In6.Cu"
				"In7.Cu" "In8.Cu"
			)
			(hatch none 0.5)
			(connect_pads
				(clearance 0)
			)
			(min_thickness 0.25)
			(keepout
				(tracks not_allowed)
				(vias allowed)
				(pads allowed)
				(copperpour not_allowed)
				(footprints allowed)
			)
			(placement
				(enabled no)
				(sheetname "")
			)
			(fill
				(thermal_gap 0.5)
				(thermal_bridge_width 0.5)
				(island_removal_mode 0)
			)
			(polygon
				(pts
					(arc
						(start -6.825488 -190.752222)
						(mid -6.825488 -192.530222)
						(end -6.825488 -190.752222)
					)
				)
			)
		)
		(zone
			(layers "F.Cu" "B.Cu" "In1.Cu" "In2.Cu" "In3.Cu" "In4.Cu" "In5.Cu" "In6.Cu"
				"In7.Cu" "In8.Cu"
			)
			(hatch none 0.5)
			(connect_pads
				(clearance 0)
			)
			(min_thickness 0.25)
			(keepout
				(tracks not_allowed)
				(vias allowed)
				(pads allowed)
				(copperpour not_allowed)
				(footprints allowed)
			)
			(placement
				(enabled no)
				(sheetname "")
			)
			(fill
				(thermal_gap 0.5)
				(thermal_bridge_width 0.5)
				(island_removal_mode 0)
			)
			(polygon
				(pts
					(arc
						(start -6.825488 -186.688222)
						(mid -6.825488 -188.466222)
						(end -6.825488 -186.688222)
					)
				)
			)
		)
	)
	(footprint ""
		(layer "F.Cu")
		(at 44.885356 -176.28616 180)
		(property "Reference" "R1006"
			(at 1.63957 -132.978144 0)
			(unlocked yes)
			(layer "F.SilkS")
			(effects
				(font
					(size 0.7874 0.5842)
					(thickness 0.1524)
				)
				(justify left)
			)
		)
		(property "Value" ""
			(at 0 0 180)
			(layer "F.Fab")
			(effects
				(font
					(size 1.27 1.27)
				)
			)
		)
		(duplicate_pad_numbers_are_jumpers no)
		(fp_line
			(start 0.7874 0.4064)
			(end -0.7874 0.4064)
			(stroke
				(width 0.1524)
				(type default)
			)
			(layer "F.SilkS")
		)
		(fp_line
			(start 0.7874 -0.4064)
			(end 0.7874 0.4064)
			(stroke
				(width 0.1524)
				(type default)
			)
			(layer "F.SilkS")
		)
		(fp_line
			(start -0.7874 0.4064)
			(end -0.7874 -0.4064)
			(stroke
				(width 0.1524)
				(type default)
			)
			(layer "F.SilkS")
		)
		(fp_line
			(start -0.7874 -0.4064)
			(end 0.7874 -0.4064)
			(stroke
				(width 0.1524)
				(type default)
			)
			(layer "F.SilkS")
		)
		(fp_poly
			(pts
				(xy -0.508 0.2794) (xy -0.508 0.2286) (xy -0.635 0.2286) (xy -0.635 -0.254) (xy -0.5334 -0.254)
				(xy -0.5334 -0.2794) (xy 0.5334 -0.2794) (xy 0.5334 -0.254) (xy 0.635 -0.254) (xy 0.635 0.254) (xy 0.5334 0.254)
				(xy 0.5334 0.2794)
			)
			(stroke
				(width 0)
				(type default)
			)
			(fill no)
			(layer "F.CrtYd")
		)
		(pad "1" smd rect
			(at 0.40005 0 180)
			(size 0.4572 0.508)
			(layers "F.Cu" "F.Mask" "F.Paste")
			(net "P12V_AUX_EN")
		)
		(pad "2" smd rect
			(at -0.40005 0 180)
			(size 0.4572 0.508)
			(layers "F.Cu" "F.Mask" "F.Paste")
			(net "P12V_PDB")
		)
	)
	(footprint ""
		(layer "F.Cu")
		(at 113.420144 -140.193522 -90)
		(property "Reference" "PR71"
			(at -4.108958 -3.597402 90)
			(unlocked yes)
			(layer "F.SilkS")
			(effects
				(font
					(size 0.635 0.4064)
					(thickness 0.1524)
				)
				(justify left)
			)
		)
		(property "Value" ""
			(at 0 0 270)
			(layer "F.Fab")
			(effects
				(font
					(size 1.27 1.27)
				)
			)
		)
		(duplicate_pad_numbers_are_jumpers no)
		(fp_line
			(start -0.7874 0.4064)
			(end -0.7874 -0.4064)
			(stroke
				(width 0.1524)
				(type default)
			)
			(layer "F.SilkS")
		)
		(fp_line
			(start 0.7874 0.4064)
			(end -0.7874 0.4064)
			(stroke
				(width 0.1524)
				(type default)
			)
			(layer "F.SilkS")
		)
		(fp_line
			(start -0.7874 -0.4064)
			(end 0.7874 -0.4064)
			(stroke
				(width 0.1524)
				(type default)
			)
			(layer "F.SilkS")
		)
		(fp_line
			(start 0.7874 -0.4064)
			(end 0.7874 0.4064)
			(stroke
				(width 0.1524)
				(type default)
			)
			(layer "F.SilkS")
		)
		(fp_poly
			(pts
				(xy -0.508 0.2794) (xy -0.508 0.2286) (xy -0.635 0.2286) (xy -0.635 -0.254) (xy -0.5334 -0.254)
				(xy -0.5334 -0.2794) (xy 0.5334 -0.2794) (xy 0.5334 -0.254) (xy 0.635 -0.254) (xy 0.635 0.254) (xy 0.5334 0.254)
				(xy 0.5334 0.2794)
			)
			(stroke
				(width 0)
				(type default)
			)
			(fill no)
			(layer "F.CrtYd")
		)
		(pad "1" smd rect
			(at 0.40005 0 270)
			(size 0.4572 0.508)
			(layers "F.Cu" "F.Mask" "F.Paste")
			(net "VSENSE_VSS_CPU_NODE1")
		)
		(pad "2" smd rect
			(at -0.40005 0 270)
			(size 0.4572 0.508)
			(layers "F.Cu" "F.Mask" "F.Paste")
			(net "GND")
		)
	)
	(footprint ""
		(layer "F.Cu")
		(at 27.932888 -130.589782 90)
		(property "Reference" "R1094"
			(at -0.722122 -1.999742 90)
			(unlocked yes)
			(layer "F.SilkS")
			(effects
				(font
					(size 0.7874 0.5842)
					(thickness 0.1524)
				)
				(justify left)
			)
		)
		(property "Value" ""
			(at 0 0 90)
			(layer "F.Fab")
			(effects
				(font
					(size 1.27 1.27)
				)
			)
		)
		(duplicate_pad_numbers_are_jumpers no)
		(fp_line
			(start 0.7874 -0.4064)
			(end 0.7874 0.4064)
			(stroke
				(width 0.1524)
				(type default)
			)
			(layer "F.SilkS")
		)
		(fp_line
			(start -0.7874 -0.4064)
			(end 0.7874 -0.4064)
			(stroke
				(width 0.1524)
				(type default)
			)
			(layer "F.SilkS")
		)
		(fp_line
			(start 0.7874 0.4064)
			(end -0.7874 0.4064)
			(stroke
				(width 0.1524)
				(type default)
			)
			(layer "F.SilkS")
		)
		(fp_line
			(start -0.7874 0.4064)
			(end -0.7874 -0.4064)
			(stroke
				(width 0.1524)
				(type default)
			)
			(layer "F.SilkS")
		)
		(fp_poly
			(pts
				(xy -0.508 0.2794) (xy -0.508 0.2286) (xy -0.635 0.2286) (xy -0.635 -0.254) (xy -0.5334 -0.254)
				(xy -0.5334 -0.2794) (xy 0.5334 -0.2794) (xy 0.5334 -0.254) (xy 0.635 -0.254) (xy 0.635 0.254) (xy 0.5334 0.254)
				(xy 0.5334 0.2794)
			)
			(stroke
				(width 0)
				(type default)
			)
			(fill no)
			(layer "F.CrtYd")
		)
		(pad "1" smd rect
			(at 0.40005 0 90)
			(size 0.4572 0.508)
			(layers "F.Cu" "F.Mask" "F.Paste")
			(net "P3V3_STB_NODE1")
		)
		(pad "2" smd rect
			(at -0.40005 0 90)
			(size 0.4572 0.508)
			(layers "F.Cu" "F.Mask" "F.Paste")
			(net "PWRGD_NODE1_P1V538_BMC_PG")
		)
	)
	(footprint ""
		(layer "F.Cu")
		(at 134.239 -51.435 -90)
		(property "Reference" "R1159"
			(at -16.3576 -30.68447 90)
			(unlocked yes)
			(layer "F.SilkS")
			(effects
				(font
					(size 0.7874 0.5842)
					(thickness 0.1524)
				)
				(justify left)
			)
		)
		(property "Value" ""
			(at 0 0 270)
			(layer "F.Fab")
			(effects
				(font
					(size 1.27 1.27)
				)
			)
		)
		(duplicate_pad_numbers_are_jumpers no)
		(fp_line
			(start -0.7874 0.4064)
			(end -0.7874 -0.4064)
			(stroke
				(width 0.1524)
				(type default)
			)
			(layer "F.SilkS")
		)
		(fp_line
			(start 0.7874 0.4064)
			(end -0.7874 0.4064)
			(stroke
				(width 0.1524)
				(type default)
			)
			(layer "F.SilkS")
		)
		(fp_line
			(start -0.7874 -0.4064)
			(end 0.7874 -0.4064)
			(stroke
				(width 0.1524)
				(type default)
			)
			(layer "F.SilkS")
		)
		(fp_line
			(start 0.7874 -0.4064)
			(end 0.7874 0.4064)
			(stroke
				(width 0.1524)
				(type default)
			)
			(layer "F.SilkS")
		)
		(fp_poly
			(pts
				(xy -0.508 0.2794) (xy -0.508 0.2286) (xy -0.635 0.2286) (xy -0.635 -0.254) (xy -0.5334 -0.254)
				(xy -0.5334 -0.2794) (xy 0.5334 -0.2794) (xy 0.5334 -0.254) (xy 0.635 -0.254) (xy 0.635 0.254) (xy 0.5334 0.254)
				(xy 0.5334 0.2794)
			)
			(stroke
				(width 0)
				(type default)
			)
			(fill no)
			(layer "F.CrtYd")
		)
		(pad "1" smd rect
			(at 0.40005 0 270)
			(size 0.4572 0.508)
			(layers "F.Cu" "F.Mask" "F.Paste")
			(net "UART_TX_P3_R")
		)
		(pad "2" smd rect
			(at -0.40005 0 270)
			(size 0.4572 0.508)
			(layers "F.Cu" "F.Mask" "F.Paste")
			(net "UART_TX_P3")
		)
	)
	(footprint ""
		(layer "F.Cu")
		(at 117.07876 -179.363624 -90)
		(property "Reference" "D23"
			(at -3.125724 -6.621272 90)
			(unlocked yes)
			(layer "F.SilkS")
			(effects
				(font
					(size 0.635 0.4064)
					(thickness 0.1524)
				)
				(justify left)
			)
		)
		(property "Value" ""
			(at 0 0 270)
			(layer "F.Fab")
			(effects
				(font
					(size 1.27 1.27)
				)
			)
		)
		(duplicate_pad_numbers_are_jumpers no)
		(fp_line
			(start -1.3208 0.5588)
			(end -1.3208 -0.5588)
			(stroke
				(width 0.1524)
				(type default)
			)
			(layer "F.SilkS")
		)
		(fp_line
			(start 1.3208 0.5588)
			(end -1.3208 0.5588)
			(stroke
				(width 0.1524)
				(type default)
			)
			(layer "F.SilkS")
		)
		(fp_line
			(start 1.6256 0.5588)
			(end 1.6256 -0.5588)
			(stroke
				(width 0.1524)
				(type default)
			)
			(layer "F.SilkS")
		)
		(fp_line
			(start 1.778 0.5588)
			(end 1.3208 0.5588)
			(stroke
				(width 0.1524)
				(type default)
			)
			(layer "F.SilkS")
		)
		(fp_line
			(start -1.3208 -0.5588)
			(end 1.3208 -0.5588)
			(stroke
				(width 0.1524)
				(type default)
			)
			(layer "F.SilkS")
		)
		(fp_line
			(start 1.3208 -0.5588)
			(end 1.3208 0.5588)
			(stroke
				(width 0.1524)
				(type default)
			)
			(layer "F.SilkS")
		)
		(fp_line
			(start 1.4732 -0.5588)
			(end 1.4732 0.5588)
			(stroke
				(width 0.1524)
				(type default)
			)
			(layer "F.SilkS")
		)
		(fp_line
			(start 1.778 -0.5588)
			(end 1.778 0.5588)
			(stroke
				(width 0.1524)
				(type default)
			)
			(layer "F.SilkS")
		)
		(fp_line
			(start 1.778 -0.5588)
			(end 1.3208 -0.5588)
			(stroke
				(width 0.1524)
				(type default)
			)
			(layer "F.SilkS")
		)
		(fp_rect
			(start -1.1684 0.508)
			(end 1.1684 -0.508)
			(stroke
				(width 0)
				(type default)
			)
			(fill no)
			(layer "F.CrtYd")
		)
		(pad "A" smd rect
			(at -0.750062 0 270)
			(size 0.8128 0.8128)
			(layers "F.Cu" "F.Mask" "F.Paste")
			(net "UART_SW_S3_N")
		)
		(pad "C" smd rect
			(at 0.750062 0 270)
			(size 0.8128 0.8128)
			(layers "F.Cu" "F.Mask" "F.Paste")
			(net "N31341803")
		)
	)
	(footprint ""
		(layer "F.Cu")
		(at 35.509962 -3.851148 -90)
		(property "Reference" "Q43"
			(at -0.5461 3.838702 0)
			(unlocked yes)
			(layer "F.SilkS")
			(effects
				(font
					(size 0.7874 0.5842)
					(thickness 0.1524)
				)
			)
		)
		(property "Value" ""
			(at 0 0 270)
			(layer "F.Fab")
			(effects
				(font
					(size 1.27 1.27)
				)
			)
		)
		(duplicate_pad_numbers_are_jumpers no)
		(fp_line
			(start -1.651 1.905)
			(end -1.651 -1.905)
			(stroke
				(width 0.1524)
				(type default)
			)
			(layer "F.SilkS")
		)
		(fp_line
			(start 1.651 1.905)
			(end -1.651 1.905)
			(stroke
				(width 0.1524)
				(type default)
			)
			(layer "F.SilkS")
		)
		(fp_line
			(start -1.651 -1.905)
			(end 1.651 -1.905)
			(stroke
				(width 0.1524)
				(type default)
			)
			(layer "F.SilkS")
		)
		(fp_line
			(start 1.651 -1.905)
			(end 1.651 1.905)
			(stroke
				(width 0.1524)
				(type default)
			)
			(layer "F.SilkS")
		)
		(fp_poly
			(pts
				(xy -1.524 0.7112) (xy -1.524 1.7526) (xy -0.508 1.7526) (xy -0.508 0.6985) (xy 0.508 0.6985) (xy 0.508 1.7526)
				(xy 1.524 1.7526) (xy 1.524 0.6985) (xy 1.524 -0.6985) (xy 0.508 -0.6985) (xy 0.508 -1.7526) (xy -0.508 -1.7526)
				(xy -0.508 -0.6985) (xy -1.524 -0.6985) (xy -1.524 0.6985)
			)
			(stroke
				(width 0)
				(type default)
			)
			(fill no)
			(layer "F.CrtYd")
		)
		(fp_text user "2"
			(at 2.051558 1.254506 270)
			(unlocked yes)
			(layer "F.SilkS")
			(effects
				(font
					(size 0.635 0.4064)
					(thickness 0.1524)
				)
			)
		)
		(fp_text user "1"
			(at -1.98374 1.088644 270)
			(unlocked yes)
			(layer "F.SilkS")
			(effects
				(font
					(size 0.635 0.4064)
					(thickness 0.1524)
				)
			)
		)
		(fp_text user "3"
			(at 2.051558 -0.846074 270)
			(unlocked yes)
			(layer "F.SilkS")
			(effects
				(font
					(size 0.635 0.4064)
					(thickness 0.1524)
				)
			)
		)
		(pad "1" smd rect
			(at -1.016 1.1176 270)
			(size 1.016 1.27)
			(layers "F.Cu" "F.Mask" "F.Paste")
			(net "VR_NODE1_VDDR_1V5_CNTL")
		)
		(pad "2" smd rect
			(at 1.016 1.1176 270)
			(size 1.016 1.27)
			(layers "F.Cu" "F.Mask" "F.Paste")
			(net "GND")
		)
		(pad "3" smd rect
			(at 0 -1.1176 270)
			(size 1.016 1.27)
			(layers "F.Cu" "F.Mask" "F.Paste")
			(net "PV_VDDR_NODE1_VID0")
		)
	)
	(footprint ""
		(layer "F.Cu")
		(at 179.999894 -7.799832)
		(property "Reference" "D19"
			(at 2.5781 -1.85674 90)
			(unlocked yes)
			(layer "F.SilkS")
			(effects
				(font
					(size 0.7874 0.5842)
					(thickness 0.1524)
				)
				(justify left)
			)
		)
		(property "Value" ""
			(at 0 0 0)
			(layer "F.Fab")
			(effects
				(font
					(size 1.27 1.27)
				)
			)
		)
		(duplicate_pad_numbers_are_jumpers no)
		(fp_line
			(start -3.109976 -1.400048)
			(end -3.109976 1.1938)
			(stroke
				(width 0.1524)
				(type default)
			)
			(layer "F.SilkS")
		)
		(fp_line
			(start -3.109976 0.8128)
			(end -3.109976 7.739888)
			(stroke
				(width 0.1524)
				(type default)
			)
			(layer "F.SilkS")
		)
		(fp_line
			(start -3.109976 7.739888)
			(end -2.499868 7.739888)
			(stroke
				(width 0.1524)
				(type default)
			)
			(layer "F.SilkS")
		)
		(fp_line
			(start -2.499868 7.739888)
			(end -2.499868 10.24001)
			(stroke
				(width 0.1524)
				(type default)
			)
			(layer "F.SilkS")
		)
		(fp_line
			(start 2.499868 7.739888)
			(end 3.109976 7.739888)
			(stroke
				(width 0.1524)
				(type default)
			)
			(layer "F.SilkS")
		)
		(fp_line
			(start 2.499868 10.24001)
			(end 2.499868 7.739888)
			(stroke
				(width 0.1524)
				(type default)
			)
			(layer "F.SilkS")
		)
		(fp_line
			(start 3.109976 -1.400048)
			(end -3.109976 -1.400048)
			(stroke
				(width 0.1524)
				(type default)
			)
			(layer "F.SilkS")
		)
		(fp_line
			(start 3.109976 1.4478)
			(end 3.109976 -1.400048)
			(stroke
				(width 0.1524)
				(type default)
			)
			(layer "F.SilkS")
		)
		(fp_line
			(start 3.109976 7.739888)
			(end 3.109976 0.6096)
			(stroke
				(width 0.1524)
				(type default)
			)
			(layer "F.SilkS")
		)
		(fp_arc
			(start 2.499868 10.24001)
			(mid 0 12.739878)
			(end -2.499868 10.24001)
			(stroke
				(width 0.1524)
				(type default)
			)
			(layer "F.SilkS")
		)
		(fp_poly
			(pts
				(xy -1.27 -1.5494) (xy -1.778 -2.5654) (xy -0.762 -2.5654)
			)
			(stroke
				(width 0)
				(type default)
			)
			(fill yes)
			(layer "F.SilkS")
		)
		(fp_poly
			(pts
				(xy -2.0828 3.354832) (xy -2.0828 1.729232) (xy -1.4478 1.729232) (xy -1.4478 1.725168) (xy -0.4572 1.725168)
				(xy -0.4572 3.3528) (xy -1.388872 3.3528) (xy -1.388872 3.354832)
			)
			(stroke
				(width 0)
				(type default)
			)
			(fill no)
			(layer "B.CrtYd")
		)
		(fp_poly
			(pts
				(arc
					(start 0 0.8128)
					(mid 0 -0.8128)
					(end 0 0.8128)
				)
			)
			(stroke
				(width 0)
				(type default)
			)
			(fill no)
			(layer "B.CrtYd")
		)
		(fp_poly
			(pts
				(arc
					(start 1.27 3.3528)
					(mid 1.27 1.7272)
					(end 1.27 3.3528)
				)
			)
			(stroke
				(width 0)
				(type default)
			)
			(fill no)
			(layer "B.CrtYd")
		)
		(fp_poly
			(pts
				(xy -2.499868 7.739888)
				(arc
					(start -2.499868 10.24001)
					(mid 0 12.739878)
					(end 2.499868 10.24001)
				)
				(xy 2.499868 7.739888) (xy 3.109976 7.739888) (xy 3.109976 -1.400048) (xy -3.109976 -1.400048) (xy -3.109976 7.739888)
			)
			(stroke
				(width 0)
				(type default)
			)
			(fill no)
			(layer "F.CrtYd")
		)
		(fp_line
			(start -3.109976 -1.400048)
			(end -3.109976 7.739888)
			(stroke
				(width 0.1)
				(type default)
			)
			(layer "F.Fab")
		)
		(fp_line
			(start -3.109976 -1.400048)
			(end -3.109976 7.739888)
			(stroke
				(width 0.1)
				(type default)
			)
			(layer "F.Fab")
		)
		(fp_line
			(start -3.109976 7.739888)
			(end -2.499868 7.739888)
			(stroke
				(width 0.1)
				(type default)
			)
			(layer "F.Fab")
		)
		(fp_line
			(start -3.109976 7.739888)
			(end -2.499868 7.739888)
			(stroke
				(width 0.1)
				(type default)
			)
			(layer "F.Fab")
		)
		(fp_line
			(start -2.499868 7.739888)
			(end -2.499868 10.24001)
			(stroke
				(width 0.1)
				(type default)
			)
			(layer "F.Fab")
		)
		(fp_line
			(start -2.499868 7.739888)
			(end -2.499868 10.24001)
			(stroke
				(width 0.1)
				(type default)
			)
			(layer "F.Fab")
		)
		(fp_line
			(start 2.499868 7.739888)
			(end 3.109976 7.739888)
			(stroke
				(width 0.1)
				(type default)
			)
			(layer "F.Fab")
		)
		(fp_line
			(start 2.499868 7.739888)
			(end 3.109976 7.739888)
			(stroke
				(width 0.1)
				(type default)
			)
			(layer "F.Fab")
		)
		(fp_line
			(start 2.499868 10.24001)
			(end 2.499868 7.739888)
			(stroke
				(width 0.1)
				(type default)
			)
			(layer "F.Fab")
		)
		(fp_line
			(start 2.499868 10.24001)
			(end 2.499868 7.739888)
			(stroke
				(width 0.1)
				(type default)
			)
			(layer "F.Fab")
		)
		(fp_line
			(start 3.109976 -1.400048)
			(end -3.109976 -1.400048)
			(stroke
				(width 0.1)
				(type default)
			)
			(layer "F.Fab")
		)
		(fp_line
			(start 3.109976 -1.400048)
			(end -3.109976 -1.400048)
			(stroke
				(width 0.1)
				(type default)
			)
			(layer "F.Fab")
		)
		(fp_line
			(start 3.109976 7.739888)
			(end 3.109976 -1.400048)
			(stroke
				(width 0.1)
				(type default)
			)
			(layer "F.Fab")
		)
		(fp_line
			(start 3.109976 7.739888)
			(end 3.109976 -1.400048)
			(stroke
				(width 0.1)
				(type default)
			)
			(layer "F.Fab")
		)
		(fp_arc
			(start 2.499868 10.24001)
			(mid 0 12.739878)
			(end -2.499868 10.24001)
			(stroke
				(width 0.1)
				(type default)
			)
			(layer "F.Fab")
		)
		(fp_arc
			(start 2.499868 10.24001)
			(mid 0 12.739878)
			(end -2.499868 10.24001)
			(stroke
				(width 0.1)
				(type default)
			)
			(layer "F.Fab")
		)
		(fp_poly
			(pts
				(xy -1.27 -1.5494) (xy -1.778 -2.5654) (xy -0.762 -2.5654)
			)
			(stroke
				(width 0)
				(type default)
			)
			(fill yes)
			(layer "F.Fab")
		)
		(fp_text user "1"
			(at -3.706622 1.747266 0)
			(unlocked yes)
			(layer "F.SilkS")
			(effects
				(font
					(size 0.635 0.4064)
					(thickness 0.1524)
				)
				(justify left)
			)
		)
		(fp_text user "2"
			(at -3.705606 -0.309372 0)
			(unlocked yes)
			(layer "F.SilkS")
			(effects
				(font
					(size 0.635 0.4064)
					(thickness 0.1524)
				)
				(justify left)
			)
		)
		(fp_text user "3"
			(at 3.406902 2.565146 0)
			(unlocked yes)
			(layer "F.SilkS")
			(effects
				(font
					(size 0.635 0.4064)
					(thickness 0.1524)
				)
				(justify left)
			)
		)
		(fp_text user "1"
			(at -2.788666 2.29489 0)
			(unlocked yes)
			(layer "B.SilkS")
			(effects
				(font
					(size 0.7874 0.5842)
					(thickness 0.1524)
				)
				(justify left mirror)
			)
		)
		(fp_text user "2"
			(at 0.339344 -1.849882 0)
			(unlocked yes)
			(layer "B.SilkS")
			(effects
				(font
					(size 0.7874 0.5842)
					(thickness 0.1524)
				)
				(justify left mirror)
			)
		)
		(fp_text user "3"
			(at 2.338324 0.907288 0)
			(unlocked yes)
			(layer "B.SilkS")
			(effects
				(font
					(size 0.7874 0.5842)
					(thickness 0.1524)
				)
				(justify left mirror)
			)
		)
		(fp_text user "1"
			(at -0.9779 1.330706 0)
			(unlocked yes)
			(layer "B.Fab")
			(effects
				(font
					(size 0.7874 0.5842)
					(thickness 0.000001)
				)
				(justify left mirror)
			)
		)
		(fp_text user "2"
			(at 0.2921 1.254506 0)
			(unlocked yes)
			(layer "B.Fab")
			(effects
				(font
					(size 0.7874 0.5842)
					(thickness 0.000001)
				)
				(justify left mirror)
			)
		)
		(fp_text user "3"
			(at 1.5621 1.330706 0)
			(unlocked yes)
			(layer "B.Fab")
			(effects
				(font
					(size 0.7874 0.5842)
					(thickness 0.000001)
				)
				(justify left mirror)
			)
		)
		(fp_text user "1"
			(at -2.1717 -2.022094 0)
			(unlocked yes)
			(layer "F.Fab")
			(effects
				(font
					(size 0.7874 0.5842)
					(thickness 0.000001)
				)
				(justify left)
			)
		)
		(fp_text user "2"
			(at -0.2921 -2.022094 0)
			(unlocked yes)
			(layer "F.Fab")
			(effects
				(font
					(size 0.7874 0.5842)
					(thickness 0.000001)
				)
				(justify left)
			)
		)
		(fp_text user "3"
			(at 0.9779 -1.996694 0)
			(unlocked yes)
			(layer "F.Fab")
			(effects
				(font
					(size 0.7874 0.5842)
					(thickness 0.000001)
				)
				(justify left)
			)
		)
		(pad "1" thru_hole rect
			(at -1.27 2.54)
			(size 1.524 1.524)
			(drill 1.016)
			(layers "*.Cu" "*.Mask")
			(remove_unused_layers no)
			(net "CM_STATUS_LED_R")
			(clearance 0)
			(padstack
				(mode front_inner_back)
				(layer "Inner"
					(shape circle)
					(size 1.524 1.524)
					(clearance 0)
				)
				(layer "B.Cu"
					(shape rect)
					(size 1.524 1.524)
					(clearance 0)
				)
			)
		)
		(pad "2" thru_hole circle
			(at 0 0)
			(size 1.524 1.524)
			(drill 1.016)
			(layers "*.Cu" "*.Mask")
			(remove_unused_layers no)
			(net "N53608970")
			(clearance 0)
		)
		(pad "3" thru_hole circle
			(at 1.27 2.54)
			(size 1.524 1.524)
			(drill 1.016)
			(layers "*.Cu" "*.Mask")
			(remove_unused_layers no)
			(net "LED_PWR_GD")
			(clearance 0)
		)
	)
	(footprint ""
		(layer "F.Cu")
		(at 50.337466 -10.963402 90)
		(property "Reference" "PL7"
			(at 4.175252 -4.137406 0)
			(unlocked yes)
			(layer "F.SilkS")
			(effects
				(font
					(size 0.7874 0.5842)
					(thickness 0.1524)
				)
				(justify left)
			)
		)
		(property "Value" ""
			(at 0 0 90)
			(layer "F.Fab")
			(effects
				(font
					(size 1.27 1.27)
				)
			)
		)
		(duplicate_pad_numbers_are_jumpers no)
		(fp_line
			(start 3.350006 -4.1656)
			(end 3.350006 4.1656)
			(stroke
				(width 0.1524)
				(type default)
			)
			(layer "F.SilkS")
		)
		(fp_line
			(start -3.350006 -4.1656)
			(end 3.350006 -4.1656)
			(stroke
				(width 0.1524)
				(type default)
			)
			(layer "F.SilkS")
		)
		(fp_line
			(start 3.350006 4.1656)
			(end -3.350006 4.1656)
			(stroke
				(width 0.1524)
				(type default)
			)
			(layer "F.SilkS")
		)
		(fp_line
			(start -3.350006 4.1656)
			(end -3.350006 -4.1656)
			(stroke
				(width 0.1524)
				(type default)
			)
			(layer "F.SilkS")
		)
		(fp_poly
			(pts
				(xy -3.350006 -3.64998) (xy -1.7018 -3.64998) (xy -1.7018 -4.05257) (xy 1.7018 -4.05257) (xy 1.7018 -3.64998)
				(xy 3.350006 -3.64998) (xy 3.350006 3.64998) (xy 1.7018 3.64998) (xy 1.7018 4.05257) (xy -1.7018 4.05257)
				(xy -1.7018 3.64998) (xy -3.350006 3.64998)
			)
			(stroke
				(width 0)
				(type default)
			)
			(fill no)
			(layer "F.CrtYd")
		)
		(fp_line
			(start 3.350006 -3.64998)
			(end 3.350006 3.64998)
			(stroke
				(width 0.1)
				(type default)
			)
			(layer "F.Fab")
		)
		(fp_line
			(start -3.350006 -3.64998)
			(end 3.350006 -3.64998)
			(stroke
				(width 0.1)
				(type default)
			)
			(layer "F.Fab")
		)
		(fp_line
			(start 3.350006 3.64998)
			(end -3.350006 3.64998)
			(stroke
				(width 0.1)
				(type default)
			)
			(layer "F.Fab")
		)
		(fp_line
			(start -3.350006 3.64998)
			(end -3.350006 -3.64998)
			(stroke
				(width 0.1)
				(type default)
			)
			(layer "F.Fab")
		)
		(pad "1" smd rect
			(at 0 -2.92481)
			(size 2.15392 3.302)
			(layers "F.Cu" "F.Mask" "F.Paste")
			(net "SW_PV_VDDR_NODE1_PH")
		)
		(pad "2" smd rect
			(at 0 2.92481)
			(size 2.15392 3.302)
			(layers "F.Cu" "F.Mask" "F.Paste")
			(net "PV_VDDR_NODE1")
		)
	)
	(footprint ""
		(layer "F.Cu")
		(at 11.12012 -3.705352 180)
		(property "Reference" "R471"
			(at 1.137412 -2.360422 0)
			(unlocked yes)
			(layer "F.SilkS")
			(effects
				(font
					(size 0.7874 0.5842)
					(thickness 0.1524)
				)
				(justify left)
			)
		)
		(property "Value" ""
			(at 0 0 180)
			(layer "F.Fab")
			(effects
				(font
					(size 1.27 1.27)
				)
			)
		)
		(duplicate_pad_numbers_are_jumpers no)
		(fp_line
			(start 0.7874 0.4064)
			(end -0.7874 0.4064)
			(stroke
				(width 0.1524)
				(type default)
			)
			(layer "F.SilkS")
		)
		(fp_line
			(start 0.7874 -0.4064)
			(end 0.7874 0.4064)
			(stroke
				(width 0.1524)
				(type default)
			)
			(layer "F.SilkS")
		)
		(fp_line
			(start -0.7874 0.4064)
			(end -0.7874 -0.4064)
			(stroke
				(width 0.1524)
				(type default)
			)
			(layer "F.SilkS")
		)
		(fp_line
			(start -0.7874 -0.4064)
			(end 0.7874 -0.4064)
			(stroke
				(width 0.1524)
				(type default)
			)
			(layer "F.SilkS")
		)
		(fp_poly
			(pts
				(xy -0.508 0.2794) (xy -0.508 0.2286) (xy -0.635 0.2286) (xy -0.635 -0.254) (xy -0.5334 -0.254)
				(xy -0.5334 -0.2794) (xy 0.5334 -0.2794) (xy 0.5334 -0.254) (xy 0.635 -0.254) (xy 0.635 0.254) (xy 0.5334 0.254)
				(xy 0.5334 0.2794)
			)
			(stroke
				(width 0)
				(type default)
			)
			(fill no)
			(layer "F.CrtYd")
		)
		(pad "1" smd rect
			(at 0.40005 0 180)
			(size 0.4572 0.508)
			(layers "F.Cu" "F.Mask" "F.Paste")
			(net "SMB_MUX_CPU_ICS_NODE1_CLK")
		)
		(pad "2" smd rect
			(at -0.40005 0 180)
			(size 0.4572 0.508)
			(layers "F.Cu" "F.Mask" "F.Paste")
			(net "SMB_DIMM_NODE1_CLK")
		)
	)
	(footprint ""
		(layer "F.Cu")
		(at 52.655978 -170.630088 180)
		(property "Reference" "C618"
			(at 9.03986 -131.070096 0)
			(unlocked yes)
			(layer "F.SilkS")
			(effects
				(font
					(size 0.7874 0.5842)
					(thickness 0.1524)
				)
				(justify left)
			)
		)
		(property "Value" ""
			(at 0 0 180)
			(layer "F.Fab")
			(effects
				(font
					(size 1.27 1.27)
				)
			)
		)
		(duplicate_pad_numbers_are_jumpers no)
		(fp_line
			(start 0.7874 0.4064)
			(end -0.7874 0.4064)
			(stroke
				(width 0.1524)
				(type default)
			)
			(layer "F.SilkS")
		)
		(fp_line
			(start 0.7874 -0.4064)
			(end 0.7874 0.4064)
			(stroke
				(width 0.1524)
				(type default)
			)
			(layer "F.SilkS")
		)
		(fp_line
			(start 0 0.381)
			(end 0 -0.381)
			(stroke
				(width 0.1524)
				(type default)
			)
			(layer "F.SilkS")
		)
		(fp_line
			(start -0.7874 0.4064)
			(end -0.7874 -0.4064)
			(stroke
				(width 0.1524)
				(type default)
			)
			(layer "F.SilkS")
		)
		(fp_line
			(start -0.7874 -0.4064)
			(end 0.7874 -0.4064)
			(stroke
				(width 0.1524)
				(type default)
			)
			(layer "F.SilkS")
		)
		(fp_poly
			(pts
				(xy -0.5334 0.254) (xy -0.635 0.254) (xy -0.635 0.2286) (xy -0.635 -0.254) (xy -0.5334 -0.254) (xy -0.5334 -0.2794)
				(xy 0.5334 -0.2794) (xy 0.5334 -0.254) (xy 0.635 -0.254) (xy 0.635 0.254) (xy 0.5334 0.254) (xy 0.5334 0.2794)
				(xy -0.508 0.2794) (xy -0.5334 0.2794)
			)
			(stroke
				(width 0)
				(type default)
			)
			(fill no)
			(layer "F.CrtYd")
		)
		(pad "1" smd rect
			(at 0.40005 0 180)
			(size 0.4572 0.508)
			(layers "F.Cu" "F.Mask" "F.Paste")
			(net "P3V3_NODE1")
		)
		(pad "2" smd rect
			(at -0.40005 0 180)
			(size 0.4572 0.508)
			(layers "F.Cu" "F.Mask" "F.Paste")
			(net "GND")
		)
	)
	(footprint ""
		(layer "F.Cu")
		(at 127.63246 -53.928518 -90)
		(property "Reference" "U136"
			(at -4.225036 -1.370584 0)
			(unlocked yes)
			(layer "F.SilkS")
			(effects
				(font
					(size 0.7874 0.5842)
					(thickness 0.1524)
				)
			)
		)
		(property "Value" ""
			(at 0 0 270)
			(layer "F.Fab")
			(effects
				(font
					(size 1.27 1.27)
				)
			)
		)
		(duplicate_pad_numbers_are_jumpers no)
		(fp_line
			(start 1.1176 1.7018)
			(end -1.1176 1.7018)
			(stroke
				(width 0.1524)
				(type default)
			)
			(layer "F.SilkS")
		)
		(fp_line
			(start -1.1176 0.254)
			(end -1.1176 1.7018)
			(stroke
				(width 0.1524)
				(type default)
			)
			(layer "F.SilkS")
		)
		(fp_line
			(start -0.7112 0)
			(end -1.1176 0.254)
			(stroke
				(width 0.1524)
				(type default)
			)
			(layer "F.SilkS")
		)
		(fp_line
			(start -1.1176 -0.254)
			(end -0.7112 0)
			(stroke
				(width 0.1524)
				(type default)
			)
			(layer "F.SilkS")
		)
		(fp_line
			(start -1.1176 -1.7018)
			(end -1.1176 -0.254)
			(stroke
				(width 0.1524)
				(type default)
			)
			(layer "F.SilkS")
		)
		(fp_line
			(start -1.1176 -1.7018)
			(end 1.1176 -1.7018)
			(stroke
				(width 0.1524)
				(type default)
			)
			(layer "F.SilkS")
		)
		(fp_line
			(start 1.1176 -1.7018)
			(end 1.1176 1.7018)
			(stroke
				(width 0.1524)
				(type default)
			)
			(layer "F.SilkS")
		)
		(fp_poly
			(pts
				(xy -1.029716 1.566164) (xy -1.281176 2.140712) (xy -1.586484 1.835404)
			)
			(stroke
				(width 0)
				(type default)
			)
			(fill yes)
			(layer "F.SilkS")
		)
		(fp_rect
			(start -1.1176 1.5494)
			(end 1.1176 -1.5494)
			(stroke
				(width 0)
				(type default)
			)
			(fill no)
			(layer "F.CrtYd")
		)
		(fp_line
			(start 1.1176 1.5494)
			(end -1.1176 1.5494)
			(stroke
				(width 0.1)
				(type default)
			)
			(layer "F.Fab")
		)
		(fp_line
			(start -1.1176 0.254)
			(end -1.1176 1.5494)
			(stroke
				(width 0.1)
				(type default)
			)
			(layer "F.Fab")
		)
		(fp_line
			(start -1.1176 -0.254)
			(end -1.1176 0.254)
			(stroke
				(width 0.1)
				(type default)
			)
			(layer "F.Fab")
		)
		(fp_line
			(start -1.1176 -1.5494)
			(end -1.1176 -0.254)
			(stroke
				(width 0.1)
				(type default)
			)
			(layer "F.Fab")
		)
		(fp_line
			(start -1.1176 -1.5494)
			(end 1.1176 -1.5494)
			(stroke
				(width 0.1)
				(type default)
			)
			(layer "F.Fab")
		)
		(fp_line
			(start 1.1176 -1.5494)
			(end 1.1176 1.5494)
			(stroke
				(width 0.1)
				(type default)
			)
			(layer "F.Fab")
		)
		(fp_poly
			(pts
				(xy -0.675386 1.8161) (xy -0.446786 2.4003) (xy -0.878586 2.4003)
			)
			(stroke
				(width 0)
				(type default)
			)
			(fill yes)
			(layer "F.Fab")
		)
		(pad "1" smd rect
			(at -0.649986 0.962406 270)
			(size 0.3302 1.1684)
			(layers "F.Cu" "F.Mask" "F.Paste")
			(net "COM4_EN_N")
		)
		(pad "2" smd rect
			(at 0 0.962406 270)
			(size 0.3302 1.1684)
			(layers "F.Cu" "F.Mask" "F.Paste")
			(net "UART_RX_P4")
		)
		(pad "3" smd rect
			(at 0.649986 0.962406 270)
			(size 0.3302 1.1684)
			(layers "F.Cu" "F.Mask" "F.Paste")
			(net "GND")
		)
		(pad "4" smd rect
			(at 0.649986 -0.962406 270)
			(size 0.3302 1.1684)
			(layers "F.Cu" "F.Mask" "F.Paste")
			(net "UART_RX_P4_BUF")
		)
		(pad "5" smd rect
			(at -0.649986 -0.962406 270)
			(size 0.3302 1.1684)
			(layers "F.Cu" "F.Mask" "F.Paste")
			(net "P3V3_NODE1")
		)
	)
	(footprint ""
		(layer "F.Cu")
		(at 72.957182 -6.929882 90)
		(property "Reference" "PC47"
			(at -3.90906 0.19812 90)
			(unlocked yes)
			(layer "F.SilkS")
			(effects
				(font
					(size 0.7874 0.5842)
					(thickness 0.1524)
				)
				(justify left)
			)
		)
		(property "Value" ""
			(at 0 0 90)
			(layer "F.Fab")
			(effects
				(font
					(size 1.27 1.27)
				)
			)
		)
		(duplicate_pad_numbers_are_jumpers no)
		(fp_line
			(start 0.7874 -0.4064)
			(end 0.7874 0.4064)
			(stroke
				(width 0.1524)
				(type default)
			)
			(layer "F.SilkS")
		)
		(fp_line
			(start -0.7874 -0.4064)
			(end 0.7874 -0.4064)
			(stroke
				(width 0.1524)
				(type default)
			)
			(layer "F.SilkS")
		)
		(fp_line
			(start 0 0.381)
			(end 0 -0.381)
			(stroke
				(width 0.1524)
				(type default)
			)
			(layer "F.SilkS")
		)
		(fp_line
			(start 0.7874 0.4064)
			(end -0.7874 0.4064)
			(stroke
				(width 0.1524)
				(type default)
			)
			(layer "F.SilkS")
		)
		(fp_line
			(start -0.7874 0.4064)
			(end -0.7874 -0.4064)
			(stroke
				(width 0.1524)
				(type default)
			)
			(layer "F.SilkS")
		)
		(fp_poly
			(pts
				(xy -0.5334 0.254) (xy -0.635 0.254) (xy -0.635 0.2286) (xy -0.635 -0.254) (xy -0.5334 -0.254) (xy -0.5334 -0.2794)
				(xy 0.5334 -0.2794) (xy 0.5334 -0.254) (xy 0.635 -0.254) (xy 0.635 0.254) (xy 0.5334 0.254) (xy 0.5334 0.2794)
				(xy -0.508 0.2794) (xy -0.5334 0.2794)
			)
			(stroke
				(width 0)
				(type default)
			)
			(fill no)
			(layer "F.CrtYd")
		)
		(pad "1" smd rect
			(at 0.40005 0 90)
			(size 0.4572 0.508)
			(layers "F.Cu" "F.Mask" "F.Paste")
			(net "SW_P3V3_NODE1_BT")
		)
		(pad "2" smd rect
			(at -0.40005 0 90)
			(size 0.4572 0.508)
			(layers "F.Cu" "F.Mask" "F.Paste")
			(net "SW_P3V3_NODE1_PH")
		)
	)
	(footprint ""
		(layer "F.Cu")
		(at 36.18865 -77.63256)
		(property "Reference" "C111"
			(at -3.634232 -0.321818 0)
			(unlocked yes)
			(layer "F.SilkS")
			(effects
				(font
					(size 0.7874 0.5842)
					(thickness 0.1524)
				)
			)
		)
		(property "Value" ""
			(at 0 0 0)
			(layer "F.Fab")
			(effects
				(font
					(size 1.27 1.27)
				)
			)
		)
		(duplicate_pad_numbers_are_jumpers no)
		(fp_line
			(start -1.2954 -0.5842)
			(end 1.2954 -0.5842)
			(stroke
				(width 0.1524)
				(type default)
			)
			(layer "F.SilkS")
		)
		(fp_line
			(start -1.2954 0.5842)
			(end -1.2954 -0.5842)
			(stroke
				(width 0.1524)
				(type default)
			)
			(layer "F.SilkS")
		)
		(fp_line
			(start 0 -0.5842)
			(end 0 0.5842)
			(stroke
				(width 0.1524)
				(type default)
			)
			(layer "F.SilkS")
		)
		(fp_line
			(start 1.2954 -0.5842)
			(end 1.2954 0.5842)
			(stroke
				(width 0.1524)
				(type default)
			)
			(layer "F.SilkS")
		)
		(fp_line
			(start 1.2954 0.5842)
			(end -1.2954 0.5842)
			(stroke
				(width 0.1524)
				(type default)
			)
			(layer "F.SilkS")
		)
		(fp_poly
			(pts
				(xy 0.8636 -0.4572) (xy 0.8636 -0.3556) (xy 1.143 -0.3556) (xy 1.143 0.3556) (xy 0.8636 0.3556)
				(xy 0.8636 0.4572) (xy -0.8636 0.4572) (xy -0.8636 0.3556) (xy -1.143 0.3556) (xy -1.143 -0.3556)
				(xy -0.8636 -0.3556) (xy -0.8636 -0.4572)
			)
			(stroke
				(width 0)
				(type default)
			)
			(fill no)
			(layer "F.CrtYd")
		)
		(fp_line
			(start -0.884936 -0.504952)
			(end 0.884936 -0.504952)
			(stroke
				(width 0.1)
				(type default)
			)
			(layer "F.Fab")
		)
		(fp_line
			(start -0.884936 0.504952)
			(end -0.884936 -0.504952)
			(stroke
				(width 0.1)
				(type default)
			)
			(layer "F.Fab")
		)
		(fp_line
			(start 0.884936 -0.504952)
			(end 0.884936 0.504952)
			(stroke
				(width 0.1)
				(type default)
			)
			(layer "F.Fab")
		)
		(fp_line
			(start 0.884936 0.504952)
			(end -0.884936 0.504952)
			(stroke
				(width 0.1)
				(type default)
			)
			(layer "F.Fab")
		)
		(pad "1" smd rect
			(at 0.7366 0 90)
			(size 0.7112 0.8128)
			(layers "F.Cu" "F.Mask" "F.Paste")
			(net "P1V8_VCCASFRHPLL_NODE1")
		)
		(pad "2" smd rect
			(at -0.7366 0 90)
			(size 0.7112 0.8128)
			(layers "F.Cu" "F.Mask" "F.Paste")
			(net "GND")
		)
	)
	(footprint ""
		(layer "F.Cu")
		(at 80.98663 -98.076766 90)
		(property "Reference" "Q31"
			(at 2.092452 3.293618 90)
			(unlocked yes)
			(layer "F.SilkS")
			(effects
				(font
					(size 0.7874 0.5842)
					(thickness 0.1524)
				)
			)
		)
		(property "Value" ""
			(at 0 0 90)
			(layer "F.Fab")
			(effects
				(font
					(size 1.27 1.27)
				)
			)
		)
		(duplicate_pad_numbers_are_jumpers no)
		(fp_line
			(start 2.899918 -0.525018)
			(end 2.899918 -0.345694)
			(stroke
				(width 0.1524)
				(type default)
			)
			(layer "F.SilkS")
		)
		(fp_line
			(start 1.755648 -0.525018)
			(end 2.899918 -0.525018)
			(stroke
				(width 0.1524)
				(type default)
			)
			(layer "F.SilkS")
		)
		(fp_line
			(start -0.100076 -0.525018)
			(end 1.044448 -0.525018)
			(stroke
				(width 0.1524)
				(type default)
			)
			(layer "F.SilkS")
		)
		(fp_line
			(start -0.100076 -0.320294)
			(end -0.100076 -0.525018)
			(stroke
				(width 0.1524)
				(type default)
			)
			(layer "F.SilkS")
		)
		(fp_line
			(start 2.899918 2.295906)
			(end 2.899918 2.474976)
			(stroke
				(width 0.1524)
				(type default)
			)
			(layer "F.SilkS")
		)
		(fp_line
			(start 2.899918 2.474976)
			(end 1.755648 2.474976)
			(stroke
				(width 0.1524)
				(type default)
			)
			(layer "F.SilkS")
		)
		(fp_line
			(start 1.044448 2.474976)
			(end -0.100076 2.474976)
			(stroke
				(width 0.1524)
				(type default)
			)
			(layer "F.SilkS")
		)
		(fp_line
			(start -0.100076 2.474976)
			(end -0.100076 2.295906)
			(stroke
				(width 0.1524)
				(type default)
			)
			(layer "F.SilkS")
		)
		(fp_poly
			(pts
				(xy -0.99695 0.26924) (xy -0.99695 -0.249682) (xy -0.419608 0.01397)
			)
			(stroke
				(width 0)
				(type default)
			)
			(fill yes)
			(layer "F.SilkS")
		)
		(fp_poly
			(pts
				(xy -0.100076 -0.525018) (xy -0.100076 -0.244094) (xy -0.301752 -0.244094) (xy -0.301752 2.194306)
				(xy -0.100076 2.194306) (xy -0.100076 2.474976) (xy 1.120648 2.474976) (xy 1.120648 2.651506) (xy 1.679448 2.651506)
				(xy 1.679448 2.474976) (xy 2.899918 2.474976) (xy 2.899918 2.219706) (xy 3.101848 2.219706) (xy 3.101848 -0.269494)
				(xy 2.899918 -0.269494) (xy 2.899918 -0.525018) (xy 1.679448 -0.525018) (xy 1.679448 -0.701294)
				(xy 1.120648 -0.701294) (xy 1.120648 -0.525018)
			)
			(stroke
				(width 0)
				(type default)
			)
			(fill no)
			(layer "F.CrtYd")
		)
		(fp_line
			(start 2.899918 -0.525018)
			(end 2.899918 2.474976)
			(stroke
				(width 0.1)
				(type default)
			)
			(layer "F.Fab")
		)
		(fp_line
			(start -0.100076 -0.525018)
			(end 2.899918 -0.525018)
			(stroke
				(width 0.1)
				(type default)
			)
			(layer "F.Fab")
		)
		(fp_line
			(start 2.899918 2.474976)
			(end -0.100076 2.474976)
			(stroke
				(width 0.1)
				(type default)
			)
			(layer "F.Fab")
		)
		(fp_line
			(start -0.100076 2.474976)
			(end -0.100076 -0.525018)
			(stroke
				(width 0.1)
				(type default)
			)
			(layer "F.Fab")
		)
		(pad "1" smd rect
			(at 0 0)
			(size 0.3556 0.508)
			(layers "F.Cu" "F.Mask" "F.Paste")
			(net "P3V3_SUS_NODE1")
		)
		(pad "2" smd rect
			(at 0 0.649986)
			(size 0.3556 0.508)
			(layers "F.Cu" "F.Mask" "F.Paste")
			(net "P3V3_SUS_NODE1")
		)
		(pad "3" smd rect
			(at 0 1.299972)
			(size 0.3556 0.508)
			(layers "F.Cu" "F.Mask" "F.Paste")
			(net "P3V3_SUS_NODE1")
		)
		(pad "4" smd rect
			(at 0 1.949958)
			(size 0.3556 0.508)
			(layers "F.Cu" "F.Mask" "F.Paste")
			(net "FM_CPLD_NODE1_P3V3_SUS_EN_LV")
		)
		(pad "5" smd custom
			(at 1.400048 0.975106)
			(size 0.569976 0.569976)
			(layers "F.Cu" "F.Mask" "F.Paste")
			(net "P3V3_STB_NODE1")
			(options
				(clearance outline)
				(anchor circle)
			)
			(primitives
				(gr_poly
					(pts
						(xy -1.225042 1.139952) (xy -1.225042 0.724916) (xy -1.605026 0.724916) (xy -1.605026 0.295148)
						(xy -1.225042 0.295148) (xy -1.225042 -0.839978) (xy -1.175004 -0.839978) (xy -1.175004 -1.139952)
						(xy -0.774954 -1.139952) (xy -0.774954 -0.839978) (xy -0.525018 -0.839978) (xy -0.525018 -1.139952)
						(xy -0.124968 -1.139952) (xy -0.124968 -0.839978) (xy 0.124968 -0.839978) (xy 0.124968 -1.139952)
						(xy 0.525018 -1.139952) (xy 0.525018 -0.839978) (xy 0.774954 -0.839978) (xy 0.774954 -1.139952)
						(xy 1.175004 -1.139952) (xy 1.175004 -0.839978) (xy 1.225042 -0.839978) (xy 1.225042 0.295148)
						(xy 1.605026 0.295148) (xy 1.605026 0.724916) (xy 1.225042 0.724916) (xy 1.225042 1.139952)
					)
					(width 0)
					(fill yes)
				)
			)
		)
		(zone
			(layer "F.Cu")
			(hatch none 0.5)
			(connect_pads
				(clearance 0)
			)
			(min_thickness 0.25)
			(keepout
				(tracks allowed)
				(vias not_allowed)
				(pads allowed)
				(copperpour not_allowed)
				(footprints allowed)
			)
			(placement
				(enabled no)
				(sheetname "")
			)
			(fill
				(thermal_gap 0.5)
				(thermal_bridge_width 0.5)
				(island_removal_mode 0)
			)
			(polygon
				(pts
					(xy 80.463136 -98.791014) (xy 83.460336 -98.791014) (xy 83.460336 -98.410014) (xy 80.463136 -98.410014)
				)
			)
		)
		(zone
			(layer "F.Cu")
			(hatch none 0.5)
			(connect_pads
				(clearance 0)
			)
			(min_thickness 0.25)
			(keepout
				(tracks not_allowed)
				(vias allowed)
				(pads allowed)
				(copperpour not_allowed)
				(footprints allowed)
			)
			(placement
				(enabled no)
				(sheetname "")
			)
			(fill
				(thermal_gap 0.5)
				(thermal_bridge_width 0.5)
				(island_removal_mode 0)
			)
			(polygon
				(pts
					(xy 80.463136 -98.410014) (xy 83.460336 -98.410014) (xy 83.460336 -98.791014) (xy 80.463136 -98.791014)
				)
			)
		)
	)
	(footprint ""
		(layer "F.Cu")
		(at 64.193166 -96.709992 -90)
		(property "Reference" "R58"
			(at 54.98719 -28.497276 90)
			(unlocked yes)
			(layer "F.SilkS")
			(effects
				(font
					(size 0.7874 0.5842)
					(thickness 0.1524)
				)
				(justify left)
			)
		)
		(property "Value" ""
			(at 0 0 270)
			(layer "F.Fab")
			(effects
				(font
					(size 1.27 1.27)
				)
			)
		)
		(duplicate_pad_numbers_are_jumpers no)
		(fp_line
			(start -0.7874 0.4064)
			(end -0.7874 -0.4064)
			(stroke
				(width 0.1524)
				(type default)
			)
			(layer "F.SilkS")
		)
		(fp_line
			(start 0.7874 0.4064)
			(end -0.7874 0.4064)
			(stroke
				(width 0.1524)
				(type default)
			)
			(layer "F.SilkS")
		)
		(fp_line
			(start -0.7874 -0.4064)
			(end 0.7874 -0.4064)
			(stroke
				(width 0.1524)
				(type default)
			)
			(layer "F.SilkS")
		)
		(fp_line
			(start 0.7874 -0.4064)
			(end 0.7874 0.4064)
			(stroke
				(width 0.1524)
				(type default)
			)
			(layer "F.SilkS")
		)
		(fp_poly
			(pts
				(xy -0.508 0.2794) (xy -0.508 0.2286) (xy -0.635 0.2286) (xy -0.635 -0.254) (xy -0.5334 -0.254)
				(xy -0.5334 -0.2794) (xy 0.5334 -0.2794) (xy 0.5334 -0.254) (xy 0.635 -0.254) (xy 0.635 0.254) (xy 0.5334 0.254)
				(xy 0.5334 0.2794)
			)
			(stroke
				(width 0)
				(type default)
			)
			(fill no)
			(layer "F.CrtYd")
		)
		(pad "1" smd rect
			(at 0.40005 0 270)
			(size 0.4572 0.508)
			(layers "F.Cu" "F.Mask" "F.Paste")
			(net "SPI_CPU_NODE1_MOSI_R")
		)
		(pad "2" smd rect
			(at -0.40005 0 270)
			(size 0.4572 0.508)
			(layers "F.Cu" "F.Mask" "F.Paste")
			(net "SPI_CPU_NODE1_MOSI")
		)
	)
	(footprint ""
		(layer "F.Cu")
		(at 35.766502 -83.294982)
		(property "Reference" "R107"
			(at -4.685284 0.049784 0)
			(unlocked yes)
			(layer "F.SilkS")
			(effects
				(font
					(size 0.7874 0.5842)
					(thickness 0.1524)
				)
				(justify left)
			)
		)
		(property "Value" ""
			(at 0 0 0)
			(layer "F.Fab")
			(effects
				(font
					(size 1.27 1.27)
				)
			)
		)
		(duplicate_pad_numbers_are_jumpers no)
		(fp_line
			(start -0.7874 -0.4064)
			(end 0.7874 -0.4064)
			(stroke
				(width 0.1524)
				(type default)
			)
			(layer "F.SilkS")
		)
		(fp_line
			(start -0.7874 0.4064)
			(end -0.7874 -0.4064)
			(stroke
				(width 0.1524)
				(type default)
			)
			(layer "F.SilkS")
		)
		(fp_line
			(start 0.7874 -0.4064)
			(end 0.7874 0.4064)
			(stroke
				(width 0.1524)
				(type default)
			)
			(layer "F.SilkS")
		)
		(fp_line
			(start 0.7874 0.4064)
			(end -0.7874 0.4064)
			(stroke
				(width 0.1524)
				(type default)
			)
			(layer "F.SilkS")
		)
		(fp_poly
			(pts
				(xy -0.508 0.2794) (xy -0.508 0.2286) (xy -0.635 0.2286) (xy -0.635 -0.254) (xy -0.5334 -0.254)
				(xy -0.5334 -0.2794) (xy 0.5334 -0.2794) (xy 0.5334 -0.254) (xy 0.635 -0.254) (xy 0.635 0.254) (xy 0.5334 0.254)
				(xy 0.5334 0.2794)
			)
			(stroke
				(width 0)
				(type default)
			)
			(fill no)
			(layer "F.CrtYd")
		)
		(pad "1" smd rect
			(at 0.40005 0)
			(size 0.4572 0.508)
			(layers "F.Cu" "F.Mask" "F.Paste")
			(net "PD_NODE1_NTB_PERP")
		)
		(pad "2" smd rect
			(at -0.40005 0)
			(size 0.4572 0.508)
			(layers "F.Cu" "F.Mask" "F.Paste")
			(net "GND")
		)
	)
	(footprint ""
		(layer "F.Cu")
		(at 149.33676 -185.205624 90)
		(property "Reference" "C750"
			(at 4.768088 0.250952 90)
			(unlocked yes)
			(layer "F.SilkS")
			(effects
				(font
					(size 0.7874 0.5842)
					(thickness 0.1524)
				)
				(justify left)
			)
		)
		(property "Value" ""
			(at 0 0 90)
			(layer "F.Fab")
			(effects
				(font
					(size 1.27 1.27)
				)
			)
		)
		(duplicate_pad_numbers_are_jumpers no)
		(fp_line
			(start 0.7874 -0.4064)
			(end 0.7874 0.4064)
			(stroke
				(width 0.1524)
				(type default)
			)
			(layer "F.SilkS")
		)
		(fp_line
			(start -0.7874 -0.4064)
			(end 0.7874 -0.4064)
			(stroke
				(width 0.1524)
				(type default)
			)
			(layer "F.SilkS")
		)
		(fp_line
			(start 0 0.381)
			(end 0 -0.381)
			(stroke
				(width 0.1524)
				(type default)
			)
			(layer "F.SilkS")
		)
		(fp_line
			(start 0.7874 0.4064)
			(end -0.7874 0.4064)
			(stroke
				(width 0.1524)
				(type default)
			)
			(layer "F.SilkS")
		)
		(fp_line
			(start -0.7874 0.4064)
			(end -0.7874 -0.4064)
			(stroke
				(width 0.1524)
				(type default)
			)
			(layer "F.SilkS")
		)
		(fp_poly
			(pts
				(xy -0.5334 0.254) (xy -0.635 0.254) (xy -0.635 0.2286) (xy -0.635 -0.254) (xy -0.5334 -0.254) (xy -0.5334 -0.2794)
				(xy 0.5334 -0.2794) (xy 0.5334 -0.254) (xy 0.635 -0.254) (xy 0.635 0.254) (xy 0.5334 0.254) (xy 0.5334 0.2794)
				(xy -0.508 0.2794) (xy -0.5334 0.2794)
			)
			(stroke
				(width 0)
				(type default)
			)
			(fill no)
			(layer "F.CrtYd")
		)
		(pad "1" smd rect
			(at 0.40005 0 90)
			(size 0.4572 0.508)
			(layers "F.Cu" "F.Mask" "F.Paste")
			(net "UART_T12_NODE2_RXD")
		)
		(pad "2" smd rect
			(at -0.40005 0 90)
			(size 0.4572 0.508)
			(layers "F.Cu" "F.Mask" "F.Paste")
			(net "GND")
		)
	)
	(footprint ""
		(layer "F.Cu")
		(at 138.922252 -154.79395 90)
		(property "Reference" "R279"
			(at -110.714282 -61.383926 90)
			(unlocked yes)
			(layer "F.SilkS")
			(effects
				(font
					(size 0.7874 0.5842)
					(thickness 0.1524)
				)
				(justify left)
			)
		)
		(property "Value" ""
			(at 0 0 90)
			(layer "F.Fab")
			(effects
				(font
					(size 1.27 1.27)
				)
			)
		)
		(duplicate_pad_numbers_are_jumpers no)
		(fp_line
			(start 0.7874 -0.4064)
			(end 0.7874 0.4064)
			(stroke
				(width 0.1524)
				(type default)
			)
			(layer "F.SilkS")
		)
		(fp_line
			(start -0.7874 -0.4064)
			(end 0.7874 -0.4064)
			(stroke
				(width 0.1524)
				(type default)
			)
			(layer "F.SilkS")
		)
		(fp_line
			(start 0.7874 0.4064)
			(end -0.7874 0.4064)
			(stroke
				(width 0.1524)
				(type default)
			)
			(layer "F.SilkS")
		)
		(fp_line
			(start -0.7874 0.4064)
			(end -0.7874 -0.4064)
			(stroke
				(width 0.1524)
				(type default)
			)
			(layer "F.SilkS")
		)
		(fp_poly
			(pts
				(xy -0.508 0.2794) (xy -0.508 0.2286) (xy -0.635 0.2286) (xy -0.635 -0.254) (xy -0.5334 -0.254)
				(xy -0.5334 -0.2794) (xy 0.5334 -0.2794) (xy 0.5334 -0.254) (xy 0.635 -0.254) (xy 0.635 0.254) (xy 0.5334 0.254)
				(xy 0.5334 0.2794)
			)
			(stroke
				(width 0)
				(type default)
			)
			(fill no)
			(layer "F.CrtYd")
		)
		(pad "1" smd rect
			(at 0.40005 0 90)
			(size 0.4572 0.508)
			(layers "F.Cu" "F.Mask" "F.Paste")
			(net "GND")
		)
		(pad "2" smd rect
			(at -0.40005 0 90)
			(size 0.4572 0.508)
			(layers "F.Cu" "F.Mask" "F.Paste")
			(net "PCIE_SW_P2_CTCDIS")
		)
	)
	(footprint ""
		(layer "F.Cu")
		(at 16.81226 -131.82219 -90)
		(property "Reference" "PU6"
			(at -1.12649 -1.823466 90)
			(unlocked yes)
			(layer "F.SilkS")
			(effects
				(font
					(size 0.7874 0.5842)
					(thickness 0.1524)
				)
				(justify left)
			)
		)
		(property "Value" ""
			(at 0 0 270)
			(layer "F.Fab")
			(effects
				(font
					(size 1.27 1.27)
				)
			)
		)
		(duplicate_pad_numbers_are_jumpers no)
		(fp_line
			(start -0.025146 2.325116)
			(end 0.457708 2.325116)
			(stroke
				(width 0.1524)
				(type default)
			)
			(layer "F.SilkS")
		)
		(fp_line
			(start 2.591308 2.325116)
			(end 3.124962 2.325116)
			(stroke
				(width 0.1524)
				(type default)
			)
			(layer "F.SilkS")
		)
		(fp_line
			(start 3.124962 2.325116)
			(end 3.124962 1.893062)
			(stroke
				(width 0.1524)
				(type default)
			)
			(layer "F.SilkS")
		)
		(fp_line
			(start -0.025146 1.842262)
			(end -0.025146 2.325116)
			(stroke
				(width 0.1524)
				(type default)
			)
			(layer "F.SilkS")
		)
		(fp_line
			(start 3.124962 -0.316738)
			(end 3.124962 -0.824992)
			(stroke
				(width 0.1524)
				(type default)
			)
			(layer "F.SilkS")
		)
		(fp_line
			(start -0.025146 -0.824992)
			(end -0.025146 -0.291338)
			(stroke
				(width 0.1524)
				(type default)
			)
			(layer "F.SilkS")
		)
		(fp_line
			(start 0.483108 -0.824992)
			(end -0.025146 -0.824992)
			(stroke
				(width 0.1524)
				(type default)
			)
			(layer "F.SilkS")
		)
		(fp_line
			(start 3.124962 -0.824992)
			(end 2.591308 -0.824992)
			(stroke
				(width 0.1524)
				(type default)
			)
			(layer "F.SilkS")
		)
		(fp_poly
			(pts
				(xy -0.550164 0) (xy -1.690116 -0.379984) (xy -1.690116 0.379984)
			)
			(stroke
				(width 0)
				(type default)
			)
			(fill yes)
			(layer "F.SilkS")
		)
		(fp_poly
			(pts
				(xy -0.025146 2.325116) (xy 0.584708 2.325116) (xy 0.584708 2.832862) (xy 2.515108 2.832862) (xy 2.515108 2.325116)
				(xy 3.124962 2.325116) (xy 3.124962 1.715262) (xy 3.632708 1.715262) (xy 3.632708 -0.215138) (xy 3.124962 -0.215138)
				(xy 3.124962 -0.824992) (xy 2.515108 -0.824992) (xy 2.515108 -1.332738) (xy 0.584708 -1.332738)
				(xy 0.584708 -0.824992) (xy -0.025146 -0.824992) (xy -0.025146 -0.215138) (xy -0.532892 -0.215138)
				(xy -0.532892 1.715262) (xy -0.025146 1.715262)
			)
			(stroke
				(width 0)
				(type default)
			)
			(fill no)
			(layer "F.CrtYd")
		)
		(fp_line
			(start -0.025146 2.325116)
			(end -0.025146 -0.824992)
			(stroke
				(width 0.1)
				(type default)
			)
			(layer "F.Fab")
		)
		(fp_line
			(start 3.124962 2.325116)
			(end -0.025146 2.325116)
			(stroke
				(width 0.1)
				(type default)
			)
			(layer "F.Fab")
		)
		(fp_line
			(start -0.025146 -0.824992)
			(end 3.124962 -0.824992)
			(stroke
				(width 0.1)
				(type default)
			)
			(layer "F.Fab")
		)
		(fp_line
			(start 3.124962 -0.824992)
			(end 3.124962 2.325116)
			(stroke
				(width 0.1)
				(type default)
			)
			(layer "F.Fab")
		)
		(fp_text user "5"
			(at 0.822198 3.301746 0)
			(unlocked yes)
			(layer "F.SilkS")
			(effects
				(font
					(size 0.635 0.4064)
					(thickness 0.1524)
				)
				(justify left)
			)
		)
		(fp_text user "9"
			(at 3.534156 2.742438 0)
			(unlocked yes)
			(layer "F.SilkS")
			(effects
				(font
					(size 0.635 0.4064)
					(thickness 0.1524)
				)
				(justify left)
			)
		)
		(fp_text user "12"
			(at 3.683508 -0.296164 0)
			(unlocked yes)
			(layer "F.SilkS")
			(effects
				(font
					(size 0.635 0.4064)
					(thickness 0.1524)
				)
				(justify left)
			)
		)
		(fp_text user "16"
			(at 0.146304 -0.936752 0)
			(unlocked yes)
			(layer "F.SilkS")
			(effects
				(font
					(size 0.635 0.4064)
					(thickness 0.1524)
				)
				(justify left)
			)
		)
		(pad "1" smd rect
			(at 0 0)
			(size 0.2794 0.9144)
			(layers "F.Cu" "F.Mask" "F.Paste")
			(net "P1V05_NODE1_VREF")
		)
		(pad "2" smd rect
			(at 0 0.500126)
			(size 0.2794 0.9144)
			(layers "F.Cu" "F.Mask" "F.Paste")
			(net "P1V05_NODE1_VREFIN")
		)
		(pad "3" smd rect
			(at 0 0.999998)
			(size 0.2794 0.9144)
			(layers "F.Cu" "F.Mask" "F.Paste")
			(net "VSENSE_P1V05_NODE1_N")
		)
		(pad "4" smd rect
			(at 0 1.500124)
			(size 0.2794 0.9144)
			(layers "F.Cu" "F.Mask" "F.Paste")
			(net "P1V05_NODE1_VSNS")
		)
		(pad "5" smd rect
			(at 0.799846 2.29997 270)
			(size 0.2794 0.9144)
			(layers "F.Cu" "F.Mask" "F.Paste")
			(net "P1V05_NODE1_COMP")
		)
		(pad "6" smd rect
			(at 1.299972 2.29997 270)
			(size 0.2794 0.9144)
			(layers "F.Cu" "F.Mask" "F.Paste")
			(net "P1V05_NODE1_TRIP")
		)
		(pad "7" smd rect
			(at 1.799844 2.29997 270)
			(size 0.2794 0.9144)
			(layers "F.Cu" "F.Mask" "F.Paste")
			(net "GND")
		)
		(pad "8" smd rect
			(at 2.29997 2.29997 270)
			(size 0.2794 0.9144)
			(layers "F.Cu" "F.Mask" "F.Paste")
			(net "GND")
		)
		(pad "9" smd rect
			(at 3.099816 1.500124)
			(size 0.2794 0.9144)
			(layers "F.Cu" "F.Mask" "F.Paste")
			(net "P5V_STB_NODE1")
		)
		(pad "10" smd rect
			(at 3.099816 0.999998)
			(size 0.2794 0.9144)
			(layers "F.Cu" "F.Mask" "F.Paste")
			(net "SW_P1V05_NODE1_DRVL")
		)
		(pad "11" smd rect
			(at 3.099816 0.500126)
			(size 0.2794 0.9144)
			(layers "F.Cu" "F.Mask" "F.Paste")
			(net "SW_P1V05_NODE1_DRVH")
		)
		(pad "12" smd rect
			(at 3.099816 0)
			(size 0.2794 0.9144)
			(layers "F.Cu" "F.Mask" "F.Paste")
			(net "SW_P1V05_NODE1_PH")
		)
		(pad "13" smd rect
			(at 2.29997 -0.799846 270)
			(size 0.2794 0.9144)
			(layers "F.Cu" "F.Mask" "F.Paste")
			(net "SW_P1V05_NODE1_BT")
		)
		(pad "14" smd rect
			(at 1.799844 -0.799846 270)
			(size 0.2794 0.9144)
			(layers "F.Cu" "F.Mask" "F.Paste")
			(net "P1V05_NODE1_EN")
		)
		(pad "15" smd rect
			(at 1.299972 -0.799846 270)
			(size 0.2794 0.9144)
			(layers "F.Cu" "F.Mask" "F.Paste")
			(net "P1V05_NODE1_MODE")
		)
		(pad "16" smd rect
			(at 0.799846 -0.799846 270)
			(size 0.2794 0.9144)
			(layers "F.Cu" "F.Mask" "F.Paste")
			(net "PWRGD_NODE1_P1V05_PG")
		)
		(pad "TH" smd rect
			(at 1.549908 0.750062)
			(size 1.651 1.651)
			(layers "F.Cu" "F.Mask" "F.Paste")
			(net "GND")
		)
		(zone
			(layer "F.Cu")
			(hatch none 0.5)
			(connect_pads
				(clearance 0)
			)
			(min_thickness 0.25)
			(keepout
				(tracks not_allowed)
				(vias allowed)
				(pads allowed)
				(copperpour not_allowed)
				(footprints allowed)
			)
			(placement
				(enabled no)
				(sheetname "")
			)
			(fill
				(thermal_gap 0.5)
				(thermal_bridge_width 0.5)
				(island_removal_mode 0)
			)
			(polygon
				(pts
					(xy 15.28826 -131.288282) (xy 17.078198 -131.288282) (xy 17.078198 -129.256282) (xy 15.046198 -129.256282)
					(xy 15.046198 -131.288282) (xy 15.21206 -131.288282) (xy 15.21206 -131.16179) (xy 15.16126 -131.16179)
					(xy 15.16126 -129.38379) (xy 16.96466 -129.38379) (xy 16.96466 -131.16179) (xy 15.23746 -131.16179)
					(xy 15.23746 -131.288282)
				)
			)
		)
		(zone
			(layer "F.Cu")
			(hatch none 0.5)
			(connect_pads
				(clearance 0)
			)
			(min_thickness 0.25)
			(keepout
				(tracks allowed)
				(vias not_allowed)
				(pads allowed)
				(copperpour not_allowed)
				(footprints allowed)
			)
			(placement
				(enabled no)
				(sheetname "")
			)
			(fill
				(thermal_gap 0.5)
				(thermal_bridge_width 0.5)
				(island_removal_mode 0)
			)
			(polygon
				(pts
					(xy 15.28826 -131.288282) (xy 17.078198 -131.288282) (xy 17.078198 -129.256282) (xy 15.046198 -129.256282)
					(xy 15.046198 -131.288282) (xy 15.21206 -131.288282) (xy 15.21206 -131.237482) (xy 15.21206 -131.16179)
					(xy 15.16126 -131.16179) (xy 15.16126 -129.38379) (xy 16.96466 -129.38379) (xy 16.96466 -131.16179)
					(xy 15.28826 -131.16179) (xy 15.23746 -131.16179) (xy 15.23746 -131.288282)
				)
			)
		)
	)
	(footprint ""
		(layer "F.Cu")
		(at 168.662096 -131.715764 90)
		(property "Reference" "R660"
			(at -2.014728 -3.01879 90)
			(unlocked yes)
			(layer "F.SilkS")
			(effects
				(font
					(size 0.7874 0.5842)
					(thickness 0.1524)
				)
				(justify left)
			)
		)
		(property "Value" ""
			(at 0 0 90)
			(layer "F.Fab")
			(effects
				(font
					(size 1.27 1.27)
				)
			)
		)
		(duplicate_pad_numbers_are_jumpers no)
		(fp_line
			(start 0.7874 -0.4064)
			(end 0.7874 0.4064)
			(stroke
				(width 0.1524)
				(type default)
			)
			(layer "F.SilkS")
		)
		(fp_line
			(start -0.7874 -0.4064)
			(end 0.7874 -0.4064)
			(stroke
				(width 0.1524)
				(type default)
			)
			(layer "F.SilkS")
		)
		(fp_line
			(start 0.7874 0.4064)
			(end -0.7874 0.4064)
			(stroke
				(width 0.1524)
				(type default)
			)
			(layer "F.SilkS")
		)
		(fp_line
			(start -0.7874 0.4064)
			(end -0.7874 -0.4064)
			(stroke
				(width 0.1524)
				(type default)
			)
			(layer "F.SilkS")
		)
		(fp_poly
			(pts
				(xy -0.508 0.2794) (xy -0.508 0.2286) (xy -0.635 0.2286) (xy -0.635 -0.254) (xy -0.5334 -0.254)
				(xy -0.5334 -0.2794) (xy 0.5334 -0.2794) (xy 0.5334 -0.254) (xy 0.635 -0.254) (xy 0.635 0.254) (xy 0.5334 0.254)
				(xy 0.5334 0.2794)
			)
			(stroke
				(width 0)
				(type default)
			)
			(fill no)
			(layer "F.CrtYd")
		)
		(pad "1" smd rect
			(at 0.40005 0 90)
			(size 0.4572 0.508)
			(layers "F.Cu" "F.Mask" "F.Paste")
			(net "CPLD123_RSV2")
		)
		(pad "2" smd rect
			(at -0.40005 0 90)
			(size 0.4572 0.508)
			(layers "F.Cu" "F.Mask" "F.Paste")
			(net "CPLD1_RSV2")
		)
	)
	(footprint ""
		(layer "F.Cu")
		(at 177.649632 -148.94052)
		(property "Reference" "C445"
			(at -5.225542 0.262128 0)
			(unlocked yes)
			(layer "F.SilkS")
			(effects
				(font
					(size 0.7874 0.5842)
					(thickness 0.1524)
				)
				(justify left)
			)
		)
		(property "Value" ""
			(at 0 0 0)
			(layer "F.Fab")
			(effects
				(font
					(size 1.27 1.27)
				)
			)
		)
		(duplicate_pad_numbers_are_jumpers no)
		(fp_line
			(start -1.905 -0.8636)
			(end 1.905 -0.8636)
			(stroke
				(width 0.1524)
				(type default)
			)
			(layer "F.SilkS")
		)
		(fp_line
			(start -1.905 0.8636)
			(end -1.905 -0.8636)
			(stroke
				(width 0.1524)
				(type default)
			)
			(layer "F.SilkS")
		)
		(fp_line
			(start 0 0.8382)
			(end 0 -0.8382)
			(stroke
				(width 0.1524)
				(type default)
			)
			(layer "F.SilkS")
		)
		(fp_line
			(start 1.905 -0.8636)
			(end 1.905 0.8636)
			(stroke
				(width 0.1524)
				(type default)
			)
			(layer "F.SilkS")
		)
		(fp_line
			(start 1.905 0.8636)
			(end -1.905 0.8636)
			(stroke
				(width 0.1524)
				(type default)
			)
			(layer "F.SilkS")
		)
		(fp_rect
			(start -1.524 0.7366)
			(end 1.524 -0.7366)
			(stroke
				(width 0)
				(type default)
			)
			(fill no)
			(layer "F.CrtYd")
		)
		(pad "1" smd rect
			(at 0.94996 0)
			(size 1.1176 1.3716)
			(layers "F.Cu" "F.Mask" "F.Paste")
			(net "P3V3_NODE1")
		)
		(pad "2" smd rect
			(at -0.94996 0)
			(size 1.1176 1.3716)
			(layers "F.Cu" "F.Mask" "F.Paste")
			(net "GND")
		)
	)
	(footprint ""
		(layer "F.Cu")
		(at 134.98576 -110.783624 -90)
		(property "Reference" "R16"
			(at 5.84835 -0.628142 90)
			(unlocked yes)
			(layer "F.SilkS")
			(effects
				(font
					(size 0.7874 0.5842)
					(thickness 0.1524)
				)
				(justify left)
			)
		)
		(property "Value" ""
			(at 0 0 270)
			(layer "F.Fab")
			(effects
				(font
					(size 1.27 1.27)
				)
			)
		)
		(duplicate_pad_numbers_are_jumpers no)
		(fp_line
			(start -0.7874 0.4064)
			(end -0.7874 -0.4064)
			(stroke
				(width 0.1524)
				(type default)
			)
			(layer "F.SilkS")
		)
		(fp_line
			(start 0.7874 0.4064)
			(end -0.7874 0.4064)
			(stroke
				(width 0.1524)
				(type default)
			)
			(layer "F.SilkS")
		)
		(fp_line
			(start -0.7874 -0.4064)
			(end 0.7874 -0.4064)
			(stroke
				(width 0.1524)
				(type default)
			)
			(layer "F.SilkS")
		)
		(fp_line
			(start 0.7874 -0.4064)
			(end 0.7874 0.4064)
			(stroke
				(width 0.1524)
				(type default)
			)
			(layer "F.SilkS")
		)
		(fp_poly
			(pts
				(xy -0.508 0.2794) (xy -0.508 0.2286) (xy -0.635 0.2286) (xy -0.635 -0.254) (xy -0.5334 -0.254)
				(xy -0.5334 -0.2794) (xy 0.5334 -0.2794) (xy 0.5334 -0.254) (xy 0.635 -0.254) (xy 0.635 0.254) (xy 0.5334 0.254)
				(xy 0.5334 0.2794)
			)
			(stroke
				(width 0)
				(type default)
			)
			(fill no)
			(layer "F.CrtYd")
		)
		(pad "1" smd rect
			(at 0.40005 0 270)
			(size 0.4572 0.508)
			(layers "F.Cu" "F.Mask" "F.Paste")
			(net "GND")
		)
		(pad "2" smd rect
			(at -0.40005 0 270)
			(size 0.4572 0.508)
			(layers "F.Cu" "F.Mask" "F.Paste")
			(net "CLK_FSLB_NODE1")
		)
	)
	(footprint ""
		(layer "F.Cu")
		(at 149.508972 -29.903928 180)
		(property "Reference" "C531"
			(at 1.243076 -2.064258 0)
			(unlocked yes)
			(layer "F.SilkS")
			(effects
				(font
					(size 0.7874 0.5842)
					(thickness 0.1524)
				)
				(justify left)
			)
		)
		(property "Value" ""
			(at 0 0 180)
			(layer "F.Fab")
			(effects
				(font
					(size 1.27 1.27)
				)
			)
		)
		(duplicate_pad_numbers_are_jumpers no)
		(fp_line
			(start 0.7874 0.4064)
			(end -0.7874 0.4064)
			(stroke
				(width 0.1524)
				(type default)
			)
			(layer "F.SilkS")
		)
		(fp_line
			(start 0.7874 -0.4064)
			(end 0.7874 0.4064)
			(stroke
				(width 0.1524)
				(type default)
			)
			(layer "F.SilkS")
		)
		(fp_line
			(start 0 0.381)
			(end 0 -0.381)
			(stroke
				(width 0.1524)
				(type default)
			)
			(layer "F.SilkS")
		)
		(fp_line
			(start -0.7874 0.4064)
			(end -0.7874 -0.4064)
			(stroke
				(width 0.1524)
				(type default)
			)
			(layer "F.SilkS")
		)
		(fp_line
			(start -0.7874 -0.4064)
			(end 0.7874 -0.4064)
			(stroke
				(width 0.1524)
				(type default)
			)
			(layer "F.SilkS")
		)
		(fp_poly
			(pts
				(xy -0.5334 0.254) (xy -0.635 0.254) (xy -0.635 0.2286) (xy -0.635 -0.254) (xy -0.5334 -0.254) (xy -0.5334 -0.2794)
				(xy 0.5334 -0.2794) (xy 0.5334 -0.254) (xy 0.635 -0.254) (xy 0.635 0.254) (xy 0.5334 0.254) (xy 0.5334 0.2794)
				(xy -0.508 0.2794) (xy -0.5334 0.2794)
			)
			(stroke
				(width 0)
				(type default)
			)
			(fill no)
			(layer "F.CrtYd")
		)
		(pad "1" smd rect
			(at 0.40005 0 180)
			(size 0.4572 0.508)
			(layers "F.Cu" "F.Mask" "F.Paste")
			(net "GND")
		)
		(pad "2" smd rect
			(at -0.40005 0 180)
			(size 0.4572 0.508)
			(layers "F.Cu" "F.Mask" "F.Paste")
			(net "N21624890")
		)
	)
	(footprint ""
		(layer "F.Cu")
		(at 79.945992 -78.192122)
		(property "Reference" "R76"
			(at -0.298196 16.248888 0)
			(unlocked yes)
			(layer "F.SilkS")
			(effects
				(font
					(size 0.7874 0.5842)
					(thickness 0.1524)
				)
				(justify left)
			)
		)
		(property "Value" ""
			(at 0 0 0)
			(layer "F.Fab")
			(effects
				(font
					(size 1.27 1.27)
				)
			)
		)
		(duplicate_pad_numbers_are_jumpers no)
		(fp_line
			(start -0.7874 -0.4064)
			(end 0.7874 -0.4064)
			(stroke
				(width 0.1524)
				(type default)
			)
			(layer "F.SilkS")
		)
		(fp_line
			(start -0.7874 0.4064)
			(end -0.7874 -0.4064)
			(stroke
				(width 0.1524)
				(type default)
			)
			(layer "F.SilkS")
		)
		(fp_line
			(start 0.7874 -0.4064)
			(end 0.7874 0.4064)
			(stroke
				(width 0.1524)
				(type default)
			)
			(layer "F.SilkS")
		)
		(fp_line
			(start 0.7874 0.4064)
			(end -0.7874 0.4064)
			(stroke
				(width 0.1524)
				(type default)
			)
			(layer "F.SilkS")
		)
		(fp_poly
			(pts
				(xy -0.508 0.2794) (xy -0.508 0.2286) (xy -0.635 0.2286) (xy -0.635 -0.254) (xy -0.5334 -0.254)
				(xy -0.5334 -0.2794) (xy 0.5334 -0.2794) (xy 0.5334 -0.254) (xy 0.635 -0.254) (xy 0.635 0.254) (xy 0.5334 0.254)
				(xy 0.5334 0.2794)
			)
			(stroke
				(width 0)
				(type default)
			)
			(fill no)
			(layer "F.CrtYd")
		)
		(pad "1" smd rect
			(at 0.40005 0)
			(size 0.4572 0.508)
			(layers "F.Cu" "F.Mask" "F.Paste")
			(net "P1V05_NODE1")
		)
		(pad "2" smd rect
			(at -0.40005 0)
			(size 0.4572 0.508)
			(layers "F.Cu" "F.Mask" "F.Paste")
			(net "XDP_SOC_CPU_NODE1_TDI")
		)
	)
	(footprint ""
		(layer "F.Cu")
		(at 65.305686 -148.476462 90)
		(property "Reference" "R313"
			(at -0.86106 1.523238 90)
			(unlocked yes)
			(layer "F.SilkS")
			(effects
				(font
					(size 0.7874 0.5842)
					(thickness 0.1524)
				)
				(justify left)
			)
		)
		(property "Value" ""
			(at 0 0 90)
			(layer "F.Fab")
			(effects
				(font
					(size 1.27 1.27)
				)
			)
		)
		(duplicate_pad_numbers_are_jumpers no)
		(fp_line
			(start 0.7874 -0.4064)
			(end 0.7874 0.4064)
			(stroke
				(width 0.1524)
				(type default)
			)
			(layer "F.SilkS")
		)
		(fp_line
			(start -0.7874 -0.4064)
			(end 0.7874 -0.4064)
			(stroke
				(width 0.1524)
				(type default)
			)
			(layer "F.SilkS")
		)
		(fp_line
			(start 0.7874 0.4064)
			(end -0.7874 0.4064)
			(stroke
				(width 0.1524)
				(type default)
			)
			(layer "F.SilkS")
		)
		(fp_line
			(start -0.7874 0.4064)
			(end -0.7874 -0.4064)
			(stroke
				(width 0.1524)
				(type default)
			)
			(layer "F.SilkS")
		)
		(fp_poly
			(pts
				(xy -0.508 0.2794) (xy -0.508 0.2286) (xy -0.635 0.2286) (xy -0.635 -0.254) (xy -0.5334 -0.254)
				(xy -0.5334 -0.2794) (xy 0.5334 -0.2794) (xy 0.5334 -0.254) (xy 0.635 -0.254) (xy 0.635 0.254) (xy 0.5334 0.254)
				(xy 0.5334 0.2794)
			)
			(stroke
				(width 0)
				(type default)
			)
			(fill no)
			(layer "F.CrtYd")
		)
		(pad "1" smd rect
			(at 0.40005 0 90)
			(size 0.4572 0.508)
			(layers "F.Cu" "F.Mask" "F.Paste")
			(net "GND")
		)
		(pad "2" smd rect
			(at -0.40005 0 90)
			(size 0.4572 0.508)
			(layers "F.Cu" "F.Mask" "F.Paste")
			(net "BMC_NODE1_ADCREXT")
		)
	)
	(footprint ""
		(layer "F.Cu")
		(at 128.940052 -133.00075 90)
		(property "Reference" "C877"
			(at -3.959352 0.148336 90)
			(unlocked yes)
			(layer "F.SilkS")
			(effects
				(font
					(size 0.7874 0.5842)
					(thickness 0.1524)
				)
				(justify left)
			)
		)
		(property "Value" ""
			(at 0 0 90)
			(layer "F.Fab")
			(effects
				(font
					(size 1.27 1.27)
				)
			)
		)
		(duplicate_pad_numbers_are_jumpers no)
		(fp_line
			(start 0.7874 -0.4064)
			(end 0.7874 0.4064)
			(stroke
				(width 0.1524)
				(type default)
			)
			(layer "F.SilkS")
		)
		(fp_line
			(start -0.7874 -0.4064)
			(end 0.7874 -0.4064)
			(stroke
				(width 0.1524)
				(type default)
			)
			(layer "F.SilkS")
		)
		(fp_line
			(start 0 0.381)
			(end 0 -0.381)
			(stroke
				(width 0.1524)
				(type default)
			)
			(layer "F.SilkS")
		)
		(fp_line
			(start 0.7874 0.4064)
			(end -0.7874 0.4064)
			(stroke
				(width 0.1524)
				(type default)
			)
			(layer "F.SilkS")
		)
		(fp_line
			(start -0.7874 0.4064)
			(end -0.7874 -0.4064)
			(stroke
				(width 0.1524)
				(type default)
			)
			(layer "F.SilkS")
		)
		(fp_poly
			(pts
				(xy -0.5334 0.254) (xy -0.635 0.254) (xy -0.635 0.2286) (xy -0.635 -0.254) (xy -0.5334 -0.254) (xy -0.5334 -0.2794)
				(xy 0.5334 -0.2794) (xy 0.5334 -0.254) (xy 0.635 -0.254) (xy 0.635 0.254) (xy 0.5334 0.254) (xy 0.5334 0.2794)
				(xy -0.508 0.2794) (xy -0.5334 0.2794)
			)
			(stroke
				(width 0)
				(type default)
			)
			(fill no)
			(layer "F.CrtYd")
		)
		(pad "1" smd rect
			(at 0.40005 0 90)
			(size 0.4572 0.508)
			(layers "F.Cu" "F.Mask" "F.Paste")
			(net "P1V0_NODE1")
		)
		(pad "2" smd rect
			(at -0.40005 0 90)
			(size 0.4572 0.508)
			(layers "F.Cu" "F.Mask" "F.Paste")
			(net "GND")
		)
	)
	(footprint ""
		(layer "F.Cu")
		(at 18.28038 -90.893392 -90)
		(property "Reference" ""
			(at 0 0 270)
			(layer "F.SilkS")
			(hide yes)
			(effects
				(font
					(size 1.27 1.27)
				)
			)
		)
		(property "Value" ""
			(at 0 0 270)
			(layer "F.Fab")
			(effects
				(font
					(size 1.27 1.27)
				)
			)
		)
		(duplicate_pad_numbers_are_jumpers no)
		(fp_poly
			(pts
				(arc
					(start 0 -1.4986)
					(mid 0 1.4986)
					(end 0 -1.4986)
				)
			)
			(stroke
				(width 0)
				(type default)
			)
			(fill no)
			(layer "F.CrtYd")
		)
		(pad "1" smd circle
			(at 0 0 270)
			(size 0.9906 0.9906)
			(layers "F.Cu" "F.Mask" "F.Paste")
			(net "Net_30")
		)
		(zone
			(layer "F.Cu")
			(hatch none 0.5)
			(connect_pads
				(clearance 0)
			)
			(min_thickness 0.25)
			(keepout
				(tracks not_allowed)
				(vias allowed)
				(pads allowed)
				(copperpour not_allowed)
				(footprints allowed)
			)
			(placement
				(enabled no)
				(sheetname "")
			)
			(fill
				(thermal_gap 0.5)
				(thermal_bridge_width 0.5)
				(island_removal_mode 0)
			)
			(polygon
				(pts
					(arc
						(start 19.90598 -90.893392)
						(mid 16.65478 -90.893392)
						(end 19.90598 -90.893392)
					)
				)
			)
		)
	)
	(footprint ""
		(layer "F.Cu")
		(at 163.255198 -161.395918 90)
		(property "Reference" "R578"
			(at -8.091678 17.572736 90)
			(unlocked yes)
			(layer "F.SilkS")
			(effects
				(font
					(size 0.7874 0.5842)
					(thickness 0.1524)
				)
				(justify left)
			)
		)
		(property "Value" ""
			(at 0 0 90)
			(layer "F.Fab")
			(effects
				(font
					(size 1.27 1.27)
				)
			)
		)
		(duplicate_pad_numbers_are_jumpers no)
		(fp_line
			(start 0.7874 -0.4064)
			(end 0.7874 0.4064)
			(stroke
				(width 0.1524)
				(type default)
			)
			(layer "F.SilkS")
		)
		(fp_line
			(start -0.7874 -0.4064)
			(end 0.7874 -0.4064)
			(stroke
				(width 0.1524)
				(type default)
			)
			(layer "F.SilkS")
		)
		(fp_line
			(start 0.7874 0.4064)
			(end -0.7874 0.4064)
			(stroke
				(width 0.1524)
				(type default)
			)
			(layer "F.SilkS")
		)
		(fp_line
			(start -0.7874 0.4064)
			(end -0.7874 -0.4064)
			(stroke
				(width 0.1524)
				(type default)
			)
			(layer "F.SilkS")
		)
		(fp_poly
			(pts
				(xy -0.508 0.2794) (xy -0.508 0.2286) (xy -0.635 0.2286) (xy -0.635 -0.254) (xy -0.5334 -0.254)
				(xy -0.5334 -0.2794) (xy 0.5334 -0.2794) (xy 0.5334 -0.254) (xy 0.635 -0.254) (xy 0.635 0.254) (xy 0.5334 0.254)
				(xy 0.5334 0.2794)
			)
			(stroke
				(width 0)
				(type default)
			)
			(fill no)
			(layer "F.CrtYd")
		)
		(pad "1" smd rect
			(at 0.40005 0 90)
			(size 0.4572 0.508)
			(layers "F.Cu" "F.Mask" "F.Paste")
			(net "P3V3_NODE1")
		)
		(pad "2" smd rect
			(at -0.40005 0 90)
			(size 0.4572 0.508)
			(layers "F.Cu" "F.Mask" "F.Paste")
			(net "LAN2_NC_SI_RXD0")
		)
	)
	(footprint ""
		(layer "F.Cu")
		(at 77.117194 -158.464758)
		(property "Reference" "PC25"
			(at -1.590294 -1.119886 0)
			(unlocked yes)
			(layer "F.SilkS")
			(effects
				(font
					(size 0.7874 0.5842)
					(thickness 0.1524)
				)
				(justify left)
			)
		)
		(property "Value" ""
			(at 0 0 0)
			(layer "F.Fab")
			(effects
				(font
					(size 1.27 1.27)
				)
			)
		)
		(duplicate_pad_numbers_are_jumpers no)
		(fp_line
			(start -0.7874 -0.4064)
			(end 0.7874 -0.4064)
			(stroke
				(width 0.1524)
				(type default)
			)
			(layer "F.SilkS")
		)
		(fp_line
			(start -0.7874 0.4064)
			(end -0.7874 -0.4064)
			(stroke
				(width 0.1524)
				(type default)
			)
			(layer "F.SilkS")
		)
		(fp_line
			(start 0 0.381)
			(end 0 -0.381)
			(stroke
				(width 0.1524)
				(type default)
			)
			(layer "F.SilkS")
		)
		(fp_line
			(start 0.7874 -0.4064)
			(end 0.7874 0.4064)
			(stroke
				(width 0.1524)
				(type default)
			)
			(layer "F.SilkS")
		)
		(fp_line
			(start 0.7874 0.4064)
			(end -0.7874 0.4064)
			(stroke
				(width 0.1524)
				(type default)
			)
			(layer "F.SilkS")
		)
		(fp_poly
			(pts
				(xy -0.5334 0.254) (xy -0.635 0.254) (xy -0.635 0.2286) (xy -0.635 -0.254) (xy -0.5334 -0.254) (xy -0.5334 -0.2794)
				(xy 0.5334 -0.2794) (xy 0.5334 -0.254) (xy 0.635 -0.254) (xy 0.635 0.254) (xy 0.5334 0.254) (xy 0.5334 0.2794)
				(xy -0.508 0.2794) (xy -0.5334 0.2794)
			)
			(stroke
				(width 0)
				(type default)
			)
			(fill no)
			(layer "F.CrtYd")
		)
		(pad "1" smd rect
			(at 0.40005 0)
			(size 0.4572 0.508)
			(layers "F.Cu" "F.Mask" "F.Paste")
			(net "P5V_STB_NODE1_EN")
		)
		(pad "2" smd rect
			(at -0.40005 0)
			(size 0.4572 0.508)
			(layers "F.Cu" "F.Mask" "F.Paste")
			(net "GND")
		)
	)
	(footprint ""
		(layer "F.Cu")
		(at 14.059154 -133.218428 90)
		(property "Reference" "PC69"
			(at -0.494792 -2.139696 90)
			(unlocked yes)
			(layer "F.SilkS")
			(effects
				(font
					(size 0.7874 0.5842)
					(thickness 0.1524)
				)
				(justify left)
			)
		)
		(property "Value" ""
			(at 0 0 90)
			(layer "F.Fab")
			(effects
				(font
					(size 1.27 1.27)
				)
			)
		)
		(duplicate_pad_numbers_are_jumpers no)
		(fp_line
			(start 0.7874 -0.4064)
			(end 0.7874 0.4064)
			(stroke
				(width 0.1524)
				(type default)
			)
			(layer "F.SilkS")
		)
		(fp_line
			(start -0.7874 -0.4064)
			(end 0.7874 -0.4064)
			(stroke
				(width 0.1524)
				(type default)
			)
			(layer "F.SilkS")
		)
		(fp_line
			(start 0 0.381)
			(end 0 -0.381)
			(stroke
				(width 0.1524)
				(type default)
			)
			(layer "F.SilkS")
		)
		(fp_line
			(start 0.7874 0.4064)
			(end -0.7874 0.4064)
			(stroke
				(width 0.1524)
				(type default)
			)
			(layer "F.SilkS")
		)
		(fp_line
			(start -0.7874 0.4064)
			(end -0.7874 -0.4064)
			(stroke
				(width 0.1524)
				(type default)
			)
			(layer "F.SilkS")
		)
		(fp_poly
			(pts
				(xy -0.5334 0.254) (xy -0.635 0.254) (xy -0.635 0.2286) (xy -0.635 -0.254) (xy -0.5334 -0.254) (xy -0.5334 -0.2794)
				(xy 0.5334 -0.2794) (xy 0.5334 -0.254) (xy 0.635 -0.254) (xy 0.635 0.254) (xy 0.5334 0.254) (xy 0.5334 0.2794)
				(xy -0.508 0.2794) (xy -0.5334 0.2794)
			)
			(stroke
				(width 0)
				(type default)
			)
			(fill no)
			(layer "F.CrtYd")
		)
		(pad "1" smd rect
			(at 0.40005 0 90)
			(size 0.4572 0.508)
			(layers "F.Cu" "F.Mask" "F.Paste")
			(net "P1V05_NODE1_VSNS")
		)
		(pad "2" smd rect
			(at -0.40005 0 90)
			(size 0.4572 0.508)
			(layers "F.Cu" "F.Mask" "F.Paste")
			(net "P1V05_NODE1_COMP")
		)
	)
	(footprint ""
		(layer "F.Cu")
		(at 61.96076 -185.205624 90)
		(property "Reference" "C700"
			(at 4.006088 -0.601218 90)
			(unlocked yes)
			(layer "F.SilkS")
			(effects
				(font
					(size 0.7874 0.5842)
					(thickness 0.1524)
				)
				(justify left)
			)
		)
		(property "Value" ""
			(at 0 0 90)
			(layer "F.Fab")
			(effects
				(font
					(size 1.27 1.27)
				)
			)
		)
		(duplicate_pad_numbers_are_jumpers no)
		(fp_line
			(start 0.7874 -0.4064)
			(end 0.7874 0.4064)
			(stroke
				(width 0.1524)
				(type default)
			)
			(layer "F.SilkS")
		)
		(fp_line
			(start -0.7874 -0.4064)
			(end 0.7874 -0.4064)
			(stroke
				(width 0.1524)
				(type default)
			)
			(layer "F.SilkS")
		)
		(fp_line
			(start 0 0.381)
			(end 0 -0.381)
			(stroke
				(width 0.1524)
				(type default)
			)
			(layer "F.SilkS")
		)
		(fp_line
			(start 0.7874 0.4064)
			(end -0.7874 0.4064)
			(stroke
				(width 0.1524)
				(type default)
			)
			(layer "F.SilkS")
		)
		(fp_line
			(start -0.7874 0.4064)
			(end -0.7874 -0.4064)
			(stroke
				(width 0.1524)
				(type default)
			)
			(layer "F.SilkS")
		)
		(fp_poly
			(pts
				(xy -0.5334 0.254) (xy -0.635 0.254) (xy -0.635 0.2286) (xy -0.635 -0.254) (xy -0.5334 -0.254) (xy -0.5334 -0.2794)
				(xy 0.5334 -0.2794) (xy 0.5334 -0.254) (xy 0.635 -0.254) (xy 0.635 0.254) (xy 0.5334 0.254) (xy 0.5334 0.2794)
				(xy -0.508 0.2794) (xy -0.5334 0.2794)
			)
			(stroke
				(width 0)
				(type default)
			)
			(fill no)
			(layer "F.CrtYd")
		)
		(pad "1" smd rect
			(at 0.40005 0 90)
			(size 0.4572 0.508)
			(layers "F.Cu" "F.Mask" "F.Paste")
			(net "UART_T2_NODE2_RXD")
		)
		(pad "2" smd rect
			(at -0.40005 0 90)
			(size 0.4572 0.508)
			(layers "F.Cu" "F.Mask" "F.Paste")
			(net "GND")
		)
	)
	(footprint ""
		(layer "F.Cu")
		(at 8.34009 -6.709156 180)
		(property "Reference" "R214"
			(at 6.44398 0.688086 0)
			(unlocked yes)
			(layer "F.SilkS")
			(effects
				(font
					(size 0.7874 0.5842)
					(thickness 0.1524)
				)
				(justify left)
			)
		)
		(property "Value" ""
			(at 0 0 180)
			(layer "F.Fab")
			(effects
				(font
					(size 1.27 1.27)
				)
			)
		)
		(duplicate_pad_numbers_are_jumpers no)
		(fp_line
			(start 0.7874 0.4064)
			(end -0.7874 0.4064)
			(stroke
				(width 0.1524)
				(type default)
			)
			(layer "F.SilkS")
		)
		(fp_line
			(start 0.7874 -0.4064)
			(end 0.7874 0.4064)
			(stroke
				(width 0.1524)
				(type default)
			)
			(layer "F.SilkS")
		)
		(fp_line
			(start -0.7874 0.4064)
			(end -0.7874 -0.4064)
			(stroke
				(width 0.1524)
				(type default)
			)
			(layer "F.SilkS")
		)
		(fp_line
			(start -0.7874 -0.4064)
			(end 0.7874 -0.4064)
			(stroke
				(width 0.1524)
				(type default)
			)
			(layer "F.SilkS")
		)
		(fp_poly
			(pts
				(xy -0.508 0.2794) (xy -0.508 0.2286) (xy -0.635 0.2286) (xy -0.635 -0.254) (xy -0.5334 -0.254)
				(xy -0.5334 -0.2794) (xy 0.5334 -0.2794) (xy 0.5334 -0.254) (xy 0.635 -0.254) (xy 0.635 0.254) (xy 0.5334 0.254)
				(xy 0.5334 0.2794)
			)
			(stroke
				(width 0)
				(type default)
			)
			(fill no)
			(layer "F.CrtYd")
		)
		(pad "1" smd rect
			(at 0.40005 0 180)
			(size 0.4572 0.508)
			(layers "F.Cu" "F.Mask" "F.Paste")
			(net "PV_VDDR_NODE1")
		)
		(pad "2" smd rect
			(at -0.40005 0 180)
			(size 0.4572 0.508)
			(layers "F.Cu" "F.Mask" "F.Paste")
			(net "PV_VDDR_NODE1_VREF_RW")
		)
	)
	(footprint ""
		(layer "F.Cu")
		(at 160.38322 -97.315528 180)
		(property "Reference" "R527"
			(at 4.331462 -0.623062 0)
			(unlocked yes)
			(layer "F.SilkS")
			(effects
				(font
					(size 0.7874 0.5842)
					(thickness 0.1524)
				)
				(justify left)
			)
		)
		(property "Value" ""
			(at 0 0 180)
			(layer "F.Fab")
			(effects
				(font
					(size 1.27 1.27)
				)
			)
		)
		(duplicate_pad_numbers_are_jumpers no)
		(fp_line
			(start 0.7874 0.4064)
			(end -0.7874 0.4064)
			(stroke
				(width 0.1524)
				(type default)
			)
			(layer "F.SilkS")
		)
		(fp_line
			(start 0.7874 -0.4064)
			(end 0.7874 0.4064)
			(stroke
				(width 0.1524)
				(type default)
			)
			(layer "F.SilkS")
		)
		(fp_line
			(start -0.7874 0.4064)
			(end -0.7874 -0.4064)
			(stroke
				(width 0.1524)
				(type default)
			)
			(layer "F.SilkS")
		)
		(fp_line
			(start -0.7874 -0.4064)
			(end 0.7874 -0.4064)
			(stroke
				(width 0.1524)
				(type default)
			)
			(layer "F.SilkS")
		)
		(fp_poly
			(pts
				(xy -0.508 0.2794) (xy -0.508 0.2286) (xy -0.635 0.2286) (xy -0.635 -0.254) (xy -0.5334 -0.254)
				(xy -0.5334 -0.2794) (xy 0.5334 -0.2794) (xy 0.5334 -0.254) (xy 0.635 -0.254) (xy 0.635 0.254) (xy 0.5334 0.254)
				(xy 0.5334 0.2794)
			)
			(stroke
				(width 0)
				(type default)
			)
			(fill no)
			(layer "F.CrtYd")
		)
		(pad "1" smd rect
			(at 0.40005 0 180)
			(size 0.4572 0.508)
			(layers "F.Cu" "F.Mask" "F.Paste")
			(net "P3V3_NODE1")
		)
		(pad "2" smd rect
			(at -0.40005 0 180)
			(size 0.4572 0.508)
			(layers "F.Cu" "F.Mask" "F.Paste")
			(net "FM_CPLD_NODE1_USB_PONRST_L")
		)
	)
	(footprint ""
		(layer "F.Cu")
		(at 154.551126 -167.785288 180)
		(property "Reference" "R573"
			(at 5.148834 4.164838 0)
			(unlocked yes)
			(layer "F.SilkS")
			(effects
				(font
					(size 0.7874 0.5842)
					(thickness 0.1524)
				)
				(justify left)
			)
		)
		(property "Value" ""
			(at 0 0 180)
			(layer "F.Fab")
			(effects
				(font
					(size 1.27 1.27)
				)
			)
		)
		(duplicate_pad_numbers_are_jumpers no)
		(fp_line
			(start 0.7874 0.4064)
			(end -0.7874 0.4064)
			(stroke
				(width 0.1524)
				(type default)
			)
			(layer "F.SilkS")
		)
		(fp_line
			(start 0.7874 -0.4064)
			(end 0.7874 0.4064)
			(stroke
				(width 0.1524)
				(type default)
			)
			(layer "F.SilkS")
		)
		(fp_line
			(start -0.7874 0.4064)
			(end -0.7874 -0.4064)
			(stroke
				(width 0.1524)
				(type default)
			)
			(layer "F.SilkS")
		)
		(fp_line
			(start -0.7874 -0.4064)
			(end 0.7874 -0.4064)
			(stroke
				(width 0.1524)
				(type default)
			)
			(layer "F.SilkS")
		)
		(fp_poly
			(pts
				(xy -0.508 0.2794) (xy -0.508 0.2286) (xy -0.635 0.2286) (xy -0.635 -0.254) (xy -0.5334 -0.254)
				(xy -0.5334 -0.2794) (xy 0.5334 -0.2794) (xy 0.5334 -0.254) (xy 0.635 -0.254) (xy 0.635 0.254) (xy 0.5334 0.254)
				(xy 0.5334 0.2794)
			)
			(stroke
				(width 0)
				(type default)
			)
			(fill no)
			(layer "F.CrtYd")
		)
		(pad "1" smd rect
			(at 0.40005 0 180)
			(size 0.4572 0.508)
			(layers "F.Cu" "F.Mask" "F.Paste")
			(net "SPI_LAN2_NVM_CS_N")
		)
		(pad "2" smd rect
			(at -0.40005 0 180)
			(size 0.4572 0.508)
			(layers "F.Cu" "F.Mask" "F.Paste")
			(net "LAN2_NVM_CS_N_R")
		)
	)
	(footprint ""
		(layer "F.Cu")
		(at 113.90376 -188.126624 -90)
		(property "Reference" "R997"
			(at -5.151882 -0.485902 90)
			(unlocked yes)
			(layer "F.SilkS")
			(effects
				(font
					(size 0.7874 0.5842)
					(thickness 0.1524)
				)
				(justify left)
			)
		)
		(property "Value" ""
			(at 0 0 270)
			(layer "F.Fab")
			(effects
				(font
					(size 1.27 1.27)
				)
			)
		)
		(duplicate_pad_numbers_are_jumpers no)
		(fp_line
			(start -0.7874 0.4064)
			(end -0.7874 -0.4064)
			(stroke
				(width 0.1524)
				(type default)
			)
			(layer "F.SilkS")
		)
		(fp_line
			(start 0.7874 0.4064)
			(end -0.7874 0.4064)
			(stroke
				(width 0.1524)
				(type default)
			)
			(layer "F.SilkS")
		)
		(fp_line
			(start -0.7874 -0.4064)
			(end 0.7874 -0.4064)
			(stroke
				(width 0.1524)
				(type default)
			)
			(layer "F.SilkS")
		)
		(fp_line
			(start 0.7874 -0.4064)
			(end 0.7874 0.4064)
			(stroke
				(width 0.1524)
				(type default)
			)
			(layer "F.SilkS")
		)
		(fp_poly
			(pts
				(xy -0.508 0.2794) (xy -0.508 0.2286) (xy -0.635 0.2286) (xy -0.635 -0.254) (xy -0.5334 -0.254)
				(xy -0.5334 -0.2794) (xy 0.5334 -0.2794) (xy 0.5334 -0.254) (xy 0.635 -0.254) (xy 0.635 0.254) (xy 0.5334 0.254)
				(xy 0.5334 0.2794)
			)
			(stroke
				(width 0)
				(type default)
			)
			(fill no)
			(layer "F.CrtYd")
		)
		(pad "1" smd rect
			(at 0.40005 0 270)
			(size 0.4572 0.508)
			(layers "F.Cu" "F.Mask" "F.Paste")
			(net "UART_T8_NODE4_RXD")
		)
		(pad "2" smd rect
			(at -0.40005 0 270)
			(size 0.4572 0.508)
			(layers "F.Cu" "F.Mask" "F.Paste")
			(net "UART_T8_NODE4_RXD_R")
		)
	)
	(footprint ""
		(layer "F.Cu")
		(at 163.154868 -80.60944 180)
		(property "Reference" "PC27"
			(at -3.537204 1.049274 0)
			(unlocked yes)
			(layer "F.SilkS")
			(effects
				(font
					(size 0.7874 0.5842)
					(thickness 0.1524)
				)
				(justify left)
			)
		)
		(property "Value" ""
			(at 0 0 180)
			(layer "F.Fab")
			(effects
				(font
					(size 1.27 1.27)
				)
			)
		)
		(duplicate_pad_numbers_are_jumpers no)
		(fp_line
			(start 1.905 0.8636)
			(end -1.905 0.8636)
			(stroke
				(width 0.1524)
				(type default)
			)
			(layer "F.SilkS")
		)
		(fp_line
			(start 1.905 -0.8636)
			(end 1.905 0.8636)
			(stroke
				(width 0.1524)
				(type default)
			)
			(layer "F.SilkS")
		)
		(fp_line
			(start 0 0.8382)
			(end 0 -0.8382)
			(stroke
				(width 0.1524)
				(type default)
			)
			(layer "F.SilkS")
		)
		(fp_line
			(start -1.905 0.8636)
			(end -1.905 -0.8636)
			(stroke
				(width 0.1524)
				(type default)
			)
			(layer "F.SilkS")
		)
		(fp_line
			(start -1.905 -0.8636)
			(end 1.905 -0.8636)
			(stroke
				(width 0.1524)
				(type default)
			)
			(layer "F.SilkS")
		)
		(fp_rect
			(start -1.524 0.7366)
			(end 1.524 -0.7366)
			(stroke
				(width 0)
				(type default)
			)
			(fill no)
			(layer "F.CrtYd")
		)
		(pad "1" smd rect
			(at 0.94996 0 180)
			(size 1.1176 1.3716)
			(layers "F.Cu" "F.Mask" "F.Paste")
			(net "P1V0_NODE1")
		)
		(pad "2" smd rect
			(at -0.94996 0 180)
			(size 1.1176 1.3716)
			(layers "F.Cu" "F.Mask" "F.Paste")
			(net "GND")
		)
	)
	(footprint ""
		(layer "F.Cu")
		(at 139.36218 -75.393296 180)
		(property "Reference" "R507"
			(at -0.948182 2.060448 0)
			(unlocked yes)
			(layer "F.SilkS")
			(effects
				(font
					(size 0.7874 0.5842)
					(thickness 0.1524)
				)
				(justify left)
			)
		)
		(property "Value" ""
			(at 0 0 180)
			(layer "F.Fab")
			(effects
				(font
					(size 1.27 1.27)
				)
			)
		)
		(duplicate_pad_numbers_are_jumpers no)
		(fp_line
			(start 0.7874 0.4064)
			(end -0.7874 0.4064)
			(stroke
				(width 0.1524)
				(type default)
			)
			(layer "F.SilkS")
		)
		(fp_line
			(start 0.7874 -0.4064)
			(end 0.7874 0.4064)
			(stroke
				(width 0.1524)
				(type default)
			)
			(layer "F.SilkS")
		)
		(fp_line
			(start -0.7874 0.4064)
			(end -0.7874 -0.4064)
			(stroke
				(width 0.1524)
				(type default)
			)
			(layer "F.SilkS")
		)
		(fp_line
			(start -0.7874 -0.4064)
			(end 0.7874 -0.4064)
			(stroke
				(width 0.1524)
				(type default)
			)
			(layer "F.SilkS")
		)
		(fp_poly
			(pts
				(xy -0.508 0.2794) (xy -0.508 0.2286) (xy -0.635 0.2286) (xy -0.635 -0.254) (xy -0.5334 -0.254)
				(xy -0.5334 -0.2794) (xy 0.5334 -0.2794) (xy 0.5334 -0.254) (xy 0.635 -0.254) (xy 0.635 0.254) (xy 0.5334 0.254)
				(xy 0.5334 0.2794)
			)
			(stroke
				(width 0)
				(type default)
			)
			(fill no)
			(layer "F.CrtYd")
		)
		(pad "1" smd rect
			(at 0.40005 0 180)
			(size 0.4572 0.508)
			(layers "F.Cu" "F.Mask" "F.Paste")
			(net "SATA_SPI_CS_NODE1")
		)
		(pad "2" smd rect
			(at -0.40005 0 180)
			(size 0.4572 0.508)
			(layers "F.Cu" "F.Mask" "F.Paste")
			(net "SATA_SPI_CS_NODE1_R")
		)
	)
	(footprint ""
		(layer "F.Cu")
		(at 143.528796 -181.506622 -90)
		(property "Reference" "R807"
			(at 1.560322 -2.09169 90)
			(unlocked yes)
			(layer "F.SilkS")
			(effects
				(font
					(size 0.7874 0.5842)
					(thickness 0.1524)
				)
				(justify left)
			)
		)
		(property "Value" ""
			(at 0 0 270)
			(layer "F.Fab")
			(effects
				(font
					(size 1.27 1.27)
				)
			)
		)
		(duplicate_pad_numbers_are_jumpers no)
		(fp_line
			(start -0.7874 0.4064)
			(end -0.7874 -0.4064)
			(stroke
				(width 0.1524)
				(type default)
			)
			(layer "F.SilkS")
		)
		(fp_line
			(start 0.7874 0.4064)
			(end -0.7874 0.4064)
			(stroke
				(width 0.1524)
				(type default)
			)
			(layer "F.SilkS")
		)
		(fp_line
			(start -0.7874 -0.4064)
			(end 0.7874 -0.4064)
			(stroke
				(width 0.1524)
				(type default)
			)
			(layer "F.SilkS")
		)
		(fp_line
			(start 0.7874 -0.4064)
			(end 0.7874 0.4064)
			(stroke
				(width 0.1524)
				(type default)
			)
			(layer "F.SilkS")
		)
		(fp_poly
			(pts
				(xy -0.508 0.2794) (xy -0.508 0.2286) (xy -0.635 0.2286) (xy -0.635 -0.254) (xy -0.5334 -0.254)
				(xy -0.5334 -0.2794) (xy 0.5334 -0.2794) (xy 0.5334 -0.254) (xy 0.635 -0.254) (xy 0.635 0.254) (xy 0.5334 0.254)
				(xy 0.5334 0.2794)
			)
			(stroke
				(width 0)
				(type default)
			)
			(fill no)
			(layer "F.CrtYd")
		)
		(pad "1" smd rect
			(at 0.40005 0 270)
			(size 0.4572 0.508)
			(layers "F.Cu" "F.Mask" "F.Paste")
			(net "CPLD_UART_DTR_P3_N")
		)
		(pad "2" smd rect
			(at -0.40005 0 270)
			(size 0.4572 0.508)
			(layers "F.Cu" "F.Mask" "F.Paste")
			(net "GND")
		)
	)
	(footprint ""
		(layer "F.Cu")
		(at 29.561282 -147.961858 90)
		(property "Reference" "R565"
			(at -1.005332 1.764538 90)
			(unlocked yes)
			(layer "F.SilkS")
			(effects
				(font
					(size 0.7874 0.5842)
					(thickness 0.1524)
				)
				(justify left)
			)
		)
		(property "Value" ""
			(at 0 0 90)
			(layer "F.Fab")
			(effects
				(font
					(size 1.27 1.27)
				)
			)
		)
		(duplicate_pad_numbers_are_jumpers no)
		(fp_line
			(start 2.2098 -0.9398)
			(end 2.2098 0.9398)
			(stroke
				(width 0.1524)
				(type default)
			)
			(layer "F.SilkS")
		)
		(fp_line
			(start -2.2098 -0.9398)
			(end 2.2098 -0.9398)
			(stroke
				(width 0.1524)
				(type default)
			)
			(layer "F.SilkS")
		)
		(fp_line
			(start 2.2098 0.9398)
			(end -2.2098 0.9398)
			(stroke
				(width 0.1524)
				(type default)
			)
			(layer "F.SilkS")
		)
		(fp_line
			(start -2.2098 0.9398)
			(end -2.2098 -0.9398)
			(stroke
				(width 0.1524)
				(type default)
			)
			(layer "F.SilkS")
		)
		(fp_poly
			(pts
				(xy 2.0574 0.8382) (xy 2.0574 -0.8382) (xy 2.0574 -0.9398) (xy -2.0574 -0.9398) (xy -2.0574 -0.8382)
				(xy -2.0574 0.8382) (xy -2.0574 0.9398) (xy 2.0574 0.9398)
			)
			(stroke
				(width 0)
				(type default)
			)
			(fill no)
			(layer "F.CrtYd")
		)
		(pad "1" smd rect
			(at 1.4732 0 90)
			(size 1.1684 1.5748)
			(layers "F.Cu" "F.Mask" "F.Paste")
			(net "LAN1_CTRL_P1V9")
		)
		(pad "2" smd rect
			(at -1.4732 0 90)
			(size 1.1684 1.5748)
			(layers "F.Cu" "F.Mask" "F.Paste")
			(net "LAN1_CTRL_P1V9_R")
		)
	)
	(footprint ""
		(layer "F.Cu")
		(at 104.073452 -162.781488)
		(property "Reference" "R1003"
			(at 87.099648 71.74738 0)
			(unlocked yes)
			(layer "F.SilkS")
			(effects
				(font
					(size 0.7874 0.5842)
					(thickness 0.1524)
				)
				(justify left)
			)
		)
		(property "Value" ""
			(at 0 0 0)
			(layer "F.Fab")
			(effects
				(font
					(size 1.27 1.27)
				)
			)
		)
		(duplicate_pad_numbers_are_jumpers no)
		(fp_line
			(start -0.7874 -0.4064)
			(end 0.7874 -0.4064)
			(stroke
				(width 0.1524)
				(type default)
			)
			(layer "F.SilkS")
		)
		(fp_line
			(start -0.7874 0.4064)
			(end -0.7874 -0.4064)
			(stroke
				(width 0.1524)
				(type default)
			)
			(layer "F.SilkS")
		)
		(fp_line
			(start 0.7874 -0.4064)
			(end 0.7874 0.4064)
			(stroke
				(width 0.1524)
				(type default)
			)
			(layer "F.SilkS")
		)
		(fp_line
			(start 0.7874 0.4064)
			(end -0.7874 0.4064)
			(stroke
				(width 0.1524)
				(type default)
			)
			(layer "F.SilkS")
		)
		(fp_poly
			(pts
				(xy -0.508 0.2794) (xy -0.508 0.2286) (xy -0.635 0.2286) (xy -0.635 -0.254) (xy -0.5334 -0.254)
				(xy -0.5334 -0.2794) (xy 0.5334 -0.2794) (xy 0.5334 -0.254) (xy 0.635 -0.254) (xy 0.635 0.254) (xy 0.5334 0.254)
				(xy 0.5334 0.2794)
			)
			(stroke
				(width 0)
				(type default)
			)
			(fill no)
			(layer "F.CrtYd")
		)
		(pad "1" smd rect
			(at 0.40005 0)
			(size 0.4572 0.508)
			(layers "F.Cu" "F.Mask" "F.Paste")
			(net "GND")
		)
		(pad "2" smd rect
			(at -0.40005 0)
			(size 0.4572 0.508)
			(layers "F.Cu" "F.Mask" "F.Paste")
			(net "POWER_SW1_PWR_CTR_12V")
		)
	)
	(footprint ""
		(layer "F.Cu")
		(at 193.170556 -144.898872 180)
		(property "Reference" "C475"
			(at -3.82651 0.233172 0)
			(unlocked yes)
			(layer "F.SilkS")
			(effects
				(font
					(size 0.7874 0.5842)
					(thickness 0.1524)
				)
			)
		)
		(property "Value" ""
			(at 0 0 180)
			(layer "F.Fab")
			(effects
				(font
					(size 1.27 1.27)
				)
			)
		)
		(duplicate_pad_numbers_are_jumpers no)
		(fp_line
			(start 1.2954 0.5842)
			(end -1.2954 0.5842)
			(stroke
				(width 0.1524)
				(type default)
			)
			(layer "F.SilkS")
		)
		(fp_line
			(start 1.2954 -0.5842)
			(end 1.2954 0.5842)
			(stroke
				(width 0.1524)
				(type default)
			)
			(layer "F.SilkS")
		)
		(fp_line
			(start 0 -0.5842)
			(end 0 0.5842)
			(stroke
				(width 0.1524)
				(type default)
			)
			(layer "F.SilkS")
		)
		(fp_line
			(start -1.2954 0.5842)
			(end -1.2954 -0.5842)
			(stroke
				(width 0.1524)
				(type default)
			)
			(layer "F.SilkS")
		)
		(fp_line
			(start -1.2954 -0.5842)
			(end 1.2954 -0.5842)
			(stroke
				(width 0.1524)
				(type default)
			)
			(layer "F.SilkS")
		)
		(fp_poly
			(pts
				(xy 0.8636 -0.4572) (xy 0.8636 -0.3556) (xy 1.143 -0.3556) (xy 1.143 0.3556) (xy 0.8636 0.3556)
				(xy 0.8636 0.4572) (xy -0.8636 0.4572) (xy -0.8636 0.3556) (xy -1.143 0.3556) (xy -1.143 -0.3556)
				(xy -0.8636 -0.3556) (xy -0.8636 -0.4572)
			)
			(stroke
				(width 0)
				(type default)
			)
			(fill no)
			(layer "F.CrtYd")
		)
		(fp_line
			(start 0.884936 0.504952)
			(end -0.884936 0.504952)
			(stroke
				(width 0.1)
				(type default)
			)
			(layer "F.Fab")
		)
		(fp_line
			(start 0.884936 -0.504952)
			(end 0.884936 0.504952)
			(stroke
				(width 0.1)
				(type default)
			)
			(layer "F.Fab")
		)
		(fp_line
			(start -0.884936 0.504952)
			(end -0.884936 -0.504952)
			(stroke
				(width 0.1)
				(type default)
			)
			(layer "F.Fab")
		)
		(fp_line
			(start -0.884936 -0.504952)
			(end 0.884936 -0.504952)
			(stroke
				(width 0.1)
				(type default)
			)
			(layer "F.Fab")
		)
		(pad "1" smd rect
			(at 0.7366 0 270)
			(size 0.7112 0.8128)
			(layers "F.Cu" "F.Mask" "F.Paste")
			(net "P1V9_LAN2")
		)
		(pad "2" smd rect
			(at -0.7366 0 270)
			(size 0.7112 0.8128)
			(layers "F.Cu" "F.Mask" "F.Paste")
			(net "GND")
		)
	)
	(footprint ""
		(layer "F.Cu")
		(at 94.471236 -166.155878)
		(property "Reference" "C584"
			(at 86.63305 73.147936 0)
			(unlocked yes)
			(layer "F.SilkS")
			(effects
				(font
					(size 0.7874 0.5842)
					(thickness 0.1524)
				)
				(justify left)
			)
		)
		(property "Value" ""
			(at 0 0 0)
			(layer "F.Fab")
			(effects
				(font
					(size 1.27 1.27)
				)
			)
		)
		(duplicate_pad_numbers_are_jumpers no)
		(fp_line
			(start -0.7874 -0.4064)
			(end 0.7874 -0.4064)
			(stroke
				(width 0.1524)
				(type default)
			)
			(layer "F.SilkS")
		)
		(fp_line
			(start -0.7874 0.4064)
			(end -0.7874 -0.4064)
			(stroke
				(width 0.1524)
				(type default)
			)
			(layer "F.SilkS")
		)
		(fp_line
			(start 0 0.381)
			(end 0 -0.381)
			(stroke
				(width 0.1524)
				(type default)
			)
			(layer "F.SilkS")
		)
		(fp_line
			(start 0.7874 -0.4064)
			(end 0.7874 0.4064)
			(stroke
				(width 0.1524)
				(type default)
			)
			(layer "F.SilkS")
		)
		(fp_line
			(start 0.7874 0.4064)
			(end -0.7874 0.4064)
			(stroke
				(width 0.1524)
				(type default)
			)
			(layer "F.SilkS")
		)
		(fp_poly
			(pts
				(xy -0.5334 0.254) (xy -0.635 0.254) (xy -0.635 0.2286) (xy -0.635 -0.254) (xy -0.5334 -0.254) (xy -0.5334 -0.2794)
				(xy 0.5334 -0.2794) (xy 0.5334 -0.254) (xy 0.635 -0.254) (xy 0.635 0.254) (xy 0.5334 0.254) (xy 0.5334 0.2794)
				(xy -0.508 0.2794) (xy -0.5334 0.2794)
			)
			(stroke
				(width 0)
				(type default)
			)
			(fill no)
			(layer "F.CrtYd")
		)
		(pad "1" smd rect
			(at 0.40005 0)
			(size 0.4572 0.508)
			(layers "F.Cu" "F.Mask" "F.Paste")
			(net "P3V3_NODE1")
		)
		(pad "2" smd rect
			(at -0.40005 0)
			(size 0.4572 0.508)
			(layers "F.Cu" "F.Mask" "F.Paste")
			(net "GND")
		)
	)
	(footprint ""
		(layer "F.Cu")
		(at 18.746724 -142.448534)
		(property "Reference" "C414"
			(at -5.348224 -0.447294 0)
			(unlocked yes)
			(layer "F.SilkS")
			(effects
				(font
					(size 0.7874 0.5842)
					(thickness 0.1524)
				)
				(justify left)
			)
		)
		(property "Value" ""
			(at 0 0 0)
			(layer "F.Fab")
			(effects
				(font
					(size 1.27 1.27)
				)
			)
		)
		(duplicate_pad_numbers_are_jumpers no)
		(fp_line
			(start -1.905 -0.8636)
			(end 1.905 -0.8636)
			(stroke
				(width 0.1524)
				(type default)
			)
			(layer "F.SilkS")
		)
		(fp_line
			(start -1.905 0.8636)
			(end -1.905 -0.8636)
			(stroke
				(width 0.1524)
				(type default)
			)
			(layer "F.SilkS")
		)
		(fp_line
			(start 0 0.8382)
			(end 0 -0.8382)
			(stroke
				(width 0.1524)
				(type default)
			)
			(layer "F.SilkS")
		)
		(fp_line
			(start 1.905 -0.8636)
			(end 1.905 0.8636)
			(stroke
				(width 0.1524)
				(type default)
			)
			(layer "F.SilkS")
		)
		(fp_line
			(start 1.905 0.8636)
			(end -1.905 0.8636)
			(stroke
				(width 0.1524)
				(type default)
			)
			(layer "F.SilkS")
		)
		(fp_rect
			(start -1.524 0.7366)
			(end 1.524 -0.7366)
			(stroke
				(width 0)
				(type default)
			)
			(fill no)
			(layer "F.CrtYd")
		)
		(pad "1" smd rect
			(at 0.94996 0)
			(size 1.1176 1.3716)
			(layers "F.Cu" "F.Mask" "F.Paste")
			(net "P3V3_NODE1")
		)
		(pad "2" smd rect
			(at -0.94996 0)
			(size 1.1176 1.3716)
			(layers "F.Cu" "F.Mask" "F.Paste")
			(net "GND")
		)
	)
	(footprint ""
		(layer "F.Cu")
		(at 84.416392 -78.569058 90)
		(property "Reference" "R1049"
			(at -4.007358 1.394714 90)
			(unlocked yes)
			(layer "F.SilkS")
			(effects
				(font
					(size 0.7874 0.5842)
					(thickness 0.1524)
				)
				(justify left)
			)
		)
		(property "Value" ""
			(at 0 0 90)
			(layer "F.Fab")
			(effects
				(font
					(size 1.27 1.27)
				)
			)
		)
		(duplicate_pad_numbers_are_jumpers no)
		(fp_line
			(start 0.7874 -0.4064)
			(end 0.7874 0.4064)
			(stroke
				(width 0.1524)
				(type default)
			)
			(layer "F.SilkS")
		)
		(fp_line
			(start -0.7874 -0.4064)
			(end 0.7874 -0.4064)
			(stroke
				(width 0.1524)
				(type default)
			)
			(layer "F.SilkS")
		)
		(fp_line
			(start 0.7874 0.4064)
			(end -0.7874 0.4064)
			(stroke
				(width 0.1524)
				(type default)
			)
			(layer "F.SilkS")
		)
		(fp_line
			(start -0.7874 0.4064)
			(end -0.7874 -0.4064)
			(stroke
				(width 0.1524)
				(type default)
			)
			(layer "F.SilkS")
		)
		(fp_poly
			(pts
				(xy -0.508 0.2794) (xy -0.508 0.2286) (xy -0.635 0.2286) (xy -0.635 -0.254) (xy -0.5334 -0.254)
				(xy -0.5334 -0.2794) (xy 0.5334 -0.2794) (xy 0.5334 -0.254) (xy 0.635 -0.254) (xy 0.635 0.254) (xy 0.5334 0.254)
				(xy 0.5334 0.2794)
			)
			(stroke
				(width 0)
				(type default)
			)
			(fill no)
			(layer "F.CrtYd")
		)
		(pad "1" smd rect
			(at 0.40005 0 90)
			(size 0.4572 0.508)
			(layers "F.Cu" "F.Mask" "F.Paste")
			(net "FM_CPU_NODE1_JTAG_POK")
		)
		(pad "2" smd rect
			(at -0.40005 0 90)
			(size 0.4572 0.508)
			(layers "F.Cu" "F.Mask" "F.Paste")
			(net "P1V05_NODE1")
		)
	)
	(footprint ""
		(layer "F.Cu")
		(at 32.014668 -171.671234)
		(property "Reference" "C794"
			(at -3.56616 7.439406 0)
			(unlocked yes)
			(layer "F.SilkS")
			(effects
				(font
					(size 0.7874 0.5842)
					(thickness 0.1524)
				)
				(justify left)
			)
		)
		(property "Value" ""
			(at 0 0 0)
			(layer "F.Fab")
			(effects
				(font
					(size 1.27 1.27)
				)
			)
		)
		(duplicate_pad_numbers_are_jumpers no)
		(fp_line
			(start -0.7874 -0.4064)
			(end 0.7874 -0.4064)
			(stroke
				(width 0.1524)
				(type default)
			)
			(layer "F.SilkS")
		)
		(fp_line
			(start -0.7874 0.4064)
			(end -0.7874 -0.4064)
			(stroke
				(width 0.1524)
				(type default)
			)
			(layer "F.SilkS")
		)
		(fp_line
			(start 0 0.381)
			(end 0 -0.381)
			(stroke
				(width 0.1524)
				(type default)
			)
			(layer "F.SilkS")
		)
		(fp_line
			(start 0.7874 -0.4064)
			(end 0.7874 0.4064)
			(stroke
				(width 0.1524)
				(type default)
			)
			(layer "F.SilkS")
		)
		(fp_line
			(start 0.7874 0.4064)
			(end -0.7874 0.4064)
			(stroke
				(width 0.1524)
				(type default)
			)
			(layer "F.SilkS")
		)
		(fp_poly
			(pts
				(xy -0.5334 0.254) (xy -0.635 0.254) (xy -0.635 0.2286) (xy -0.635 -0.254) (xy -0.5334 -0.254) (xy -0.5334 -0.2794)
				(xy 0.5334 -0.2794) (xy 0.5334 -0.254) (xy 0.635 -0.254) (xy 0.635 0.254) (xy 0.5334 0.254) (xy 0.5334 0.2794)
				(xy -0.508 0.2794) (xy -0.5334 0.2794)
			)
			(stroke
				(width 0)
				(type default)
			)
			(fill no)
			(layer "F.CrtYd")
		)
		(pad "1" smd rect
			(at 0.40005 0)
			(size 0.4572 0.508)
			(layers "F.Cu" "F.Mask" "F.Paste")
			(net "CM_PWR_CTL_IN_R")
		)
		(pad "2" smd rect
			(at -0.40005 0)
			(size 0.4572 0.508)
			(layers "F.Cu" "F.Mask" "F.Paste")
			(net "GND")
		)
	)
	(footprint ""
		(layer "F.Cu")
		(at 136.450324 -158.553658)
		(property "Reference" "R647"
			(at -64.67602 108.381038 0)
			(unlocked yes)
			(layer "F.SilkS")
			(effects
				(font
					(size 0.7874 0.5842)
					(thickness 0.1524)
				)
				(justify left)
			)
		)
		(property "Value" ""
			(at 0 0 0)
			(layer "F.Fab")
			(effects
				(font
					(size 1.27 1.27)
				)
			)
		)
		(duplicate_pad_numbers_are_jumpers no)
		(fp_line
			(start -0.7874 -0.4064)
			(end 0.7874 -0.4064)
			(stroke
				(width 0.1524)
				(type default)
			)
			(layer "F.SilkS")
		)
		(fp_line
			(start -0.7874 0.4064)
			(end -0.7874 -0.4064)
			(stroke
				(width 0.1524)
				(type default)
			)
			(layer "F.SilkS")
		)
		(fp_line
			(start 0.7874 -0.4064)
			(end 0.7874 0.4064)
			(stroke
				(width 0.1524)
				(type default)
			)
			(layer "F.SilkS")
		)
		(fp_line
			(start 0.7874 0.4064)
			(end -0.7874 0.4064)
			(stroke
				(width 0.1524)
				(type default)
			)
			(layer "F.SilkS")
		)
		(fp_poly
			(pts
				(xy -0.508 0.2794) (xy -0.508 0.2286) (xy -0.635 0.2286) (xy -0.635 -0.254) (xy -0.5334 -0.254)
				(xy -0.5334 -0.2794) (xy 0.5334 -0.2794) (xy 0.5334 -0.254) (xy 0.635 -0.254) (xy 0.635 0.254) (xy 0.5334 0.254)
				(xy 0.5334 0.2794)
			)
			(stroke
				(width 0)
				(type default)
			)
			(fill no)
			(layer "F.CrtYd")
		)
		(pad "1" smd rect
			(at 0.40005 0)
			(size 0.4572 0.508)
			(layers "F.Cu" "F.Mask" "F.Paste")
			(net "I2C_PSU3_SDA")
		)
		(pad "2" smd rect
			(at -0.40005 0)
			(size 0.4572 0.508)
			(layers "F.Cu" "F.Mask" "F.Paste")
			(net "I2C_PSU3_SDA_MOS")
		)
	)
	(footprint ""
		(layer "F.Cu")
		(at 112.717072 -132.012944 90)
		(property "Reference" "PR55"
			(at -0.690372 5.279136 90)
			(unlocked yes)
			(layer "F.SilkS")
			(effects
				(font
					(size 0.7874 0.5842)
					(thickness 0.1524)
				)
				(justify left)
			)
		)
		(property "Value" ""
			(at 0 0 90)
			(layer "F.Fab")
			(effects
				(font
					(size 1.27 1.27)
				)
			)
		)
		(duplicate_pad_numbers_are_jumpers no)
		(fp_line
			(start 0.7874 -0.4064)
			(end 0.7874 0.4064)
			(stroke
				(width 0.1524)
				(type default)
			)
			(layer "F.SilkS")
		)
		(fp_line
			(start -0.7874 -0.4064)
			(end 0.7874 -0.4064)
			(stroke
				(width 0.1524)
				(type default)
			)
			(layer "F.SilkS")
		)
		(fp_line
			(start 0.7874 0.4064)
			(end -0.7874 0.4064)
			(stroke
				(width 0.1524)
				(type default)
			)
			(layer "F.SilkS")
		)
		(fp_line
			(start -0.7874 0.4064)
			(end -0.7874 -0.4064)
			(stroke
				(width 0.1524)
				(type default)
			)
			(layer "F.SilkS")
		)
		(fp_poly
			(pts
				(xy -0.508 0.2794) (xy -0.508 0.2286) (xy -0.635 0.2286) (xy -0.635 -0.254) (xy -0.5334 -0.254)
				(xy -0.5334 -0.2794) (xy 0.5334 -0.2794) (xy 0.5334 -0.254) (xy 0.635 -0.254) (xy 0.635 0.254) (xy 0.5334 0.254)
				(xy 0.5334 0.2794)
			)
			(stroke
				(width 0)
				(type default)
			)
			(fill no)
			(layer "F.CrtYd")
		)
		(pad "1" smd rect
			(at 0.40005 0 90)
			(size 0.4572 0.508)
			(layers "F.Cu" "F.Mask" "F.Paste")
			(net "VR_PVCCP_NODE1_ISEN1P_CC")
		)
		(pad "2" smd rect
			(at -0.40005 0 90)
			(size 0.4572 0.508)
			(layers "F.Cu" "F.Mask" "F.Paste")
			(net "ISENSE_PVCCP_NODE1_ISEN1P")
		)
	)
	(footprint ""
		(layer "F.Cu")
		(at 108.82376 -166.790624)
		(property "Reference" "U68"
			(at 87.40648 71.02729 0)
			(unlocked yes)
			(layer "F.SilkS")
			(effects
				(font
					(size 0.7874 0.5842)
					(thickness 0.1524)
				)
			)
		)
		(property "Value" ""
			(at 0 0 0)
			(layer "F.Fab")
			(effects
				(font
					(size 1.27 1.27)
				)
			)
		)
		(duplicate_pad_numbers_are_jumpers no)
		(fp_line
			(start -1.651 -2.0574)
			(end 1.651 -2.0574)
			(stroke
				(width 0.1524)
				(type default)
			)
			(layer "F.SilkS")
		)
		(fp_line
			(start -1.651 -0.381)
			(end -1.651 -2.0574)
			(stroke
				(width 0.1524)
				(type default)
			)
			(layer "F.SilkS")
		)
		(fp_line
			(start -1.651 0.381)
			(end -1.016 0)
			(stroke
				(width 0.1524)
				(type default)
			)
			(layer "F.SilkS")
		)
		(fp_line
			(start -1.651 2.0574)
			(end -1.651 0.381)
			(stroke
				(width 0.1524)
				(type default)
			)
			(layer "F.SilkS")
		)
		(fp_line
			(start -1.016 0)
			(end -1.651 -0.381)
			(stroke
				(width 0.1524)
				(type default)
			)
			(layer "F.SilkS")
		)
		(fp_line
			(start 1.651 -2.0574)
			(end 1.651 2.0574)
			(stroke
				(width 0.1524)
				(type default)
			)
			(layer "F.SilkS")
		)
		(fp_line
			(start 1.651 2.0574)
			(end -1.651 2.0574)
			(stroke
				(width 0.1524)
				(type default)
			)
			(layer "F.SilkS")
		)
		(fp_rect
			(start -1.524 1.905)
			(end 1.524 -1.905)
			(stroke
				(width 0)
				(type default)
			)
			(fill no)
			(layer "F.CrtYd")
		)
		(pad "1" smd rect
			(at -0.94996 1.225042)
			(size 0.5588 1.3462)
			(layers "F.Cu" "F.Mask" "F.Paste")
			(net "FNACTRL1_TMP_IN")
		)
		(pad "2" smd rect
			(at 0 1.225042)
			(size 0.5588 1.3462)
			(layers "F.Cu" "F.Mask" "F.Paste")
			(net "CPLD_FAN_MAX_CTRL")
		)
		(pad "3" smd rect
			(at 0.94996 1.225042)
			(size 0.5588 1.3462)
			(layers "F.Cu" "F.Mask" "F.Paste")
			(net "TMP05_FUNC1")
		)
		(pad "4" smd rect
			(at 0.94996 -1.225042)
			(size 0.5588 1.3462)
			(layers "F.Cu" "F.Mask" "F.Paste")
			(net "GND")
		)
		(pad "5" smd rect
			(at -0.94996 -1.225042)
			(size 0.5588 1.3462)
			(layers "F.Cu" "F.Mask" "F.Paste")
			(net "P3V3_NODE1")
		)
	)
	(footprint ""
		(layer "F.Cu")
		(at 61.96076 -188.126624 -90)
		(property "Reference" "R937"
			(at -4.548886 -0.107442 90)
			(unlocked yes)
			(layer "F.SilkS")
			(effects
				(font
					(size 0.7874 0.5842)
					(thickness 0.1524)
				)
				(justify left)
			)
		)
		(property "Value" ""
			(at 0 0 270)
			(layer "F.Fab")
			(effects
				(font
					(size 1.27 1.27)
				)
			)
		)
		(duplicate_pad_numbers_are_jumpers no)
		(fp_line
			(start -0.7874 0.4064)
			(end -0.7874 -0.4064)
			(stroke
				(width 0.1524)
				(type default)
			)
			(layer "F.SilkS")
		)
		(fp_line
			(start 0.7874 0.4064)
			(end -0.7874 0.4064)
			(stroke
				(width 0.1524)
				(type default)
			)
			(layer "F.SilkS")
		)
		(fp_line
			(start -0.7874 -0.4064)
			(end 0.7874 -0.4064)
			(stroke
				(width 0.1524)
				(type default)
			)
			(layer "F.SilkS")
		)
		(fp_line
			(start 0.7874 -0.4064)
			(end 0.7874 0.4064)
			(stroke
				(width 0.1524)
				(type default)
			)
			(layer "F.SilkS")
		)
		(fp_poly
			(pts
				(xy -0.508 0.2794) (xy -0.508 0.2286) (xy -0.635 0.2286) (xy -0.635 -0.254) (xy -0.5334 -0.254)
				(xy -0.5334 -0.2794) (xy 0.5334 -0.2794) (xy 0.5334 -0.254) (xy 0.635 -0.254) (xy 0.635 0.254) (xy 0.5334 0.254)
				(xy 0.5334 0.2794)
			)
			(stroke
				(width 0)
				(type default)
			)
			(fill no)
			(layer "F.CrtYd")
		)
		(pad "1" smd rect
			(at 0.40005 0 270)
			(size 0.4572 0.508)
			(layers "F.Cu" "F.Mask" "F.Paste")
			(net "UART_T2_NODE2_RXD")
		)
		(pad "2" smd rect
			(at -0.40005 0 270)
			(size 0.4572 0.508)
			(layers "F.Cu" "F.Mask" "F.Paste")
			(net "UART_T2_NODE2_RXD_R")
		)
	)
	(footprint ""
		(layer "F.Cu")
		(at 18.746724 -144.480534)
		(property "Reference" "C415"
			(at -5.513324 0.022606 0)
			(unlocked yes)
			(layer "F.SilkS")
			(effects
				(font
					(size 0.7874 0.5842)
					(thickness 0.1524)
				)
				(justify left)
			)
		)
		(property "Value" ""
			(at 0 0 0)
			(layer "F.Fab")
			(effects
				(font
					(size 1.27 1.27)
				)
			)
		)
		(duplicate_pad_numbers_are_jumpers no)
		(fp_line
			(start -1.905 -0.8636)
			(end 1.905 -0.8636)
			(stroke
				(width 0.1524)
				(type default)
			)
			(layer "F.SilkS")
		)
		(fp_line
			(start -1.905 0.8636)
			(end -1.905 -0.8636)
			(stroke
				(width 0.1524)
				(type default)
			)
			(layer "F.SilkS")
		)
		(fp_line
			(start 0 0.8382)
			(end 0 -0.8382)
			(stroke
				(width 0.1524)
				(type default)
			)
			(layer "F.SilkS")
		)
		(fp_line
			(start 1.905 -0.8636)
			(end 1.905 0.8636)
			(stroke
				(width 0.1524)
				(type default)
			)
			(layer "F.SilkS")
		)
		(fp_line
			(start 1.905 0.8636)
			(end -1.905 0.8636)
			(stroke
				(width 0.1524)
				(type default)
			)
			(layer "F.SilkS")
		)
		(fp_rect
			(start -1.524 0.7366)
			(end 1.524 -0.7366)
			(stroke
				(width 0)
				(type default)
			)
			(fill no)
			(layer "F.CrtYd")
		)
		(pad "1" smd rect
			(at 0.94996 0)
			(size 1.1176 1.3716)
			(layers "F.Cu" "F.Mask" "F.Paste")
			(net "P3V3_NODE1")
		)
		(pad "2" smd rect
			(at -0.94996 0)
			(size 1.1176 1.3716)
			(layers "F.Cu" "F.Mask" "F.Paste")
			(net "GND")
		)
	)
	(footprint ""
		(layer "F.Cu")
		(at 153.90876 -185.205624 -90)
		(property "Reference" "R900"
			(at -4.768088 -0.259588 90)
			(unlocked yes)
			(layer "F.SilkS")
			(effects
				(font
					(size 0.7874 0.5842)
					(thickness 0.1524)
				)
				(justify left)
			)
		)
		(property "Value" ""
			(at 0 0 270)
			(layer "F.Fab")
			(effects
				(font
					(size 1.27 1.27)
				)
			)
		)
		(duplicate_pad_numbers_are_jumpers no)
		(fp_line
			(start -0.7874 0.4064)
			(end -0.7874 -0.4064)
			(stroke
				(width 0.1524)
				(type default)
			)
			(layer "F.SilkS")
		)
		(fp_line
			(start 0.7874 0.4064)
			(end -0.7874 0.4064)
			(stroke
				(width 0.1524)
				(type default)
			)
			(layer "F.SilkS")
		)
		(fp_line
			(start -0.7874 -0.4064)
			(end 0.7874 -0.4064)
			(stroke
				(width 0.1524)
				(type default)
			)
			(layer "F.SilkS")
		)
		(fp_line
			(start 0.7874 -0.4064)
			(end 0.7874 0.4064)
			(stroke
				(width 0.1524)
				(type default)
			)
			(layer "F.SilkS")
		)
		(fp_poly
			(pts
				(xy -0.508 0.2794) (xy -0.508 0.2286) (xy -0.635 0.2286) (xy -0.635 -0.254) (xy -0.5334 -0.254)
				(xy -0.5334 -0.2794) (xy 0.5334 -0.2794) (xy 0.5334 -0.254) (xy 0.635 -0.254) (xy 0.635 0.254) (xy 0.5334 0.254)
				(xy 0.5334 0.2794)
			)
			(stroke
				(width 0)
				(type default)
			)
			(fill no)
			(layer "F.CrtYd")
		)
		(pad "1" smd rect
			(at 0.40005 0 270)
			(size 0.4572 0.508)
			(layers "F.Cu" "F.Mask" "F.Paste")
			(net "T12_NODE2_EN")
		)
		(pad "2" smd rect
			(at -0.40005 0 270)
			(size 0.4572 0.508)
			(layers "F.Cu" "F.Mask" "F.Paste")
			(net "T12_NODE2_EN_R")
		)
	)
	(footprint ""
		(layer "F.Cu")
		(at 117.68836 -170.346624 -90)
		(property "Reference" "U60"
			(at 52.482496 -32.0294 0)
			(unlocked yes)
			(layer "F.SilkS")
			(effects
				(font
					(size 0.7874 0.5842)
					(thickness 0.1524)
				)
				(justify left)
			)
		)
		(property "Value" ""
			(at 0 0 270)
			(layer "F.Fab")
			(effects
				(font
					(size 1.27 1.27)
				)
			)
		)
		(duplicate_pad_numbers_are_jumpers no)
		(fp_line
			(start -2.5654 2.0066)
			(end -2.5654 0.5842)
			(stroke
				(width 0.1524)
				(type default)
			)
			(layer "F.SilkS")
		)
		(fp_line
			(start 2.5654 2.0066)
			(end -2.5654 2.0066)
			(stroke
				(width 0.1524)
				(type default)
			)
			(layer "F.SilkS")
		)
		(fp_line
			(start -2.5654 0.5842)
			(end -1.9812 0)
			(stroke
				(width 0.1524)
				(type default)
			)
			(layer "F.SilkS")
		)
		(fp_line
			(start -1.9812 0)
			(end -2.5654 -0.5842)
			(stroke
				(width 0.1524)
				(type default)
			)
			(layer "F.SilkS")
		)
		(fp_line
			(start -2.5654 -0.5842)
			(end -2.5654 -2.0066)
			(stroke
				(width 0.1524)
				(type default)
			)
			(layer "F.SilkS")
		)
		(fp_line
			(start -2.5654 -2.0066)
			(end 2.5654 -2.0066)
			(stroke
				(width 0.1524)
				(type default)
			)
			(layer "F.SilkS")
		)
		(fp_line
			(start 2.5654 -2.0066)
			(end 2.5654 2.0066)
			(stroke
				(width 0.1524)
				(type default)
			)
			(layer "F.SilkS")
		)
		(fp_circle
			(center -2.032 1.524)
			(end -2.032 1.27)
			(stroke
				(width 0.1524)
				(type default)
			)
			(fill no)
			(layer "F.SilkS")
		)
		(fp_rect
			(start -2.5654 3.6703)
			(end 2.5654 -3.6703)
			(stroke
				(width 0)
				(type default)
			)
			(fill no)
			(layer "F.CrtYd")
		)
		(pad "1" smd rect
			(at -2.275078 2.921 270)
			(size 0.3556 1.4986)
			(layers "F.Cu" "F.Mask" "F.Paste")
			(net "I2C_COM3_SCL")
		)
		(pad "2" smd rect
			(at -1.625092 2.921 270)
			(size 0.3556 1.4986)
			(layers "F.Cu" "F.Mask" "F.Paste")
			(net "I2C_COM3_SDA")
		)
		(pad "3" smd rect
			(at -0.975106 2.921 270)
			(size 0.3556 1.4986)
			(layers "F.Cu" "F.Mask" "F.Paste")
			(net "I2C_PSU1_SCL_MOS")
		)
		(pad "4" smd rect
			(at -0.32512 2.921 270)
			(size 0.3556 1.4986)
			(layers "F.Cu" "F.Mask" "F.Paste")
			(net "I2C_PSU1_SDA_MOS")
		)
		(pad "5" smd rect
			(at 0.32512 2.921 270)
			(size 0.3556 1.4986)
			(layers "F.Cu" "F.Mask" "F.Paste")
			(net "PSU1_HUB_EN")
		)
		(pad "6" smd rect
			(at 0.975106 2.921 270)
			(size 0.3556 1.4986)
			(layers "F.Cu" "F.Mask" "F.Paste")
			(net "I2C_PSU2_SCL_MOS")
		)
		(pad "7" smd rect
			(at 1.625092 2.921 270)
			(size 0.3556 1.4986)
			(layers "F.Cu" "F.Mask" "F.Paste")
			(net "I2C_PSU2_SDA_MOS")
		)
		(pad "8" smd rect
			(at 2.275078 2.921 270)
			(size 0.3556 1.4986)
			(layers "F.Cu" "F.Mask" "F.Paste")
			(net "GND")
		)
		(pad "9" smd rect
			(at 2.275078 -2.921 270)
			(size 0.3556 1.4986)
			(layers "F.Cu" "F.Mask" "F.Paste")
			(net "PSU2_HUB_EN")
		)
		(pad "10" smd rect
			(at 1.625092 -2.921 270)
			(size 0.3556 1.4986)
			(layers "F.Cu" "F.Mask" "F.Paste")
			(net "I2C_PSU3_SCL_MOS")
		)
		(pad "11" smd rect
			(at 0.975106 -2.921 270)
			(size 0.3556 1.4986)
			(layers "F.Cu" "F.Mask" "F.Paste")
			(net "I2C_PSU3_SDA_MOS")
		)
		(pad "12" smd rect
			(at 0.32512 -2.921 270)
			(size 0.3556 1.4986)
			(layers "F.Cu" "F.Mask" "F.Paste")
			(net "PSU3_HUB_EN")
		)
		(pad "13" smd rect
			(at -0.32512 -2.921 270)
			(size 0.3556 1.4986)
			(layers "F.Cu" "F.Mask" "F.Paste")
			(net "PU_I2C_SCL4")
		)
		(pad "14" smd rect
			(at -0.975106 -2.921 270)
			(size 0.3556 1.4986)
			(layers "F.Cu" "F.Mask" "F.Paste")
			(net "PU_I2C_SDA4")
		)
		(pad "15" smd rect
			(at -1.625092 -2.921 270)
			(size 0.3556 1.4986)
			(layers "F.Cu" "F.Mask" "F.Paste")
			(net "N21699069")
		)
		(pad "16" smd rect
			(at -2.275078 -2.921 270)
			(size 0.3556 1.4986)
			(layers "F.Cu" "F.Mask" "F.Paste")
			(net "P3V3_NODE1")
		)
	)
	(footprint ""
		(layer "F.Cu")
		(at 79.10576 -185.205624 -90)
		(property "Reference" "R904"
			(at -4.198112 1.795272 90)
			(unlocked yes)
			(layer "F.SilkS")
			(effects
				(font
					(size 0.7874 0.5842)
					(thickness 0.1524)
				)
				(justify left)
			)
		)
		(property "Value" ""
			(at 0 0 270)
			(layer "F.Fab")
			(effects
				(font
					(size 1.27 1.27)
				)
			)
		)
		(duplicate_pad_numbers_are_jumpers no)
		(fp_line
			(start -0.7874 0.4064)
			(end -0.7874 -0.4064)
			(stroke
				(width 0.1524)
				(type default)
			)
			(layer "F.SilkS")
		)
		(fp_line
			(start 0.7874 0.4064)
			(end -0.7874 0.4064)
			(stroke
				(width 0.1524)
				(type default)
			)
			(layer "F.SilkS")
		)
		(fp_line
			(start -0.7874 -0.4064)
			(end 0.7874 -0.4064)
			(stroke
				(width 0.1524)
				(type default)
			)
			(layer "F.SilkS")
		)
		(fp_line
			(start 0.7874 -0.4064)
			(end 0.7874 0.4064)
			(stroke
				(width 0.1524)
				(type default)
			)
			(layer "F.SilkS")
		)
		(fp_poly
			(pts
				(xy -0.508 0.2794) (xy -0.508 0.2286) (xy -0.635 0.2286) (xy -0.635 -0.254) (xy -0.5334 -0.254)
				(xy -0.5334 -0.2794) (xy 0.5334 -0.2794) (xy 0.5334 -0.254) (xy 0.635 -0.254) (xy 0.635 0.254) (xy 0.5334 0.254)
				(xy 0.5334 0.2794)
			)
			(stroke
				(width 0)
				(type default)
			)
			(fill no)
			(layer "F.CrtYd")
		)
		(pad "1" smd rect
			(at 0.40005 0 270)
			(size 0.4572 0.508)
			(layers "F.Cu" "F.Mask" "F.Paste")
			(net "T4_NODE4_EN")
		)
		(pad "2" smd rect
			(at -0.40005 0 270)
			(size 0.4572 0.508)
			(layers "F.Cu" "F.Mask" "F.Paste")
			(net "T4_NODE4_EN_R")
		)
	)
	(footprint ""
		(layer "F.Cu")
		(at 138.79576 -185.205624 -90)
		(property "Reference" "R879"
			(at -4.768088 0.474472 90)
			(unlocked yes)
			(layer "F.SilkS")
			(effects
				(font
					(size 0.7874 0.5842)
					(thickness 0.1524)
				)
				(justify left)
			)
		)
		(property "Value" ""
			(at 0 0 270)
			(layer "F.Fab")
			(effects
				(font
					(size 1.27 1.27)
				)
			)
		)
		(duplicate_pad_numbers_are_jumpers no)
		(fp_line
			(start -0.7874 0.4064)
			(end -0.7874 -0.4064)
			(stroke
				(width 0.1524)
				(type default)
			)
			(layer "F.SilkS")
		)
		(fp_line
			(start 0.7874 0.4064)
			(end -0.7874 0.4064)
			(stroke
				(width 0.1524)
				(type default)
			)
			(layer "F.SilkS")
		)
		(fp_line
			(start -0.7874 -0.4064)
			(end 0.7874 -0.4064)
			(stroke
				(width 0.1524)
				(type default)
			)
			(layer "F.SilkS")
		)
		(fp_line
			(start 0.7874 -0.4064)
			(end 0.7874 0.4064)
			(stroke
				(width 0.1524)
				(type default)
			)
			(layer "F.SilkS")
		)
		(fp_poly
			(pts
				(xy -0.508 0.2794) (xy -0.508 0.2286) (xy -0.635 0.2286) (xy -0.635 -0.254) (xy -0.5334 -0.254)
				(xy -0.5334 -0.2794) (xy 0.5334 -0.2794) (xy 0.5334 -0.254) (xy 0.635 -0.254) (xy 0.635 0.254) (xy 0.5334 0.254)
				(xy 0.5334 0.2794)
			)
			(stroke
				(width 0)
				(type default)
			)
			(fill no)
			(layer "F.CrtYd")
		)
		(pad "1" smd rect
			(at 0.40005 0 270)
			(size 0.4572 0.508)
			(layers "F.Cu" "F.Mask" "F.Paste")
			(net "T10_NODE3_EN")
		)
		(pad "2" smd rect
			(at -0.40005 0 270)
			(size 0.4572 0.508)
			(layers "F.Cu" "F.Mask" "F.Paste")
			(net "T10_NODE3_EN_R")
		)
	)
	(footprint ""
		(layer "F.Cu")
		(at 156.19476 -185.205624 -90)
		(property "Reference" "R825"
			(at -4.768088 -0.297942 90)
			(unlocked yes)
			(layer "F.SilkS")
			(effects
				(font
					(size 0.7874 0.5842)
					(thickness 0.1524)
				)
				(justify left)
			)
		)
		(property "Value" ""
			(at 0 0 270)
			(layer "F.Fab")
			(effects
				(font
					(size 1.27 1.27)
				)
			)
		)
		(duplicate_pad_numbers_are_jumpers no)
		(fp_line
			(start -0.7874 0.4064)
			(end -0.7874 -0.4064)
			(stroke
				(width 0.1524)
				(type default)
			)
			(layer "F.SilkS")
		)
		(fp_line
			(start 0.7874 0.4064)
			(end -0.7874 0.4064)
			(stroke
				(width 0.1524)
				(type default)
			)
			(layer "F.SilkS")
		)
		(fp_line
			(start -0.7874 -0.4064)
			(end 0.7874 -0.4064)
			(stroke
				(width 0.1524)
				(type default)
			)
			(layer "F.SilkS")
		)
		(fp_line
			(start 0.7874 -0.4064)
			(end 0.7874 0.4064)
			(stroke
				(width 0.1524)
				(type default)
			)
			(layer "F.SilkS")
		)
		(fp_poly
			(pts
				(xy -0.508 0.2794) (xy -0.508 0.2286) (xy -0.635 0.2286) (xy -0.635 -0.254) (xy -0.5334 -0.254)
				(xy -0.5334 -0.2794) (xy 0.5334 -0.2794) (xy 0.5334 -0.254) (xy 0.635 -0.254) (xy 0.635 0.254) (xy 0.5334 0.254)
				(xy 0.5334 0.2794)
			)
			(stroke
				(width 0)
				(type default)
			)
			(fill no)
			(layer "F.CrtYd")
		)
		(pad "1" smd rect
			(at 0.40005 0 270)
			(size 0.4572 0.508)
			(layers "F.Cu" "F.Mask" "F.Paste")
			(net "FAN3_TACH")
		)
		(pad "2" smd rect
			(at -0.40005 0 270)
			(size 0.4572 0.508)
			(layers "F.Cu" "F.Mask" "F.Paste")
			(net "FAN3_TACH_R")
		)
	)
	(footprint ""
		(layer "F.Cu")
		(at 98.297746 -15.941294 90)
		(property "Reference" "R190"
			(at 0.688848 -0.963168 90)
			(unlocked yes)
			(layer "F.SilkS")
			(effects
				(font
					(size 0.7874 0.5842)
					(thickness 0.1524)
				)
				(justify left)
			)
		)
		(property "Value" ""
			(at 0 0 90)
			(layer "F.Fab")
			(effects
				(font
					(size 1.27 1.27)
				)
			)
		)
		(duplicate_pad_numbers_are_jumpers no)
		(fp_line
			(start 0.7874 -0.4064)
			(end 0.7874 0.4064)
			(stroke
				(width 0.1524)
				(type default)
			)
			(layer "F.SilkS")
		)
		(fp_line
			(start -0.7874 -0.4064)
			(end 0.7874 -0.4064)
			(stroke
				(width 0.1524)
				(type default)
			)
			(layer "F.SilkS")
		)
		(fp_line
			(start 0.7874 0.4064)
			(end -0.7874 0.4064)
			(stroke
				(width 0.1524)
				(type default)
			)
			(layer "F.SilkS")
		)
		(fp_line
			(start -0.7874 0.4064)
			(end -0.7874 -0.4064)
			(stroke
				(width 0.1524)
				(type default)
			)
			(layer "F.SilkS")
		)
		(fp_poly
			(pts
				(xy -0.508 0.2794) (xy -0.508 0.2286) (xy -0.635 0.2286) (xy -0.635 -0.254) (xy -0.5334 -0.254)
				(xy -0.5334 -0.2794) (xy 0.5334 -0.2794) (xy 0.5334 -0.254) (xy 0.635 -0.254) (xy 0.635 0.254) (xy 0.5334 0.254)
				(xy 0.5334 0.2794)
			)
			(stroke
				(width 0)
				(type default)
			)
			(fill no)
			(layer "F.CrtYd")
		)
		(pad "1" smd rect
			(at 0.40005 0 90)
			(size 0.4572 0.508)
			(layers "F.Cu" "F.Mask" "F.Paste")
			(net "LPC_CPU_NODE1_LAD0")
		)
		(pad "2" smd rect
			(at -0.40005 0 90)
			(size 0.4572 0.508)
			(layers "F.Cu" "F.Mask" "F.Paste")
			(net "LPC_CPU_TPM_LAD0")
		)
	)
	(footprint ""
		(layer "F.Cu")
		(at 11.04392 -8.35279)
		(property "Reference" "U11"
			(at -4.445762 0.18923 90)
			(unlocked yes)
			(layer "F.SilkS")
			(effects
				(font
					(size 0.7874 0.5842)
					(thickness 0.1524)
				)
			)
		)
		(property "Value" ""
			(at 0 0 0)
			(layer "F.Fab")
			(effects
				(font
					(size 1.27 1.27)
				)
			)
		)
		(duplicate_pad_numbers_are_jumpers no)
		(fp_line
			(start -1.651 -2.0574)
			(end 1.651 -2.0574)
			(stroke
				(width 0.1524)
				(type default)
			)
			(layer "F.SilkS")
		)
		(fp_line
			(start -1.651 -0.381)
			(end -1.651 -2.0574)
			(stroke
				(width 0.1524)
				(type default)
			)
			(layer "F.SilkS")
		)
		(fp_line
			(start -1.651 0.381)
			(end -1.016 0)
			(stroke
				(width 0.1524)
				(type default)
			)
			(layer "F.SilkS")
		)
		(fp_line
			(start -1.651 2.0574)
			(end -1.651 0.381)
			(stroke
				(width 0.1524)
				(type default)
			)
			(layer "F.SilkS")
		)
		(fp_line
			(start -1.016 0)
			(end -1.651 -0.381)
			(stroke
				(width 0.1524)
				(type default)
			)
			(layer "F.SilkS")
		)
		(fp_line
			(start 1.651 -2.0574)
			(end 1.651 2.0574)
			(stroke
				(width 0.1524)
				(type default)
			)
			(layer "F.SilkS")
		)
		(fp_line
			(start 1.651 2.0574)
			(end -1.651 2.0574)
			(stroke
				(width 0.1524)
				(type default)
			)
			(layer "F.SilkS")
		)
		(fp_rect
			(start -1.524 1.905)
			(end 1.524 -1.905)
			(stroke
				(width 0)
				(type default)
			)
			(fill no)
			(layer "F.CrtYd")
		)
		(pad "1" smd rect
			(at -0.94996 1.225042)
			(size 0.5588 1.3462)
			(layers "F.Cu" "F.Mask" "F.Paste")
			(net "PV_VDDR_NODE1_VREF_RW")
		)
		(pad "2" smd rect
			(at 0 1.225042)
			(size 0.5588 1.3462)
			(layers "F.Cu" "F.Mask" "F.Paste")
			(net "GND")
		)
		(pad "3" smd rect
			(at 0.94996 1.225042)
			(size 0.5588 1.3462)
			(layers "F.Cu" "F.Mask" "F.Paste")
			(net "PV_VDDR_NODE1_VREF_R")
		)
		(pad "4" smd rect
			(at 0.94996 -1.225042)
			(size 0.5588 1.3462)
			(layers "F.Cu" "F.Mask" "F.Paste")
			(net "PV_VDDR_NODE1_VREF_R")
		)
		(pad "5" smd rect
			(at -0.94996 -1.225042)
			(size 0.5588 1.3462)
			(layers "F.Cu" "F.Mask" "F.Paste")
			(net "P5V_STB_NODE1")
		)
	)
	(footprint ""
		(layer "F.Cu")
		(at 191.389 -121.666)
		(property "Reference" "R1265"
			(at 0.2032 2.43967 0)
			(unlocked yes)
			(layer "F.SilkS")
			(effects
				(font
					(size 0.7874 0.5842)
					(thickness 0.1524)
				)
				(justify left)
			)
		)
		(property "Value" ""
			(at 0 0 0)
			(layer "F.Fab")
			(effects
				(font
					(size 1.27 1.27)
				)
			)
		)
		(duplicate_pad_numbers_are_jumpers no)
		(fp_line
			(start -0.7874 -0.4064)
			(end 0.7874 -0.4064)
			(stroke
				(width 0.1524)
				(type default)
			)
			(layer "F.SilkS")
		)
		(fp_line
			(start -0.7874 0.4064)
			(end -0.7874 -0.4064)
			(stroke
				(width 0.1524)
				(type default)
			)
			(layer "F.SilkS")
		)
		(fp_line
			(start 0.7874 -0.4064)
			(end 0.7874 0.4064)
			(stroke
				(width 0.1524)
				(type default)
			)
			(layer "F.SilkS")
		)
		(fp_line
			(start 0.7874 0.4064)
			(end -0.7874 0.4064)
			(stroke
				(width 0.1524)
				(type default)
			)
			(layer "F.SilkS")
		)
		(fp_poly
			(pts
				(xy -0.508 0.2794) (xy -0.508 0.2286) (xy -0.635 0.2286) (xy -0.635 -0.254) (xy -0.5334 -0.254)
				(xy -0.5334 -0.2794) (xy 0.5334 -0.2794) (xy 0.5334 -0.254) (xy 0.635 -0.254) (xy 0.635 0.254) (xy 0.5334 0.254)
				(xy 0.5334 0.2794)
			)
			(stroke
				(width 0)
				(type default)
			)
			(fill no)
			(layer "F.CrtYd")
		)
		(pad "1" smd rect
			(at 0.40005 0)
			(size 0.4572 0.508)
			(layers "F.Cu" "F.Mask" "F.Paste")
			(net "SIO_JTAG_CPLD1_TDI_R")
		)
		(pad "2" smd rect
			(at -0.40005 0)
			(size 0.4572 0.508)
			(layers "F.Cu" "F.Mask" "F.Paste")
			(net "SIO_JTAG_CPLD1_TDI")
		)
	)
	(footprint ""
		(layer "F.Cu")
		(at 176.510442 -120.865646 180)
		(property "Reference" "U102"
			(at 0.566166 -9.43737 0)
			(unlocked yes)
			(layer "F.SilkS")
			(effects
				(font
					(size 0.7874 0.5842)
					(thickness 0.1524)
				)
				(justify left)
			)
		)
		(property "Value" ""
			(at 0 0 180)
			(layer "F.Fab")
			(effects
				(font
					(size 1.27 1.27)
				)
			)
		)
		(duplicate_pad_numbers_are_jumpers no)
		(fp_line
			(start 8.599932 8.599932)
			(end -8.599932 8.599932)
			(stroke
				(width 0.1524)
				(type default)
			)
			(layer "F.SilkS")
		)
		(fp_line
			(start 8.599932 -8.599932)
			(end 8.599932 8.599932)
			(stroke
				(width 0.1524)
				(type default)
			)
			(layer "F.SilkS")
		)
		(fp_line
			(start 5.599938 5.599938)
			(end -5.599938 5.599938)
			(stroke
				(width 0.1524)
				(type default)
			)
			(layer "F.SilkS")
		)
		(fp_line
			(start 5.599938 -5.599938)
			(end 5.599938 5.599938)
			(stroke
				(width 0.1524)
				(type default)
			)
			(layer "F.SilkS")
		)
		(fp_line
			(start -5.599938 5.599938)
			(end -5.599938 -5.599938)
			(stroke
				(width 0.1524)
				(type default)
			)
			(layer "F.SilkS")
		)
		(fp_line
			(start -5.599938 -5.599938)
			(end 5.599938 -5.599938)
			(stroke
				(width 0.1524)
				(type default)
			)
			(layer "F.SilkS")
		)
		(fp_line
			(start -8.599932 8.599932)
			(end -8.599932 -8.599932)
			(stroke
				(width 0.1524)
				(type default)
			)
			(layer "F.SilkS")
		)
		(fp_line
			(start -8.599932 -8.599932)
			(end 8.599932 -8.599932)
			(stroke
				(width 0.1524)
				(type default)
			)
			(layer "F.SilkS")
		)
		(fp_poly
			(pts
				(xy -8.6106 -8.6106) (xy -3.81 -8.6106) (xy -5.2832 -7.1374) (xy -3.7338 -5.588) (xy -5.588 -5.588)
				(xy -5.588 -3.7338) (xy -7.1374 -5.2832) (xy -8.6106 -3.81)
			)
			(stroke
				(width 0)
				(type default)
			)
			(fill yes)
			(layer "F.SilkS")
		)
		(fp_rect
			(start -5.6134 5.6134)
			(end 5.6134 -5.6134)
			(stroke
				(width 0)
				(type default)
			)
			(fill no)
			(layer "F.CrtYd")
		)
		(fp_text user "10"
			(at 5.211318 -6.907276 0)
			(unlocked yes)
			(layer "F.SilkS")
			(effects
				(font
					(size 0.7874 0.5842)
					(thickness 0.1524)
				)
				(justify left)
			)
		)
		(fp_text user "9"
			(at 4.60502 -7.907274 0)
			(unlocked yes)
			(layer "F.SilkS")
			(effects
				(font
					(size 0.7874 0.5842)
					(thickness 0.1524)
				)
				(justify left)
			)
		)
		(fp_text user "8"
			(at 3.605022 -6.907276 0)
			(unlocked yes)
			(layer "F.SilkS")
			(effects
				(font
					(size 0.7874 0.5842)
					(thickness 0.1524)
				)
				(justify left)
			)
		)
		(fp_text user "7"
			(at 2.605024 -7.907274 0)
			(unlocked yes)
			(layer "F.SilkS")
			(effects
				(font
					(size 0.7874 0.5842)
					(thickness 0.1524)
				)
				(justify left)
			)
		)
		(fp_text user "6"
			(at 1.604772 -6.907276 0)
			(unlocked yes)
			(layer "F.SilkS")
			(effects
				(font
					(size 0.7874 0.5842)
					(thickness 0.1524)
				)
				(justify left)
			)
		)
		(fp_text user "5"
			(at 0.605028 -7.907274 0)
			(unlocked yes)
			(layer "F.SilkS")
			(effects
				(font
					(size 0.7874 0.5842)
					(thickness 0.1524)
				)
				(justify left)
			)
		)
		(fp_text user "4"
			(at -0.395224 -6.907276 0)
			(unlocked yes)
			(layer "F.SilkS")
			(effects
				(font
					(size 0.7874 0.5842)
					(thickness 0.1524)
				)
				(justify left)
			)
		)
		(fp_text user "3"
			(at -1.395222 -7.907274 0)
			(unlocked yes)
			(layer "F.SilkS")
			(effects
				(font
					(size 0.7874 0.5842)
					(thickness 0.1524)
				)
				(justify left)
			)
		)
		(fp_text user "2"
			(at -2.39522 -6.907276 0)
			(unlocked yes)
			(layer "F.SilkS")
			(effects
				(font
					(size 0.7874 0.5842)
					(thickness 0.1524)
				)
				(justify left)
			)
		)
		(fp_text user "1"
			(at -3.395218 -7.907274 0)
			(unlocked yes)
			(layer "F.SilkS")
			(effects
				(font
					(size 0.7874 0.5842)
					(thickness 0.1524)
				)
				(justify left)
			)
		)
		(fp_text user "K"
			(at -6.284214 4.98983 0)
			(unlocked yes)
			(layer "F.SilkS")
			(effects
				(font
					(size 0.7874 0.5842)
					(thickness 0.1524)
				)
				(justify left)
			)
		)
		(fp_text user "H"
			(at -6.284214 2.989834 0)
			(unlocked yes)
			(layer "F.SilkS")
			(effects
				(font
					(size 0.7874 0.5842)
					(thickness 0.1524)
				)
				(justify left)
			)
		)
		(fp_text user "F"
			(at -6.284214 0.989838 0)
			(unlocked yes)
			(layer "F.SilkS")
			(effects
				(font
					(size 0.7874 0.5842)
					(thickness 0.1524)
				)
				(justify left)
			)
		)
		(fp_text user "D"
			(at -6.284214 -1.010158 0)
			(unlocked yes)
			(layer "F.SilkS")
			(effects
				(font
					(size 0.7874 0.5842)
					(thickness 0.1524)
				)
				(justify left)
			)
		)
		(fp_text user "B"
			(at -6.284214 -3.010154 0)
			(unlocked yes)
			(layer "F.SilkS")
			(effects
				(font
					(size 0.7874 0.5842)
					(thickness 0.1524)
				)
				(justify left)
			)
		)
		(fp_text user "J"
			(at -6.784086 3.989832 0)
			(unlocked yes)
			(layer "F.SilkS")
			(effects
				(font
					(size 0.7874 0.5842)
					(thickness 0.1524)
				)
				(justify left)
			)
		)
		(fp_text user "G"
			(at -6.784086 1.989836 0)
			(unlocked yes)
			(layer "F.SilkS")
			(effects
				(font
					(size 0.7874 0.5842)
					(thickness 0.1524)
				)
				(justify left)
			)
		)
		(fp_text user "E"
			(at -6.784086 -0.01016 0)
			(unlocked yes)
			(layer "F.SilkS")
			(effects
				(font
					(size 0.7874 0.5842)
					(thickness 0.1524)
				)
				(justify left)
			)
		)
		(fp_text user "C"
			(at -6.784086 -2.010156 0)
			(unlocked yes)
			(layer "F.SilkS")
			(effects
				(font
					(size 0.7874 0.5842)
					(thickness 0.1524)
				)
				(justify left)
			)
		)
		(fp_text user "A"
			(at -6.784086 -4.010152 0)
			(unlocked yes)
			(layer "F.SilkS")
			(effects
				(font
					(size 0.7874 0.5842)
					(thickness 0.1524)
				)
				(justify left)
			)
		)
		(pad "A1" smd circle
			(at -4.500118 -4.500118 180)
			(size 0.49022 0.49022)
			(layers "F.Cu" "F.Mask" "F.Paste")
			(net "FM_CPLD_NODE1_P5V_EN")
		)
		(pad "A2" smd circle
			(at -3.50012 -4.500118 180)
			(size 0.49022 0.49022)
			(layers "F.Cu" "F.Mask" "F.Paste")
			(net "XDP_CPU_NODE1_PWROK")
		)
		(pad "A3" smd circle
			(at -2.500122 -4.500118 180)
			(size 0.49022 0.49022)
			(layers "F.Cu" "F.Mask" "F.Paste")
			(net "FM_CPLD_NODE1_P1V8_STB_EN")
		)
		(pad "A4" smd circle
			(at -1.500124 -4.500118 180)
			(size 0.49022 0.49022)
			(layers "F.Cu" "F.Mask" "F.Paste")
			(net "FM_CPLD_NODE1_P1V538_BMC_EN")
		)
		(pad "A5" smd circle
			(at -0.499872 -4.500118 180)
			(size 0.49022 0.49022)
			(layers "F.Cu" "F.Mask" "F.Paste")
			(net "FM_CPLD_NODE1_P1V26_BMC_EN")
		)
		(pad "A6" smd circle
			(at 0.499872 -4.500118 180)
			(size 0.49022 0.49022)
			(layers "F.Cu" "F.Mask" "F.Paste")
			(net "FM_CPLD_NODE1_P1V5_SUS_EN")
		)
		(pad "A7" smd circle
			(at 1.500124 -4.500118 180)
			(size 0.49022 0.49022)
			(layers "F.Cu" "F.Mask" "F.Paste")
			(net "FM_CPLD_NODE1_PVDDR_STB_EN")
		)
		(pad "A8" smd circle
			(at 2.500122 -4.500118 180)
			(size 0.49022 0.49022)
			(layers "F.Cu" "F.Mask" "F.Paste")
			(net "TP_FM_CPLD_NODE1_P1V0_STB_EN")
		)
		(pad "A9" smd circle
			(at 3.50012 -4.500118 180)
			(size 0.49022 0.49022)
			(layers "F.Cu" "F.Mask" "F.Paste")
			(net "FM_CPLD_NODE1_P1V05_SUS_EN")
		)
		(pad "A10" smd circle
			(at 4.500118 -4.500118 180)
			(size 0.49022 0.49022)
			(layers "F.Cu" "F.Mask" "F.Paste")
			(net "FM_CPLD_NODE1_P3V3_EN")
		)
		(pad "B1" smd circle
			(at -4.500118 -3.50012 180)
			(size 0.49022 0.49022)
			(layers "F.Cu" "F.Mask" "F.Paste")
			(net "PWRGD_NODE1_P12V_PG")
		)
		(pad "B2" smd circle
			(at -3.50012 -3.50012 180)
			(size 0.49022 0.49022)
			(layers "F.Cu" "F.Mask" "F.Paste")
			(net "FM_CPLD_NODE1_P1V8_EN")
		)
		(pad "B3" smd circle
			(at -2.500122 -3.50012 180)
			(size 0.49022 0.49022)
			(layers "F.Cu" "F.Mask" "F.Paste")
			(net "FM_CPLD_NODE1_P1V5_EN")
		)
		(pad "B4" smd circle
			(at -1.500124 -3.50012 180)
			(size 0.49022 0.49022)
			(layers "F.Cu" "F.Mask" "F.Paste")
			(net "FM_CPLD_NODE1_P1V0_EN")
		)
		(pad "B5" smd circle
			(at -0.499872 -3.50012 180)
			(size 0.49022 0.49022)
			(layers "F.Cu" "F.Mask" "F.Paste")
			(net "FM_CPLD_NODE1_P1V05_EN")
		)
		(pad "B6" smd circle
			(at 0.499872 -3.50012 180)
			(size 0.49022 0.49022)
			(layers "F.Cu" "F.Mask" "F.Paste")
			(net "FM_CPLD_NODE1_PVTT_DDR_EN")
		)
		(pad "B7" smd circle
			(at 1.500124 -3.50012 180)
			(size 0.49022 0.49022)
			(layers "F.Cu" "F.Mask" "F.Paste")
			(net "FM_CPLD_NODE1_PVCCP_EN")
		)
		(pad "B8" smd circle
			(at 2.500122 -3.50012 180)
			(size 0.49022 0.49022)
			(layers "F.Cu" "F.Mask" "F.Paste")
			(net "FM_CPLD_NODE1_CLK_PG")
		)
		(pad "B9" smd circle
			(at 3.50012 -3.50012 180)
			(size 0.49022 0.49022)
			(layers "F.Cu" "F.Mask" "F.Paste")
			(net "FM_CPLD_NODE1_P1V8_SUS_EN")
		)
		(pad "B10" smd circle
			(at 4.500118 -3.50012 180)
			(size 0.49022 0.49022)
			(layers "F.Cu" "F.Mask" "F.Paste")
			(net "FM_CPLD_NODE1_P3V3_SUS_EN")
		)
		(pad "C1" smd circle
			(at -4.500118 -2.500122 180)
			(size 0.49022 0.49022)
			(layers "F.Cu" "F.Mask" "F.Paste")
			(net "FM_CPLD_PCIE_SW_PERST_L")
		)
		(pad "C2" smd circle
			(at -3.50012 -2.500122 180)
			(size 0.49022 0.49022)
			(layers "F.Cu" "F.Mask" "F.Paste")
			(net "PWRGD_NODE1_P5V_STB_PG_CPLD")
		)
		(pad "C3" smd circle
			(at -2.500122 -2.500122 180)
			(size 0.49022 0.49022)
			(layers "F.Cu" "F.Mask" "F.Paste")
			(net "TP_FM_CPLD_NODE1_P3V3_STB_SW_EN")
		)
		(pad "C4" smd circle
			(at -1.500124 -2.500122 180)
			(size 0.49022 0.49022)
			(layers "F.Cu" "F.Mask" "F.Paste")
			(net "TP_FM_CPLD_NODE1_PWR_BTN_BMC")
		)
		(pad "C5" smd circle
			(at -0.499872 -2.500122 180)
			(size 0.49022 0.49022)
			(layers "F.Cu" "F.Mask" "F.Paste")
			(net "FM_CPLD_NODE1_LPCRST_L")
		)
		(pad "C6" smd circle
			(at 0.499872 -2.500122 180)
			(size 0.49022 0.49022)
			(layers "F.Cu" "F.Mask" "F.Paste")
			(net "TP_FM_CPLD_NODE1_SSI_PERST_L")
		)
		(pad "C7" smd circle
			(at 1.500124 -2.500122 180)
			(size 0.49022 0.49022)
			(layers "F.Cu" "F.Mask" "F.Paste")
			(net "CM_STATUS_LED_N")
		)
		(pad "C8" smd circle
			(at 2.500122 -2.500122 180)
			(size 0.49022 0.49022)
			(layers "F.Cu" "F.Mask" "F.Paste")
			(net "FM_CPLD_NODE1_SATA_PERST_L")
		)
		(pad "C9" smd circle
			(at 3.50012 -2.500122 180)
			(size 0.49022 0.49022)
			(layers "F.Cu" "F.Mask" "F.Paste")
			(net "FM_CPLD_NODE1_USB_PERST_L")
		)
		(pad "C10" smd circle
			(at 4.500118 -2.500122 180)
			(size 0.49022 0.49022)
			(layers "F.Cu" "F.Mask" "F.Paste")
			(net "FM_CPLD_NODE1_USB_PONRST_L")
		)
		(pad "D1" smd circle
			(at -4.500118 -1.500124 180)
			(size 0.49022 0.49022)
			(layers "F.Cu" "F.Mask" "F.Paste")
			(net "PWRGD_NODE1_P3V3_STB_PG_CPLD")
		)
		(pad "D2" smd circle
			(at -3.50012 -1.500124 180)
			(size 0.49022 0.49022)
			(layers "F.Cu" "F.Mask" "F.Paste")
			(net "PWRGD_NODE1_P1V8_STB_PG")
		)
		(pad "D3" smd circle
			(at -2.500122 -1.500124 180)
			(size 0.49022 0.49022)
			(layers "F.Cu" "F.Mask" "F.Paste")
			(net "PWRGD_NODE1_P1V538_BMC_PG")
		)
		(pad "D4" smd circle
			(at -1.500124 -1.500124 180)
			(size 0.49022 0.49022)
			(layers "F.Cu" "F.Mask" "F.Paste")
			(net "P3V3_STB_NODE1")
		)
		(pad "D5" smd circle
			(at -0.499872 -1.500124 180)
			(size 0.49022 0.49022)
			(layers "F.Cu" "F.Mask" "F.Paste")
			(net "GND")
		)
		(pad "D6" smd circle
			(at 0.499872 -1.500124 180)
			(size 0.49022 0.49022)
			(layers "F.Cu" "F.Mask" "F.Paste")
			(net "P3V3_STB_NODE1")
		)
		(pad "D7" smd circle
			(at 1.500124 -1.500124 180)
			(size 0.49022 0.49022)
			(layers "F.Cu" "F.Mask" "F.Paste")
			(net "GND")
		)
		(pad "D8" smd circle
			(at 2.500122 -1.500124 180)
			(size 0.49022 0.49022)
			(layers "F.Cu" "F.Mask" "F.Paste")
			(net "FM_CPLD_NODE1_BMC_PERST_L")
		)
		(pad "D9" smd circle
			(at 3.50012 -1.500124 180)
			(size 0.49022 0.49022)
			(layers "F.Cu" "F.Mask" "F.Paste")
			(net "TP_FM_CPLD_NODE1_BMC_EXTRST_L")
		)
		(pad "D10" smd circle
			(at 4.500118 -1.500124 180)
			(size 0.49022 0.49022)
			(layers "F.Cu" "F.Mask" "F.Paste")
			(net "FM_CPLD_NODE1_BMC_SRST_L")
		)
		(pad "E1" smd circle
			(at -4.500118 -0.499872 180)
			(size 0.49022 0.49022)
			(layers "F.Cu" "F.Mask" "F.Paste")
			(net "FM_CPLD_NODE1_PWR_BTN_CPU")
		)
		(pad "E2" smd circle
			(at -3.50012 -0.499872 180)
			(size 0.49022 0.49022)
			(layers "F.Cu" "F.Mask" "F.Paste")
			(net "CLK_33K_CPU_NODE1_SUSCLK")
		)
		(pad "E3" smd circle
			(at -2.500122 -0.499872 180)
			(size 0.49022 0.49022)
			(layers "F.Cu" "F.Mask" "F.Paste")
			(net "PWRGD_NODE1_P1V26_BMC_PG")
		)
		(pad "E4" smd circle
			(at -1.500124 -0.499872 180)
			(size 0.49022 0.49022)
			(layers "F.Cu" "F.Mask" "F.Paste")
			(net "P3V3_STB_NODE1")
		)
		(pad "E5" smd circle
			(at -0.499872 -0.499872 180)
			(size 0.49022 0.49022)
			(layers "F.Cu" "F.Mask" "F.Paste")
			(net "GND")
		)
		(pad "E6" smd circle
			(at 0.499872 -0.499872 180)
			(size 0.49022 0.49022)
			(layers "F.Cu" "F.Mask" "F.Paste")
			(net "GND")
		)
		(pad "E7" smd circle
			(at 1.500124 -0.499872 180)
			(size 0.49022 0.49022)
			(layers "F.Cu" "F.Mask" "F.Paste")
			(net "P3V3_STB_NODE1")
		)
		(pad "E8" smd circle
			(at 2.500122 -0.499872 180)
			(size 0.49022 0.49022)
			(layers "F.Cu" "F.Mask" "F.Paste")
			(net "FM_CPU_NODE1_RSTWARN")
		)
		(pad "E9" smd circle
			(at 3.50012 -0.499872 180)
			(size 0.49022 0.49022)
			(layers "F.Cu" "F.Mask" "F.Paste")
			(net "RST_CPU_NODE1_SRTCRST_L")
		)
		(pad "E10" smd circle
			(at 4.500118 -0.499872 180)
			(size 0.49022 0.49022)
			(layers "F.Cu" "F.Mask" "F.Paste")
			(net "TP_CPLD_NODE1_IO39")
		)
		(pad "F1" smd circle
			(at -4.500118 0.499872 180)
			(size 0.49022 0.49022)
			(layers "F.Cu" "F.Mask" "F.Paste")
			(net "PWRGD_NODE1_P1V5_SUS_PG")
		)
		(pad "F2" smd circle
			(at -3.50012 0.499872 180)
			(size 0.49022 0.49022)
			(layers "F.Cu" "F.Mask" "F.Paste")
			(net "PWRGD_NODE1_PVDDR_STB_PG")
		)
		(pad "F3" smd circle
			(at -2.500122 0.499872 180)
			(size 0.49022 0.49022)
			(layers "F.Cu" "F.Mask" "F.Paste")
			(net "PWRGD_NODE1_P1V0")
		)
		(pad "F4" smd circle
			(at -1.500124 0.499872 180)
			(size 0.49022 0.49022)
			(layers "F.Cu" "F.Mask" "F.Paste")
			(net "P3V3_STB_NODE1")
		)
		(pad "F5" smd circle
			(at -0.499872 0.499872 180)
			(size 0.49022 0.49022)
			(layers "F.Cu" "F.Mask" "F.Paste")
			(net "GND")
		)
		(pad "F6" smd circle
			(at 0.499872 0.499872 180)
			(size 0.49022 0.49022)
			(layers "F.Cu" "F.Mask" "F.Paste")
			(net "GND")
		)
		(pad "F7" smd circle
			(at 1.500124 0.499872 180)
			(size 0.49022 0.49022)
			(layers "F.Cu" "F.Mask" "F.Paste")
			(net "P3V3_STB_NODE1")
		)
		(pad "F8" smd circle
			(at 2.500122 0.499872 180)
			(size 0.49022 0.49022)
			(layers "F.Cu" "F.Mask" "F.Paste")
			(net "CPLD_EXT_RST_N")
		)
		(pad "F9" smd circle
			(at 3.50012 0.499872 180)
			(size 0.49022 0.49022)
			(layers "F.Cu" "F.Mask" "F.Paste")
			(net "FM_CPLD_NODE1_CPU_RSMRST_L")
		)
		(pad "F10" smd circle
			(at 4.500118 0.499872 180)
			(size 0.49022 0.49022)
			(layers "F.Cu" "F.Mask" "F.Paste")
			(net "FM_CPLD_NODE1_SYS_PG")
		)
		(pad "G1" smd circle
			(at -4.500118 1.500124 180)
			(size 0.49022 0.49022)
			(layers "F.Cu" "F.Mask" "F.Paste")
			(net "PWRGD_NODE1_P1V05_SUS_PG")
		)
		(pad "G2" smd circle
			(at -3.50012 1.500124 180)
			(size 0.49022 0.49022)
			(layers "F.Cu" "F.Mask" "F.Paste")
			(net "PWRGD_NODE1_P3V3_PG")
		)
		(pad "G3" smd circle
			(at -2.500122 1.500124 180)
			(size 0.49022 0.49022)
			(layers "F.Cu" "F.Mask" "F.Paste")
			(net "PWRGD_NODE1_P1V05_PG")
		)
		(pad "G4" smd circle
			(at -1.500124 1.500124 180)
			(size 0.49022 0.49022)
			(layers "F.Cu" "F.Mask" "F.Paste")
			(net "P3V3_STB_NODE1")
		)
		(pad "G5" smd circle
			(at -0.499872 1.500124 180)
			(size 0.49022 0.49022)
			(layers "F.Cu" "F.Mask" "F.Paste")
			(net "GND")
		)
		(pad "G6" smd circle
			(at 0.499872 1.500124 180)
			(size 0.49022 0.49022)
			(layers "F.Cu" "F.Mask" "F.Paste")
			(net "P3V3_STB_NODE1")
		)
		(pad "G7" smd circle
			(at 1.500124 1.500124 180)
			(size 0.49022 0.49022)
			(layers "F.Cu" "F.Mask" "F.Paste")
			(net "GND")
		)
		(pad "G8" smd circle
			(at 2.500122 1.500124 180)
			(size 0.49022 0.49022)
			(layers "F.Cu" "F.Mask" "F.Paste")
			(net "FM_CPLD_NODE1_CPU_RESET_L")
		)
		(pad "G9" smd circle
			(at 3.50012 1.500124 180)
			(size 0.49022 0.49022)
			(layers "F.Cu" "F.Mask" "F.Paste")
			(net "FM_NODE1_DDR3_DRAM_POK_L")
		)
		(pad "G10" smd circle
			(at 4.500118 1.500124 180)
			(size 0.49022 0.49022)
			(layers "F.Cu" "F.Mask" "F.Paste")
			(net "FM_NODE1_DDR3_SYSPWRGD_L")
		)
		(pad "H1" smd circle
			(at -4.500118 2.500122 180)
			(size 0.49022 0.49022)
			(layers "F.Cu" "F.Mask" "F.Paste")
			(net "PWRGD_NODE1_PVTT_DDR_PG")
		)
		(pad "H2" smd circle
			(at -3.50012 2.500122 180)
			(size 0.49022 0.49022)
			(layers "F.Cu" "F.Mask" "F.Paste")
			(net "JTAG_CPLD1_TDI")
		)
		(pad "H3" smd circle
			(at -2.500122 2.500122 180)
			(size 0.49022 0.49022)
			(layers "F.Cu" "F.Mask" "F.Paste")
			(net "JTAG_CPLD1_TCK")
		)
		(pad "H4" smd circle
			(at -1.500124 2.500122 180)
			(size 0.49022 0.49022)
			(layers "F.Cu" "F.Mask" "F.Paste")
			(net "PWRGD_NODE1_PVCCP_PG")
		)
		(pad "H5" smd circle
			(at -0.499872 2.500122 180)
			(size 0.49022 0.49022)
			(layers "F.Cu" "F.Mask" "F.Paste")
			(net "CPLD_CPU_THRMTRIP_N")
		)
		(pad "H6" smd circle
			(at 0.499872 2.500122 180)
			(size 0.49022 0.49022)
			(layers "F.Cu" "F.Mask" "F.Paste")
			(net "FM_CPU_NODE1_XDP_PG_RST")
		)
		(pad "H7" smd circle
			(at 1.500124 2.500122 180)
			(size 0.49022 0.49022)
			(layers "F.Cu" "F.Mask" "F.Paste")
			(net "XDP_CPU_NODE1_PWROK_STALL_L")
		)
		(pad "H8" smd circle
			(at 2.500122 2.500122 180)
			(size 0.49022 0.49022)
			(layers "F.Cu" "F.Mask" "F.Paste")
			(net "CPLD_THRMTRIP_LOG_N")
		)
		(pad "H9" smd circle
			(at 3.50012 2.500122 180)
			(size 0.49022 0.49022)
			(layers "F.Cu" "F.Mask" "F.Paste")
			(net "FM_CPLD_NODE1_JTAG_POK_L")
		)
		(pad "H10" smd circle
			(at 4.500118 2.500122 180)
			(size 0.49022 0.49022)
			(layers "F.Cu" "F.Mask" "F.Paste")
			(net "LED_PWR_NODE1_L")
		)
		(pad "J1" smd circle
			(at -4.500118 3.50012 180)
			(size 0.49022 0.49022)
			(layers "F.Cu" "F.Mask" "F.Paste")
			(net "JTAG_CPLD1_TMS")
		)
		(pad "J2" smd circle
			(at -3.50012 3.50012 180)
			(size 0.49022 0.49022)
			(layers "F.Cu" "F.Mask" "F.Paste")
			(net "JTAG_CPLD1_TDO")
		)
		(pad "J3" smd circle
			(at -2.500122 3.50012 180)
			(size 0.49022 0.49022)
			(layers "F.Cu" "F.Mask" "F.Paste")
			(net "CPLD_ROW_EN")
		)
		(pad "J4" smd circle
			(at -1.500124 3.50012 180)
			(size 0.49022 0.49022)
			(layers "F.Cu" "F.Mask" "F.Paste")
			(net "CPLD_ROW_LATCH")
		)
		(pad "J5" smd circle
			(at -0.499872 3.50012 180)
			(size 0.49022 0.49022)
			(layers "F.Cu" "F.Mask" "F.Paste")
			(net "FM_CPU_NODE1_RSTRDY_L")
		)
		(pad "J6" smd circle
			(at 0.499872 3.50012 180)
			(size 0.49022 0.49022)
			(layers "F.Cu" "F.Mask" "F.Paste")
			(net "FM_CPLD_NODE1_DEBUG_MODE")
		)
		(pad "J7" smd circle
			(at 1.500124 3.50012 180)
			(size 0.49022 0.49022)
			(layers "F.Cu" "F.Mask" "F.Paste")
			(net "RST_BTN_NODE1_L")
		)
		(pad "J8" smd circle
			(at 2.500122 3.50012 180)
			(size 0.49022 0.49022)
			(layers "F.Cu" "F.Mask" "F.Paste")
			(net "FM_CPLD_NODE1_PWR_BTN_L")
		)
		(pad "J9" smd circle
			(at 3.50012 3.50012 180)
			(size 0.49022 0.49022)
			(layers "F.Cu" "F.Mask" "F.Paste")
			(net "RST_NODE1_CPU_XDP_RSTIN_L")
		)
		(pad "J10" smd circle
			(at 4.500118 3.50012 180)
			(size 0.49022 0.49022)
			(layers "F.Cu" "F.Mask" "F.Paste")
			(net "LED_CPU_NODE1_CPLD")
		)
		(pad "K1" smd circle
			(at -4.500118 4.500118 180)
			(size 0.49022 0.49022)
			(layers "F.Cu" "F.Mask" "F.Paste")
			(net "SYS_AUTO_POWER_ON_N")
		)
		(pad "K2" smd circle
			(at -3.50012 4.500118 180)
			(size 0.49022 0.49022)
			(layers "F.Cu" "F.Mask" "F.Paste")
			(net "FM_NODE1_CORE0_1_RST_L")
		)
		(pad "K3" smd circle
			(at -2.500122 4.500118 180)
			(size 0.49022 0.49022)
			(layers "F.Cu" "F.Mask" "F.Paste")
			(net "FM_CPLD_NODE1_WDT")
		)
		(pad "K4" smd circle
			(at -1.500124 4.500118 180)
			(size 0.49022 0.49022)
			(layers "F.Cu" "F.Mask" "F.Paste")
			(net "FM_CPU_NODE1_SLPMODE")
		)
		(pad "K5" smd circle
			(at -0.499872 4.500118 180)
			(size 0.49022 0.49022)
			(layers "F.Cu" "F.Mask" "F.Paste")
			(net "FM_CPU_NODE1_SLPRDY_L")
		)
		(pad "K6" smd circle
			(at 0.499872 4.500118 180)
			(size 0.49022 0.49022)
			(layers "F.Cu" "F.Mask" "F.Paste")
			(net "CPLD1_RSV3")
		)
		(pad "K7" smd circle
			(at 1.500124 4.500118 180)
			(size 0.49022 0.49022)
			(layers "F.Cu" "F.Mask" "F.Paste")
			(net "CPLD1_RSV2")
		)
		(pad "K8" smd circle
			(at 2.500122 4.500118 180)
			(size 0.49022 0.49022)
			(layers "F.Cu" "F.Mask" "F.Paste")
			(net "CPLD1_RSV1")
		)
		(pad "K9" smd circle
			(at 3.50012 4.500118 180)
			(size 0.49022 0.49022)
			(layers "F.Cu" "F.Mask" "F.Paste")
			(net "H_CPU_NODE1_VR_HOT_L")
		)
		(pad "K10" smd circle
			(at 4.500118 4.500118 180)
			(size 0.49022 0.49022)
			(layers "F.Cu" "F.Mask" "F.Paste")
			(net "IRQ_LVC3_CPU_NODE1_WAKE_L")
		)
	)
	(footprint ""
		(layer "F.Cu")
		(at 130.29057 -26.569416 -90)
		(property "Reference" "R1144"
			(at 5.325618 -0.028448 90)
			(unlocked yes)
			(layer "F.SilkS")
			(effects
				(font
					(size 0.7874 0.5842)
					(thickness 0.1524)
				)
				(justify left)
			)
		)
		(property "Value" ""
			(at 0 0 270)
			(layer "F.Fab")
			(effects
				(font
					(size 1.27 1.27)
				)
			)
		)
		(duplicate_pad_numbers_are_jumpers no)
		(fp_line
			(start -0.7874 0.4064)
			(end -0.7874 -0.4064)
			(stroke
				(width 0.1524)
				(type default)
			)
			(layer "F.SilkS")
		)
		(fp_line
			(start 0.7874 0.4064)
			(end -0.7874 0.4064)
			(stroke
				(width 0.1524)
				(type default)
			)
			(layer "F.SilkS")
		)
		(fp_line
			(start -0.7874 -0.4064)
			(end 0.7874 -0.4064)
			(stroke
				(width 0.1524)
				(type default)
			)
			(layer "F.SilkS")
		)
		(fp_line
			(start 0.7874 -0.4064)
			(end 0.7874 0.4064)
			(stroke
				(width 0.1524)
				(type default)
			)
			(layer "F.SilkS")
		)
		(fp_poly
			(pts
				(xy -0.508 0.2794) (xy -0.508 0.2286) (xy -0.635 0.2286) (xy -0.635 -0.254) (xy -0.5334 -0.254)
				(xy -0.5334 -0.2794) (xy 0.5334 -0.2794) (xy 0.5334 -0.254) (xy 0.635 -0.254) (xy 0.635 0.254) (xy 0.5334 0.254)
				(xy 0.5334 0.2794)
			)
			(stroke
				(width 0)
				(type default)
			)
			(fill no)
			(layer "F.CrtYd")
		)
		(pad "1" smd rect
			(at 0.40005 0 270)
			(size 0.4572 0.508)
			(layers "F.Cu" "F.Mask" "F.Paste")
			(net "P3V3_STB_NODE1")
		)
		(pad "2" smd rect
			(at -0.40005 0 270)
			(size 0.4572 0.508)
			(layers "F.Cu" "F.Mask" "F.Paste")
			(net "SIO_PIN78")
		)
	)
	(footprint ""
		(layer "F.Cu")
		(at 133.223 -51.435 90)
		(property "Reference" "R615"
			(at 16.3576 30.63367 90)
			(unlocked yes)
			(layer "F.SilkS")
			(effects
				(font
					(size 0.7874 0.5842)
					(thickness 0.1524)
				)
				(justify left)
			)
		)
		(property "Value" ""
			(at 0 0 90)
			(layer "F.Fab")
			(effects
				(font
					(size 1.27 1.27)
				)
			)
		)
		(duplicate_pad_numbers_are_jumpers no)
		(fp_line
			(start 0.7874 -0.4064)
			(end 0.7874 0.4064)
			(stroke
				(width 0.1524)
				(type default)
			)
			(layer "F.SilkS")
		)
		(fp_line
			(start -0.7874 -0.4064)
			(end 0.7874 -0.4064)
			(stroke
				(width 0.1524)
				(type default)
			)
			(layer "F.SilkS")
		)
		(fp_line
			(start 0.7874 0.4064)
			(end -0.7874 0.4064)
			(stroke
				(width 0.1524)
				(type default)
			)
			(layer "F.SilkS")
		)
		(fp_line
			(start -0.7874 0.4064)
			(end -0.7874 -0.4064)
			(stroke
				(width 0.1524)
				(type default)
			)
			(layer "F.SilkS")
		)
		(fp_poly
			(pts
				(xy -0.508 0.2794) (xy -0.508 0.2286) (xy -0.635 0.2286) (xy -0.635 -0.254) (xy -0.5334 -0.254)
				(xy -0.5334 -0.2794) (xy 0.5334 -0.2794) (xy 0.5334 -0.254) (xy 0.635 -0.254) (xy 0.635 0.254) (xy 0.5334 0.254)
				(xy 0.5334 0.2794)
			)
			(stroke
				(width 0)
				(type default)
			)
			(fill no)
			(layer "F.CrtYd")
		)
		(pad "1" smd rect
			(at 0.40005 0 90)
			(size 0.4572 0.508)
			(layers "F.Cu" "F.Mask" "F.Paste")
			(net "P5V_NODE1")
		)
		(pad "2" smd rect
			(at -0.40005 0 90)
			(size 0.4572 0.508)
			(layers "F.Cu" "F.Mask" "F.Paste")
			(net "UART_RI_P4_R_N")
		)
	)
	(footprint ""
		(layer "F.Cu")
		(at 133.766052 -154.84475 -90)
		(property "Reference" "R299"
			(at 110.763812 60.83808 90)
			(unlocked yes)
			(layer "F.SilkS")
			(effects
				(font
					(size 0.7874 0.5842)
					(thickness 0.1524)
				)
				(justify left)
			)
		)
		(property "Value" ""
			(at 0 0 270)
			(layer "F.Fab")
			(effects
				(font
					(size 1.27 1.27)
				)
			)
		)
		(duplicate_pad_numbers_are_jumpers no)
		(fp_line
			(start -0.7874 0.4064)
			(end -0.7874 -0.4064)
			(stroke
				(width 0.1524)
				(type default)
			)
			(layer "F.SilkS")
		)
		(fp_line
			(start 0.7874 0.4064)
			(end -0.7874 0.4064)
			(stroke
				(width 0.1524)
				(type default)
			)
			(layer "F.SilkS")
		)
		(fp_line
			(start -0.7874 -0.4064)
			(end 0.7874 -0.4064)
			(stroke
				(width 0.1524)
				(type default)
			)
			(layer "F.SilkS")
		)
		(fp_line
			(start 0.7874 -0.4064)
			(end 0.7874 0.4064)
			(stroke
				(width 0.1524)
				(type default)
			)
			(layer "F.SilkS")
		)
		(fp_poly
			(pts
				(xy -0.508 0.2794) (xy -0.508 0.2286) (xy -0.635 0.2286) (xy -0.635 -0.254) (xy -0.5334 -0.254)
				(xy -0.5334 -0.2794) (xy 0.5334 -0.2794) (xy 0.5334 -0.254) (xy 0.635 -0.254) (xy 0.635 0.254) (xy 0.5334 0.254)
				(xy 0.5334 0.2794)
			)
			(stroke
				(width 0)
				(type default)
			)
			(fill no)
			(layer "F.CrtYd")
		)
		(pad "1" smd rect
			(at 0.40005 0 270)
			(size 0.4572 0.508)
			(layers "F.Cu" "F.Mask" "F.Paste")
			(net "P3V3_NODE1")
		)
		(pad "2" smd rect
			(at -0.40005 0 270)
			(size 0.4572 0.508)
			(layers "F.Cu" "F.Mask" "F.Paste")
			(net "PCIE_SW_P0_ERR")
		)
	)
	(footprint ""
		(layer "F.Cu")
		(at 90.98534 -113.771426 90)
		(property "Reference" "R1257"
			(at -0.319532 -4.22148 0)
			(unlocked yes)
			(layer "F.SilkS")
			(effects
				(font
					(size 0.7874 0.5842)
					(thickness 0.1524)
				)
				(justify left)
			)
		)
		(property "Value" ""
			(at 0 0 90)
			(layer "F.Fab")
			(effects
				(font
					(size 1.27 1.27)
				)
			)
		)
		(duplicate_pad_numbers_are_jumpers no)
		(fp_line
			(start 0.7874 -0.4064)
			(end 0.7874 0.4064)
			(stroke
				(width 0.1524)
				(type default)
			)
			(layer "F.SilkS")
		)
		(fp_line
			(start -0.7874 -0.4064)
			(end 0.7874 -0.4064)
			(stroke
				(width 0.1524)
				(type default)
			)
			(layer "F.SilkS")
		)
		(fp_line
			(start 0.7874 0.4064)
			(end -0.7874 0.4064)
			(stroke
				(width 0.1524)
				(type default)
			)
			(layer "F.SilkS")
		)
		(fp_line
			(start -0.7874 0.4064)
			(end -0.7874 -0.4064)
			(stroke
				(width 0.1524)
				(type default)
			)
			(layer "F.SilkS")
		)
		(fp_poly
			(pts
				(xy -0.508 0.2794) (xy -0.508 0.2286) (xy -0.635 0.2286) (xy -0.635 -0.254) (xy -0.5334 -0.254)
				(xy -0.5334 -0.2794) (xy 0.5334 -0.2794) (xy 0.5334 -0.254) (xy 0.635 -0.254) (xy 0.635 0.254) (xy 0.5334 0.254)
				(xy 0.5334 0.2794)
			)
			(stroke
				(width 0)
				(type default)
			)
			(fill no)
			(layer "F.CrtYd")
		)
		(pad "1" smd rect
			(at 0.40005 0 90)
			(size 0.4572 0.508)
			(layers "F.Cu" "F.Mask" "F.Paste")
			(net "PORT80_LOUT6")
		)
		(pad "2" smd rect
			(at -0.40005 0 90)
			(size 0.4572 0.508)
			(layers "F.Cu" "F.Mask" "F.Paste")
			(net "N53313577")
		)
	)
	(footprint ""
		(layer "F.Cu")
		(at 157.572964 -75.126596)
		(property "Reference" "J28"
			(at -2.983738 0.467106 0)
			(unlocked yes)
			(layer "F.SilkS")
			(effects
				(font
					(size 0.7874 0.5842)
					(thickness 0.1524)
				)
				(justify left)
			)
		)
		(property "Value" ""
			(at 0 0 0)
			(layer "F.Fab")
			(effects
				(font
					(size 1.27 1.27)
				)
			)
		)
		(duplicate_pad_numbers_are_jumpers no)
		(fp_poly
			(pts
				(xy 0.2794 0.907796) (xy 0.254 0.907796) (xy 0.254 1.0414) (xy -0.254 1.0414) (xy -0.254 1.034796)
				(xy -0.254 0.933196) (xy -0.2794 0.933196) (xy -0.2794 -0.133604) (xy -0.254 -0.133604) (xy -0.254 -0.235204)
				(xy 0.254 -0.235204) (xy 0.254 -0.133604) (xy 0.2794 -0.133604)
			)
			(stroke
				(width 0)
				(type default)
			)
			(fill no)
			(layer "F.CrtYd")
		)
		(pad "1" smd custom
			(at 0 -0.000254)
			(size 0.127 0.127)
			(layers "F.Cu" "F.Mask" "F.Paste")
			(net "P1V0_NODE1")
			(options
				(clearance outline)
				(anchor circle)
			)
			(primitives
				(gr_poly
					(pts
						(xy -0.127 0.508) (xy -0.127 -0.0508) (xy -0.254 -0.0508) (xy -0.254 -0.508) (xy 0.254 -0.508)
						(xy 0.254 -0.0508) (xy 0.127 -0.0508) (xy 0.127 0.508)
					)
					(width 0)
					(fill yes)
				)
			)
		)
		(pad "2" smd rect
			(at 0 0.799846 90)
			(size 0.4572 0.508)
			(layers "F.Cu" "F.Mask" "F.Paste")
			(net "P1V0_ADJ_S")
		)
		(zone
			(layer "F.Cu")
			(hatch none 0.5)
			(connect_pads
				(clearance 0)
			)
			(min_thickness 0.25)
			(keepout
				(tracks allowed)
				(vias not_allowed)
				(pads allowed)
				(copperpour not_allowed)
				(footprints allowed)
			)
			(placement
				(enabled no)
				(sheetname "")
			)
			(fill
				(thermal_gap 0.5)
				(thermal_bridge_width 0.5)
				(island_removal_mode 0)
			)
			(polygon
				(pts
					(xy 157.268164 -74.041) (xy 157.877764 -74.041) (xy 157.877764 -75.4126) (xy 157.268164 -75.4126)
				)
			)
		)
	)
	(footprint ""
		(layer "F.Cu")
		(at 106.082084 -153.797 180)
		(property "Reference" "PR16"
			(at 2.189226 -4.682998 0)
			(unlocked yes)
			(layer "F.SilkS")
			(effects
				(font
					(size 0.635 0.4064)
					(thickness 0.1524)
				)
				(justify left)
			)
		)
		(property "Value" ""
			(at 0 0 180)
			(layer "F.Fab")
			(effects
				(font
					(size 1.27 1.27)
				)
			)
		)
		(duplicate_pad_numbers_are_jumpers no)
		(fp_line
			(start 0.7874 0.4064)
			(end -0.7874 0.4064)
			(stroke
				(width 0.1524)
				(type default)
			)
			(layer "F.SilkS")
		)
		(fp_line
			(start 0.7874 -0.4064)
			(end 0.7874 0.4064)
			(stroke
				(width 0.1524)
				(type default)
			)
			(layer "F.SilkS")
		)
		(fp_line
			(start -0.7874 0.4064)
			(end -0.7874 -0.4064)
			(stroke
				(width 0.1524)
				(type default)
			)
			(layer "F.SilkS")
		)
		(fp_line
			(start -0.7874 -0.4064)
			(end 0.7874 -0.4064)
			(stroke
				(width 0.1524)
				(type default)
			)
			(layer "F.SilkS")
		)
		(fp_poly
			(pts
				(xy -0.508 0.2794) (xy -0.508 0.2286) (xy -0.635 0.2286) (xy -0.635 -0.254) (xy -0.5334 -0.254)
				(xy -0.5334 -0.2794) (xy 0.5334 -0.2794) (xy 0.5334 -0.254) (xy 0.635 -0.254) (xy 0.635 0.254) (xy 0.5334 0.254)
				(xy 0.5334 0.2794)
			)
			(stroke
				(width 0)
				(type default)
			)
			(fill no)
			(layer "F.CrtYd")
		)
		(pad "1" smd rect
			(at 0.40005 0 180)
			(size 0.4572 0.508)
			(layers "F.Cu" "F.Mask" "F.Paste")
			(net "P1V8_STB_NODE1_FB")
		)
		(pad "2" smd rect
			(at -0.40005 0 180)
			(size 0.4572 0.508)
			(layers "F.Cu" "F.Mask" "F.Paste")
			(net "GND")
		)
	)
	(footprint ""
		(layer "F.Cu")
		(at 163.889944 -93.840808 -90)
		(property "Reference" "R522"
			(at 1.2192 4.223512 90)
			(unlocked yes)
			(layer "F.SilkS")
			(effects
				(font
					(size 0.7874 0.5842)
					(thickness 0.1524)
				)
				(justify left)
			)
		)
		(property "Value" ""
			(at 0 0 270)
			(layer "F.Fab")
			(effects
				(font
					(size 1.27 1.27)
				)
			)
		)
		(duplicate_pad_numbers_are_jumpers no)
		(fp_line
			(start -0.7874 0.4064)
			(end -0.7874 -0.4064)
			(stroke
				(width 0.1524)
				(type default)
			)
			(layer "F.SilkS")
		)
		(fp_line
			(start 0.7874 0.4064)
			(end -0.7874 0.4064)
			(stroke
				(width 0.1524)
				(type default)
			)
			(layer "F.SilkS")
		)
		(fp_line
			(start -0.7874 -0.4064)
			(end 0.7874 -0.4064)
			(stroke
				(width 0.1524)
				(type default)
			)
			(layer "F.SilkS")
		)
		(fp_line
			(start 0.7874 -0.4064)
			(end 0.7874 0.4064)
			(stroke
				(width 0.1524)
				(type default)
			)
			(layer "F.SilkS")
		)
		(fp_poly
			(pts
				(xy -0.508 0.2794) (xy -0.508 0.2286) (xy -0.635 0.2286) (xy -0.635 -0.254) (xy -0.5334 -0.254)
				(xy -0.5334 -0.2794) (xy 0.5334 -0.2794) (xy 0.5334 -0.254) (xy 0.635 -0.254) (xy 0.635 0.254) (xy 0.5334 0.254)
				(xy 0.5334 0.2794)
			)
			(stroke
				(width 0)
				(type default)
			)
			(fill no)
			(layer "F.CrtYd")
		)
		(pad "1" smd rect
			(at 0.40005 0 270)
			(size 0.4572 0.508)
			(layers "F.Cu" "F.Mask" "F.Paste")
			(net "SPI_USB_NODE1_CLK")
		)
		(pad "2" smd rect
			(at -0.40005 0 270)
			(size 0.4572 0.508)
			(layers "F.Cu" "F.Mask" "F.Paste")
			(net "SPI_USB_NODE1_CLK_R")
		)
	)
	(footprint ""
		(layer "F.Cu")
		(at 84.82076 -188.126624 90)
		(property "Reference" "C593"
			(at 4.548886 -1.908048 90)
			(unlocked yes)
			(layer "F.SilkS")
			(effects
				(font
					(size 0.7874 0.5842)
					(thickness 0.1524)
				)
				(justify left)
			)
		)
		(property "Value" ""
			(at 0 0 90)
			(layer "F.Fab")
			(effects
				(font
					(size 1.27 1.27)
				)
			)
		)
		(duplicate_pad_numbers_are_jumpers no)
		(fp_line
			(start 0.7874 -0.4064)
			(end 0.7874 0.4064)
			(stroke
				(width 0.1524)
				(type default)
			)
			(layer "F.SilkS")
		)
		(fp_line
			(start -0.7874 -0.4064)
			(end 0.7874 -0.4064)
			(stroke
				(width 0.1524)
				(type default)
			)
			(layer "F.SilkS")
		)
		(fp_line
			(start 0 0.381)
			(end 0 -0.381)
			(stroke
				(width 0.1524)
				(type default)
			)
			(layer "F.SilkS")
		)
		(fp_line
			(start 0.7874 0.4064)
			(end -0.7874 0.4064)
			(stroke
				(width 0.1524)
				(type default)
			)
			(layer "F.SilkS")
		)
		(fp_line
			(start -0.7874 0.4064)
			(end -0.7874 -0.4064)
			(stroke
				(width 0.1524)
				(type default)
			)
			(layer "F.SilkS")
		)
		(fp_poly
			(pts
				(xy -0.5334 0.254) (xy -0.635 0.254) (xy -0.635 0.2286) (xy -0.635 -0.254) (xy -0.5334 -0.254) (xy -0.5334 -0.2794)
				(xy 0.5334 -0.2794) (xy 0.5334 -0.254) (xy 0.635 -0.254) (xy 0.635 0.254) (xy 0.5334 0.254) (xy 0.5334 0.2794)
				(xy -0.508 0.2794) (xy -0.5334 0.2794)
			)
			(stroke
				(width 0)
				(type default)
			)
			(fill no)
			(layer "F.CrtYd")
		)
		(pad "1" smd rect
			(at 0.40005 0 90)
			(size 0.4572 0.508)
			(layers "F.Cu" "F.Mask" "F.Paste")
			(net "I2C_PSU2_R_SCL")
		)
		(pad "2" smd rect
			(at -0.40005 0 90)
			(size 0.4572 0.508)
			(layers "F.Cu" "F.Mask" "F.Paste")
			(net "GND")
		)
	)
	(footprint ""
		(layer "F.Cu")
		(at 77.96276 -185.205624 90)
		(property "Reference" "C695"
			(at 4.198112 -1.736598 90)
			(unlocked yes)
			(layer "F.SilkS")
			(effects
				(font
					(size 0.7874 0.5842)
					(thickness 0.1524)
				)
				(justify left)
			)
		)
		(property "Value" ""
			(at 0 0 90)
			(layer "F.Fab")
			(effects
				(font
					(size 1.27 1.27)
				)
			)
		)
		(duplicate_pad_numbers_are_jumpers no)
		(fp_line
			(start 0.7874 -0.4064)
			(end 0.7874 0.4064)
			(stroke
				(width 0.1524)
				(type default)
			)
			(layer "F.SilkS")
		)
		(fp_line
			(start -0.7874 -0.4064)
			(end 0.7874 -0.4064)
			(stroke
				(width 0.1524)
				(type default)
			)
			(layer "F.SilkS")
		)
		(fp_line
			(start 0 0.381)
			(end 0 -0.381)
			(stroke
				(width 0.1524)
				(type default)
			)
			(layer "F.SilkS")
		)
		(fp_line
			(start 0.7874 0.4064)
			(end -0.7874 0.4064)
			(stroke
				(width 0.1524)
				(type default)
			)
			(layer "F.SilkS")
		)
		(fp_line
			(start -0.7874 0.4064)
			(end -0.7874 -0.4064)
			(stroke
				(width 0.1524)
				(type default)
			)
			(layer "F.SilkS")
		)
		(fp_poly
			(pts
				(xy -0.5334 0.254) (xy -0.635 0.254) (xy -0.635 0.2286) (xy -0.635 -0.254) (xy -0.5334 -0.254) (xy -0.5334 -0.2794)
				(xy 0.5334 -0.2794) (xy 0.5334 -0.254) (xy 0.635 -0.254) (xy 0.635 0.254) (xy 0.5334 0.254) (xy 0.5334 0.2794)
				(xy -0.508 0.2794) (xy -0.5334 0.2794)
			)
			(stroke
				(width 0)
				(type default)
			)
			(fill no)
			(layer "F.CrtYd")
		)
		(pad "1" smd rect
			(at 0.40005 0 90)
			(size 0.4572 0.508)
			(layers "F.Cu" "F.Mask" "F.Paste")
			(net "UART_T4_NODE1_RXD")
		)
		(pad "2" smd rect
			(at -0.40005 0 90)
			(size 0.4572 0.508)
			(layers "F.Cu" "F.Mask" "F.Paste")
			(net "GND")
		)
	)
	(footprint ""
		(layer "F.Cu")
		(at 106.426508 -176.965102 180)
		(property "Reference" "R735"
			(at 0.545338 3.08356 0)
			(unlocked yes)
			(layer "F.SilkS")
			(effects
				(font
					(size 0.7874 0.5842)
					(thickness 0.1524)
				)
				(justify left)
			)
		)
		(property "Value" ""
			(at 0 0 180)
			(layer "F.Fab")
			(effects
				(font
					(size 1.27 1.27)
				)
			)
		)
		(duplicate_pad_numbers_are_jumpers no)
		(fp_line
			(start 0.7874 0.4064)
			(end -0.7874 0.4064)
			(stroke
				(width 0.1524)
				(type default)
			)
			(layer "F.SilkS")
		)
		(fp_line
			(start 0.7874 -0.4064)
			(end 0.7874 0.4064)
			(stroke
				(width 0.1524)
				(type default)
			)
			(layer "F.SilkS")
		)
		(fp_line
			(start -0.7874 0.4064)
			(end -0.7874 -0.4064)
			(stroke
				(width 0.1524)
				(type default)
			)
			(layer "F.SilkS")
		)
		(fp_line
			(start -0.7874 -0.4064)
			(end 0.7874 -0.4064)
			(stroke
				(width 0.1524)
				(type default)
			)
			(layer "F.SilkS")
		)
		(fp_poly
			(pts
				(xy -0.508 0.2794) (xy -0.508 0.2286) (xy -0.635 0.2286) (xy -0.635 -0.254) (xy -0.5334 -0.254)
				(xy -0.5334 -0.2794) (xy 0.5334 -0.2794) (xy 0.5334 -0.254) (xy 0.635 -0.254) (xy 0.635 0.254) (xy 0.5334 0.254)
				(xy 0.5334 0.2794)
			)
			(stroke
				(width 0)
				(type default)
			)
			(fill no)
			(layer "F.CrtYd")
		)
		(pad "1" smd rect
			(at 0.40005 0 180)
			(size 0.4572 0.508)
			(layers "F.Cu" "F.Mask" "F.Paste")
			(net "N21700943")
		)
		(pad "2" smd rect
			(at -0.40005 0 180)
			(size 0.4572 0.508)
			(layers "F.Cu" "F.Mask" "F.Paste")
			(net "P3V3_NODE1")
		)
	)
	(footprint ""
		(layer "F.Cu")
		(at 150.055326 -41.881044 -90)
		(property "Reference" "R1011"
			(at -0.355346 -10.260076 90)
			(unlocked yes)
			(layer "F.SilkS")
			(effects
				(font
					(size 0.7874 0.5842)
					(thickness 0.1524)
				)
				(justify left)
			)
		)
		(property "Value" ""
			(at 0 0 270)
			(layer "F.Fab")
			(effects
				(font
					(size 1.27 1.27)
				)
			)
		)
		(duplicate_pad_numbers_are_jumpers no)
		(fp_line
			(start -0.7874 0.4064)
			(end -0.7874 -0.4064)
			(stroke
				(width 0.1524)
				(type default)
			)
			(layer "F.SilkS")
		)
		(fp_line
			(start 0.7874 0.4064)
			(end -0.7874 0.4064)
			(stroke
				(width 0.1524)
				(type default)
			)
			(layer "F.SilkS")
		)
		(fp_line
			(start -0.7874 -0.4064)
			(end 0.7874 -0.4064)
			(stroke
				(width 0.1524)
				(type default)
			)
			(layer "F.SilkS")
		)
		(fp_line
			(start 0.7874 -0.4064)
			(end 0.7874 0.4064)
			(stroke
				(width 0.1524)
				(type default)
			)
			(layer "F.SilkS")
		)
		(fp_poly
			(pts
				(xy -0.508 0.2794) (xy -0.508 0.2286) (xy -0.635 0.2286) (xy -0.635 -0.254) (xy -0.5334 -0.254)
				(xy -0.5334 -0.2794) (xy 0.5334 -0.2794) (xy 0.5334 -0.254) (xy 0.635 -0.254) (xy 0.635 0.254) (xy 0.5334 0.254)
				(xy 0.5334 0.2794)
			)
			(stroke
				(width 0)
				(type default)
			)
			(fill no)
			(layer "F.CrtYd")
		)
		(pad "1" smd rect
			(at 0.40005 0 270)
			(size 0.4572 0.508)
			(layers "F.Cu" "F.Mask" "F.Paste")
			(net "P5V_NODE1")
		)
		(pad "2" smd rect
			(at -0.40005 0 270)
			(size 0.4572 0.508)
			(layers "F.Cu" "F.Mask" "F.Paste")
			(net "UART_RTS_P1_N")
		)
	)
	(footprint ""
		(layer "F.Cu")
		(at 154.983688 -178.689254 -90)
		(property "Reference" "R1168"
			(at -1.157732 1.076198 90)
			(unlocked yes)
			(layer "F.SilkS")
			(effects
				(font
					(size 0.7874 0.5842)
					(thickness 0.1524)
				)
				(justify left)
			)
		)
		(property "Value" ""
			(at 0 0 270)
			(layer "F.Fab")
			(effects
				(font
					(size 1.27 1.27)
				)
			)
		)
		(duplicate_pad_numbers_are_jumpers no)
		(fp_line
			(start -0.7874 0.4064)
			(end -0.7874 -0.4064)
			(stroke
				(width 0.1524)
				(type default)
			)
			(layer "F.SilkS")
		)
		(fp_line
			(start 0.7874 0.4064)
			(end -0.7874 0.4064)
			(stroke
				(width 0.1524)
				(type default)
			)
			(layer "F.SilkS")
		)
		(fp_line
			(start -0.7874 -0.4064)
			(end 0.7874 -0.4064)
			(stroke
				(width 0.1524)
				(type default)
			)
			(layer "F.SilkS")
		)
		(fp_line
			(start 0.7874 -0.4064)
			(end 0.7874 0.4064)
			(stroke
				(width 0.1524)
				(type default)
			)
			(layer "F.SilkS")
		)
		(fp_poly
			(pts
				(xy -0.508 0.2794) (xy -0.508 0.2286) (xy -0.635 0.2286) (xy -0.635 -0.254) (xy -0.5334 -0.254)
				(xy -0.5334 -0.2794) (xy 0.5334 -0.2794) (xy 0.5334 -0.254) (xy 0.635 -0.254) (xy 0.635 0.254) (xy 0.5334 0.254)
				(xy 0.5334 0.2794)
			)
			(stroke
				(width 0)
				(type default)
			)
			(fill no)
			(layer "F.CrtYd")
		)
		(pad "1" smd rect
			(at 0.40005 0 270)
			(size 0.4572 0.508)
			(layers "F.Cu" "F.Mask" "F.Paste")
			(net "CPLD_UART_RX_P3")
		)
		(pad "2" smd rect
			(at -0.40005 0 270)
			(size 0.4572 0.508)
			(layers "F.Cu" "F.Mask" "F.Paste")
			(net "GND")
		)
	)
	(footprint ""
		(layer "F.Cu")
		(at 45.858684 -109.977936)
		(property "Reference" "PU2"
			(at 2.526538 2.727452 90)
			(unlocked yes)
			(layer "F.SilkS")
			(effects
				(font
					(size 0.7874 0.5842)
					(thickness 0.1524)
				)
				(justify left)
			)
		)
		(property "Value" ""
			(at 0 0 0)
			(layer "F.Fab")
			(effects
				(font
					(size 1.27 1.27)
				)
			)
		)
		(duplicate_pad_numbers_are_jumpers no)
		(fp_line
			(start -1.575054 -1.575054)
			(end -1.575054 -1.0414)
			(stroke
				(width 0.1524)
				(type default)
			)
			(layer "F.SilkS")
		)
		(fp_line
			(start -1.575054 1.0922)
			(end -1.575054 1.575054)
			(stroke
				(width 0.1524)
				(type default)
			)
			(layer "F.SilkS")
		)
		(fp_line
			(start -1.575054 1.575054)
			(end -1.0922 1.575054)
			(stroke
				(width 0.1524)
				(type default)
			)
			(layer "F.SilkS")
		)
		(fp_line
			(start -1.0668 -1.575054)
			(end -1.575054 -1.575054)
			(stroke
				(width 0.1524)
				(type default)
			)
			(layer "F.SilkS")
		)
		(fp_line
			(start -0.750062 2.043938)
			(end -0.750062 2.348738)
			(stroke
				(width 0.1524)
				(type default)
			)
			(layer "F.SilkS")
		)
		(fp_line
			(start -0.255778 -2.350262)
			(end -0.255778 -2.045462)
			(stroke
				(width 0.1524)
				(type default)
			)
			(layer "F.SilkS")
		)
		(fp_line
			(start 1.0414 1.575054)
			(end 1.575054 1.575054)
			(stroke
				(width 0.1524)
				(type default)
			)
			(layer "F.SilkS")
		)
		(fp_line
			(start 1.575054 -1.575054)
			(end 1.0414 -1.575054)
			(stroke
				(width 0.1524)
				(type default)
			)
			(layer "F.SilkS")
		)
		(fp_line
			(start 1.575054 -1.0668)
			(end 1.575054 -1.575054)
			(stroke
				(width 0.1524)
				(type default)
			)
			(layer "F.SilkS")
		)
		(fp_line
			(start 1.575054 1.575054)
			(end 1.575054 1.143)
			(stroke
				(width 0.1524)
				(type default)
			)
			(layer "F.SilkS")
		)
		(fp_line
			(start 2.055622 0.25019)
			(end 2.563622 0.25019)
			(stroke
				(width 0.1524)
				(type default)
			)
			(layer "F.SilkS")
		)
		(fp_poly
			(pts
				(xy -1.69291 -1.110742) (xy -2.230374 -2.18567) (xy -2.767584 -1.648206)
			)
			(stroke
				(width 0)
				(type default)
			)
			(fill yes)
			(layer "F.SilkS")
		)
		(fp_poly
			(pts
				(xy -1.575054 1.575054) (xy -0.9398 1.575054) (xy -0.9398 1.9558) (xy 0.9398 1.9558) (xy 0.9398 1.575054)
				(xy 1.575054 1.575054) (xy 1.575054 0.9398) (xy 1.9558 0.9398) (xy 1.9558 -0.9398) (xy 1.575054 -0.9398)
				(xy 1.575054 -1.575054) (xy 0.9398 -1.575054) (xy 0.9398 -1.9558) (xy -0.9398 -1.9558) (xy -0.9398 -1.575054)
				(xy -1.575054 -1.575054) (xy -1.575054 -0.9398) (xy -1.9558 -0.9398) (xy -1.9558 0.9398) (xy -1.575054 0.9398)
			)
			(stroke
				(width 0)
				(type default)
			)
			(fill no)
			(layer "F.CrtYd")
		)
		(fp_line
			(start -1.575054 -1.575054)
			(end 1.575054 -1.575054)
			(stroke
				(width 0.1)
				(type default)
			)
			(layer "F.Fab")
		)
		(fp_line
			(start -1.575054 1.575054)
			(end -1.575054 -1.575054)
			(stroke
				(width 0.1)
				(type default)
			)
			(layer "F.Fab")
		)
		(fp_line
			(start -0.750062 2.043938)
			(end -0.750062 2.348738)
			(stroke
				(width 0.1)
				(type default)
			)
			(layer "F.Fab")
		)
		(fp_line
			(start -0.255778 -2.350262)
			(end -0.255778 -2.045462)
			(stroke
				(width 0.1)
				(type default)
			)
			(layer "F.Fab")
		)
		(fp_line
			(start 1.575054 -1.575054)
			(end 1.575054 1.575054)
			(stroke
				(width 0.1)
				(type default)
			)
			(layer "F.Fab")
		)
		(fp_line
			(start 1.575054 1.575054)
			(end -1.575054 1.575054)
			(stroke
				(width 0.1)
				(type default)
			)
			(layer "F.Fab")
		)
		(fp_line
			(start 2.055622 0.25019)
			(end 2.563622 0.25019)
			(stroke
				(width 0.1)
				(type default)
			)
			(layer "F.Fab")
		)
		(fp_poly
			(pts
				(xy -2.100072 -0.750062) (xy -3.240024 -1.130046) (xy -3.240024 -0.370078)
			)
			(stroke
				(width 0)
				(type default)
			)
			(fill yes)
			(layer "F.Fab")
		)
		(fp_text user "16"
			(at -2.033016 -2.04343 0)
			(unlocked yes)
			(layer "F.SilkS")
			(effects
				(font
					(size 0.635 0.4064)
					(thickness 0.1524)
				)
				(justify left)
			)
		)
		(fp_text user "5"
			(at -1.452118 2.25171 0)
			(unlocked yes)
			(layer "F.SilkS")
			(effects
				(font
					(size 0.635 0.4064)
					(thickness 0.1524)
				)
				(justify left)
			)
		)
		(fp_text user "9"
			(at 1.508252 2.123186 0)
			(unlocked yes)
			(layer "F.SilkS")
			(effects
				(font
					(size 0.635 0.4064)
					(thickness 0.1524)
				)
				(justify left)
			)
		)
		(fp_text user "12"
			(at 1.616456 -1.820418 0)
			(unlocked yes)
			(layer "F.SilkS")
			(effects
				(font
					(size 0.635 0.4064)
					(thickness 0.1524)
				)
				(justify left)
			)
		)
		(fp_text user "16"
			(at -2.457958 -2.225675 0)
			(unlocked yes)
			(layer "F.Fab")
			(effects
				(font
					(size 0.78994 0.579882)
					(thickness 0.000001)
				)
				(justify left)
			)
		)
		(fp_text user "5"
			(at -1.737868 2.295525 0)
			(unlocked yes)
			(layer "F.Fab")
			(effects
				(font
					(size 0.78994 0.579882)
					(thickness 0.000001)
				)
				(justify left)
			)
		)
		(fp_text user "12"
			(at 1.708912 -1.514475 0)
			(unlocked yes)
			(layer "F.Fab")
			(effects
				(font
					(size 0.78994 0.579882)
					(thickness 0.000001)
				)
				(justify left)
			)
		)
		(fp_text user "9"
			(at 1.767586 1.584325 0)
			(unlocked yes)
			(layer "F.Fab")
			(effects
				(font
					(size 0.78994 0.579882)
					(thickness 0.000001)
				)
				(justify left)
			)
		)
		(pad "1" smd rect
			(at -1.474978 -0.750062 90)
			(size 0.254 0.8382)
			(layers "F.Cu" "F.Mask" "F.Paste")
			(net "P3V3_STB_NODE1_FB")
		)
		(pad "2" smd rect
			(at -1.474978 -0.249936 90)
			(size 0.254 0.8382)
			(layers "F.Cu" "F.Mask" "F.Paste")
			(net "P3V3_STB_NODE1_VREG5")
		)
		(pad "3" smd rect
			(at -1.474978 0.249936 90)
			(size 0.254 0.8382)
			(layers "F.Cu" "F.Mask" "F.Paste")
			(net "P3V3_STB_NODE1_SS")
		)
		(pad "4" smd rect
			(at -1.474978 0.750062 90)
			(size 0.254 0.8382)
			(layers "F.Cu" "F.Mask" "F.Paste")
			(net "GND")
		)
		(pad "5" smd rect
			(at -0.750062 1.474978)
			(size 0.254 0.8382)
			(layers "F.Cu" "F.Mask" "F.Paste")
			(net "PWRGD_NODE1_P3V3_STB_PG")
		)
		(pad "6" smd rect
			(at -0.249936 1.474978)
			(size 0.254 0.8382)
			(layers "F.Cu" "F.Mask" "F.Paste")
			(net "P3V3_STB_NODE1_EN")
		)
		(pad "7" smd rect
			(at 0.249936 1.474978)
			(size 0.254 0.8382)
			(layers "F.Cu" "F.Mask" "F.Paste")
			(net "GND")
		)
		(pad "8" smd rect
			(at 0.750062 1.474978)
			(size 0.254 0.8382)
			(layers "F.Cu" "F.Mask" "F.Paste")
			(net "GND")
		)
		(pad "9" smd rect
			(at 1.474978 0.750062 90)
			(size 0.254 0.8382)
			(layers "F.Cu" "F.Mask" "F.Paste")
			(net "SW_P3V3_STB_NODE1_PH")
		)
		(pad "10" smd rect
			(at 1.474978 0.249936 90)
			(size 0.254 0.8382)
			(layers "F.Cu" "F.Mask" "F.Paste")
			(net "SW_P3V3_STB_NODE1_PH")
		)
		(pad "11" smd rect
			(at 1.474978 -0.249936 90)
			(size 0.254 0.8382)
			(layers "F.Cu" "F.Mask" "F.Paste")
			(net "SW_P3V3_STB_NODE1_PH")
		)
		(pad "12" smd rect
			(at 1.474978 -0.750062 90)
			(size 0.254 0.8382)
			(layers "F.Cu" "F.Mask" "F.Paste")
			(net "SW_P3V3_STB_NODE1_BT")
		)
		(pad "13" smd rect
			(at 0.750062 -1.474978)
			(size 0.254 0.8382)
			(layers "F.Cu" "F.Mask" "F.Paste")
			(net "P12V_AUX")
		)
		(pad "14" smd rect
			(at 0.249936 -1.474978)
			(size 0.254 0.8382)
			(layers "F.Cu" "F.Mask" "F.Paste")
			(net "P12V_AUX")
		)
		(pad "15" smd rect
			(at -0.249936 -1.474978)
			(size 0.254 0.8382)
			(layers "F.Cu" "F.Mask" "F.Paste")
			(net "P5V_STB_NODE1")
		)
		(pad "16" smd rect
			(at -0.750062 -1.474978)
			(size 0.254 0.8382)
			(layers "F.Cu" "F.Mask" "F.Paste")
			(net "P3V3_STB_NODE1")
		)
		(pad "TH" smd rect
			(at 0 0 90)
			(size 1.7018 1.7018)
			(layers "F.Cu" "F.Mask" "F.Paste")
			(net "GND")
		)
		(zone
			(layer "F.Cu")
			(hatch none 0.5)
			(connect_pads
				(clearance 0)
			)
			(min_thickness 0.25)
			(keepout
				(tracks allowed)
				(vias not_allowed)
				(pads allowed)
				(copperpour not_allowed)
				(footprints allowed)
			)
			(placement
				(enabled no)
				(sheetname "")
			)
			(fill
				(thermal_gap 0.5)
				(thermal_bridge_width 0.5)
				(island_removal_mode 0)
			)
			(polygon
				(pts
					(xy 44.868084 -110.968536) (xy 46.849284 -110.968536) (xy 46.849284 -108.987336) (xy 44.868084 -108.987336)
					(xy 44.868084 -109.063536) (xy 46.773084 -109.063536) (xy 46.773084 -110.892336) (xy 44.944284 -110.892336)
					(xy 44.944284 -109.088936) (xy 44.868084 -109.088936)
				)
			)
		)
	)
	(footprint ""
		(layer "F.Cu")
		(at 170.765724 -133.640322 -90)
		(property "Reference" "R116"
			(at -7.610094 0.189992 90)
			(unlocked yes)
			(layer "F.SilkS")
			(effects
				(font
					(size 0.7874 0.5842)
					(thickness 0.1524)
				)
				(justify left)
			)
		)
		(property "Value" ""
			(at 0 0 270)
			(layer "F.Fab")
			(effects
				(font
					(size 1.27 1.27)
				)
			)
		)
		(duplicate_pad_numbers_are_jumpers no)
		(fp_line
			(start -0.7874 0.4064)
			(end -0.7874 -0.4064)
			(stroke
				(width 0.1524)
				(type default)
			)
			(layer "F.SilkS")
		)
		(fp_line
			(start 0.7874 0.4064)
			(end -0.7874 0.4064)
			(stroke
				(width 0.1524)
				(type default)
			)
			(layer "F.SilkS")
		)
		(fp_line
			(start -0.7874 -0.4064)
			(end 0.7874 -0.4064)
			(stroke
				(width 0.1524)
				(type default)
			)
			(layer "F.SilkS")
		)
		(fp_line
			(start 0.7874 -0.4064)
			(end 0.7874 0.4064)
			(stroke
				(width 0.1524)
				(type default)
			)
			(layer "F.SilkS")
		)
		(fp_poly
			(pts
				(xy -0.508 0.2794) (xy -0.508 0.2286) (xy -0.635 0.2286) (xy -0.635 -0.254) (xy -0.5334 -0.254)
				(xy -0.5334 -0.2794) (xy 0.5334 -0.2794) (xy 0.5334 -0.254) (xy 0.635 -0.254) (xy 0.635 0.254) (xy 0.5334 0.254)
				(xy 0.5334 0.2794)
			)
			(stroke
				(width 0)
				(type default)
			)
			(fill no)
			(layer "F.CrtYd")
		)
		(pad "1" smd rect
			(at 0.40005 0 270)
			(size 0.4572 0.508)
			(layers "F.Cu" "F.Mask" "F.Paste")
			(net "H_CPU_NODE1_THRMTRIP_L")
		)
		(pad "2" smd rect
			(at -0.40005 0 270)
			(size 0.4572 0.508)
			(layers "F.Cu" "F.Mask" "F.Paste")
			(net "P1V05_NODE1")
		)
	)
	(footprint ""
		(layer "F.Cu")
		(at 105.947718 -152.719278)
		(property "Reference" "PC42"
			(at -2.05486 4.649216 0)
			(unlocked yes)
			(layer "F.SilkS")
			(effects
				(font
					(size 0.635 0.4064)
					(thickness 0.1524)
				)
				(justify left)
			)
		)
		(property "Value" ""
			(at 0 0 0)
			(layer "F.Fab")
			(effects
				(font
					(size 1.27 1.27)
				)
			)
		)
		(duplicate_pad_numbers_are_jumpers no)
		(fp_line
			(start -0.7874 -0.4064)
			(end 0.7874 -0.4064)
			(stroke
				(width 0.1524)
				(type default)
			)
			(layer "F.SilkS")
		)
		(fp_line
			(start -0.7874 0.4064)
			(end -0.7874 -0.4064)
			(stroke
				(width 0.1524)
				(type default)
			)
			(layer "F.SilkS")
		)
		(fp_line
			(start 0 0.381)
			(end 0 -0.381)
			(stroke
				(width 0.1524)
				(type default)
			)
			(layer "F.SilkS")
		)
		(fp_line
			(start 0.7874 -0.4064)
			(end 0.7874 0.4064)
			(stroke
				(width 0.1524)
				(type default)
			)
			(layer "F.SilkS")
		)
		(fp_line
			(start 0.7874 0.4064)
			(end -0.7874 0.4064)
			(stroke
				(width 0.1524)
				(type default)
			)
			(layer "F.SilkS")
		)
		(fp_poly
			(pts
				(xy -0.5334 0.254) (xy -0.635 0.254) (xy -0.635 0.2286) (xy -0.635 -0.254) (xy -0.5334 -0.254) (xy -0.5334 -0.2794)
				(xy 0.5334 -0.2794) (xy 0.5334 -0.254) (xy 0.635 -0.254) (xy 0.635 0.254) (xy 0.5334 0.254) (xy 0.5334 0.2794)
				(xy -0.508 0.2794) (xy -0.5334 0.2794)
			)
			(stroke
				(width 0)
				(type default)
			)
			(fill no)
			(layer "F.CrtYd")
		)
		(pad "1" smd rect
			(at 0.40005 0)
			(size 0.4572 0.508)
			(layers "F.Cu" "F.Mask" "F.Paste")
			(net "P1V8_STB_NODE1_FB")
		)
		(pad "2" smd rect
			(at -0.40005 0)
			(size 0.4572 0.508)
			(layers "F.Cu" "F.Mask" "F.Paste")
			(net "P1V8_STB_NODE1")
		)
	)
	(footprint ""
		(layer "F.Cu")
		(at 62.291214 -148.121624 180)
		(property "Reference" "C264"
			(at 30.37078 7.27329 0)
			(unlocked yes)
			(layer "F.SilkS")
			(effects
				(font
					(size 0.7874 0.5842)
					(thickness 0.1524)
				)
				(justify left)
			)
		)
		(property "Value" ""
			(at 0 0 180)
			(layer "F.Fab")
			(effects
				(font
					(size 1.27 1.27)
				)
			)
		)
		(duplicate_pad_numbers_are_jumpers no)
		(fp_line
			(start 0.7874 0.4064)
			(end -0.7874 0.4064)
			(stroke
				(width 0.1524)
				(type default)
			)
			(layer "F.SilkS")
		)
		(fp_line
			(start 0.7874 -0.4064)
			(end 0.7874 0.4064)
			(stroke
				(width 0.1524)
				(type default)
			)
			(layer "F.SilkS")
		)
		(fp_line
			(start 0 0.381)
			(end 0 -0.381)
			(stroke
				(width 0.1524)
				(type default)
			)
			(layer "F.SilkS")
		)
		(fp_line
			(start -0.7874 0.4064)
			(end -0.7874 -0.4064)
			(stroke
				(width 0.1524)
				(type default)
			)
			(layer "F.SilkS")
		)
		(fp_line
			(start -0.7874 -0.4064)
			(end 0.7874 -0.4064)
			(stroke
				(width 0.1524)
				(type default)
			)
			(layer "F.SilkS")
		)
		(fp_poly
			(pts
				(xy -0.5334 0.254) (xy -0.635 0.254) (xy -0.635 0.2286) (xy -0.635 -0.254) (xy -0.5334 -0.254) (xy -0.5334 -0.2794)
				(xy 0.5334 -0.2794) (xy 0.5334 -0.254) (xy 0.635 -0.254) (xy 0.635 0.254) (xy 0.5334 0.254) (xy 0.5334 0.2794)
				(xy -0.508 0.2794) (xy -0.5334 0.2794)
			)
			(stroke
				(width 0)
				(type default)
			)
			(fill no)
			(layer "F.CrtYd")
		)
		(pad "1" smd rect
			(at 0.40005 0 180)
			(size 0.4572 0.508)
			(layers "F.Cu" "F.Mask" "F.Paste")
			(net "BMC_NODE1_DACAV33")
		)
		(pad "2" smd rect
			(at -0.40005 0 180)
			(size 0.4572 0.508)
			(layers "F.Cu" "F.Mask" "F.Paste")
			(net "GND")
		)
	)
	(footprint ""
		(layer "F.Cu")
		(at 58.216546 -161.928556 90)
		(property "Reference" "R547"
			(at -1.333754 12.174728 90)
			(unlocked yes)
			(layer "F.SilkS")
			(effects
				(font
					(size 0.7874 0.5842)
					(thickness 0.1524)
				)
				(justify left)
			)
		)
		(property "Value" ""
			(at 0 0 90)
			(layer "F.Fab")
			(effects
				(font
					(size 1.27 1.27)
				)
			)
		)
		(duplicate_pad_numbers_are_jumpers no)
		(fp_line
			(start 0.7874 -0.4064)
			(end 0.7874 0.4064)
			(stroke
				(width 0.1524)
				(type default)
			)
			(layer "F.SilkS")
		)
		(fp_line
			(start -0.7874 -0.4064)
			(end 0.7874 -0.4064)
			(stroke
				(width 0.1524)
				(type default)
			)
			(layer "F.SilkS")
		)
		(fp_line
			(start 0.7874 0.4064)
			(end -0.7874 0.4064)
			(stroke
				(width 0.1524)
				(type default)
			)
			(layer "F.SilkS")
		)
		(fp_line
			(start -0.7874 0.4064)
			(end -0.7874 -0.4064)
			(stroke
				(width 0.1524)
				(type default)
			)
			(layer "F.SilkS")
		)
		(fp_poly
			(pts
				(xy -0.508 0.2794) (xy -0.508 0.2286) (xy -0.635 0.2286) (xy -0.635 -0.254) (xy -0.5334 -0.254)
				(xy -0.5334 -0.2794) (xy 0.5334 -0.2794) (xy 0.5334 -0.254) (xy 0.635 -0.254) (xy 0.635 0.254) (xy 0.5334 0.254)
				(xy 0.5334 0.2794)
			)
			(stroke
				(width 0)
				(type default)
			)
			(fill no)
			(layer "F.CrtYd")
		)
		(pad "1" smd rect
			(at 0.40005 0 90)
			(size 0.4572 0.508)
			(layers "F.Cu" "F.Mask" "F.Paste")
			(net "SPI_LAN1_NVM_SI")
		)
		(pad "2" smd rect
			(at -0.40005 0 90)
			(size 0.4572 0.508)
			(layers "F.Cu" "F.Mask" "F.Paste")
			(net "LAN1_NVM_SI_R")
		)
	)
	(footprint ""
		(layer "F.Cu")
		(at 128.25857 -26.569416 -90)
		(property "Reference" "R1142"
			(at 5.325618 -0.028448 90)
			(unlocked yes)
			(layer "F.SilkS")
			(effects
				(font
					(size 0.7874 0.5842)
					(thickness 0.1524)
				)
				(justify left)
			)
		)
		(property "Value" ""
			(at 0 0 270)
			(layer "F.Fab")
			(effects
				(font
					(size 1.27 1.27)
				)
			)
		)
		(duplicate_pad_numbers_are_jumpers no)
		(fp_line
			(start -0.7874 0.4064)
			(end -0.7874 -0.4064)
			(stroke
				(width 0.1524)
				(type default)
			)
			(layer "F.SilkS")
		)
		(fp_line
			(start 0.7874 0.4064)
			(end -0.7874 0.4064)
			(stroke
				(width 0.1524)
				(type default)
			)
			(layer "F.SilkS")
		)
		(fp_line
			(start -0.7874 -0.4064)
			(end 0.7874 -0.4064)
			(stroke
				(width 0.1524)
				(type default)
			)
			(layer "F.SilkS")
		)
		(fp_line
			(start 0.7874 -0.4064)
			(end 0.7874 0.4064)
			(stroke
				(width 0.1524)
				(type default)
			)
			(layer "F.SilkS")
		)
		(fp_poly
			(pts
				(xy -0.508 0.2794) (xy -0.508 0.2286) (xy -0.635 0.2286) (xy -0.635 -0.254) (xy -0.5334 -0.254)
				(xy -0.5334 -0.2794) (xy 0.5334 -0.2794) (xy 0.5334 -0.254) (xy 0.635 -0.254) (xy 0.635 0.254) (xy 0.5334 0.254)
				(xy 0.5334 0.2794)
			)
			(stroke
				(width 0)
				(type default)
			)
			(fill no)
			(layer "F.CrtYd")
		)
		(pad "1" smd rect
			(at 0.40005 0 270)
			(size 0.4572 0.508)
			(layers "F.Cu" "F.Mask" "F.Paste")
			(net "P3V3_STB_NODE1")
		)
		(pad "2" smd rect
			(at -0.40005 0 270)
			(size 0.4572 0.508)
			(layers "F.Cu" "F.Mask" "F.Paste")
			(net "SIO_PIN75")
		)
	)
	(footprint ""
		(layer "F.Cu")
		(at 166.70782 -123.76531 180)
		(property "Reference" "R1031"
			(at 2.79019 -9.851644 0)
			(unlocked yes)
			(layer "F.SilkS")
			(effects
				(font
					(size 0.7874 0.5842)
					(thickness 0.1524)
				)
				(justify left)
			)
		)
		(property "Value" ""
			(at 0 0 180)
			(layer "F.Fab")
			(effects
				(font
					(size 1.27 1.27)
				)
			)
		)
		(duplicate_pad_numbers_are_jumpers no)
		(fp_line
			(start 0.7874 0.4064)
			(end -0.7874 0.4064)
			(stroke
				(width 0.1524)
				(type default)
			)
			(layer "F.SilkS")
		)
		(fp_line
			(start 0.7874 -0.4064)
			(end 0.7874 0.4064)
			(stroke
				(width 0.1524)
				(type default)
			)
			(layer "F.SilkS")
		)
		(fp_line
			(start -0.7874 0.4064)
			(end -0.7874 -0.4064)
			(stroke
				(width 0.1524)
				(type default)
			)
			(layer "F.SilkS")
		)
		(fp_line
			(start -0.7874 -0.4064)
			(end 0.7874 -0.4064)
			(stroke
				(width 0.1524)
				(type default)
			)
			(layer "F.SilkS")
		)
		(fp_poly
			(pts
				(xy -0.508 0.2794) (xy -0.508 0.2286) (xy -0.635 0.2286) (xy -0.635 -0.254) (xy -0.5334 -0.254)
				(xy -0.5334 -0.2794) (xy 0.5334 -0.2794) (xy 0.5334 -0.254) (xy 0.635 -0.254) (xy 0.635 0.254) (xy 0.5334 0.254)
				(xy 0.5334 0.2794)
			)
			(stroke
				(width 0)
				(type default)
			)
			(fill no)
			(layer "F.CrtYd")
		)
		(pad "1" smd rect
			(at 0.40005 0 180)
			(size 0.4572 0.508)
			(layers "F.Cu" "F.Mask" "F.Paste")
			(net "P3V3_STB_NODE1")
		)
		(pad "2" smd rect
			(at -0.40005 0 180)
			(size 0.4572 0.508)
			(layers "F.Cu" "F.Mask" "F.Paste")
			(net "LED_PWR_NODE1_L")
		)
	)
	(footprint ""
		(layer "F.Cu")
		(at 28.498546 -98.546412)
		(property "Reference" "R180"
			(at 1.778254 0.367284 0)
			(unlocked yes)
			(layer "F.SilkS")
			(effects
				(font
					(size 0.7874 0.5842)
					(thickness 0.1524)
				)
				(justify left)
			)
		)
		(property "Value" ""
			(at 0 0 0)
			(layer "F.Fab")
			(effects
				(font
					(size 1.27 1.27)
				)
			)
		)
		(duplicate_pad_numbers_are_jumpers no)
		(fp_line
			(start -0.7874 -0.4064)
			(end 0.7874 -0.4064)
			(stroke
				(width 0.1524)
				(type default)
			)
			(layer "F.SilkS")
		)
		(fp_line
			(start -0.7874 0.4064)
			(end -0.7874 -0.4064)
			(stroke
				(width 0.1524)
				(type default)
			)
			(layer "F.SilkS")
		)
		(fp_line
			(start 0.7874 -0.4064)
			(end 0.7874 0.4064)
			(stroke
				(width 0.1524)
				(type default)
			)
			(layer "F.SilkS")
		)
		(fp_line
			(start 0.7874 0.4064)
			(end -0.7874 0.4064)
			(stroke
				(width 0.1524)
				(type default)
			)
			(layer "F.SilkS")
		)
		(fp_poly
			(pts
				(xy -0.508 0.2794) (xy -0.508 0.2286) (xy -0.635 0.2286) (xy -0.635 -0.254) (xy -0.5334 -0.254)
				(xy -0.5334 -0.2794) (xy 0.5334 -0.2794) (xy 0.5334 -0.254) (xy 0.635 -0.254) (xy 0.635 0.254) (xy 0.5334 0.254)
				(xy 0.5334 0.2794)
			)
			(stroke
				(width 0)
				(type default)
			)
			(fill no)
			(layer "F.CrtYd")
		)
		(pad "1" smd rect
			(at 0.40005 0)
			(size 0.4572 0.508)
			(layers "F.Cu" "F.Mask" "F.Paste")
			(net "P3V3_NODE1")
		)
		(pad "2" smd rect
			(at -0.40005 0)
			(size 0.4572 0.508)
			(layers "F.Cu" "F.Mask" "F.Paste")
			(net "FRU_SYS_A0")
		)
	)
	(footprint ""
		(layer "F.Cu")
		(at 141.08176 -185.205624 -90)
		(property "Reference" "R873"
			(at -4.768088 0.535432 90)
			(unlocked yes)
			(layer "F.SilkS")
			(effects
				(font
					(size 0.7874 0.5842)
					(thickness 0.1524)
				)
				(justify left)
			)
		)
		(property "Value" ""
			(at 0 0 270)
			(layer "F.Fab")
			(effects
				(font
					(size 1.27 1.27)
				)
			)
		)
		(duplicate_pad_numbers_are_jumpers no)
		(fp_line
			(start -0.7874 0.4064)
			(end -0.7874 -0.4064)
			(stroke
				(width 0.1524)
				(type default)
			)
			(layer "F.SilkS")
		)
		(fp_line
			(start 0.7874 0.4064)
			(end -0.7874 0.4064)
			(stroke
				(width 0.1524)
				(type default)
			)
			(layer "F.SilkS")
		)
		(fp_line
			(start -0.7874 -0.4064)
			(end 0.7874 -0.4064)
			(stroke
				(width 0.1524)
				(type default)
			)
			(layer "F.SilkS")
		)
		(fp_line
			(start 0.7874 -0.4064)
			(end 0.7874 0.4064)
			(stroke
				(width 0.1524)
				(type default)
			)
			(layer "F.SilkS")
		)
		(fp_poly
			(pts
				(xy -0.508 0.2794) (xy -0.508 0.2286) (xy -0.635 0.2286) (xy -0.635 -0.254) (xy -0.5334 -0.254)
				(xy -0.5334 -0.2794) (xy 0.5334 -0.2794) (xy 0.5334 -0.254) (xy 0.635 -0.254) (xy 0.635 0.254) (xy 0.5334 0.254)
				(xy 0.5334 0.2794)
			)
			(stroke
				(width 0)
				(type default)
			)
			(fill no)
			(layer "F.CrtYd")
		)
		(pad "1" smd rect
			(at 0.40005 0 270)
			(size 0.4572 0.508)
			(layers "F.Cu" "F.Mask" "F.Paste")
			(net "T10_NODE1_EN")
		)
		(pad "2" smd rect
			(at -0.40005 0 270)
			(size 0.4572 0.508)
			(layers "F.Cu" "F.Mask" "F.Paste")
			(net "T10_NODE1_EN_R")
		)
	)
	(footprint ""
		(layer "F.Cu")
		(at 162.143694 -129.85242)
		(property "Reference" "D21"
			(at 2.934716 1.07442 0)
			(unlocked yes)
			(layer "F.SilkS")
			(effects
				(font
					(size 0.7874 0.5842)
					(thickness 0.1524)
				)
				(justify left)
			)
		)
		(property "Value" ""
			(at 0 0 0)
			(layer "F.Fab")
			(effects
				(font
					(size 1.27 1.27)
				)
			)
		)
		(duplicate_pad_numbers_are_jumpers no)
		(fp_line
			(start -1.3208 -0.5588)
			(end 1.3208 -0.5588)
			(stroke
				(width 0.1524)
				(type default)
			)
			(layer "F.SilkS")
		)
		(fp_line
			(start -1.3208 0.5588)
			(end -1.3208 -0.5588)
			(stroke
				(width 0.1524)
				(type default)
			)
			(layer "F.SilkS")
		)
		(fp_line
			(start 1.3208 -0.5588)
			(end 1.3208 0.5588)
			(stroke
				(width 0.1524)
				(type default)
			)
			(layer "F.SilkS")
		)
		(fp_line
			(start 1.3208 0.5588)
			(end -1.3208 0.5588)
			(stroke
				(width 0.1524)
				(type default)
			)
			(layer "F.SilkS")
		)
		(fp_line
			(start 1.4732 -0.5588)
			(end 1.4732 0.5588)
			(stroke
				(width 0.1524)
				(type default)
			)
			(layer "F.SilkS")
		)
		(fp_line
			(start 1.6256 0.5588)
			(end 1.6256 -0.5588)
			(stroke
				(width 0.1524)
				(type default)
			)
			(layer "F.SilkS")
		)
		(fp_line
			(start 1.778 -0.5588)
			(end 1.3208 -0.5588)
			(stroke
				(width 0.1524)
				(type default)
			)
			(layer "F.SilkS")
		)
		(fp_line
			(start 1.778 -0.5588)
			(end 1.778 0.5588)
			(stroke
				(width 0.1524)
				(type default)
			)
			(layer "F.SilkS")
		)
		(fp_line
			(start 1.778 0.5588)
			(end 1.3208 0.5588)
			(stroke
				(width 0.1524)
				(type default)
			)
			(layer "F.SilkS")
		)
		(fp_circle
			(center 2.50952 0.72898)
			(end 2.923032 0.72898)
			(stroke
				(width 0.1524)
				(type default)
			)
			(fill no)
			(layer "F.SilkS")
		)
		(fp_rect
			(start -1.1684 0.508)
			(end 1.1684 -0.508)
			(stroke
				(width 0)
				(type default)
			)
			(fill no)
			(layer "F.CrtYd")
		)
		(pad "A" smd rect
			(at -0.750062 0)
			(size 0.8128 0.8128)
			(layers "F.Cu" "F.Mask" "F.Paste")
			(net "LED_CPU_NODE1_CPLD_D")
		)
		(pad "C" smd rect
			(at 0.750062 0)
			(size 0.8128 0.8128)
			(layers "F.Cu" "F.Mask" "F.Paste")
			(net "LED_CPU_NODE1_CPLD")
		)
	)
	(footprint ""
		(layer "F.Cu")
		(at 60.352686 -118.910862 90)
		(property "Reference" "R317"
			(at -5.140706 0.75184 90)
			(unlocked yes)
			(layer "F.SilkS")
			(effects
				(font
					(size 0.7874 0.5842)
					(thickness 0.1524)
				)
				(justify left)
			)
		)
		(property "Value" ""
			(at 0 0 90)
			(layer "F.Fab")
			(effects
				(font
					(size 1.27 1.27)
				)
			)
		)
		(duplicate_pad_numbers_are_jumpers no)
		(fp_line
			(start 0.7874 -0.4064)
			(end 0.7874 0.4064)
			(stroke
				(width 0.1524)
				(type default)
			)
			(layer "F.SilkS")
		)
		(fp_line
			(start -0.7874 -0.4064)
			(end 0.7874 -0.4064)
			(stroke
				(width 0.1524)
				(type default)
			)
			(layer "F.SilkS")
		)
		(fp_line
			(start 0.7874 0.4064)
			(end -0.7874 0.4064)
			(stroke
				(width 0.1524)
				(type default)
			)
			(layer "F.SilkS")
		)
		(fp_line
			(start -0.7874 0.4064)
			(end -0.7874 -0.4064)
			(stroke
				(width 0.1524)
				(type default)
			)
			(layer "F.SilkS")
		)
		(fp_poly
			(pts
				(xy -0.508 0.2794) (xy -0.508 0.2286) (xy -0.635 0.2286) (xy -0.635 -0.254) (xy -0.5334 -0.254)
				(xy -0.5334 -0.2794) (xy 0.5334 -0.2794) (xy 0.5334 -0.254) (xy 0.635 -0.254) (xy 0.635 0.254) (xy 0.5334 0.254)
				(xy 0.5334 0.2794)
			)
			(stroke
				(width 0)
				(type default)
			)
			(fill no)
			(layer "F.CrtYd")
		)
		(pad "1" smd rect
			(at 0.40005 0 90)
			(size 0.4572 0.508)
			(layers "F.Cu" "F.Mask" "F.Paste")
			(net "P3V3_NODE1")
		)
		(pad "2" smd rect
			(at -0.40005 0 90)
			(size 0.4572 0.508)
			(layers "F.Cu" "F.Mask" "F.Paste")
			(net "BMC_ROMA1")
		)
	)
	(footprint ""
		(layer "F.Cu")
		(at 154.542998 -142.88643 -90)
		(property "Reference" "R592"
			(at -1.289304 -0.58801 90)
			(unlocked yes)
			(layer "F.SilkS")
			(effects
				(font
					(size 0.7874 0.5842)
					(thickness 0.1524)
				)
				(justify left)
			)
		)
		(property "Value" ""
			(at 0 0 270)
			(layer "F.Fab")
			(effects
				(font
					(size 1.27 1.27)
				)
			)
		)
		(duplicate_pad_numbers_are_jumpers no)
		(fp_line
			(start -0.7874 0.4064)
			(end -0.7874 -0.4064)
			(stroke
				(width 0.1524)
				(type default)
			)
			(layer "F.SilkS")
		)
		(fp_line
			(start 0.7874 0.4064)
			(end -0.7874 0.4064)
			(stroke
				(width 0.1524)
				(type default)
			)
			(layer "F.SilkS")
		)
		(fp_line
			(start -0.7874 -0.4064)
			(end 0.7874 -0.4064)
			(stroke
				(width 0.1524)
				(type default)
			)
			(layer "F.SilkS")
		)
		(fp_line
			(start 0.7874 -0.4064)
			(end 0.7874 0.4064)
			(stroke
				(width 0.1524)
				(type default)
			)
			(layer "F.SilkS")
		)
		(fp_poly
			(pts
				(xy -0.508 0.2794) (xy -0.508 0.2286) (xy -0.635 0.2286) (xy -0.635 -0.254) (xy -0.5334 -0.254)
				(xy -0.5334 -0.2794) (xy 0.5334 -0.2794) (xy 0.5334 -0.254) (xy 0.635 -0.254) (xy 0.635 0.254) (xy 0.5334 0.254)
				(xy 0.5334 0.2794)
			)
			(stroke
				(width 0)
				(type default)
			)
			(fill no)
			(layer "F.CrtYd")
		)
		(pad "1" smd rect
			(at 0.40005 0 270)
			(size 0.4572 0.508)
			(layers "F.Cu" "F.Mask" "F.Paste")
			(net "SMB_PCH_SDA")
		)
		(pad "2" smd rect
			(at -0.40005 0 270)
			(size 0.4572 0.508)
			(layers "F.Cu" "F.Mask" "F.Paste")
			(net "SMB_LAN2_DAT")
		)
	)
	(footprint ""
		(layer "F.Cu")
		(at 148.058632 -141.02969 180)
		(property "Reference" "R309"
			(at -1.545336 -0.942848 0)
			(unlocked yes)
			(layer "F.SilkS")
			(effects
				(font
					(size 0.635 0.4064)
					(thickness 0.1524)
				)
				(justify left)
			)
		)
		(property "Value" ""
			(at 0 0 180)
			(layer "F.Fab")
			(effects
				(font
					(size 1.27 1.27)
				)
			)
		)
		(duplicate_pad_numbers_are_jumpers no)
		(fp_line
			(start 0.7874 0.4064)
			(end -0.7874 0.4064)
			(stroke
				(width 0.1524)
				(type default)
			)
			(layer "F.SilkS")
		)
		(fp_line
			(start 0.7874 -0.4064)
			(end 0.7874 0.4064)
			(stroke
				(width 0.1524)
				(type default)
			)
			(layer "F.SilkS")
		)
		(fp_line
			(start -0.7874 0.4064)
			(end -0.7874 -0.4064)
			(stroke
				(width 0.1524)
				(type default)
			)
			(layer "F.SilkS")
		)
		(fp_line
			(start -0.7874 -0.4064)
			(end 0.7874 -0.4064)
			(stroke
				(width 0.1524)
				(type default)
			)
			(layer "F.SilkS")
		)
		(fp_poly
			(pts
				(xy -0.508 0.2794) (xy -0.508 0.2286) (xy -0.635 0.2286) (xy -0.635 -0.254) (xy -0.5334 -0.254)
				(xy -0.5334 -0.2794) (xy 0.5334 -0.2794) (xy 0.5334 -0.254) (xy 0.635 -0.254) (xy 0.635 0.254) (xy 0.5334 0.254)
				(xy 0.5334 0.2794)
			)
			(stroke
				(width 0)
				(type default)
			)
			(fill no)
			(layer "F.CrtYd")
		)
		(pad "1" smd rect
			(at 0.40005 0 180)
			(size 0.4572 0.508)
			(layers "F.Cu" "F.Mask" "F.Paste")
			(net "PCIE_SW_I2C_SCL")
		)
		(pad "2" smd rect
			(at -0.40005 0 180)
			(size 0.4572 0.508)
			(layers "F.Cu" "F.Mask" "F.Paste")
			(net "P3V3_NODE1")
		)
	)
	(footprint ""
		(layer "F.Cu")
		(at 155.989528 -133.849618 180)
		(property "Reference" "C802"
			(at 5.089652 -0.688594 0)
			(unlocked yes)
			(layer "F.SilkS")
			(effects
				(font
					(size 0.7874 0.5842)
					(thickness 0.1524)
				)
				(justify left)
			)
		)
		(property "Value" ""
			(at 0 0 180)
			(layer "F.Fab")
			(effects
				(font
					(size 1.27 1.27)
				)
			)
		)
		(duplicate_pad_numbers_are_jumpers no)
		(fp_line
			(start 1.905 0.8636)
			(end -1.905 0.8636)
			(stroke
				(width 0.1524)
				(type default)
			)
			(layer "F.SilkS")
		)
		(fp_line
			(start 1.905 -0.8636)
			(end 1.905 0.8636)
			(stroke
				(width 0.1524)
				(type default)
			)
			(layer "F.SilkS")
		)
		(fp_line
			(start 0 0.8382)
			(end 0 -0.8382)
			(stroke
				(width 0.1524)
				(type default)
			)
			(layer "F.SilkS")
		)
		(fp_line
			(start -1.905 0.8636)
			(end -1.905 -0.8636)
			(stroke
				(width 0.1524)
				(type default)
			)
			(layer "F.SilkS")
		)
		(fp_line
			(start -1.905 -0.8636)
			(end 1.905 -0.8636)
			(stroke
				(width 0.1524)
				(type default)
			)
			(layer "F.SilkS")
		)
		(fp_rect
			(start -1.524 0.7366)
			(end 1.524 -0.7366)
			(stroke
				(width 0)
				(type default)
			)
			(fill no)
			(layer "F.CrtYd")
		)
		(pad "1" smd rect
			(at 0.94996 0 180)
			(size 1.1176 1.3716)
			(layers "F.Cu" "F.Mask" "F.Paste")
			(net "RST_BTN_NODE1_C_L")
		)
		(pad "2" smd rect
			(at -0.94996 0 180)
			(size 1.1176 1.3716)
			(layers "F.Cu" "F.Mask" "F.Paste")
			(net "GND")
		)
	)
	(footprint ""
		(layer "F.Cu")
		(at 133.71576 -108.370624 90)
		(property "Reference" "R11"
			(at -6.585204 0.466852 90)
			(unlocked yes)
			(layer "F.SilkS")
			(effects
				(font
					(size 0.7874 0.5842)
					(thickness 0.1524)
				)
				(justify left)
			)
		)
		(property "Value" ""
			(at 0 0 90)
			(layer "F.Fab")
			(effects
				(font
					(size 1.27 1.27)
				)
			)
		)
		(duplicate_pad_numbers_are_jumpers no)
		(fp_line
			(start 0.7874 -0.4064)
			(end 0.7874 0.4064)
			(stroke
				(width 0.1524)
				(type default)
			)
			(layer "F.SilkS")
		)
		(fp_line
			(start -0.7874 -0.4064)
			(end 0.7874 -0.4064)
			(stroke
				(width 0.1524)
				(type default)
			)
			(layer "F.SilkS")
		)
		(fp_line
			(start 0.7874 0.4064)
			(end -0.7874 0.4064)
			(stroke
				(width 0.1524)
				(type default)
			)
			(layer "F.SilkS")
		)
		(fp_line
			(start -0.7874 0.4064)
			(end -0.7874 -0.4064)
			(stroke
				(width 0.1524)
				(type default)
			)
			(layer "F.SilkS")
		)
		(fp_poly
			(pts
				(xy -0.508 0.2794) (xy -0.508 0.2286) (xy -0.635 0.2286) (xy -0.635 -0.254) (xy -0.5334 -0.254)
				(xy -0.5334 -0.2794) (xy 0.5334 -0.2794) (xy 0.5334 -0.254) (xy 0.635 -0.254) (xy 0.635 0.254) (xy 0.5334 0.254)
				(xy 0.5334 0.2794)
			)
			(stroke
				(width 0)
				(type default)
			)
			(fill no)
			(layer "F.CrtYd")
		)
		(pad "1" smd rect
			(at 0.40005 0 90)
			(size 0.4572 0.508)
			(layers "F.Cu" "F.Mask" "F.Paste")
			(net "CLP_ITP_EN_NODE1")
		)
		(pad "2" smd rect
			(at -0.40005 0 90)
			(size 0.4572 0.508)
			(layers "F.Cu" "F.Mask" "F.Paste")
			(net "P3V3_CLK_NODE1")
		)
	)
	(footprint ""
		(layer "F.Cu")
		(at 155.999688 -178.689254 -90)
		(property "Reference" "R1167"
			(at -1.69926 -1.103884 90)
			(unlocked yes)
			(layer "F.SilkS")
			(effects
				(font
					(size 0.7874 0.5842)
					(thickness 0.1524)
				)
				(justify left)
			)
		)
		(property "Value" ""
			(at 0 0 270)
			(layer "F.Fab")
			(effects
				(font
					(size 1.27 1.27)
				)
			)
		)
		(duplicate_pad_numbers_are_jumpers no)
		(fp_line
			(start -0.7874 0.406146)
			(end -0.7874 -0.406146)
			(stroke
				(width 0.1524)
				(type default)
			)
			(layer "F.SilkS")
		)
		(fp_line
			(start 0.7874 0.406146)
			(end -0.7874 0.406146)
			(stroke
				(width 0.1524)
				(type default)
			)
			(layer "F.SilkS")
		)
		(fp_line
			(start -0.7874 -0.406146)
			(end 0.7874 -0.406146)
			(stroke
				(width 0.1524)
				(type default)
			)
			(layer "F.SilkS")
		)
		(fp_line
			(start 0.7874 -0.406146)
			(end 0.7874 0.406146)
			(stroke
				(width 0.1524)
				(type default)
			)
			(layer "F.SilkS")
		)
		(fp_poly
			(pts
				(xy -0.508 0.2794) (xy -0.508 0.2286) (xy -0.635 0.2286) (xy -0.635 -0.254) (xy -0.5334 -0.254)
				(xy -0.5334 -0.2794) (xy 0.5334 -0.2794) (xy 0.5334 -0.254) (xy 0.635 -0.254) (xy 0.635 0.254) (xy 0.5334 0.254)
				(xy 0.5334 0.2794)
			)
			(stroke
				(width 0)
				(type default)
			)
			(fill no)
			(layer "F.CrtYd")
		)
		(pad "1" smd rect
			(at 0.40005 0 270)
			(size 0.4572 0.508)
			(layers "F.Cu" "F.Mask" "F.Paste")
			(net "CPLD_UART_RX_P3_R")
		)
		(pad "2" smd rect
			(at -0.40005 0 270)
			(size 0.4572 0.508)
			(layers "F.Cu" "F.Mask" "F.Paste")
			(net "CPLD_UART_RX_P3")
		)
	)
	(footprint ""
		(layer "F.Cu")
		(at 136.125966 -55.324502 90)
		(property "Reference" "R1135"
			(at 0.936498 -0.260096 90)
			(unlocked yes)
			(layer "F.SilkS")
			(effects
				(font
					(size 0.7874 0.5842)
					(thickness 0.1524)
				)
				(justify left)
			)
		)
		(property "Value" ""
			(at 0 0 90)
			(layer "F.Fab")
			(effects
				(font
					(size 1.27 1.27)
				)
			)
		)
		(duplicate_pad_numbers_are_jumpers no)
		(fp_line
			(start 0.7874 -0.4064)
			(end 0.7874 0.4064)
			(stroke
				(width 0.1524)
				(type default)
			)
			(layer "F.SilkS")
		)
		(fp_line
			(start -0.7874 -0.4064)
			(end 0.7874 -0.4064)
			(stroke
				(width 0.1524)
				(type default)
			)
			(layer "F.SilkS")
		)
		(fp_line
			(start 0.7874 0.4064)
			(end -0.7874 0.4064)
			(stroke
				(width 0.1524)
				(type default)
			)
			(layer "F.SilkS")
		)
		(fp_line
			(start -0.7874 0.4064)
			(end -0.7874 -0.4064)
			(stroke
				(width 0.1524)
				(type default)
			)
			(layer "F.SilkS")
		)
		(fp_poly
			(pts
				(xy -0.508 0.2794) (xy -0.508 0.2286) (xy -0.635 0.2286) (xy -0.635 -0.254) (xy -0.5334 -0.254)
				(xy -0.5334 -0.2794) (xy 0.5334 -0.2794) (xy 0.5334 -0.254) (xy 0.635 -0.254) (xy 0.635 0.254) (xy 0.5334 0.254)
				(xy 0.5334 0.2794)
			)
			(stroke
				(width 0)
				(type default)
			)
			(fill no)
			(layer "F.CrtYd")
		)
		(pad "1" smd rect
			(at 0.40005 0 90)
			(size 0.4572 0.508)
			(layers "F.Cu" "F.Mask" "F.Paste")
			(net "GND")
		)
		(pad "2" smd rect
			(at -0.40005 0 90)
			(size 0.4572 0.508)
			(layers "F.Cu" "F.Mask" "F.Paste")
			(net "UART_TX_P3_R")
		)
	)
	(footprint ""
		(layer "F.Cu")
		(at 88.24976 -185.205624 -90)
		(property "Reference" "R948"
			(at -4.198112 2.110486 90)
			(unlocked yes)
			(layer "F.SilkS")
			(effects
				(font
					(size 0.7874 0.5842)
					(thickness 0.1524)
				)
				(justify left)
			)
		)
		(property "Value" ""
			(at 0 0 270)
			(layer "F.Fab")
			(effects
				(font
					(size 1.27 1.27)
				)
			)
		)
		(duplicate_pad_numbers_are_jumpers no)
		(fp_line
			(start -0.7874 0.4064)
			(end -0.7874 -0.4064)
			(stroke
				(width 0.1524)
				(type default)
			)
			(layer "F.SilkS")
		)
		(fp_line
			(start 0.7874 0.4064)
			(end -0.7874 0.4064)
			(stroke
				(width 0.1524)
				(type default)
			)
			(layer "F.SilkS")
		)
		(fp_line
			(start -0.7874 -0.4064)
			(end 0.7874 -0.4064)
			(stroke
				(width 0.1524)
				(type default)
			)
			(layer "F.SilkS")
		)
		(fp_line
			(start 0.7874 -0.4064)
			(end 0.7874 0.4064)
			(stroke
				(width 0.1524)
				(type default)
			)
			(layer "F.SilkS")
		)
		(fp_poly
			(pts
				(xy -0.508 0.2794) (xy -0.508 0.2286) (xy -0.635 0.2286) (xy -0.635 -0.254) (xy -0.5334 -0.254)
				(xy -0.5334 -0.2794) (xy 0.5334 -0.2794) (xy 0.5334 -0.254) (xy 0.635 -0.254) (xy 0.635 0.254) (xy 0.5334 0.254)
				(xy 0.5334 0.2794)
			)
			(stroke
				(width 0)
				(type default)
			)
			(fill no)
			(layer "F.CrtYd")
		)
		(pad "1" smd rect
			(at 0.40005 0 270)
			(size 0.4572 0.508)
			(layers "F.Cu" "F.Mask" "F.Paste")
			(net "UART_T6_NODE3_TXD")
		)
		(pad "2" smd rect
			(at -0.40005 0 270)
			(size 0.4572 0.508)
			(layers "F.Cu" "F.Mask" "F.Paste")
			(net "UART_T6_NODE3_TXD_R")
		)
	)
	(footprint ""
		(layer "F.Cu")
		(at 47.60214 -163.89985 90)
		(property "Reference" "R536"
			(at -131.03606 -3.553968 90)
			(unlocked yes)
			(layer "F.SilkS")
			(effects
				(font
					(size 0.7874 0.5842)
					(thickness 0.1524)
				)
				(justify left)
			)
		)
		(property "Value" ""
			(at 0 0 90)
			(layer "F.Fab")
			(effects
				(font
					(size 1.27 1.27)
				)
			)
		)
		(duplicate_pad_numbers_are_jumpers no)
		(fp_line
			(start 0.7874 -0.4064)
			(end 0.7874 0.4064)
			(stroke
				(width 0.1524)
				(type default)
			)
			(layer "F.SilkS")
		)
		(fp_line
			(start -0.7874 -0.4064)
			(end 0.7874 -0.4064)
			(stroke
				(width 0.1524)
				(type default)
			)
			(layer "F.SilkS")
		)
		(fp_line
			(start 0.7874 0.4064)
			(end -0.7874 0.4064)
			(stroke
				(width 0.1524)
				(type default)
			)
			(layer "F.SilkS")
		)
		(fp_line
			(start -0.7874 0.4064)
			(end -0.7874 -0.4064)
			(stroke
				(width 0.1524)
				(type default)
			)
			(layer "F.SilkS")
		)
		(fp_poly
			(pts
				(xy -0.508 0.2794) (xy -0.508 0.2286) (xy -0.635 0.2286) (xy -0.635 -0.254) (xy -0.5334 -0.254)
				(xy -0.5334 -0.2794) (xy 0.5334 -0.2794) (xy 0.5334 -0.254) (xy 0.635 -0.254) (xy 0.635 0.254) (xy 0.5334 0.254)
				(xy 0.5334 0.2794)
			)
			(stroke
				(width 0)
				(type default)
			)
			(fill no)
			(layer "F.CrtYd")
		)
		(pad "1" smd rect
			(at 0.40005 0 90)
			(size 0.4572 0.508)
			(layers "F.Cu" "F.Mask" "F.Paste")
			(net "P3V3_NODE1")
		)
		(pad "2" smd rect
			(at -0.40005 0 90)
			(size 0.4572 0.508)
			(layers "F.Cu" "F.Mask" "F.Paste")
			(net "PU_LAN1_TDI")
		)
	)
	(footprint ""
		(layer "F.Cu")
		(at 60.785756 -14.910054 -90)
		(property "Reference" "PC82"
			(at 0.031242 7.668768 90)
			(unlocked yes)
			(layer "F.SilkS")
			(effects
				(font
					(size 0.7874 0.5842)
					(thickness 0.1524)
				)
				(justify left)
			)
		)
		(property "Value" ""
			(at 0 0 270)
			(layer "F.Fab")
			(effects
				(font
					(size 1.27 1.27)
				)
			)
		)
		(duplicate_pad_numbers_are_jumpers no)
		(fp_line
			(start -1.905 0.8636)
			(end -1.905 -0.8636)
			(stroke
				(width 0.1524)
				(type default)
			)
			(layer "F.SilkS")
		)
		(fp_line
			(start 1.905 0.8636)
			(end -1.905 0.8636)
			(stroke
				(width 0.1524)
				(type default)
			)
			(layer "F.SilkS")
		)
		(fp_line
			(start 0 0.8382)
			(end 0 -0.8382)
			(stroke
				(width 0.1524)
				(type default)
			)
			(layer "F.SilkS")
		)
		(fp_line
			(start -1.905 -0.8636)
			(end 1.905 -0.8636)
			(stroke
				(width 0.1524)
				(type default)
			)
			(layer "F.SilkS")
		)
		(fp_line
			(start 1.905 -0.8636)
			(end 1.905 0.8636)
			(stroke
				(width 0.1524)
				(type default)
			)
			(layer "F.SilkS")
		)
		(fp_rect
			(start -1.524 0.7366)
			(end 1.524 -0.7366)
			(stroke
				(width 0)
				(type default)
			)
			(fill no)
			(layer "F.CrtYd")
		)
		(pad "1" smd rect
			(at 0.94996 0 270)
			(size 1.1176 1.3716)
			(layers "F.Cu" "F.Mask" "F.Paste")
			(net "PV_VDDR_NODE1")
		)
		(pad "2" smd rect
			(at -0.94996 0 270)
			(size 1.1176 1.3716)
			(layers "F.Cu" "F.Mask" "F.Paste")
			(net "GND")
		)
	)
	(footprint ""
		(layer "F.Cu")
		(at 19.38528 -43.84167 180)
		(property "Reference" "R640"
			(at -2.55524 -0.188468 0)
			(unlocked yes)
			(layer "F.SilkS")
			(effects
				(font
					(size 0.7874 0.5842)
					(thickness 0.1524)
				)
				(justify left)
			)
		)
		(property "Value" ""
			(at 0 0 180)
			(layer "F.Fab")
			(effects
				(font
					(size 1.27 1.27)
				)
			)
		)
		(duplicate_pad_numbers_are_jumpers no)
		(fp_line
			(start 0.7874 0.4064)
			(end -0.7874 0.4064)
			(stroke
				(width 0.1524)
				(type default)
			)
			(layer "F.SilkS")
		)
		(fp_line
			(start 0.7874 -0.4064)
			(end 0.7874 0.4064)
			(stroke
				(width 0.1524)
				(type default)
			)
			(layer "F.SilkS")
		)
		(fp_line
			(start -0.7874 0.4064)
			(end -0.7874 -0.4064)
			(stroke
				(width 0.1524)
				(type default)
			)
			(layer "F.SilkS")
		)
		(fp_line
			(start -0.7874 -0.4064)
			(end 0.7874 -0.4064)
			(stroke
				(width 0.1524)
				(type default)
			)
			(layer "F.SilkS")
		)
		(fp_poly
			(pts
				(xy -0.508 0.2794) (xy -0.508 0.2286) (xy -0.635 0.2286) (xy -0.635 -0.254) (xy -0.5334 -0.254)
				(xy -0.5334 -0.2794) (xy 0.5334 -0.2794) (xy 0.5334 -0.254) (xy 0.635 -0.254) (xy 0.635 0.254) (xy 0.5334 0.254)
				(xy 0.5334 0.2794)
			)
			(stroke
				(width 0)
				(type default)
			)
			(fill no)
			(layer "F.CrtYd")
		)
		(pad "1" smd rect
			(at 0.40005 0 180)
			(size 0.4572 0.508)
			(layers "F.Cu" "F.Mask" "F.Paste")
			(net "CRT_R_L")
		)
		(pad "2" smd rect
			(at -0.40005 0 180)
			(size 0.4572 0.508)
			(layers "F.Cu" "F.Mask" "F.Paste")
			(net "GND")
		)
	)
	(footprint ""
		(layer "F.Cu")
		(at 70.192138 -114.300254 90)
		(property "Reference" "R1114"
			(at -0.401066 0.513842 0)
			(unlocked yes)
			(layer "F.SilkS")
			(effects
				(font
					(size 0.7874 0.5842)
					(thickness 0.1524)
				)
				(justify left)
			)
		)
		(property "Value" ""
			(at 0 0 90)
			(layer "F.Fab")
			(effects
				(font
					(size 1.27 1.27)
				)
			)
		)
		(duplicate_pad_numbers_are_jumpers no)
		(fp_line
			(start 0.7874 -0.4064)
			(end 0.7874 0.4064)
			(stroke
				(width 0.1524)
				(type default)
			)
			(layer "F.SilkS")
		)
		(fp_line
			(start -0.7874 -0.4064)
			(end 0.7874 -0.4064)
			(stroke
				(width 0.1524)
				(type default)
			)
			(layer "F.SilkS")
		)
		(fp_line
			(start 0.7874 0.4064)
			(end -0.7874 0.4064)
			(stroke
				(width 0.1524)
				(type default)
			)
			(layer "F.SilkS")
		)
		(fp_line
			(start -0.7874 0.4064)
			(end -0.7874 -0.4064)
			(stroke
				(width 0.1524)
				(type default)
			)
			(layer "F.SilkS")
		)
		(fp_poly
			(pts
				(xy -0.508 0.2794) (xy -0.508 0.2286) (xy -0.635 0.2286) (xy -0.635 -0.254) (xy -0.5334 -0.254)
				(xy -0.5334 -0.2794) (xy 0.5334 -0.2794) (xy 0.5334 -0.254) (xy 0.635 -0.254) (xy 0.635 0.254) (xy 0.5334 0.254)
				(xy 0.5334 0.2794)
			)
			(stroke
				(width 0)
				(type default)
			)
			(fill no)
			(layer "F.CrtYd")
		)
		(pad "1" smd rect
			(at 0.40005 0 90)
			(size 0.4572 0.508)
			(layers "F.Cu" "F.Mask" "F.Paste")
			(net "GND")
		)
		(pad "2" smd rect
			(at -0.40005 0 90)
			(size 0.4572 0.508)
			(layers "F.Cu" "F.Mask" "F.Paste")
			(net "P1V8_NODE1")
		)
	)
	(footprint ""
		(layer "F.Cu")
		(at 109.45876 -188.126624 90)
		(property "Reference" "C653"
			(at 5.151882 0.791972 90)
			(unlocked yes)
			(layer "F.SilkS")
			(effects
				(font
					(size 0.7874 0.5842)
					(thickness 0.1524)
				)
				(justify left)
			)
		)
		(property "Value" ""
			(at 0 0 90)
			(layer "F.Fab")
			(effects
				(font
					(size 1.27 1.27)
				)
			)
		)
		(duplicate_pad_numbers_are_jumpers no)
		(fp_line
			(start 0.7874 -0.4064)
			(end 0.7874 0.4064)
			(stroke
				(width 0.1524)
				(type default)
			)
			(layer "F.SilkS")
		)
		(fp_line
			(start -0.7874 -0.4064)
			(end 0.7874 -0.4064)
			(stroke
				(width 0.1524)
				(type default)
			)
			(layer "F.SilkS")
		)
		(fp_line
			(start 0 0.381)
			(end 0 -0.381)
			(stroke
				(width 0.1524)
				(type default)
			)
			(layer "F.SilkS")
		)
		(fp_line
			(start 0.7874 0.4064)
			(end -0.7874 0.4064)
			(stroke
				(width 0.1524)
				(type default)
			)
			(layer "F.SilkS")
		)
		(fp_line
			(start -0.7874 0.4064)
			(end -0.7874 -0.4064)
			(stroke
				(width 0.1524)
				(type default)
			)
			(layer "F.SilkS")
		)
		(fp_poly
			(pts
				(xy -0.5334 0.254) (xy -0.635 0.254) (xy -0.635 0.2286) (xy -0.635 -0.254) (xy -0.5334 -0.254) (xy -0.5334 -0.2794)
				(xy 0.5334 -0.2794) (xy 0.5334 -0.254) (xy 0.635 -0.254) (xy 0.635 0.254) (xy 0.5334 0.254) (xy 0.5334 0.2794)
				(xy -0.508 0.2794) (xy -0.5334 0.2794)
			)
			(stroke
				(width 0)
				(type default)
			)
			(fill no)
			(layer "F.CrtYd")
		)
		(pad "1" smd rect
			(at 0.40005 0 90)
			(size 0.4572 0.508)
			(layers "F.Cu" "F.Mask" "F.Paste")
			(net "T6_NODE3_EN_R")
		)
		(pad "2" smd rect
			(at -0.40005 0 90)
			(size 0.4572 0.508)
			(layers "F.Cu" "F.Mask" "F.Paste")
			(net "GND")
		)
	)
	(footprint ""
		(layer "F.Cu")
		(at 187.579 -120.65)
		(property "Reference" "R1285"
			(at 5.588 19.07667 0)
			(unlocked yes)
			(layer "F.SilkS")
			(effects
				(font
					(size 0.7874 0.5842)
					(thickness 0.1524)
				)
				(justify left)
			)
		)
		(property "Value" ""
			(at 0 0 0)
			(layer "F.Fab")
			(effects
				(font
					(size 1.27 1.27)
				)
			)
		)
		(duplicate_pad_numbers_are_jumpers no)
		(fp_line
			(start -0.7874 -0.4064)
			(end 0.7874 -0.4064)
			(stroke
				(width 0.1524)
				(type default)
			)
			(layer "F.SilkS")
		)
		(fp_line
			(start -0.7874 0.4064)
			(end -0.7874 -0.4064)
			(stroke
				(width 0.1524)
				(type default)
			)
			(layer "F.SilkS")
		)
		(fp_line
			(start 0.7874 -0.4064)
			(end 0.7874 0.4064)
			(stroke
				(width 0.1524)
				(type default)
			)
			(layer "F.SilkS")
		)
		(fp_line
			(start 0.7874 0.4064)
			(end -0.7874 0.4064)
			(stroke
				(width 0.1524)
				(type default)
			)
			(layer "F.SilkS")
		)
		(fp_poly
			(pts
				(xy -0.508 0.2794) (xy -0.508 0.2286) (xy -0.635 0.2286) (xy -0.635 -0.254) (xy -0.5334 -0.254)
				(xy -0.5334 -0.2794) (xy 0.5334 -0.2794) (xy 0.5334 -0.254) (xy 0.635 -0.254) (xy 0.635 0.254) (xy 0.5334 0.254)
				(xy 0.5334 0.2794)
			)
			(stroke
				(width 0)
				(type default)
			)
			(fill no)
			(layer "F.CrtYd")
		)
		(pad "1" smd rect
			(at 0.40005 0)
			(size 0.4572 0.508)
			(layers "F.Cu" "F.Mask" "F.Paste")
			(net "SIO_JTAG_CPLD1_TDI")
		)
		(pad "2" smd rect
			(at -0.40005 0)
			(size 0.4572 0.508)
			(layers "F.Cu" "F.Mask" "F.Paste")
			(net "JTAG_CPLD1_TDI")
		)
	)
	(footprint ""
		(layer "F.Cu")
		(at 124.391166 -57.900062 180)
		(property "Reference" "R1217"
			(at 4.614418 0.49149 0)
			(unlocked yes)
			(layer "F.SilkS")
			(effects
				(font
					(size 0.7874 0.5842)
					(thickness 0.1524)
				)
				(justify left)
			)
		)
		(property "Value" ""
			(at 0 0 180)
			(layer "F.Fab")
			(effects
				(font
					(size 1.27 1.27)
				)
			)
		)
		(duplicate_pad_numbers_are_jumpers no)
		(fp_line
			(start 0.7874 0.4064)
			(end -0.7874 0.4064)
			(stroke
				(width 0.1524)
				(type default)
			)
			(layer "F.SilkS")
		)
		(fp_line
			(start 0.7874 -0.4064)
			(end 0.7874 0.4064)
			(stroke
				(width 0.1524)
				(type default)
			)
			(layer "F.SilkS")
		)
		(fp_line
			(start -0.7874 0.4064)
			(end -0.7874 -0.4064)
			(stroke
				(width 0.1524)
				(type default)
			)
			(layer "F.SilkS")
		)
		(fp_line
			(start -0.7874 -0.4064)
			(end 0.7874 -0.4064)
			(stroke
				(width 0.1524)
				(type default)
			)
			(layer "F.SilkS")
		)
		(fp_poly
			(pts
				(xy -0.508 0.2794) (xy -0.508 0.2286) (xy -0.635 0.2286) (xy -0.635 -0.254) (xy -0.5334 -0.254)
				(xy -0.5334 -0.2794) (xy 0.5334 -0.2794) (xy 0.5334 -0.254) (xy 0.635 -0.254) (xy 0.635 0.254) (xy 0.5334 0.254)
				(xy 0.5334 0.2794)
			)
			(stroke
				(width 0)
				(type default)
			)
			(fill no)
			(layer "F.CrtYd")
		)
		(pad "1" smd rect
			(at 0.40005 0 180)
			(size 0.4572 0.508)
			(layers "F.Cu" "F.Mask" "F.Paste")
			(net "COM4_EN_N")
		)
		(pad "2" smd rect
			(at -0.40005 0 180)
			(size 0.4572 0.508)
			(layers "F.Cu" "F.Mask" "F.Paste")
			(net "P3V3_NODE1")
		)
	)
	(footprint ""
		(layer "F.Cu")
		(at 118.17477 -123.296934 90)
		(property "Reference" "PC91"
			(at -0.529844 3.730752 90)
			(unlocked yes)
			(layer "F.SilkS")
			(effects
				(font
					(size 0.7874 0.5842)
					(thickness 0.1524)
				)
				(justify left)
			)
		)
		(property "Value" ""
			(at 0 0 90)
			(layer "F.Fab")
			(effects
				(font
					(size 1.27 1.27)
				)
			)
		)
		(duplicate_pad_numbers_are_jumpers no)
		(fp_line
			(start 2.2098 -0.9398)
			(end 2.2098 0.9398)
			(stroke
				(width 0.1524)
				(type default)
			)
			(layer "F.SilkS")
		)
		(fp_line
			(start 0 -0.9398)
			(end 0 0.9398)
			(stroke
				(width 0.1524)
				(type default)
			)
			(layer "F.SilkS")
		)
		(fp_line
			(start -2.2098 -0.9398)
			(end 2.2098 -0.9398)
			(stroke
				(width 0.1524)
				(type default)
			)
			(layer "F.SilkS")
		)
		(fp_line
			(start 2.2098 0.9398)
			(end -2.2098 0.9398)
			(stroke
				(width 0.1524)
				(type default)
			)
			(layer "F.SilkS")
		)
		(fp_line
			(start -2.2098 0.9398)
			(end -2.2098 -0.9398)
			(stroke
				(width 0.1524)
				(type default)
			)
			(layer "F.SilkS")
		)
		(fp_poly
			(pts
				(xy -1.6764 0.889) (xy -1.6764 0.7874) (xy -2.0574 0.7874) (xy -2.0574 -0.7874) (xy -1.6764 -0.7874)
				(xy -1.6764 -0.9398) (xy 1.6764 -0.9398) (xy 1.6764 -0.7874) (xy 2.0574 -0.7874) (xy 2.0574 0.7874)
				(xy 1.6764 0.7874) (xy 1.6764 0.9398) (xy -1.6764 0.9398)
			)
			(stroke
				(width 0)
				(type default)
			)
			(fill no)
			(layer "F.CrtYd")
		)
		(fp_line
			(start 1.700022 -0.899922)
			(end 1.700022 0.899922)
			(stroke
				(width 0.1)
				(type default)
			)
			(layer "F.Fab")
		)
		(fp_line
			(start -1.700022 -0.899922)
			(end 1.700022 -0.899922)
			(stroke
				(width 0.1)
				(type default)
			)
			(layer "F.Fab")
		)
		(fp_line
			(start 1.700022 0.899922)
			(end -1.700022 0.899922)
			(stroke
				(width 0.1)
				(type default)
			)
			(layer "F.Fab")
		)
		(fp_line
			(start -1.700022 0.899922)
			(end -1.700022 -0.899922)
			(stroke
				(width 0.1)
				(type default)
			)
			(layer "F.Fab")
		)
		(pad "1" smd rect
			(at 1.4732 0 90)
			(size 1.1684 1.5748)
			(layers "F.Cu" "F.Mask" "F.Paste")
			(net "SW_VR_PVCCP_NODE1_VIN_FLT")
		)
		(pad "2" smd rect
			(at -1.4732 0 90)
			(size 1.1684 1.5748)
			(layers "F.Cu" "F.Mask" "F.Paste")
			(net "GND")
		)
	)
	(footprint ""
		(layer "F.Cu")
		(at 82.7278 -83.641184 90)
		(property "Reference" "C24"
			(at -18.13306 1.853184 90)
			(unlocked yes)
			(layer "F.SilkS")
			(effects
				(font
					(size 0.7874 0.5842)
					(thickness 0.1524)
				)
				(justify left)
			)
		)
		(property "Value" ""
			(at 0 0 90)
			(layer "F.Fab")
			(effects
				(font
					(size 1.27 1.27)
				)
			)
		)
		(duplicate_pad_numbers_are_jumpers no)
		(fp_line
			(start 0.7874 -0.4064)
			(end 0.7874 0.4064)
			(stroke
				(width 0.1524)
				(type default)
			)
			(layer "F.SilkS")
		)
		(fp_line
			(start -0.7874 -0.4064)
			(end 0.7874 -0.4064)
			(stroke
				(width 0.1524)
				(type default)
			)
			(layer "F.SilkS")
		)
		(fp_line
			(start 0 0.381)
			(end 0 -0.381)
			(stroke
				(width 0.1524)
				(type default)
			)
			(layer "F.SilkS")
		)
		(fp_line
			(start 0.7874 0.4064)
			(end -0.7874 0.4064)
			(stroke
				(width 0.1524)
				(type default)
			)
			(layer "F.SilkS")
		)
		(fp_line
			(start -0.7874 0.4064)
			(end -0.7874 -0.4064)
			(stroke
				(width 0.1524)
				(type default)
			)
			(layer "F.SilkS")
		)
		(fp_poly
			(pts
				(xy -0.5334 0.254) (xy -0.635 0.254) (xy -0.635 0.2286) (xy -0.635 -0.254) (xy -0.5334 -0.254) (xy -0.5334 -0.2794)
				(xy 0.5334 -0.2794) (xy 0.5334 -0.254) (xy 0.635 -0.254) (xy 0.635 0.254) (xy 0.5334 0.254) (xy 0.5334 0.2794)
				(xy -0.508 0.2794) (xy -0.5334 0.2794)
			)
			(stroke
				(width 0)
				(type default)
			)
			(fill no)
			(layer "F.CrtYd")
		)
		(pad "1" smd rect
			(at 0.40005 0 90)
			(size 0.4572 0.508)
			(layers "F.Cu" "F.Mask" "F.Paste")
			(net "XTAL_CPU_NODE1_X1PAD")
		)
		(pad "2" smd rect
			(at -0.40005 0 90)
			(size 0.4572 0.508)
			(layers "F.Cu" "F.Mask" "F.Paste")
			(net "GND")
		)
	)
	(footprint ""
		(layer "F.Cu")
		(at 186.182 -125.984)
		(property "Reference" "R1272"
			(at 4.064 19.83867 0)
			(unlocked yes)
			(layer "F.SilkS")
			(effects
				(font
					(size 0.7874 0.5842)
					(thickness 0.1524)
				)
				(justify left)
			)
		)
		(property "Value" ""
			(at 0 0 0)
			(layer "F.Fab")
			(effects
				(font
					(size 1.27 1.27)
				)
			)
		)
		(duplicate_pad_numbers_are_jumpers no)
		(fp_line
			(start -0.7874 -0.4064)
			(end 0.7874 -0.4064)
			(stroke
				(width 0.1524)
				(type default)
			)
			(layer "F.SilkS")
		)
		(fp_line
			(start -0.7874 0.4064)
			(end -0.7874 -0.4064)
			(stroke
				(width 0.1524)
				(type default)
			)
			(layer "F.SilkS")
		)
		(fp_line
			(start 0.7874 -0.4064)
			(end 0.7874 0.4064)
			(stroke
				(width 0.1524)
				(type default)
			)
			(layer "F.SilkS")
		)
		(fp_line
			(start 0.7874 0.4064)
			(end -0.7874 0.4064)
			(stroke
				(width 0.1524)
				(type default)
			)
			(layer "F.SilkS")
		)
		(fp_poly
			(pts
				(xy -0.508 0.2794) (xy -0.508 0.2286) (xy -0.635 0.2286) (xy -0.635 -0.254) (xy -0.5334 -0.254)
				(xy -0.5334 -0.2794) (xy 0.5334 -0.2794) (xy 0.5334 -0.254) (xy 0.635 -0.254) (xy 0.635 0.254) (xy 0.5334 0.254)
				(xy 0.5334 0.2794)
			)
			(stroke
				(width 0)
				(type default)
			)
			(fill no)
			(layer "F.CrtYd")
		)
		(pad "1" smd rect
			(at 0.40005 0)
			(size 0.4572 0.508)
			(layers "F.Cu" "F.Mask" "F.Paste")
			(net "SIO_JTAG_CPLD1_TMS")
		)
		(pad "2" smd rect
			(at -0.40005 0)
			(size 0.4572 0.508)
			(layers "F.Cu" "F.Mask" "F.Paste")
			(net "JTAG_CPLD1_TMS")
		)
	)
	(footprint ""
		(layer "F.Cu")
		(at 62.291214 -149.137624 180)
		(property "Reference" "C263"
			(at 30.37205 7.322058 0)
			(unlocked yes)
			(layer "F.SilkS")
			(effects
				(font
					(size 0.7874 0.5842)
					(thickness 0.1524)
				)
				(justify left)
			)
		)
		(property "Value" ""
			(at 0 0 180)
			(layer "F.Fab")
			(effects
				(font
					(size 1.27 1.27)
				)
			)
		)
		(duplicate_pad_numbers_are_jumpers no)
		(fp_line
			(start 0.7874 0.4064)
			(end -0.7874 0.4064)
			(stroke
				(width 0.1524)
				(type default)
			)
			(layer "F.SilkS")
		)
		(fp_line
			(start 0.7874 -0.4064)
			(end 0.7874 0.4064)
			(stroke
				(width 0.1524)
				(type default)
			)
			(layer "F.SilkS")
		)
		(fp_line
			(start 0 0.381)
			(end 0 -0.381)
			(stroke
				(width 0.1524)
				(type default)
			)
			(layer "F.SilkS")
		)
		(fp_line
			(start -0.7874 0.4064)
			(end -0.7874 -0.4064)
			(stroke
				(width 0.1524)
				(type default)
			)
			(layer "F.SilkS")
		)
		(fp_line
			(start -0.7874 -0.4064)
			(end 0.7874 -0.4064)
			(stroke
				(width 0.1524)
				(type default)
			)
			(layer "F.SilkS")
		)
		(fp_poly
			(pts
				(xy -0.5334 0.254) (xy -0.635 0.254) (xy -0.635 0.2286) (xy -0.635 -0.254) (xy -0.5334 -0.254) (xy -0.5334 -0.2794)
				(xy 0.5334 -0.2794) (xy 0.5334 -0.254) (xy 0.635 -0.254) (xy 0.635 0.254) (xy 0.5334 0.254) (xy 0.5334 0.2794)
				(xy -0.508 0.2794) (xy -0.5334 0.2794)
			)
			(stroke
				(width 0)
				(type default)
			)
			(fill no)
			(layer "F.CrtYd")
		)
		(pad "1" smd rect
			(at 0.40005 0 180)
			(size 0.4572 0.508)
			(layers "F.Cu" "F.Mask" "F.Paste")
			(net "BMC_NODE1_DACAV33")
		)
		(pad "2" smd rect
			(at -0.40005 0 180)
			(size 0.4572 0.508)
			(layers "F.Cu" "F.Mask" "F.Paste")
			(net "GND")
		)
	)
	(footprint ""
		(layer "F.Cu")
		(at 90.063066 -100.491544)
		(property "Reference" "U4"
			(at 5.493766 -3.376422 0)
			(unlocked yes)
			(layer "F.SilkS")
			(effects
				(font
					(size 0.7874 0.5842)
					(thickness 0.1524)
				)
				(justify left)
			)
		)
		(property "Value" ""
			(at 0 0 0)
			(layer "F.Fab")
			(effects
				(font
					(size 1.27 1.27)
				)
			)
		)
		(duplicate_pad_numbers_are_jumpers no)
		(fp_line
			(start -2.690114 -2.599944)
			(end 2.690114 -2.599944)
			(stroke
				(width 0.1524)
				(type default)
			)
			(layer "F.SilkS")
		)
		(fp_line
			(start -2.690114 -0.40005)
			(end -2.690114 -2.599944)
			(stroke
				(width 0.1524)
				(type default)
			)
			(layer "F.SilkS")
		)
		(fp_line
			(start -2.690114 0.40005)
			(end -1.905 0)
			(stroke
				(width 0.1524)
				(type default)
			)
			(layer "F.SilkS")
		)
		(fp_line
			(start -2.690114 2.599944)
			(end -2.690114 0.40005)
			(stroke
				(width 0.1524)
				(type default)
			)
			(layer "F.SilkS")
		)
		(fp_line
			(start -1.905 0)
			(end -2.690114 -0.40005)
			(stroke
				(width 0.1524)
				(type default)
			)
			(layer "F.SilkS")
		)
		(fp_line
			(start 2.690114 -2.599944)
			(end 2.690114 2.599944)
			(stroke
				(width 0.1524)
				(type default)
			)
			(layer "F.SilkS")
		)
		(fp_line
			(start 2.690114 2.599944)
			(end -2.690114 2.599944)
			(stroke
				(width 0.1524)
				(type default)
			)
			(layer "F.SilkS")
		)
		(fp_circle
			(center -1.9304 2.0066)
			(end -1.6764 2.0066)
			(stroke
				(width 0.1524)
				(type default)
			)
			(fill no)
			(layer "F.SilkS")
		)
		(fp_poly
			(pts
				(xy -2.1844 4.4958) (xy -2.1844 2.5908) (xy -2.6924 2.5908) (xy -2.6924 -2.5908) (xy -2.1844 -2.5908)
				(xy -2.1844 -4.4958) (xy 2.1844 -4.4958) (xy 2.1844 -2.5908) (xy 2.667 -2.5908) (xy 2.667 2.5908)
				(xy 2.1844 2.5908) (xy 2.1844 4.4958)
			)
			(stroke
				(width 0)
				(type default)
			)
			(fill no)
			(layer "F.CrtYd")
		)
		(pad "1" smd rect
			(at -1.905 3.636518)
			(size 0.5588 1.7272)
			(layers "F.Cu" "F.Mask" "F.Paste")
			(net "SPI_CPU_NODE1_CS0_L")
		)
		(pad "2" smd rect
			(at -0.635 3.636518)
			(size 0.5588 1.7272)
			(layers "F.Cu" "F.Mask" "F.Paste")
			(net "SPI_CPU_NODE1_MISO_R")
		)
		(pad "3" smd rect
			(at 0.635 3.636518)
			(size 0.5588 1.7272)
			(layers "F.Cu" "F.Mask" "F.Paste")
			(net "SPI_CPU_NODE1_WP_L")
		)
		(pad "4" smd rect
			(at 1.905 3.636518)
			(size 0.5588 1.7272)
			(layers "F.Cu" "F.Mask" "F.Paste")
			(net "GND")
		)
		(pad "5" smd rect
			(at 1.905 -3.636518)
			(size 0.5588 1.7272)
			(layers "F.Cu" "F.Mask" "F.Paste")
			(net "SPI_CPU_NODE1_MOSI")
		)
		(pad "6" smd rect
			(at 0.635 -3.636518)
			(size 0.5588 1.7272)
			(layers "F.Cu" "F.Mask" "F.Paste")
			(net "SPI_CPU_NODE1_SCLK")
		)
		(pad "7" smd rect
			(at -0.635 -3.636518)
			(size 0.5588 1.7272)
			(layers "F.Cu" "F.Mask" "F.Paste")
			(net "SPI_CPU_NODE1_HOLD_L")
		)
		(pad "8" smd rect
			(at -1.905 -3.636518)
			(size 0.5588 1.7272)
			(layers "F.Cu" "F.Mask" "F.Paste")
			(net "P3V3_NODE1")
		)
	)
	(footprint ""
		(layer "F.Cu")
		(at 144.916652 -138.53795)
		(property "Reference" "R288"
			(at -0.990346 17.192244 0)
			(unlocked yes)
			(layer "F.SilkS")
			(effects
				(font
					(size 0.7874 0.5842)
					(thickness 0.1524)
				)
				(justify left)
			)
		)
		(property "Value" ""
			(at 0 0 0)
			(layer "F.Fab")
			(effects
				(font
					(size 1.27 1.27)
				)
			)
		)
		(duplicate_pad_numbers_are_jumpers no)
		(fp_line
			(start -0.7874 -0.4064)
			(end 0.7874 -0.4064)
			(stroke
				(width 0.1524)
				(type default)
			)
			(layer "F.SilkS")
		)
		(fp_line
			(start -0.7874 0.4064)
			(end -0.7874 -0.4064)
			(stroke
				(width 0.1524)
				(type default)
			)
			(layer "F.SilkS")
		)
		(fp_line
			(start 0.7874 -0.4064)
			(end 0.7874 0.4064)
			(stroke
				(width 0.1524)
				(type default)
			)
			(layer "F.SilkS")
		)
		(fp_line
			(start 0.7874 0.4064)
			(end -0.7874 0.4064)
			(stroke
				(width 0.1524)
				(type default)
			)
			(layer "F.SilkS")
		)
		(fp_poly
			(pts
				(xy -0.508 0.2794) (xy -0.508 0.2286) (xy -0.635 0.2286) (xy -0.635 -0.254) (xy -0.5334 -0.254)
				(xy -0.5334 -0.2794) (xy 0.5334 -0.2794) (xy 0.5334 -0.254) (xy 0.635 -0.254) (xy 0.635 0.254) (xy 0.5334 0.254)
				(xy 0.5334 0.2794)
			)
			(stroke
				(width 0)
				(type default)
			)
			(fill no)
			(layer "F.CrtYd")
		)
		(pad "1" smd rect
			(at 0.40005 0)
			(size 0.4572 0.508)
			(layers "F.Cu" "F.Mask" "F.Paste")
			(net "GND")
		)
		(pad "2" smd rect
			(at -0.40005 0)
			(size 0.4572 0.508)
			(layers "F.Cu" "F.Mask" "F.Paste")
			(net "PCIE_SW_TEST5")
		)
	)
	(footprint ""
		(layer "F.Cu")
		(at 114.574828 -66.621914)
		(property "Reference" "C197"
			(at 3.47599 -0.185674 0)
			(unlocked yes)
			(layer "F.SilkS")
			(effects
				(font
					(size 0.7874 0.5842)
					(thickness 0.1524)
				)
			)
		)
		(property "Value" ""
			(at 0 0 0)
			(layer "F.Fab")
			(effects
				(font
					(size 1.27 1.27)
				)
			)
		)
		(duplicate_pad_numbers_are_jumpers no)
		(fp_line
			(start -1.2954 -0.5842)
			(end 1.2954 -0.5842)
			(stroke
				(width 0.1524)
				(type default)
			)
			(layer "F.SilkS")
		)
		(fp_line
			(start -1.2954 0.5842)
			(end -1.2954 -0.5842)
			(stroke
				(width 0.1524)
				(type default)
			)
			(layer "F.SilkS")
		)
		(fp_line
			(start 0 -0.5842)
			(end 0 0.5842)
			(stroke
				(width 0.1524)
				(type default)
			)
			(layer "F.SilkS")
		)
		(fp_line
			(start 1.2954 -0.5842)
			(end 1.2954 0.5842)
			(stroke
				(width 0.1524)
				(type default)
			)
			(layer "F.SilkS")
		)
		(fp_line
			(start 1.2954 0.5842)
			(end -1.2954 0.5842)
			(stroke
				(width 0.1524)
				(type default)
			)
			(layer "F.SilkS")
		)
		(fp_poly
			(pts
				(xy 0.8636 -0.4572) (xy 0.8636 -0.3556) (xy 1.143 -0.3556) (xy 1.143 0.3556) (xy 0.8636 0.3556)
				(xy 0.8636 0.4572) (xy -0.8636 0.4572) (xy -0.8636 0.3556) (xy -1.143 0.3556) (xy -1.143 -0.3556)
				(xy -0.8636 -0.3556) (xy -0.8636 -0.4572)
			)
			(stroke
				(width 0)
				(type default)
			)
			(fill no)
			(layer "F.CrtYd")
		)
		(fp_line
			(start -0.884936 -0.504952)
			(end 0.884936 -0.504952)
			(stroke
				(width 0.1)
				(type default)
			)
			(layer "F.Fab")
		)
		(fp_line
			(start -0.884936 0.504952)
			(end -0.884936 -0.504952)
			(stroke
				(width 0.1)
				(type default)
			)
			(layer "F.Fab")
		)
		(fp_line
			(start 0.884936 -0.504952)
			(end 0.884936 0.504952)
			(stroke
				(width 0.1)
				(type default)
			)
			(layer "F.Fab")
		)
		(fp_line
			(start 0.884936 0.504952)
			(end -0.884936 0.504952)
			(stroke
				(width 0.1)
				(type default)
			)
			(layer "F.Fab")
		)
		(pad "1" smd rect
			(at 0.7366 0 90)
			(size 0.7112 0.8128)
			(layers "F.Cu" "F.Mask" "F.Paste")
			(net "GND")
		)
		(pad "2" smd rect
			(at -0.7366 0 90)
			(size 0.7112 0.8128)
			(layers "F.Cu" "F.Mask" "F.Paste")
			(net "P1V05_STB_NODE1_XDP_B")
		)
	)
	(footprint ""
		(layer "F.Cu")
		(at 81.398364 -17.679416 90)
		(property "Reference" "C148"
			(at -4.546854 5.52323 90)
			(unlocked yes)
			(layer "F.SilkS")
			(effects
				(font
					(size 0.7874 0.5842)
					(thickness 0.1524)
				)
				(justify left)
			)
		)
		(property "Value" ""
			(at 0 0 90)
			(layer "F.Fab")
			(effects
				(font
					(size 1.27 1.27)
				)
			)
		)
		(duplicate_pad_numbers_are_jumpers no)
		(fp_line
			(start 0.7874 -0.4064)
			(end 0.7874 0.4064)
			(stroke
				(width 0.1524)
				(type default)
			)
			(layer "F.SilkS")
		)
		(fp_line
			(start -0.7874 -0.4064)
			(end 0.7874 -0.4064)
			(stroke
				(width 0.1524)
				(type default)
			)
			(layer "F.SilkS")
		)
		(fp_line
			(start 0 0.381)
			(end 0 -0.381)
			(stroke
				(width 0.1524)
				(type default)
			)
			(layer "F.SilkS")
		)
		(fp_line
			(start 0.7874 0.4064)
			(end -0.7874 0.4064)
			(stroke
				(width 0.1524)
				(type default)
			)
			(layer "F.SilkS")
		)
		(fp_line
			(start -0.7874 0.4064)
			(end -0.7874 -0.4064)
			(stroke
				(width 0.1524)
				(type default)
			)
			(layer "F.SilkS")
		)
		(fp_poly
			(pts
				(xy -0.5334 0.254) (xy -0.635 0.254) (xy -0.635 0.2286) (xy -0.635 -0.254) (xy -0.5334 -0.254) (xy -0.5334 -0.2794)
				(xy 0.5334 -0.2794) (xy 0.5334 -0.254) (xy 0.635 -0.254) (xy 0.635 0.254) (xy 0.5334 0.254) (xy 0.5334 0.2794)
				(xy -0.508 0.2794) (xy -0.5334 0.2794)
			)
			(stroke
				(width 0)
				(type default)
			)
			(fill no)
			(layer "F.CrtYd")
		)
		(pad "1" smd rect
			(at 0.40005 0 90)
			(size 0.4572 0.508)
			(layers "F.Cu" "F.Mask" "F.Paste")
			(net "PV_VDDR_NODE1")
		)
		(pad "2" smd rect
			(at -0.40005 0 90)
			(size 0.4572 0.508)
			(layers "F.Cu" "F.Mask" "F.Paste")
			(net "GND")
		)
	)
	(footprint ""
		(layer "F.Cu")
		(at 106.170476 -171.990512)
		(property "Reference" "R762"
			(at 1.206754 0.213614 0)
			(unlocked yes)
			(layer "F.SilkS")
			(effects
				(font
					(size 0.7874 0.5842)
					(thickness 0.1524)
				)
				(justify left)
			)
		)
		(property "Value" ""
			(at 0 0 0)
			(layer "F.Fab")
			(effects
				(font
					(size 1.27 1.27)
				)
			)
		)
		(duplicate_pad_numbers_are_jumpers no)
		(fp_line
			(start -0.7874 -0.4064)
			(end 0.7874 -0.4064)
			(stroke
				(width 0.1524)
				(type default)
			)
			(layer "F.SilkS")
		)
		(fp_line
			(start -0.7874 0.4064)
			(end -0.7874 -0.4064)
			(stroke
				(width 0.1524)
				(type default)
			)
			(layer "F.SilkS")
		)
		(fp_line
			(start 0.7874 -0.4064)
			(end 0.7874 0.4064)
			(stroke
				(width 0.1524)
				(type default)
			)
			(layer "F.SilkS")
		)
		(fp_line
			(start 0.7874 0.4064)
			(end -0.7874 0.4064)
			(stroke
				(width 0.1524)
				(type default)
			)
			(layer "F.SilkS")
		)
		(fp_poly
			(pts
				(xy -0.508 0.2794) (xy -0.508 0.2286) (xy -0.635 0.2286) (xy -0.635 -0.254) (xy -0.5334 -0.254)
				(xy -0.5334 -0.2794) (xy 0.5334 -0.2794) (xy 0.5334 -0.254) (xy 0.635 -0.254) (xy 0.635 0.254) (xy 0.5334 0.254)
				(xy 0.5334 0.2794)
			)
			(stroke
				(width 0)
				(type default)
			)
			(fill no)
			(layer "F.CrtYd")
		)
		(pad "1" smd rect
			(at 0.40005 0)
			(size 0.4572 0.508)
			(layers "F.Cu" "F.Mask" "F.Paste")
			(net "P3V3_NODE1")
		)
		(pad "2" smd rect
			(at -0.40005 0)
			(size 0.4572 0.508)
			(layers "F.Cu" "F.Mask" "F.Paste")
			(net "FNACTRL1_ADD")
		)
	)
	(footprint ""
		(layer "F.Cu")
		(at 102.393496 -141.891004 90)
		(property "Reference" "PJ17"
			(at 4.273296 -0.777494 0)
			(unlocked yes)
			(layer "F.SilkS")
			(effects
				(font
					(size 0.635 0.4064)
					(thickness 0.1524)
				)
				(justify left)
			)
		)
		(property "Value" ""
			(at 0 0 90)
			(layer "F.Fab")
			(effects
				(font
					(size 1.27 1.27)
				)
			)
		)
		(duplicate_pad_numbers_are_jumpers no)
		(fp_poly
			(pts
				(xy -0.360426 0.359156) (xy -0.360426 -0.381) (xy 0.3556 -0.381) (xy 0.3556 1.905) (xy -0.360426 1.905)
			)
			(stroke
				(width 0)
				(type default)
			)
			(fill no)
			(layer "F.CrtYd")
		)
		(pad "1" smd custom
			(at 0 0 90)
			(size 0.1778 0.1778)
			(layers "F.Cu" "F.Mask" "F.Paste")
			(net "GND")
			(options
				(clearance outline)
				(anchor circle)
			)
			(primitives
				(gr_poly
					(pts
						(xy -0.127 0.9398) (xy -0.127 -0.127) (xy -0.3556 -0.127) (xy -0.3556 -0.9398) (xy 0.3556 -0.9398)
						(xy 0.3556 -0.127) (xy 0.127 -0.127) (xy 0.127 0.9398)
					)
					(width 0)
					(fill yes)
				)
			)
		)
		(pad "2" smd rect
			(at 0 1.4986 270)
			(size 0.7112 0.8128)
			(layers "F.Cu" "F.Mask" "F.Paste")
			(net "AGND_PVCCP_NODE1")
		)
		(zone
			(layer "F.Cu")
			(hatch none 0.5)
			(connect_pads
				(clearance 0)
			)
			(min_thickness 0.25)
			(keepout
				(tracks allowed)
				(vias not_allowed)
				(pads allowed)
				(copperpour not_allowed)
				(footprints allowed)
			)
			(placement
				(enabled no)
				(sheetname "")
			)
			(fill
				(thermal_gap 0.5)
				(thermal_bridge_width 0.5)
				(island_removal_mode 0)
			)
			(polygon
				(pts
					(xy 104.349296 -142.297404) (xy 101.961696 -142.297404) (xy 101.961696 -141.479778) (xy 104.349296 -141.479778)
				)
			)
		)
	)
	(footprint ""
		(layer "F.Cu")
		(at 191.4525 -26.714704 180)
		(property "Reference" "C556"
			(at 1.275842 -2.018538 0)
			(unlocked yes)
			(layer "F.SilkS")
			(effects
				(font
					(size 0.7874 0.5842)
					(thickness 0.1524)
				)
				(justify left)
			)
		)
		(property "Value" ""
			(at 0 0 180)
			(layer "F.Fab")
			(effects
				(font
					(size 1.27 1.27)
				)
			)
		)
		(duplicate_pad_numbers_are_jumpers no)
		(fp_line
			(start 1.905 0.8636)
			(end -1.905 0.8636)
			(stroke
				(width 0.1524)
				(type default)
			)
			(layer "F.SilkS")
		)
		(fp_line
			(start 1.905 -0.8636)
			(end 1.905 0.8636)
			(stroke
				(width 0.1524)
				(type default)
			)
			(layer "F.SilkS")
		)
		(fp_line
			(start 0 0.8382)
			(end 0 -0.8382)
			(stroke
				(width 0.1524)
				(type default)
			)
			(layer "F.SilkS")
		)
		(fp_line
			(start -1.905 0.8636)
			(end -1.905 -0.8636)
			(stroke
				(width 0.1524)
				(type default)
			)
			(layer "F.SilkS")
		)
		(fp_line
			(start -1.905 -0.8636)
			(end 1.905 -0.8636)
			(stroke
				(width 0.1524)
				(type default)
			)
			(layer "F.SilkS")
		)
		(fp_rect
			(start -1.524 0.7366)
			(end 1.524 -0.7366)
			(stroke
				(width 0)
				(type default)
			)
			(fill no)
			(layer "F.CrtYd")
		)
		(pad "1" smd rect
			(at 0.94996 0 180)
			(size 1.1176 1.3716)
			(layers "F.Cu" "F.Mask" "F.Paste")
			(net "P5V_NODE1")
		)
		(pad "2" smd rect
			(at -0.94996 0 180)
			(size 1.1176 1.3716)
			(layers "F.Cu" "F.Mask" "F.Paste")
			(net "GND")
		)
	)
	(footprint ""
		(layer "F.Cu")
		(at 119.48922 -185.209942 -90)
		(property "Reference" "C635"
			(at -4.774692 -0.35306 90)
			(unlocked yes)
			(layer "F.SilkS")
			(effects
				(font
					(size 0.7874 0.5842)
					(thickness 0.1524)
				)
				(justify left)
			)
		)
		(property "Value" ""
			(at 0 0 270)
			(layer "F.Fab")
			(effects
				(font
					(size 1.27 1.27)
				)
			)
		)
		(duplicate_pad_numbers_are_jumpers no)
		(fp_line
			(start -0.7874 0.4064)
			(end -0.7874 -0.4064)
			(stroke
				(width 0.1524)
				(type default)
			)
			(layer "F.SilkS")
		)
		(fp_line
			(start 0.7874 0.4064)
			(end -0.7874 0.4064)
			(stroke
				(width 0.1524)
				(type default)
			)
			(layer "F.SilkS")
		)
		(fp_line
			(start 0 0.381)
			(end 0 -0.381)
			(stroke
				(width 0.1524)
				(type default)
			)
			(layer "F.SilkS")
		)
		(fp_line
			(start -0.7874 -0.4064)
			(end 0.7874 -0.4064)
			(stroke
				(width 0.1524)
				(type default)
			)
			(layer "F.SilkS")
		)
		(fp_line
			(start 0.7874 -0.4064)
			(end 0.7874 0.4064)
			(stroke
				(width 0.1524)
				(type default)
			)
			(layer "F.SilkS")
		)
		(fp_poly
			(pts
				(xy -0.5334 0.254) (xy -0.635 0.254) (xy -0.635 0.2286) (xy -0.635 -0.254) (xy -0.5334 -0.254) (xy -0.5334 -0.2794)
				(xy 0.5334 -0.2794) (xy 0.5334 -0.254) (xy 0.635 -0.254) (xy 0.635 0.254) (xy 0.5334 0.254) (xy 0.5334 0.2794)
				(xy -0.508 0.2794) (xy -0.5334 0.2794)
			)
			(stroke
				(width 0)
				(type default)
			)
			(fill no)
			(layer "F.CrtYd")
		)
		(pad "1" smd rect
			(at 0.40005 0 270)
			(size 0.4572 0.508)
			(layers "F.Cu" "F.Mask" "F.Paste")
			(net "T7_NODE1_EN_R")
		)
		(pad "2" smd rect
			(at -0.40005 0 270)
			(size 0.4572 0.508)
			(layers "F.Cu" "F.Mask" "F.Paste")
			(net "GND")
		)
	)
	(footprint ""
		(layer "F.Cu")
		(at 147.11045 -51.671474 -90)
		(property "Reference" "R630"
			(at -16.205708 -28.023566 90)
			(unlocked yes)
			(layer "F.SilkS")
			(effects
				(font
					(size 0.7874 0.5842)
					(thickness 0.1524)
				)
				(justify left)
			)
		)
		(property "Value" ""
			(at 0 0 270)
			(layer "F.Fab")
			(effects
				(font
					(size 1.27 1.27)
				)
			)
		)
		(duplicate_pad_numbers_are_jumpers no)
		(fp_line
			(start -1.905 0.8636)
			(end -1.905 -0.8636)
			(stroke
				(width 0.1524)
				(type default)
			)
			(layer "F.SilkS")
		)
		(fp_line
			(start 1.905 0.8636)
			(end -1.905 0.8636)
			(stroke
				(width 0.1524)
				(type default)
			)
			(layer "F.SilkS")
		)
		(fp_line
			(start -1.905 -0.8636)
			(end 1.905 -0.8636)
			(stroke
				(width 0.1524)
				(type default)
			)
			(layer "F.SilkS")
		)
		(fp_line
			(start 1.905 -0.8636)
			(end 1.905 0.8636)
			(stroke
				(width 0.1524)
				(type default)
			)
			(layer "F.SilkS")
		)
		(fp_poly
			(pts
				(xy 1.524 0.6858) (xy 1.524 -0.6858) (xy 1.524 -0.7366) (xy -1.524 -0.7366) (xy -1.524 -0.6858)
				(xy -1.524 0.6858) (xy -1.524 0.7366) (xy 1.524 0.7366)
			)
			(stroke
				(width 0)
				(type default)
			)
			(fill no)
			(layer "F.CrtYd")
		)
		(pad "1" smd rect
			(at 0.94996 0 270)
			(size 1.1176 1.3716)
			(layers "F.Cu" "F.Mask" "F.Paste")
			(net "GND")
		)
		(pad "2" smd rect
			(at -0.94996 0 270)
			(size 1.1176 1.3716)
			(layers "F.Cu" "F.Mask" "F.Paste")
			(net "SATA_P7")
		)
	)
	(footprint ""
		(layer "F.Cu")
		(at 162.696906 -117.319552)
		(property "Reference" "R176"
			(at -4.621784 0.897636 0)
			(unlocked yes)
			(layer "F.SilkS")
			(effects
				(font
					(size 0.7874 0.5842)
					(thickness 0.1524)
				)
				(justify left)
			)
		)
		(property "Value" ""
			(at 0 0 0)
			(layer "F.Fab")
			(effects
				(font
					(size 1.27 1.27)
				)
			)
		)
		(duplicate_pad_numbers_are_jumpers no)
		(fp_line
			(start -0.7874 -0.4064)
			(end 0.7874 -0.4064)
			(stroke
				(width 0.1524)
				(type default)
			)
			(layer "F.SilkS")
		)
		(fp_line
			(start -0.7874 0.4064)
			(end -0.7874 -0.4064)
			(stroke
				(width 0.1524)
				(type default)
			)
			(layer "F.SilkS")
		)
		(fp_line
			(start 0.7874 -0.4064)
			(end 0.7874 0.4064)
			(stroke
				(width 0.1524)
				(type default)
			)
			(layer "F.SilkS")
		)
		(fp_line
			(start 0.7874 0.4064)
			(end -0.7874 0.4064)
			(stroke
				(width 0.1524)
				(type default)
			)
			(layer "F.SilkS")
		)
		(fp_poly
			(pts
				(xy -0.508 0.2794) (xy -0.508 0.2286) (xy -0.635 0.2286) (xy -0.635 -0.254) (xy -0.5334 -0.254)
				(xy -0.5334 -0.2794) (xy 0.5334 -0.2794) (xy 0.5334 -0.254) (xy 0.635 -0.254) (xy 0.635 0.254) (xy 0.5334 0.254)
				(xy 0.5334 0.2794)
			)
			(stroke
				(width 0)
				(type default)
			)
			(fill no)
			(layer "F.CrtYd")
		)
		(pad "1" smd rect
			(at 0.40005 0)
			(size 0.4572 0.508)
			(layers "F.Cu" "F.Mask" "F.Paste")
			(net "RST_CPU_NODE1_SRTCRST_L")
		)
		(pad "2" smd rect
			(at -0.40005 0)
			(size 0.4572 0.508)
			(layers "F.Cu" "F.Mask" "F.Paste")
			(net "GND")
		)
	)
	(footprint ""
		(layer "F.Cu")
		(at 46.121828 -4.35483 90)
		(property "Reference" "PC73"
			(at -3.775202 -14.21384 90)
			(unlocked yes)
			(layer "F.SilkS")
			(effects
				(font
					(size 0.7874 0.5842)
					(thickness 0.1524)
				)
				(justify left)
			)
		)
		(property "Value" ""
			(at 0 0 90)
			(layer "F.Fab")
			(effects
				(font
					(size 1.27 1.27)
				)
			)
		)
		(duplicate_pad_numbers_are_jumpers no)
		(fp_line
			(start 2.2098 -0.9398)
			(end 2.2098 0.9398)
			(stroke
				(width 0.1524)
				(type default)
			)
			(layer "F.SilkS")
		)
		(fp_line
			(start 0 -0.9398)
			(end 0 0.9398)
			(stroke
				(width 0.1524)
				(type default)
			)
			(layer "F.SilkS")
		)
		(fp_line
			(start -2.2098 -0.9398)
			(end 2.2098 -0.9398)
			(stroke
				(width 0.1524)
				(type default)
			)
			(layer "F.SilkS")
		)
		(fp_line
			(start 2.2098 0.9398)
			(end -2.2098 0.9398)
			(stroke
				(width 0.1524)
				(type default)
			)
			(layer "F.SilkS")
		)
		(fp_line
			(start -2.2098 0.9398)
			(end -2.2098 -0.9398)
			(stroke
				(width 0.1524)
				(type default)
			)
			(layer "F.SilkS")
		)
		(fp_poly
			(pts
				(xy -1.6764 0.889) (xy -1.6764 0.7874) (xy -2.0574 0.7874) (xy -2.0574 -0.7874) (xy -1.6764 -0.7874)
				(xy -1.6764 -0.9398) (xy 1.6764 -0.9398) (xy 1.6764 -0.7874) (xy 2.0574 -0.7874) (xy 2.0574 0.7874)
				(xy 1.6764 0.7874) (xy 1.6764 0.9398) (xy -1.6764 0.9398)
			)
			(stroke
				(width 0)
				(type default)
			)
			(fill no)
			(layer "F.CrtYd")
		)
		(fp_line
			(start 1.700022 -0.899922)
			(end 1.700022 0.899922)
			(stroke
				(width 0.1)
				(type default)
			)
			(layer "F.Fab")
		)
		(fp_line
			(start -1.700022 -0.899922)
			(end 1.700022 -0.899922)
			(stroke
				(width 0.1)
				(type default)
			)
			(layer "F.Fab")
		)
		(fp_line
			(start 1.700022 0.899922)
			(end -1.700022 0.899922)
			(stroke
				(width 0.1)
				(type default)
			)
			(layer "F.Fab")
		)
		(fp_line
			(start -1.700022 0.899922)
			(end -1.700022 -0.899922)
			(stroke
				(width 0.1)
				(type default)
			)
			(layer "F.Fab")
		)
		(pad "1" smd rect
			(at 1.4732 0 90)
			(size 1.1684 1.5748)
			(layers "F.Cu" "F.Mask" "F.Paste")
			(net "SW_PV_VDDR_NODE1_VIN_FLT")
		)
		(pad "2" smd rect
			(at -1.4732 0 90)
			(size 1.1684 1.5748)
			(layers "F.Cu" "F.Mask" "F.Paste")
			(net "GND")
		)
	)
	(footprint ""
		(layer "F.Cu")
		(at 7.465568 -145.471642 180)
		(property "Reference" "U56"
			(at 5.543296 -1.264666 90)
			(unlocked yes)
			(layer "F.SilkS")
			(effects
				(font
					(size 0.7874 0.5842)
					(thickness 0.1524)
				)
				(justify left)
			)
		)
		(property "Value" ""
			(at 0 0 180)
			(layer "F.Fab")
			(effects
				(font
					(size 1.27 1.27)
				)
			)
		)
		(duplicate_pad_numbers_are_jumpers no)
		(fp_line
			(start 4.9022 2.0066)
			(end -4.9022 2.0066)
			(stroke
				(width 0.1524)
				(type default)
			)
			(layer "F.SilkS")
		)
		(fp_line
			(start 4.9022 -2.0066)
			(end 4.9022 2.0066)
			(stroke
				(width 0.1524)
				(type default)
			)
			(layer "F.SilkS")
		)
		(fp_line
			(start -4.318 0)
			(end -4.9022 -0.5842)
			(stroke
				(width 0.1524)
				(type default)
			)
			(layer "F.SilkS")
		)
		(fp_line
			(start -4.9022 2.0066)
			(end -4.9022 0.5842)
			(stroke
				(width 0.1524)
				(type default)
			)
			(layer "F.SilkS")
		)
		(fp_line
			(start -4.9022 0.5842)
			(end -4.318 0)
			(stroke
				(width 0.1524)
				(type default)
			)
			(layer "F.SilkS")
		)
		(fp_line
			(start -4.9022 -0.5842)
			(end -4.9022 -2.0066)
			(stroke
				(width 0.1524)
				(type default)
			)
			(layer "F.SilkS")
		)
		(fp_line
			(start -4.9022 -2.0066)
			(end 4.9022 -2.0066)
			(stroke
				(width 0.1524)
				(type default)
			)
			(layer "F.SilkS")
		)
		(fp_circle
			(center -4.318 1.524)
			(end -4.572 1.524)
			(stroke
				(width 0.1524)
				(type default)
			)
			(fill no)
			(layer "F.SilkS")
		)
		(fp_rect
			(start -4.9022 3.6703)
			(end 4.9022 -3.6703)
			(stroke
				(width 0)
				(type default)
			)
			(fill no)
			(layer "F.CrtYd")
		)
		(pad "1" smd rect
			(at -4.225036 2.921 180)
			(size 0.3556 1.4986)
			(layers "F.Cu" "F.Mask" "F.Paste")
			(net "N54310596")
		)
		(pad "2" smd rect
			(at -3.57505 2.921 180)
			(size 0.3556 1.4986)
			(layers "F.Cu" "F.Mask" "F.Paste")
			(net "N54310598")
		)
		(pad "3" smd rect
			(at -2.925064 2.921 180)
			(size 0.3556 1.4986)
			(layers "F.Cu" "F.Mask" "F.Paste")
			(net "N54310606")
		)
		(pad "4" smd rect
			(at -2.275078 2.921 180)
			(size 0.3556 1.4986)
			(layers "F.Cu" "F.Mask" "F.Paste")
			(net "UART_RX_P6_L")
		)
		(pad "5" smd rect
			(at -1.625092 2.921 180)
			(size 0.3556 1.4986)
			(layers "F.Cu" "F.Mask" "F.Paste")
			(net "UART_RI_P6_L_N")
		)
		(pad "6" smd rect
			(at -0.975106 2.921 180)
			(size 0.3556 1.4986)
			(layers "F.Cu" "F.Mask" "F.Paste")
			(net "UART_DSR_P6_L_N")
		)
		(pad "7" smd rect
			(at -0.32512 2.921 180)
			(size 0.3556 1.4986)
			(layers "F.Cu" "F.Mask" "F.Paste")
			(net "UART_CTS_P6_L_N")
		)
		(pad "8" smd rect
			(at 0.32512 2.921 180)
			(size 0.3556 1.4986)
			(layers "F.Cu" "F.Mask" "F.Paste")
			(net "N54310531")
		)
		(pad "9" smd rect
			(at 0.975106 2.921 180)
			(size 0.3556 1.4986)
			(layers "F.Cu" "F.Mask" "F.Paste")
			(net "UART_RTS_P6_L_N")
		)
		(pad "10" smd rect
			(at 1.625092 2.921 180)
			(size 0.3556 1.4986)
			(layers "F.Cu" "F.Mask" "F.Paste")
			(net "UART_TX_P6_L")
		)
		(pad "11" smd rect
			(at 2.275078 2.921 180)
			(size 0.3556 1.4986)
			(layers "F.Cu" "F.Mask" "F.Paste")
			(net "UART_DTR_P6_L_N")
		)
		(pad "12" smd rect
			(at 2.925064 2.921 180)
			(size 0.3556 1.4986)
			(layers "F.Cu" "F.Mask" "F.Paste")
			(net "UART_DTR_P6_N")
		)
		(pad "13" smd rect
			(at 3.57505 2.921 180)
			(size 0.3556 1.4986)
			(layers "F.Cu" "F.Mask" "F.Paste")
			(net "UART_TX_P6")
		)
		(pad "14" smd rect
			(at 4.225036 2.921 180)
			(size 0.3556 1.4986)
			(layers "F.Cu" "F.Mask" "F.Paste")
			(net "UART_RTS_P6_N")
		)
		(pad "15" smd rect
			(at 4.225036 -2.921 180)
			(size 0.3556 1.4986)
			(layers "F.Cu" "F.Mask" "F.Paste")
			(net "Net_2303")
		)
		(pad "16" smd rect
			(at 3.57505 -2.921 180)
			(size 0.3556 1.4986)
			(layers "F.Cu" "F.Mask" "F.Paste")
			(net "UART_CTS_P6_N")
		)
		(pad "17" smd rect
			(at 2.925064 -2.921 180)
			(size 0.3556 1.4986)
			(layers "F.Cu" "F.Mask" "F.Paste")
			(net "UART_DSR_P6_N")
		)
		(pad "18" smd rect
			(at 2.275078 -2.921 180)
			(size 0.3556 1.4986)
			(layers "F.Cu" "F.Mask" "F.Paste")
			(net "UART_RI_P6_LS_N")
		)
		(pad "19" smd rect
			(at 1.625092 -2.921 180)
			(size 0.3556 1.4986)
			(layers "F.Cu" "F.Mask" "F.Paste")
			(net "UART_RX_P6")
		)
		(pad "20" smd rect
			(at 0.975106 -2.921 180)
			(size 0.3556 1.4986)
			(layers "F.Cu" "F.Mask" "F.Paste")
			(net "Net_2304")
		)
		(pad "21" smd rect
			(at 0.32512 -2.921 180)
			(size 0.3556 1.4986)
			(layers "F.Cu" "F.Mask" "F.Paste")
			(net "Net_2305")
		)
		(pad "22" smd rect
			(at -0.32512 -2.921 180)
			(size 0.3556 1.4986)
			(layers "F.Cu" "F.Mask" "F.Paste")
			(net "N54310545")
		)
		(pad "23" smd rect
			(at -0.975106 -2.921 180)
			(size 0.3556 1.4986)
			(layers "F.Cu" "F.Mask" "F.Paste")
			(net "N54310543")
		)
		(pad "24" smd rect
			(at -1.625092 -2.921 180)
			(size 0.3556 1.4986)
			(layers "F.Cu" "F.Mask" "F.Paste")
			(net "N54310592")
		)
		(pad "25" smd rect
			(at -2.275078 -2.921 180)
			(size 0.3556 1.4986)
			(layers "F.Cu" "F.Mask" "F.Paste")
			(net "GND")
		)
		(pad "26" smd rect
			(at -2.925064 -2.921 180)
			(size 0.3556 1.4986)
			(layers "F.Cu" "F.Mask" "F.Paste")
			(net "P3V3_NODE1")
		)
		(pad "27" smd rect
			(at -3.57505 -2.921 180)
			(size 0.3556 1.4986)
			(layers "F.Cu" "F.Mask" "F.Paste")
			(net "N54310604")
		)
		(pad "28" smd rect
			(at -4.225036 -2.921 180)
			(size 0.3556 1.4986)
			(layers "F.Cu" "F.Mask" "F.Paste")
			(net "N54310590")
		)
	)
	(footprint ""
		(layer "F.Cu")
		(at 114.52225 -153.548588)
		(property "Reference" "C887"
			(at -0.011684 1.914144 0)
			(unlocked yes)
			(layer "F.SilkS")
			(effects
				(font
					(size 0.635 0.4064)
					(thickness 0.1524)
				)
			)
		)
		(property "Value" ""
			(at 0 0 0)
			(layer "F.Fab")
			(effects
				(font
					(size 1.27 1.27)
				)
			)
		)
		(duplicate_pad_numbers_are_jumpers no)
		(fp_line
			(start -1.2954 -0.5842)
			(end 1.2954 -0.5842)
			(stroke
				(width 0.1524)
				(type default)
			)
			(layer "F.SilkS")
		)
		(fp_line
			(start -1.2954 0.5842)
			(end -1.2954 -0.5842)
			(stroke
				(width 0.1524)
				(type default)
			)
			(layer "F.SilkS")
		)
		(fp_line
			(start 0 -0.5842)
			(end 0 0.5842)
			(stroke
				(width 0.1524)
				(type default)
			)
			(layer "F.SilkS")
		)
		(fp_line
			(start 1.2954 -0.5842)
			(end 1.2954 0.5842)
			(stroke
				(width 0.1524)
				(type default)
			)
			(layer "F.SilkS")
		)
		(fp_line
			(start 1.2954 0.5842)
			(end -1.2954 0.5842)
			(stroke
				(width 0.1524)
				(type default)
			)
			(layer "F.SilkS")
		)
		(fp_poly
			(pts
				(xy 0.8636 -0.4572) (xy 0.8636 -0.3556) (xy 1.143 -0.3556) (xy 1.143 0.3556) (xy 0.8636 0.3556)
				(xy 0.8636 0.4572) (xy -0.8636 0.4572) (xy -0.8636 0.3556) (xy -1.143 0.3556) (xy -1.143 -0.3556)
				(xy -0.8636 -0.3556) (xy -0.8636 -0.4572)
			)
			(stroke
				(width 0)
				(type default)
			)
			(fill no)
			(layer "F.CrtYd")
		)
		(fp_line
			(start -0.884936 -0.504952)
			(end 0.884936 -0.504952)
			(stroke
				(width 0.1)
				(type default)
			)
			(layer "F.Fab")
		)
		(fp_line
			(start -0.884936 0.504952)
			(end -0.884936 -0.504952)
			(stroke
				(width 0.1)
				(type default)
			)
			(layer "F.Fab")
		)
		(fp_line
			(start 0.884936 -0.504952)
			(end 0.884936 0.504952)
			(stroke
				(width 0.1)
				(type default)
			)
			(layer "F.Fab")
		)
		(fp_line
			(start 0.884936 0.504952)
			(end -0.884936 0.504952)
			(stroke
				(width 0.1)
				(type default)
			)
			(layer "F.Fab")
		)
		(pad "1" smd rect
			(at 0.7366 0 90)
			(size 0.7112 0.8128)
			(layers "F.Cu" "F.Mask" "F.Paste")
			(net "GND")
		)
		(pad "2" smd rect
			(at -0.7366 0 90)
			(size 0.7112 0.8128)
			(layers "F.Cu" "F.Mask" "F.Paste")
			(net "N52410978")
		)
	)
	(footprint ""
		(layer "F.Cu")
		(at 191.369442 -115.705128 180)
		(property "Reference" "R1026"
			(at -1.524254 -0.157734 0)
			(unlocked yes)
			(layer "F.SilkS")
			(effects
				(font
					(size 0.7874 0.5842)
					(thickness 0.1524)
				)
				(justify left)
			)
		)
		(property "Value" ""
			(at 0 0 180)
			(layer "F.Fab")
			(effects
				(font
					(size 1.27 1.27)
				)
			)
		)
		(duplicate_pad_numbers_are_jumpers no)
		(fp_line
			(start 0.7874 0.4064)
			(end -0.7874 0.4064)
			(stroke
				(width 0.1524)
				(type default)
			)
			(layer "F.SilkS")
		)
		(fp_line
			(start 0.7874 -0.4064)
			(end 0.7874 0.4064)
			(stroke
				(width 0.1524)
				(type default)
			)
			(layer "F.SilkS")
		)
		(fp_line
			(start -0.7874 0.4064)
			(end -0.7874 -0.4064)
			(stroke
				(width 0.1524)
				(type default)
			)
			(layer "F.SilkS")
		)
		(fp_line
			(start -0.7874 -0.4064)
			(end 0.7874 -0.4064)
			(stroke
				(width 0.1524)
				(type default)
			)
			(layer "F.SilkS")
		)
		(fp_poly
			(pts
				(xy -0.508 0.2794) (xy -0.508 0.2286) (xy -0.635 0.2286) (xy -0.635 -0.254) (xy -0.5334 -0.254)
				(xy -0.5334 -0.2794) (xy 0.5334 -0.2794) (xy 0.5334 -0.254) (xy 0.635 -0.254) (xy 0.635 0.254) (xy 0.5334 0.254)
				(xy 0.5334 0.2794)
			)
			(stroke
				(width 0)
				(type default)
			)
			(fill no)
			(layer "F.CrtYd")
		)
		(pad "1" smd rect
			(at 0.40005 0 180)
			(size 0.4572 0.508)
			(layers "F.Cu" "F.Mask" "F.Paste")
			(net "P12V_NODE1_PWRGD_EN")
		)
		(pad "2" smd rect
			(at -0.40005 0 180)
			(size 0.4572 0.508)
			(layers "F.Cu" "F.Mask" "F.Paste")
			(net "P12V_AUX")
		)
	)
	(footprint ""
		(layer "F.Cu")
		(at 143.105886 -53.513228 180)
		(property "Reference" "R1016"
			(at -1.112266 0.915416 0)
			(unlocked yes)
			(layer "F.SilkS")
			(effects
				(font
					(size 0.7874 0.5842)
					(thickness 0.1524)
				)
				(justify left)
			)
		)
		(property "Value" ""
			(at 0 0 180)
			(layer "F.Fab")
			(effects
				(font
					(size 1.27 1.27)
				)
			)
		)
		(duplicate_pad_numbers_are_jumpers no)
		(fp_line
			(start 0.7874 0.4064)
			(end -0.7874 0.4064)
			(stroke
				(width 0.1524)
				(type default)
			)
			(layer "F.SilkS")
		)
		(fp_line
			(start 0.7874 -0.4064)
			(end 0.7874 0.4064)
			(stroke
				(width 0.1524)
				(type default)
			)
			(layer "F.SilkS")
		)
		(fp_line
			(start -0.7874 0.4064)
			(end -0.7874 -0.4064)
			(stroke
				(width 0.1524)
				(type default)
			)
			(layer "F.SilkS")
		)
		(fp_line
			(start -0.7874 -0.4064)
			(end 0.7874 -0.4064)
			(stroke
				(width 0.1524)
				(type default)
			)
			(layer "F.SilkS")
		)
		(fp_poly
			(pts
				(xy -0.508 0.2794) (xy -0.508 0.2286) (xy -0.635 0.2286) (xy -0.635 -0.254) (xy -0.5334 -0.254)
				(xy -0.5334 -0.2794) (xy 0.5334 -0.2794) (xy 0.5334 -0.254) (xy 0.635 -0.254) (xy 0.635 0.254) (xy 0.5334 0.254)
				(xy 0.5334 0.2794)
			)
			(stroke
				(width 0)
				(type default)
			)
			(fill no)
			(layer "F.CrtYd")
		)
		(pad "1" smd rect
			(at 0.40005 0 180)
			(size 0.4572 0.508)
			(layers "F.Cu" "F.Mask" "F.Paste")
			(net "GND")
		)
		(pad "2" smd rect
			(at -0.40005 0 180)
			(size 0.4572 0.508)
			(layers "F.Cu" "F.Mask" "F.Paste")
			(net "UART_DTR_P2_N")
		)
	)
	(footprint ""
		(layer "F.Cu")
		(at 162.873944 -93.840808 -90)
		(property "Reference" "R523"
			(at 1.2192 4.223512 90)
			(unlocked yes)
			(layer "F.SilkS")
			(effects
				(font
					(size 0.7874 0.5842)
					(thickness 0.1524)
				)
				(justify left)
			)
		)
		(property "Value" ""
			(at 0 0 270)
			(layer "F.Fab")
			(effects
				(font
					(size 1.27 1.27)
				)
			)
		)
		(duplicate_pad_numbers_are_jumpers no)
		(fp_line
			(start -0.7874 0.4064)
			(end -0.7874 -0.4064)
			(stroke
				(width 0.1524)
				(type default)
			)
			(layer "F.SilkS")
		)
		(fp_line
			(start 0.7874 0.4064)
			(end -0.7874 0.4064)
			(stroke
				(width 0.1524)
				(type default)
			)
			(layer "F.SilkS")
		)
		(fp_line
			(start -0.7874 -0.4064)
			(end 0.7874 -0.4064)
			(stroke
				(width 0.1524)
				(type default)
			)
			(layer "F.SilkS")
		)
		(fp_line
			(start 0.7874 -0.4064)
			(end 0.7874 0.4064)
			(stroke
				(width 0.1524)
				(type default)
			)
			(layer "F.SilkS")
		)
		(fp_poly
			(pts
				(xy -0.508 0.2794) (xy -0.508 0.2286) (xy -0.635 0.2286) (xy -0.635 -0.254) (xy -0.5334 -0.254)
				(xy -0.5334 -0.2794) (xy 0.5334 -0.2794) (xy 0.5334 -0.254) (xy 0.635 -0.254) (xy 0.635 0.254) (xy 0.5334 0.254)
				(xy 0.5334 0.2794)
			)
			(stroke
				(width 0)
				(type default)
			)
			(fill no)
			(layer "F.CrtYd")
		)
		(pad "1" smd rect
			(at 0.40005 0 270)
			(size 0.4572 0.508)
			(layers "F.Cu" "F.Mask" "F.Paste")
			(net "SPI_USB_NODE1_CSB_N")
		)
		(pad "2" smd rect
			(at -0.40005 0 270)
			(size 0.4572 0.508)
			(layers "F.Cu" "F.Mask" "F.Paste")
			(net "SPI_USB_NODE1_CSB_R_L")
		)
	)
	(footprint ""
		(layer "F.Cu")
		(at 7.65556 -138.620246 -90)
		(property "Reference" "R1301"
			(at 4.242054 4.237482 90)
			(unlocked yes)
			(layer "F.SilkS")
			(effects
				(font
					(size 0.7874 0.5842)
					(thickness 0.1524)
				)
				(justify left)
			)
		)
		(property "Value" ""
			(at 0 0 270)
			(layer "F.Fab")
			(effects
				(font
					(size 1.27 1.27)
				)
			)
		)
		(duplicate_pad_numbers_are_jumpers no)
		(fp_line
			(start -0.7874 0.4064)
			(end -0.7874 -0.4064)
			(stroke
				(width 0.1524)
				(type default)
			)
			(layer "F.SilkS")
		)
		(fp_line
			(start 0.7874 0.4064)
			(end -0.7874 0.4064)
			(stroke
				(width 0.1524)
				(type default)
			)
			(layer "F.SilkS")
		)
		(fp_line
			(start -0.7874 -0.4064)
			(end 0.7874 -0.4064)
			(stroke
				(width 0.1524)
				(type default)
			)
			(layer "F.SilkS")
		)
		(fp_line
			(start 0.7874 -0.4064)
			(end 0.7874 0.4064)
			(stroke
				(width 0.1524)
				(type default)
			)
			(layer "F.SilkS")
		)
		(fp_poly
			(pts
				(xy -0.508 0.2794) (xy -0.508 0.2286) (xy -0.635 0.2286) (xy -0.635 -0.254) (xy -0.5334 -0.254)
				(xy -0.5334 -0.2794) (xy 0.5334 -0.2794) (xy 0.5334 -0.254) (xy 0.635 -0.254) (xy 0.635 0.254) (xy 0.5334 0.254)
				(xy 0.5334 0.2794)
			)
			(stroke
				(width 0)
				(type default)
			)
			(fill no)
			(layer "F.CrtYd")
		)
		(pad "1" smd rect
			(at 0.40005 0 270)
			(size 0.4572 0.508)
			(layers "F.Cu" "F.Mask" "F.Paste")
			(net "P3V3_NODE1")
		)
		(pad "2" smd rect
			(at -0.40005 0 270)
			(size 0.4572 0.508)
			(layers "F.Cu" "F.Mask" "F.Paste")
			(net "N54310545")
		)
	)
	(footprint ""
		(layer "F.Cu")
		(at 179.53863 -138.152632 180)
		(property "Reference" "C798"
			(at -2.058416 -0.136398 0)
			(unlocked yes)
			(layer "F.SilkS")
			(effects
				(font
					(size 0.7874 0.5842)
					(thickness 0.1524)
				)
				(justify left)
			)
		)
		(property "Value" ""
			(at 0 0 180)
			(layer "F.Fab")
			(effects
				(font
					(size 1.27 1.27)
				)
			)
		)
		(duplicate_pad_numbers_are_jumpers no)
		(fp_line
			(start 1.905 0.8636)
			(end -1.905 0.8636)
			(stroke
				(width 0.1524)
				(type default)
			)
			(layer "F.SilkS")
		)
		(fp_line
			(start 1.905 -0.8636)
			(end 1.905 0.8636)
			(stroke
				(width 0.1524)
				(type default)
			)
			(layer "F.SilkS")
		)
		(fp_line
			(start 0 0.8382)
			(end 0 -0.8382)
			(stroke
				(width 0.1524)
				(type default)
			)
			(layer "F.SilkS")
		)
		(fp_line
			(start -1.905 0.8636)
			(end -1.905 -0.8636)
			(stroke
				(width 0.1524)
				(type default)
			)
			(layer "F.SilkS")
		)
		(fp_line
			(start -1.905 -0.8636)
			(end 1.905 -0.8636)
			(stroke
				(width 0.1524)
				(type default)
			)
			(layer "F.SilkS")
		)
		(fp_rect
			(start -1.524 0.7366)
			(end 1.524 -0.7366)
			(stroke
				(width 0)
				(type default)
			)
			(fill no)
			(layer "F.CrtYd")
		)
		(pad "1" smd rect
			(at 0.94996 0 180)
			(size 1.1176 1.3716)
			(layers "F.Cu" "F.Mask" "F.Paste")
			(net "PWR_BTN_NODE1_C_L")
		)
		(pad "2" smd rect
			(at -0.94996 0 180)
			(size 1.1176 1.3716)
			(layers "F.Cu" "F.Mask" "F.Paste")
			(net "GND")
		)
	)
	(footprint ""
		(layer "F.Cu")
		(at 187.591954 -121.65965)
		(property "Reference" "R1035"
			(at 5.448046 18.94332 0)
			(unlocked yes)
			(layer "F.SilkS")
			(effects
				(font
					(size 0.7874 0.5842)
					(thickness 0.1524)
				)
				(justify left)
			)
		)
		(property "Value" ""
			(at 0 0 0)
			(layer "F.Fab")
			(effects
				(font
					(size 1.27 1.27)
				)
			)
		)
		(duplicate_pad_numbers_are_jumpers no)
		(fp_line
			(start -0.7874 -0.4064)
			(end 0.7874 -0.4064)
			(stroke
				(width 0.1524)
				(type default)
			)
			(layer "F.SilkS")
		)
		(fp_line
			(start -0.7874 0.4064)
			(end -0.7874 -0.4064)
			(stroke
				(width 0.1524)
				(type default)
			)
			(layer "F.SilkS")
		)
		(fp_line
			(start 0.7874 -0.4064)
			(end 0.7874 0.4064)
			(stroke
				(width 0.1524)
				(type default)
			)
			(layer "F.SilkS")
		)
		(fp_line
			(start 0.7874 0.4064)
			(end -0.7874 0.4064)
			(stroke
				(width 0.1524)
				(type default)
			)
			(layer "F.SilkS")
		)
		(fp_poly
			(pts
				(xy -0.508 0.2794) (xy -0.508 0.2286) (xy -0.635 0.2286) (xy -0.635 -0.254) (xy -0.5334 -0.254)
				(xy -0.5334 -0.2794) (xy 0.5334 -0.2794) (xy 0.5334 -0.254) (xy 0.635 -0.254) (xy 0.635 0.254) (xy 0.5334 0.254)
				(xy 0.5334 0.2794)
			)
			(stroke
				(width 0)
				(type default)
			)
			(fill no)
			(layer "F.CrtYd")
		)
		(pad "1" smd rect
			(at 0.40005 0)
			(size 0.4572 0.508)
			(layers "F.Cu" "F.Mask" "F.Paste")
			(net "P3V3_STB_NODE1")
		)
		(pad "2" smd rect
			(at -0.40005 0)
			(size 0.4572 0.508)
			(layers "F.Cu" "F.Mask" "F.Paste")
			(net "JTAG_CPLD1_TDI")
		)
	)
	(footprint ""
		(layer "F.Cu")
		(at 100.550472 -151.877268)
		(property "Reference" "PC33"
			(at -2.59334 3.216656 0)
			(unlocked yes)
			(layer "F.SilkS")
			(effects
				(font
					(size 0.7874 0.5842)
					(thickness 0.1524)
				)
				(justify left)
			)
		)
		(property "Value" ""
			(at 0 0 0)
			(layer "F.Fab")
			(effects
				(font
					(size 1.27 1.27)
				)
			)
		)
		(duplicate_pad_numbers_are_jumpers no)
		(fp_line
			(start -0.7874 -0.4064)
			(end 0.7874 -0.4064)
			(stroke
				(width 0.1524)
				(type default)
			)
			(layer "F.SilkS")
		)
		(fp_line
			(start -0.7874 0.4064)
			(end -0.7874 -0.4064)
			(stroke
				(width 0.1524)
				(type default)
			)
			(layer "F.SilkS")
		)
		(fp_line
			(start 0 0.381)
			(end 0 -0.381)
			(stroke
				(width 0.1524)
				(type default)
			)
			(layer "F.SilkS")
		)
		(fp_line
			(start 0.7874 -0.4064)
			(end 0.7874 0.4064)
			(stroke
				(width 0.1524)
				(type default)
			)
			(layer "F.SilkS")
		)
		(fp_line
			(start 0.7874 0.4064)
			(end -0.7874 0.4064)
			(stroke
				(width 0.1524)
				(type default)
			)
			(layer "F.SilkS")
		)
		(fp_poly
			(pts
				(xy -0.5334 0.254) (xy -0.635 0.254) (xy -0.635 0.2286) (xy -0.635 -0.254) (xy -0.5334 -0.254) (xy -0.5334 -0.2794)
				(xy 0.5334 -0.2794) (xy 0.5334 -0.254) (xy 0.635 -0.254) (xy 0.635 0.254) (xy 0.5334 0.254) (xy 0.5334 0.2794)
				(xy -0.508 0.2794) (xy -0.5334 0.2794)
			)
			(stroke
				(width 0)
				(type default)
			)
			(fill no)
			(layer "F.CrtYd")
		)
		(pad "1" smd rect
			(at 0.40005 0)
			(size 0.4572 0.508)
			(layers "F.Cu" "F.Mask" "F.Paste")
			(net "P12V_AUX")
		)
		(pad "2" smd rect
			(at -0.40005 0)
			(size 0.4572 0.508)
			(layers "F.Cu" "F.Mask" "F.Paste")
			(net "GND")
		)
	)
	(footprint ""
		(layer "F.Cu")
		(at 171.05122 -49.05121)
		(property "Reference" "C559"
			(at -3.896614 2.135886 0)
			(unlocked yes)
			(layer "F.SilkS")
			(effects
				(font
					(size 0.7874 0.5842)
					(thickness 0.1524)
				)
				(justify left)
			)
		)
		(property "Value" ""
			(at 0 0 0)
			(layer "F.Fab")
			(effects
				(font
					(size 1.27 1.27)
				)
			)
		)
		(duplicate_pad_numbers_are_jumpers no)
		(fp_line
			(start -1.905 -0.8636)
			(end 1.905 -0.8636)
			(stroke
				(width 0.1524)
				(type default)
			)
			(layer "F.SilkS")
		)
		(fp_line
			(start -1.905 0.8636)
			(end -1.905 -0.8636)
			(stroke
				(width 0.1524)
				(type default)
			)
			(layer "F.SilkS")
		)
		(fp_line
			(start 0 0.8382)
			(end 0 -0.8382)
			(stroke
				(width 0.1524)
				(type default)
			)
			(layer "F.SilkS")
		)
		(fp_line
			(start 1.905 -0.8636)
			(end 1.905 0.8636)
			(stroke
				(width 0.1524)
				(type default)
			)
			(layer "F.SilkS")
		)
		(fp_line
			(start 1.905 0.8636)
			(end -1.905 0.8636)
			(stroke
				(width 0.1524)
				(type default)
			)
			(layer "F.SilkS")
		)
		(fp_rect
			(start -1.524 0.7366)
			(end 1.524 -0.7366)
			(stroke
				(width 0)
				(type default)
			)
			(fill no)
			(layer "F.CrtYd")
		)
		(pad "1" smd rect
			(at 0.94996 0)
			(size 1.1176 1.3716)
			(layers "F.Cu" "F.Mask" "F.Paste")
			(net "P5V_NODE1")
		)
		(pad "2" smd rect
			(at -0.94996 0)
			(size 1.1176 1.3716)
			(layers "F.Cu" "F.Mask" "F.Paste")
			(net "GND")
		)
	)
	(footprint ""
		(layer "F.Cu")
		(at 40.17391 -6.190742 180)
		(property "Reference" "PJ10"
			(at 9.209532 -1.064768 90)
			(unlocked yes)
			(layer "F.SilkS")
			(effects
				(font
					(size 0.7874 0.5842)
					(thickness 0.1524)
				)
				(justify left)
			)
		)
		(property "Value" ""
			(at 0 0 180)
			(layer "F.Fab")
			(effects
				(font
					(size 1.27 1.27)
				)
			)
		)
		(duplicate_pad_numbers_are_jumpers no)
		(fp_poly
			(pts
				(xy 0.2794 0.907796) (xy 0.254 0.907796) (xy 0.254 1.0414) (xy -0.254 1.0414) (xy -0.254 1.034796)
				(xy -0.254 0.933196) (xy -0.2794 0.933196) (xy -0.2794 -0.133604) (xy -0.254 -0.133604) (xy -0.254 -0.235204)
				(xy 0.254 -0.235204) (xy 0.254 -0.133604) (xy 0.2794 -0.133604)
			)
			(stroke
				(width 0)
				(type default)
			)
			(fill no)
			(layer "F.CrtYd")
		)
		(pad "1" smd custom
			(at 0 -0.000254 180)
			(size 0.127 0.127)
			(layers "F.Cu" "F.Mask" "F.Paste")
			(net "FM_CPLD_NODE1_PVDDR_STB_EN")
			(options
				(clearance outline)
				(anchor circle)
			)
			(primitives
				(gr_poly
					(pts
						(xy -0.127 0.508) (xy -0.127 -0.0508) (xy -0.254 -0.0508) (xy -0.254 -0.508) (xy 0.254 -0.508)
						(xy 0.254 -0.0508) (xy 0.127 -0.0508) (xy 0.127 0.508)
					)
					(width 0)
					(fill yes)
				)
			)
		)
		(pad "2" smd rect
			(at 0 0.799846 270)
			(size 0.4572 0.508)
			(layers "F.Cu" "F.Mask" "F.Paste")
			(net "PV_VDDR_NODE1_EN")
		)
		(zone
			(layer "F.Cu")
			(hatch none 0.5)
			(connect_pads
				(clearance 0)
			)
			(min_thickness 0.25)
			(keepout
				(tracks allowed)
				(vias not_allowed)
				(pads allowed)
				(copperpour not_allowed)
				(footprints allowed)
			)
			(placement
				(enabled no)
				(sheetname "")
			)
			(fill
				(thermal_gap 0.5)
				(thermal_bridge_width 0.5)
				(island_removal_mode 0)
			)
			(polygon
				(pts
					(xy 40.47871 -7.276338) (xy 39.86911 -7.276338) (xy 39.86911 -5.904738) (xy 40.47871 -5.904738)
				)
			)
		)
	)
	(footprint ""
		(layer "F.Cu")
		(at 185.2676 -188.4172 -90)
		(property "Reference" "R1072"
			(at -1.1176 -0.28067 90)
			(unlocked yes)
			(layer "F.SilkS")
			(effects
				(font
					(size 0.7874 0.5842)
					(thickness 0.1524)
				)
				(justify left)
			)
		)
		(property "Value" ""
			(at 0 0 270)
			(layer "F.Fab")
			(effects
				(font
					(size 1.27 1.27)
				)
			)
		)
		(duplicate_pad_numbers_are_jumpers no)
		(fp_line
			(start -0.7874 0.4064)
			(end -0.7874 -0.4064)
			(stroke
				(width 0.1524)
				(type default)
			)
			(layer "F.SilkS")
		)
		(fp_line
			(start 0.7874 0.4064)
			(end -0.7874 0.4064)
			(stroke
				(width 0.1524)
				(type default)
			)
			(layer "F.SilkS")
		)
		(fp_line
			(start -0.7874 -0.4064)
			(end 0.7874 -0.4064)
			(stroke
				(width 0.1524)
				(type default)
			)
			(layer "F.SilkS")
		)
		(fp_line
			(start 0.7874 -0.4064)
			(end 0.7874 0.4064)
			(stroke
				(width 0.1524)
				(type default)
			)
			(layer "F.SilkS")
		)
		(fp_poly
			(pts
				(xy -0.508 0.2794) (xy -0.508 0.2286) (xy -0.635 0.2286) (xy -0.635 -0.254) (xy -0.5334 -0.254)
				(xy -0.5334 -0.2794) (xy 0.5334 -0.2794) (xy 0.5334 -0.254) (xy 0.635 -0.254) (xy 0.635 0.254) (xy 0.5334 0.254)
				(xy 0.5334 0.2794)
			)
			(stroke
				(width 0)
				(type default)
			)
			(fill no)
			(layer "F.CrtYd")
		)
		(pad "1" smd rect
			(at 0.40005 0 270)
			(size 0.4572 0.508)
			(layers "F.Cu" "F.Mask" "F.Paste")
			(net "POWER_SW1_PWR_CTR_12V")
		)
		(pad "2" smd rect
			(at -0.40005 0 270)
			(size 0.4572 0.508)
			(layers "F.Cu" "F.Mask" "F.Paste")
			(net "POWER_SW1_PWR_CTR_12V_R")
		)
	)
	(footprint ""
		(layer "F.Cu")
		(at 28.466288 -123.274582 90)
		(property "Reference" "C829"
			(at -4.108958 -1.249934 90)
			(unlocked yes)
			(layer "F.SilkS")
			(effects
				(font
					(size 0.7874 0.5842)
					(thickness 0.1524)
				)
				(justify left)
			)
		)
		(property "Value" ""
			(at 0 0 90)
			(layer "F.Fab")
			(effects
				(font
					(size 1.27 1.27)
				)
			)
		)
		(duplicate_pad_numbers_are_jumpers no)
		(fp_line
			(start 0.7874 -0.4064)
			(end 0.7874 0.4064)
			(stroke
				(width 0.1524)
				(type default)
			)
			(layer "F.SilkS")
		)
		(fp_line
			(start -0.7874 -0.4064)
			(end 0.7874 -0.4064)
			(stroke
				(width 0.1524)
				(type default)
			)
			(layer "F.SilkS")
		)
		(fp_line
			(start 0 0.381)
			(end 0 -0.381)
			(stroke
				(width 0.1524)
				(type default)
			)
			(layer "F.SilkS")
		)
		(fp_line
			(start 0.7874 0.4064)
			(end -0.7874 0.4064)
			(stroke
				(width 0.1524)
				(type default)
			)
			(layer "F.SilkS")
		)
		(fp_line
			(start -0.7874 0.4064)
			(end -0.7874 -0.4064)
			(stroke
				(width 0.1524)
				(type default)
			)
			(layer "F.SilkS")
		)
		(fp_poly
			(pts
				(xy -0.5334 0.254) (xy -0.635 0.254) (xy -0.635 0.2286) (xy -0.635 -0.254) (xy -0.5334 -0.254) (xy -0.5334 -0.2794)
				(xy 0.5334 -0.2794) (xy 0.5334 -0.254) (xy 0.635 -0.254) (xy 0.635 0.254) (xy 0.5334 0.254) (xy 0.5334 0.2794)
				(xy -0.508 0.2794) (xy -0.5334 0.2794)
			)
			(stroke
				(width 0)
				(type default)
			)
			(fill no)
			(layer "F.CrtYd")
		)
		(pad "1" smd rect
			(at 0.40005 0 90)
			(size 0.4572 0.508)
			(layers "F.Cu" "F.Mask" "F.Paste")
			(net "FM_CPLD_NODE1_P1V538_BMC_EN")
		)
		(pad "2" smd rect
			(at -0.40005 0 90)
			(size 0.4572 0.508)
			(layers "F.Cu" "F.Mask" "F.Paste")
			(net "GND")
		)
	)
	(footprint ""
		(layer "F.Cu")
		(at 168.87698 -169.633646 -90)
		(property "Reference" "C563"
			(at -0.430784 -2.786126 0)
			(unlocked yes)
			(layer "F.SilkS")
			(effects
				(font
					(size 0.7874 0.5842)
					(thickness 0.1524)
				)
				(justify left)
			)
		)
		(property "Value" ""
			(at 0 0 270)
			(layer "F.Fab")
			(effects
				(font
					(size 1.27 1.27)
				)
			)
		)
		(duplicate_pad_numbers_are_jumpers no)
		(fp_line
			(start -0.7874 0.4064)
			(end -0.7874 -0.4064)
			(stroke
				(width 0.1524)
				(type default)
			)
			(layer "F.SilkS")
		)
		(fp_line
			(start 0.7874 0.4064)
			(end -0.7874 0.4064)
			(stroke
				(width 0.1524)
				(type default)
			)
			(layer "F.SilkS")
		)
		(fp_line
			(start 0 0.381)
			(end 0 -0.381)
			(stroke
				(width 0.1524)
				(type default)
			)
			(layer "F.SilkS")
		)
		(fp_line
			(start -0.7874 -0.4064)
			(end 0.7874 -0.4064)
			(stroke
				(width 0.1524)
				(type default)
			)
			(layer "F.SilkS")
		)
		(fp_line
			(start 0.7874 -0.4064)
			(end 0.7874 0.4064)
			(stroke
				(width 0.1524)
				(type default)
			)
			(layer "F.SilkS")
		)
		(fp_poly
			(pts
				(xy -0.5334 0.254) (xy -0.635 0.254) (xy -0.635 0.2286) (xy -0.635 -0.254) (xy -0.5334 -0.254) (xy -0.5334 -0.2794)
				(xy 0.5334 -0.2794) (xy 0.5334 -0.254) (xy 0.635 -0.254) (xy 0.635 0.254) (xy 0.5334 0.254) (xy 0.5334 0.2794)
				(xy -0.508 0.2794) (xy -0.5334 0.2794)
			)
			(stroke
				(width 0)
				(type default)
			)
			(fill no)
			(layer "F.CrtYd")
		)
		(pad "1" smd rect
			(at 0.40005 0 270)
			(size 0.4572 0.508)
			(layers "F.Cu" "F.Mask" "F.Paste")
			(net "N54365611")
		)
		(pad "2" smd rect
			(at -0.40005 0 270)
			(size 0.4572 0.508)
			(layers "F.Cu" "F.Mask" "F.Paste")
			(net "N54365613")
		)
	)
	(footprint ""
		(layer "F.Cu")
		(at 187.7695 -164.040566)
		(property "Reference" "R1278"
			(at -1.672844 5.349494 0)
			(unlocked yes)
			(layer "F.SilkS")
			(effects
				(font
					(size 0.7874 0.5842)
					(thickness 0.1524)
				)
				(justify left)
			)
		)
		(property "Value" ""
			(at 0 0 0)
			(layer "F.Fab")
			(effects
				(font
					(size 1.27 1.27)
				)
			)
		)
		(duplicate_pad_numbers_are_jumpers no)
		(fp_line
			(start -0.7874 -0.4064)
			(end 0.7874 -0.4064)
			(stroke
				(width 0.1524)
				(type default)
			)
			(layer "F.SilkS")
		)
		(fp_line
			(start -0.7874 0.4064)
			(end -0.7874 -0.4064)
			(stroke
				(width 0.1524)
				(type default)
			)
			(layer "F.SilkS")
		)
		(fp_line
			(start 0.7874 -0.4064)
			(end 0.7874 0.4064)
			(stroke
				(width 0.1524)
				(type default)
			)
			(layer "F.SilkS")
		)
		(fp_line
			(start 0.7874 0.4064)
			(end -0.7874 0.4064)
			(stroke
				(width 0.1524)
				(type default)
			)
			(layer "F.SilkS")
		)
		(fp_poly
			(pts
				(xy -0.508 0.2794) (xy -0.508 0.2286) (xy -0.635 0.2286) (xy -0.635 -0.254) (xy -0.5334 -0.254)
				(xy -0.5334 -0.2794) (xy 0.5334 -0.2794) (xy 0.5334 -0.254) (xy 0.635 -0.254) (xy 0.635 0.254) (xy 0.5334 0.254)
				(xy 0.5334 0.2794)
			)
			(stroke
				(width 0)
				(type default)
			)
			(fill no)
			(layer "F.CrtYd")
		)
		(pad "1" smd rect
			(at 0.40005 0)
			(size 0.4572 0.508)
			(layers "F.Cu" "F.Mask" "F.Paste")
			(net "N54134271")
		)
		(pad "2" smd rect
			(at -0.40005 0)
			(size 0.4572 0.508)
			(layers "F.Cu" "F.Mask" "F.Paste")
			(net "LAN2_P2_R")
		)
	)
	(footprint ""
		(layer "F.Cu")
		(at 177.40122 -53.881528 90)
		(property "Reference" "D10"
			(at 2.388616 -4.25323 0)
			(unlocked yes)
			(layer "F.SilkS")
			(effects
				(font
					(size 0.7874 0.5842)
					(thickness 0.1524)
				)
				(justify left)
			)
		)
		(property "Value" ""
			(at 0 0 90)
			(layer "F.Fab")
			(effects
				(font
					(size 1.27 1.27)
				)
			)
		)
		(duplicate_pad_numbers_are_jumpers no)
		(fp_line
			(start 0.450088 -1.370076)
			(end -0.450088 -1.370076)
			(stroke
				(width 0.1524)
				(type default)
			)
			(layer "F.SilkS")
		)
		(fp_line
			(start -0.450088 -1.370076)
			(end -0.450088 0.430022)
			(stroke
				(width 0.1524)
				(type default)
			)
			(layer "F.SilkS")
		)
		(fp_line
			(start -0.2794 -1.2954)
			(end 0.4064 -1.27)
			(stroke
				(width 0.1524)
				(type default)
			)
			(layer "F.SilkS")
		)
		(fp_line
			(start 0.4064 -1.27)
			(end -0.381 -1.27)
			(stroke
				(width 0.1524)
				(type default)
			)
			(layer "F.SilkS")
		)
		(fp_line
			(start -0.149098 -0.487172)
			(end 0.185674 -0.487172)
			(stroke
				(width 0.050038)
				(type default)
			)
			(layer "F.SilkS")
		)
		(fp_line
			(start 0.0127 -0.4699)
			(end -0.0762 -0.3556)
			(stroke
				(width 0.050038)
				(type default)
			)
			(layer "F.SilkS")
		)
		(fp_line
			(start 0.1016 -0.3556)
			(end 0.0127 -0.4699)
			(stroke
				(width 0.050038)
				(type default)
			)
			(layer "F.SilkS")
		)
		(fp_line
			(start -0.0762 -0.3556)
			(end 0.1016 -0.3556)
			(stroke
				(width 0.050038)
				(type default)
			)
			(layer "F.SilkS")
		)
		(fp_line
			(start 0.450088 0.430022)
			(end 0.450088 -1.35001)
			(stroke
				(width 0.1524)
				(type default)
			)
			(layer "F.SilkS")
		)
		(fp_line
			(start -0.450088 0.430022)
			(end 0.450088 0.430022)
			(stroke
				(width 0.1524)
				(type default)
			)
			(layer "F.SilkS")
		)
		(fp_poly
			(pts
				(xy -0.350012 -0.501142) (xy -0.350012 -0.348742) (xy -0.3556 -0.348742) (xy -0.3556 0.337058) (xy 0.3556 0.337058)
				(xy 0.3556 -0.348742) (xy 0.350012 -0.348742) (xy 0.350012 -0.475742) (xy 0.3556 -0.475742) (xy 0.3556 -1.186942)
				(xy -0.3556 -1.186942) (xy -0.3556 -0.501142)
			)
			(stroke
				(width 0)
				(type default)
			)
			(fill no)
			(layer "F.CrtYd")
		)
		(fp_line
			(start 0.350012 -0.975106)
			(end -0.350012 -0.975106)
			(stroke
				(width 0.1)
				(type default)
			)
			(layer "F.Fab")
		)
		(fp_line
			(start -0.350012 -0.975106)
			(end -0.350012 0.124968)
			(stroke
				(width 0.1)
				(type default)
			)
			(layer "F.Fab")
		)
		(fp_line
			(start 0.350012 0.124968)
			(end 0.350012 -0.975106)
			(stroke
				(width 0.1)
				(type default)
			)
			(layer "F.Fab")
		)
		(fp_line
			(start -0.350012 0.124968)
			(end 0.350012 0.124968)
			(stroke
				(width 0.1)
				(type default)
			)
			(layer "F.Fab")
		)
		(fp_text user "-"
			(at -0.734568 -1.92024 0)
			(unlocked yes)
			(layer "F.SilkS")
			(effects
				(font
					(size 1.27 0.9652)
					(thickness 0.1524)
				)
				(justify left)
			)
		)
		(fp_text user "+"
			(at 0.494538 1.40081 180)
			(unlocked yes)
			(layer "F.SilkS")
			(effects
				(font
					(size 1.27 0.9652)
					(thickness 0.1524)
				)
				(justify left)
			)
		)
		(pad "A" smd rect
			(at 0 0 180)
			(size 0.5588 0.6096)
			(layers "F.Cu" "F.Mask" "F.Paste")
			(net "GND")
		)
		(pad "C" smd rect
			(at 0 -0.849884)
			(size 0.5588 0.6096)
			(layers "F.Cu" "F.Mask" "F.Paste")
			(net "USBPWR_P1")
		)
	)
	(footprint ""
		(layer "F.Cu")
		(at 16.278606 -126.354078)
		(property "Reference" "PQ1"
			(at 7.107936 2.467356 90)
			(unlocked yes)
			(layer "F.SilkS")
			(effects
				(font
					(size 0.7874 0.5842)
					(thickness 0.1524)
				)
				(justify left)
			)
		)
		(property "Value" ""
			(at 0 0 0)
			(layer "F.Fab")
			(effects
				(font
					(size 1.27 1.27)
				)
			)
		)
		(duplicate_pad_numbers_are_jumpers no)
		(fp_line
			(start -0.157988 -0.525018)
			(end 4.341876 -0.525018)
			(stroke
				(width 0.1524)
				(type default)
			)
			(layer "F.SilkS")
		)
		(fp_line
			(start -0.157988 -0.294894)
			(end -0.157988 -0.525018)
			(stroke
				(width 0.1524)
				(type default)
			)
			(layer "F.SilkS")
		)
		(fp_line
			(start -0.157988 2.47523)
			(end -0.157988 2.245106)
			(stroke
				(width 0.1524)
				(type default)
			)
			(layer "F.SilkS")
		)
		(fp_line
			(start 4.341876 -0.525018)
			(end 4.341876 -0.294894)
			(stroke
				(width 0.1524)
				(type default)
			)
			(layer "F.SilkS")
		)
		(fp_line
			(start 4.341876 2.245106)
			(end 4.341876 2.47523)
			(stroke
				(width 0.1524)
				(type default)
			)
			(layer "F.SilkS")
		)
		(fp_line
			(start 4.341876 2.47523)
			(end -0.157988 2.47523)
			(stroke
				(width 0.1524)
				(type default)
			)
			(layer "F.SilkS")
		)
		(fp_poly
			(pts
				(xy -0.615188 -0.030988) (xy -1.69291 0.328168) (xy -0.974344 1.046734)
			)
			(stroke
				(width 0)
				(type default)
			)
			(fill yes)
			(layer "F.SilkS")
		)
		(fp_poly
			(pts
				(xy -0.157988 -0.525018) (xy -0.157988 -0.294894) (xy -0.346456 -0.294894) (xy -0.346456 2.245106)
				(xy -0.157988 2.245106) (xy -0.157988 2.47523) (xy 4.341876 2.47523) (xy 4.341876 2.245106) (xy 4.530344 2.245106)
				(xy 4.530344 -0.294894) (xy 4.341876 -0.294894) (xy 4.341876 -0.525018)
			)
			(stroke
				(width 0)
				(type default)
			)
			(fill no)
			(layer "F.CrtYd")
		)
		(fp_line
			(start -0.157988 -0.525018)
			(end 4.341876 -0.525018)
			(stroke
				(width 0.1)
				(type default)
			)
			(layer "F.Fab")
		)
		(fp_line
			(start -0.157988 2.47523)
			(end -0.157988 -0.525018)
			(stroke
				(width 0.1)
				(type default)
			)
			(layer "F.Fab")
		)
		(fp_line
			(start 4.341876 -0.525018)
			(end 4.341876 2.47523)
			(stroke
				(width 0.1)
				(type default)
			)
			(layer "F.Fab")
		)
		(fp_line
			(start 4.341876 2.47523)
			(end -0.157988 2.47523)
			(stroke
				(width 0.1)
				(type default)
			)
			(layer "F.Fab")
		)
		(fp_circle
			(center 2.091944 0.975106)
			(end 2.221484 0.975106)
			(stroke
				(width 0.1)
				(type default)
			)
			(fill no)
			(layer "F.Fab")
		)
		(fp_poly
			(pts
				(xy -0.339598 0) (xy -1.355598 -0.508) (xy -1.355598 0.508)
			)
			(stroke
				(width 0)
				(type default)
			)
			(fill yes)
			(layer "F.Fab")
		)
		(pad "1" smd rect
			(at 0 0 270)
			(size 0.4318 0.5588)
			(layers "F.Cu" "F.Mask" "F.Paste")
			(net "SW_P1V05_NODE1_DRVH")
		)
		(pad "2" smd rect
			(at 0 0.649986 270)
			(size 0.4318 0.5588)
			(layers "F.Cu" "F.Mask" "F.Paste")
			(net "SW_P1V05_NODE1_VIN_FLT")
		)
		(pad "3" smd rect
			(at 0 1.300226 270)
			(size 0.4318 0.5588)
			(layers "F.Cu" "F.Mask" "F.Paste")
			(net "SW_P1V05_NODE1_VIN_FLT")
		)
		(pad "4" smd rect
			(at 0 1.950212 270)
			(size 0.4318 0.5588)
			(layers "F.Cu" "F.Mask" "F.Paste")
			(net "SW_P1V05_NODE1_VIN_FLT")
		)
		(pad "5-6-7" smd custom
			(at 4.181856 1.300226 270)
			(size 0.143764 0.143764)
			(layers "F.Cu" "F.Mask" "F.Paste")
			(net "GND")
			(options
				(clearance outline)
				(anchor circle)
			)
			(primitives
				(gr_poly
					(pts
						(xy -0.87503 -0.287528) (xy -0.87503 0.287528) (xy 0.87503 0.287528) (xy 0.87503 -0.287528) (xy 0.424942 -0.287528)
						(xy 0.424942 -0.180086) (xy 0.424942 -0.107442) (xy 0.225044 -0.107442) (xy 0.225044 -0.180086)
						(xy 0.225044 -0.287528) (xy -0.225044 -0.287528) (xy -0.225044 -0.180086) (xy -0.225044 -0.107442)
						(xy -0.424942 -0.107442) (xy -0.424942 -0.180086) (xy -0.424942 -0.287528) (xy -0.42545 -0.287528)
					)
					(width 0)
					(fill yes)
				)
			)
		)
		(pad "8" smd rect
			(at 4.181856 0 270)
			(size 0.4318 0.5588)
			(layers "F.Cu" "F.Mask" "F.Paste")
			(net "SW_P1V05_NODE1_DRVL")
		)
		(pad "D1_EP" smd rect
			(at 0.901954 0.975106)
			(size 0.8382 2.5146)
			(layers "F.Cu" "F.Mask" "F.Paste")
			(net "SW_P1V05_NODE1_VIN_FLT")
		)
		(pad "S1/D2_EP" smd rect
			(at 2.675128 0.975106)
			(size 2.032 2.5146)
			(layers "F.Cu" "F.Mask" "F.Paste")
			(net "SW_P1V05_NODE1_PH")
		)
		(zone
			(layer "F.Cu")
			(hatch none 0.5)
			(connect_pads
				(clearance 0)
			)
			(min_thickness 0.25)
			(keepout
				(tracks allowed)
				(vias not_allowed)
				(pads allowed)
				(copperpour not_allowed)
				(footprints allowed)
			)
			(placement
				(enabled no)
				(sheetname "")
			)
			(fill
				(thermal_gap 0.5)
				(thermal_bridge_width 0.5)
				(island_removal_mode 0)
			)
			(polygon
				(pts
					(xy 16.634206 -123.890278) (xy 16.634206 -126.862078) (xy 20.114006 -126.862078) (xy 20.114006 -123.890278)
					(xy 16.735806 -123.890278) (xy 16.710406 -123.890278) (xy 16.710406 -124.042678) (xy 16.735806 -124.042678)
					(xy 17.675606 -124.042678) (xy 17.675606 -126.684278) (xy 17.878806 -126.684278) (xy 17.878806 -124.068078)
					(xy 20.037806 -124.068078) (xy 20.037806 -126.709678) (xy 16.685006 -126.709678) (xy 16.685006 -123.890278)
				)
			)
		)
	)
	(footprint ""
		(layer "F.Cu")
		(at 41.908222 -176.667668 180)
		(property "Reference" "Q22"
			(at 6.706362 5.85724 0)
			(unlocked yes)
			(layer "F.SilkS")
			(effects
				(font
					(size 0.7874 0.5842)
					(thickness 0.1524)
				)
				(justify left)
			)
		)
		(property "Value" ""
			(at 0 0 180)
			(layer "F.Fab")
			(effects
				(font
					(size 1.27 1.27)
				)
			)
		)
		(duplicate_pad_numbers_are_jumpers no)
		(fp_line
			(start 5.350002 4.554982)
			(end 0.649986 4.554982)
			(stroke
				(width 0.1524)
				(type default)
			)
			(layer "F.SilkS")
		)
		(fp_line
			(start 5.350002 4.3942)
			(end 5.350002 4.554982)
			(stroke
				(width 0.1524)
				(type default)
			)
			(layer "F.SilkS")
		)
		(fp_line
			(start 5.350002 -0.744982)
			(end 5.350002 -0.5842)
			(stroke
				(width 0.1524)
				(type default)
			)
			(layer "F.SilkS")
		)
		(fp_line
			(start 0.649986 4.554982)
			(end 0.649986 4.318)
			(stroke
				(width 0.1524)
				(type default)
			)
			(layer "F.SilkS")
		)
		(fp_line
			(start 0.649986 -0.5334)
			(end 0.649986 -0.744982)
			(stroke
				(width 0.1524)
				(type default)
			)
			(layer "F.SilkS")
		)
		(fp_line
			(start 0.649986 -0.744982)
			(end 5.350002 -0.744982)
			(stroke
				(width 0.1524)
				(type default)
			)
			(layer "F.SilkS")
		)
		(fp_poly
			(pts
				(xy -0.79375 -0.000762) (xy -1.83515 -0.419862) (xy -1.83515 0.380238)
			)
			(stroke
				(width 0)
				(type default)
			)
			(fill yes)
			(layer "F.SilkS")
		)
		(fp_poly
			(pts
				(xy 0.649986 4.554982) (xy 5.350002 4.554982) (xy 5.350002 4.318) (xy 6.2738 4.318) (xy 6.2738 -0.508)
				(xy 5.350002 -0.508) (xy 5.350002 -0.744982) (xy 0.649986 -0.744982) (xy 0.649986 -0.4064) (xy -0.635 -0.4064)
				(xy -0.635 4.2164) (xy 0.649986 4.2164)
			)
			(stroke
				(width 0)
				(type default)
			)
			(fill no)
			(layer "F.CrtYd")
		)
		(fp_line
			(start 5.350002 4.554982)
			(end 0.649986 4.554982)
			(stroke
				(width 0.1)
				(type default)
			)
			(layer "F.Fab")
		)
		(fp_line
			(start 5.350002 -0.744982)
			(end 5.350002 4.554982)
			(stroke
				(width 0.1)
				(type default)
			)
			(layer "F.Fab")
		)
		(fp_line
			(start 0.649986 4.554982)
			(end 0.649986 -0.744982)
			(stroke
				(width 0.1)
				(type default)
			)
			(layer "F.Fab")
		)
		(fp_line
			(start 0.649986 -0.744982)
			(end 5.350002 -0.744982)
			(stroke
				(width 0.1)
				(type default)
			)
			(layer "F.Fab")
		)
		(fp_circle
			(center 2.724912 1.905)
			(end 2.470912 1.905)
			(stroke
				(width 0.1)
				(type default)
			)
			(fill no)
			(layer "F.Fab")
		)
		(pad "1" smd rect
			(at 0 0 90)
			(size 0.7112 1.1684)
			(layers "F.Cu" "F.Mask" "F.Paste")
			(net "P12V_AUX")
		)
		(pad "2" smd rect
			(at 0 1.27 90)
			(size 0.7112 1.1684)
			(layers "F.Cu" "F.Mask" "F.Paste")
			(net "P12V_AUX")
		)
		(pad "3" smd rect
			(at 0 2.54 90)
			(size 0.7112 1.1684)
			(layers "F.Cu" "F.Mask" "F.Paste")
			(net "P12V_AUX")
		)
		(pad "4" smd rect
			(at 0 3.81 90)
			(size 0.7112 1.1684)
			(layers "F.Cu" "F.Mask" "F.Paste")
			(net "VR_HSC_NODE1_GATE")
		)
		(pad "5" smd custom
			(at 3.925062 1.905 90)
			(size 1.149985 1.149985)
			(layers "F.Cu" "F.Mask" "F.Paste")
			(net "VSENSE_HSC_NODE1")
			(options
				(clearance outline)
				(anchor circle)
			)
			(primitives
				(gr_poly
					(pts
						(xy -2.350008 -2.29997) (xy -2.350008 -0.8001) (xy -2.100072 -0.8001) (xy -2.100072 2.29997) (xy 2.100072 2.29997)
						(xy 2.100072 -0.8001) (xy 2.350008 -0.8001) (xy 2.350008 -2.29997)
					)
					(width 0)
					(fill yes)
				)
			)
		)
	)
	(footprint ""
		(layer "F.Cu")
		(at 36.34359 -104.502712 180)
		(property "Reference" "R1088"
			(at 0.802132 -3.263138 0)
			(unlocked yes)
			(layer "F.SilkS")
			(effects
				(font
					(size 0.7874 0.5842)
					(thickness 0.1524)
				)
				(justify left)
			)
		)
		(property "Value" ""
			(at 0 0 180)
			(layer "F.Fab")
			(effects
				(font
					(size 1.27 1.27)
				)
			)
		)
		(duplicate_pad_numbers_are_jumpers no)
		(fp_line
			(start 0.7874 0.4064)
			(end -0.7874 0.4064)
			(stroke
				(width 0.1524)
				(type default)
			)
			(layer "F.SilkS")
		)
		(fp_line
			(start 0.7874 -0.4064)
			(end 0.7874 0.4064)
			(stroke
				(width 0.1524)
				(type default)
			)
			(layer "F.SilkS")
		)
		(fp_line
			(start -0.7874 0.4064)
			(end -0.7874 -0.4064)
			(stroke
				(width 0.1524)
				(type default)
			)
			(layer "F.SilkS")
		)
		(fp_line
			(start -0.7874 -0.4064)
			(end 0.7874 -0.4064)
			(stroke
				(width 0.1524)
				(type default)
			)
			(layer "F.SilkS")
		)
		(fp_poly
			(pts
				(xy -0.508 0.2794) (xy -0.508 0.2286) (xy -0.635 0.2286) (xy -0.635 -0.254) (xy -0.5334 -0.254)
				(xy -0.5334 -0.2794) (xy 0.5334 -0.2794) (xy 0.5334 -0.254) (xy 0.635 -0.254) (xy 0.635 0.254) (xy 0.5334 0.254)
				(xy 0.5334 0.2794)
			)
			(stroke
				(width 0)
				(type default)
			)
			(fill no)
			(layer "F.CrtYd")
		)
		(pad "1" smd rect
			(at 0.40005 0 180)
			(size 0.4572 0.508)
			(layers "F.Cu" "F.Mask" "F.Paste")
			(net "P1V5_SUS_NODE1_ADJ")
		)
		(pad "2" smd rect
			(at -0.40005 0 180)
			(size 0.4572 0.508)
			(layers "F.Cu" "F.Mask" "F.Paste")
			(net "P1V5_SUS_NODE1")
		)
	)
	(footprint ""
		(layer "F.Cu")
		(at 82.340196 -107.097322)
		(property "Reference" "R1235"
			(at -5.44957 -0.57277 0)
			(unlocked yes)
			(layer "F.SilkS")
			(effects
				(font
					(size 0.7874 0.5842)
					(thickness 0.1524)
				)
				(justify left)
			)
		)
		(property "Value" ""
			(at 0 0 0)
			(layer "F.Fab")
			(effects
				(font
					(size 1.27 1.27)
				)
			)
		)
		(duplicate_pad_numbers_are_jumpers no)
		(fp_line
			(start -0.7874 -0.4064)
			(end 0.7874 -0.4064)
			(stroke
				(width 0.1524)
				(type default)
			)
			(layer "F.SilkS")
		)
		(fp_line
			(start -0.7874 0.4064)
			(end -0.7874 -0.4064)
			(stroke
				(width 0.1524)
				(type default)
			)
			(layer "F.SilkS")
		)
		(fp_line
			(start 0.7874 -0.4064)
			(end 0.7874 0.4064)
			(stroke
				(width 0.1524)
				(type default)
			)
			(layer "F.SilkS")
		)
		(fp_line
			(start 0.7874 0.4064)
			(end -0.7874 0.4064)
			(stroke
				(width 0.1524)
				(type default)
			)
			(layer "F.SilkS")
		)
		(fp_poly
			(pts
				(xy -0.508 0.2794) (xy -0.508 0.2286) (xy -0.635 0.2286) (xy -0.635 -0.254) (xy -0.5334 -0.254)
				(xy -0.5334 -0.2794) (xy 0.5334 -0.2794) (xy 0.5334 -0.254) (xy 0.635 -0.254) (xy 0.635 0.254) (xy 0.5334 0.254)
				(xy 0.5334 0.2794)
			)
			(stroke
				(width 0)
				(type default)
			)
			(fill no)
			(layer "F.CrtYd")
		)
		(pad "1" smd rect
			(at 0.40005 0)
			(size 0.4572 0.508)
			(layers "F.Cu" "F.Mask" "F.Paste")
			(net "GND")
		)
		(pad "2" smd rect
			(at -0.40005 0)
			(size 0.4572 0.508)
			(layers "F.Cu" "F.Mask" "F.Paste")
			(net "FM_CPLD_NODE1_P3V3_SUS_EN")
		)
	)
	(footprint ""
		(layer "F.Cu")
		(at 95.404432 -4.518406)
		(property "Reference" "C135"
			(at -1.055116 1.38557 0)
			(unlocked yes)
			(layer "F.SilkS")
			(effects
				(font
					(size 0.7874 0.5842)
					(thickness 0.1524)
				)
				(justify left)
			)
		)
		(property "Value" ""
			(at 0 0 0)
			(layer "F.Fab")
			(effects
				(font
					(size 1.27 1.27)
				)
			)
		)
		(duplicate_pad_numbers_are_jumpers no)
		(fp_line
			(start -0.7874 -0.4064)
			(end 0.7874 -0.4064)
			(stroke
				(width 0.1524)
				(type default)
			)
			(layer "F.SilkS")
		)
		(fp_line
			(start -0.7874 0.4064)
			(end -0.7874 -0.4064)
			(stroke
				(width 0.1524)
				(type default)
			)
			(layer "F.SilkS")
		)
		(fp_line
			(start 0 0.381)
			(end 0 -0.381)
			(stroke
				(width 0.1524)
				(type default)
			)
			(layer "F.SilkS")
		)
		(fp_line
			(start 0.7874 -0.4064)
			(end 0.7874 0.4064)
			(stroke
				(width 0.1524)
				(type default)
			)
			(layer "F.SilkS")
		)
		(fp_line
			(start 0.7874 0.4064)
			(end -0.7874 0.4064)
			(stroke
				(width 0.1524)
				(type default)
			)
			(layer "F.SilkS")
		)
		(fp_poly
			(pts
				(xy -0.5334 0.254) (xy -0.635 0.254) (xy -0.635 0.2286) (xy -0.635 -0.254) (xy -0.5334 -0.254) (xy -0.5334 -0.2794)
				(xy 0.5334 -0.2794) (xy 0.5334 -0.254) (xy 0.635 -0.254) (xy 0.635 0.254) (xy 0.5334 0.254) (xy 0.5334 0.2794)
				(xy -0.508 0.2794) (xy -0.5334 0.2794)
			)
			(stroke
				(width 0)
				(type default)
			)
			(fill no)
			(layer "F.CrtYd")
		)
		(pad "1" smd rect
			(at 0.40005 0)
			(size 0.4572 0.508)
			(layers "F.Cu" "F.Mask" "F.Paste")
			(net "GND")
		)
		(pad "2" smd rect
			(at -0.40005 0)
			(size 0.4572 0.508)
			(layers "F.Cu" "F.Mask" "F.Paste")
			(net "P5V_NODE1")
		)
	)
	(footprint ""
		(layer "F.Cu")
		(at 134.60476 -188.126624 90)
		(property "Reference" "C746"
			(at 4.949444 -1.209548 90)
			(unlocked yes)
			(layer "F.SilkS")
			(effects
				(font
					(size 0.7874 0.5842)
					(thickness 0.1524)
				)
				(justify left)
			)
		)
		(property "Value" ""
			(at 0 0 90)
			(layer "F.Fab")
			(effects
				(font
					(size 1.27 1.27)
				)
			)
		)
		(duplicate_pad_numbers_are_jumpers no)
		(fp_line
			(start 0.7874 -0.4064)
			(end 0.7874 0.4064)
			(stroke
				(width 0.1524)
				(type default)
			)
			(layer "F.SilkS")
		)
		(fp_line
			(start -0.7874 -0.4064)
			(end 0.7874 -0.4064)
			(stroke
				(width 0.1524)
				(type default)
			)
			(layer "F.SilkS")
		)
		(fp_line
			(start 0 0.381)
			(end 0 -0.381)
			(stroke
				(width 0.1524)
				(type default)
			)
			(layer "F.SilkS")
		)
		(fp_line
			(start 0.7874 0.4064)
			(end -0.7874 0.4064)
			(stroke
				(width 0.1524)
				(type default)
			)
			(layer "F.SilkS")
		)
		(fp_line
			(start -0.7874 0.4064)
			(end -0.7874 -0.4064)
			(stroke
				(width 0.1524)
				(type default)
			)
			(layer "F.SilkS")
		)
		(fp_poly
			(pts
				(xy -0.5334 0.254) (xy -0.635 0.254) (xy -0.635 0.2286) (xy -0.635 -0.254) (xy -0.5334 -0.254) (xy -0.5334 -0.2794)
				(xy 0.5334 -0.2794) (xy 0.5334 -0.254) (xy 0.635 -0.254) (xy 0.635 0.254) (xy 0.5334 0.254) (xy 0.5334 0.2794)
				(xy -0.508 0.2794) (xy -0.5334 0.2794)
			)
			(stroke
				(width 0)
				(type default)
			)
			(fill no)
			(layer "F.CrtYd")
		)
		(pad "1" smd rect
			(at 0.40005 0 90)
			(size 0.4572 0.508)
			(layers "F.Cu" "F.Mask" "F.Paste")
			(net "UART_T10_NODE1_TXD_R")
		)
		(pad "2" smd rect
			(at -0.40005 0 90)
			(size 0.4572 0.508)
			(layers "F.Cu" "F.Mask" "F.Paste")
			(net "GND")
		)
	)
	(footprint ""
		(layer "F.Cu")
		(at 2.693162 -155.480766 180)
		(property "Reference" "R1068"
			(at 1.343152 0.014478 90)
			(unlocked yes)
			(layer "F.SilkS")
			(effects
				(font
					(size 0.7874 0.5842)
					(thickness 0.1524)
				)
				(justify left)
			)
		)
		(property "Value" ""
			(at 0 0 180)
			(layer "F.Fab")
			(effects
				(font
					(size 1.27 1.27)
				)
			)
		)
		(duplicate_pad_numbers_are_jumpers no)
		(fp_line
			(start 0.7874 0.4064)
			(end -0.7874 0.4064)
			(stroke
				(width 0.1524)
				(type default)
			)
			(layer "F.SilkS")
		)
		(fp_line
			(start 0.7874 -0.4064)
			(end 0.7874 0.4064)
			(stroke
				(width 0.1524)
				(type default)
			)
			(layer "F.SilkS")
		)
		(fp_line
			(start -0.7874 0.4064)
			(end -0.7874 -0.4064)
			(stroke
				(width 0.1524)
				(type default)
			)
			(layer "F.SilkS")
		)
		(fp_line
			(start -0.7874 -0.4064)
			(end 0.7874 -0.4064)
			(stroke
				(width 0.1524)
				(type default)
			)
			(layer "F.SilkS")
		)
		(fp_poly
			(pts
				(xy -0.508 0.2794) (xy -0.508 0.2286) (xy -0.635 0.2286) (xy -0.635 -0.254) (xy -0.5334 -0.254)
				(xy -0.5334 -0.2794) (xy 0.5334 -0.2794) (xy 0.5334 -0.254) (xy 0.635 -0.254) (xy 0.635 0.254) (xy 0.5334 0.254)
				(xy 0.5334 0.2794)
			)
			(stroke
				(width 0)
				(type default)
			)
			(fill no)
			(layer "F.CrtYd")
		)
		(pad "1" smd rect
			(at 0.40005 0 180)
			(size 0.4572 0.508)
			(layers "F.Cu" "F.Mask" "F.Paste")
			(net "UART_RI_P5_LS_N")
		)
		(pad "2" smd rect
			(at -0.40005 0 180)
			(size 0.4572 0.508)
			(layers "F.Cu" "F.Mask" "F.Paste")
			(net "UART_RI_P5_N")
		)
	)
	(footprint ""
		(layer "F.Cu")
		(at 168.244012 -77.328776 180)
		(property "Reference" "PC22"
			(at -2.634234 -0.240538 0)
			(unlocked yes)
			(layer "F.SilkS")
			(effects
				(font
					(size 0.7874 0.5842)
					(thickness 0.1524)
				)
				(justify left)
			)
		)
		(property "Value" ""
			(at 0 0 180)
			(layer "F.Fab")
			(effects
				(font
					(size 1.27 1.27)
				)
			)
		)
		(duplicate_pad_numbers_are_jumpers no)
		(fp_line
			(start 1.905 0.8636)
			(end -1.905 0.8636)
			(stroke
				(width 0.1524)
				(type default)
			)
			(layer "F.SilkS")
		)
		(fp_line
			(start 1.905 -0.8636)
			(end 1.905 0.8636)
			(stroke
				(width 0.1524)
				(type default)
			)
			(layer "F.SilkS")
		)
		(fp_line
			(start 0 0.8382)
			(end 0 -0.8382)
			(stroke
				(width 0.1524)
				(type default)
			)
			(layer "F.SilkS")
		)
		(fp_line
			(start -1.905 0.8636)
			(end -1.905 -0.8636)
			(stroke
				(width 0.1524)
				(type default)
			)
			(layer "F.SilkS")
		)
		(fp_line
			(start -1.905 -0.8636)
			(end 1.905 -0.8636)
			(stroke
				(width 0.1524)
				(type default)
			)
			(layer "F.SilkS")
		)
		(fp_rect
			(start -1.524 0.7366)
			(end 1.524 -0.7366)
			(stroke
				(width 0)
				(type default)
			)
			(fill no)
			(layer "F.CrtYd")
		)
		(pad "1" smd rect
			(at 0.94996 0 180)
			(size 1.1176 1.3716)
			(layers "F.Cu" "F.Mask" "F.Paste")
			(net "P1V8_NODE1")
		)
		(pad "2" smd rect
			(at -0.94996 0 180)
			(size 1.1176 1.3716)
			(layers "F.Cu" "F.Mask" "F.Paste")
			(net "GND")
		)
	)
	(footprint ""
		(layer "F.Cu")
		(at 33.344104 -119.567452)
		(property "Reference" "R1117"
			(at -6.021324 0.992124 0)
			(unlocked yes)
			(layer "F.SilkS")
			(effects
				(font
					(size 0.7874 0.5842)
					(thickness 0.1524)
				)
				(justify left)
			)
		)
		(property "Value" ""
			(at 0 0 0)
			(layer "F.Fab")
			(effects
				(font
					(size 1.27 1.27)
				)
			)
		)
		(duplicate_pad_numbers_are_jumpers no)
		(fp_line
			(start -0.7874 -0.4064)
			(end 0.7874 -0.4064)
			(stroke
				(width 0.1524)
				(type default)
			)
			(layer "F.SilkS")
		)
		(fp_line
			(start -0.7874 0.4064)
			(end -0.7874 -0.4064)
			(stroke
				(width 0.1524)
				(type default)
			)
			(layer "F.SilkS")
		)
		(fp_line
			(start 0.7874 -0.4064)
			(end 0.7874 0.4064)
			(stroke
				(width 0.1524)
				(type default)
			)
			(layer "F.SilkS")
		)
		(fp_line
			(start 0.7874 0.4064)
			(end -0.7874 0.4064)
			(stroke
				(width 0.1524)
				(type default)
			)
			(layer "F.SilkS")
		)
		(fp_poly
			(pts
				(xy -0.508 0.2794) (xy -0.508 0.2286) (xy -0.635 0.2286) (xy -0.635 -0.254) (xy -0.5334 -0.254)
				(xy -0.5334 -0.2794) (xy 0.5334 -0.2794) (xy 0.5334 -0.254) (xy 0.635 -0.254) (xy 0.635 0.254) (xy 0.5334 0.254)
				(xy 0.5334 0.2794)
			)
			(stroke
				(width 0)
				(type default)
			)
			(fill no)
			(layer "F.CrtYd")
		)
		(pad "1" smd rect
			(at 0.40005 0)
			(size 0.4572 0.508)
			(layers "F.Cu" "F.Mask" "F.Paste")
			(net "FM_CPLD_NODE1_P1V5_EN_G")
		)
		(pad "2" smd rect
			(at -0.40005 0)
			(size 0.4572 0.508)
			(layers "F.Cu" "F.Mask" "F.Paste")
			(net "P3V3_STB_NODE1")
		)
	)
	(footprint ""
		(layer "F.Cu")
		(at 127.24257 -26.569416 -90)
		(property "Reference" "R1140"
			(at 5.325618 -0.028448 90)
			(unlocked yes)
			(layer "F.SilkS")
			(effects
				(font
					(size 0.7874 0.5842)
					(thickness 0.1524)
				)
				(justify left)
			)
		)
		(property "Value" ""
			(at 0 0 270)
			(layer "F.Fab")
			(effects
				(font
					(size 1.27 1.27)
				)
			)
		)
		(duplicate_pad_numbers_are_jumpers no)
		(fp_line
			(start -0.7874 0.4064)
			(end -0.7874 -0.4064)
			(stroke
				(width 0.1524)
				(type default)
			)
			(layer "F.SilkS")
		)
		(fp_line
			(start 0.7874 0.4064)
			(end -0.7874 0.4064)
			(stroke
				(width 0.1524)
				(type default)
			)
			(layer "F.SilkS")
		)
		(fp_line
			(start -0.7874 -0.4064)
			(end 0.7874 -0.4064)
			(stroke
				(width 0.1524)
				(type default)
			)
			(layer "F.SilkS")
		)
		(fp_line
			(start 0.7874 -0.4064)
			(end 0.7874 0.4064)
			(stroke
				(width 0.1524)
				(type default)
			)
			(layer "F.SilkS")
		)
		(fp_poly
			(pts
				(xy -0.508 0.2794) (xy -0.508 0.2286) (xy -0.635 0.2286) (xy -0.635 -0.254) (xy -0.5334 -0.254)
				(xy -0.5334 -0.2794) (xy 0.5334 -0.2794) (xy 0.5334 -0.254) (xy 0.635 -0.254) (xy 0.635 0.254) (xy 0.5334 0.254)
				(xy 0.5334 0.2794)
			)
			(stroke
				(width 0)
				(type default)
			)
			(fill no)
			(layer "F.CrtYd")
		)
		(pad "1" smd rect
			(at 0.40005 0 270)
			(size 0.4572 0.508)
			(layers "F.Cu" "F.Mask" "F.Paste")
			(net "P3V3_STB_NODE1")
		)
		(pad "2" smd rect
			(at -0.40005 0 270)
			(size 0.4572 0.508)
			(layers "F.Cu" "F.Mask" "F.Paste")
			(net "SIO_PIN73")
		)
	)
	(footprint ""
		(layer "F.Cu")
		(at 121.516394 -151.266906 -90)
		(property "Reference" "R1250"
			(at 1.75641 -2.386584 90)
			(unlocked yes)
			(layer "F.SilkS")
			(effects
				(font
					(size 0.635 0.4064)
					(thickness 0.1524)
				)
				(justify left)
			)
		)
		(property "Value" ""
			(at 0 0 270)
			(layer "F.Fab")
			(effects
				(font
					(size 1.27 1.27)
				)
			)
		)
		(duplicate_pad_numbers_are_jumpers no)
		(fp_line
			(start -0.7874 0.4064)
			(end -0.7874 -0.4064)
			(stroke
				(width 0.1524)
				(type default)
			)
			(layer "F.SilkS")
		)
		(fp_line
			(start 0.7874 0.4064)
			(end -0.7874 0.4064)
			(stroke
				(width 0.1524)
				(type default)
			)
			(layer "F.SilkS")
		)
		(fp_line
			(start -0.7874 -0.4064)
			(end 0.7874 -0.4064)
			(stroke
				(width 0.1524)
				(type default)
			)
			(layer "F.SilkS")
		)
		(fp_line
			(start 0.7874 -0.4064)
			(end 0.7874 0.4064)
			(stroke
				(width 0.1524)
				(type default)
			)
			(layer "F.SilkS")
		)
		(fp_poly
			(pts
				(xy -0.508 0.2794) (xy -0.508 0.2286) (xy -0.635 0.2286) (xy -0.635 -0.254) (xy -0.5334 -0.254)
				(xy -0.5334 -0.2794) (xy 0.5334 -0.2794) (xy 0.5334 -0.254) (xy 0.635 -0.254) (xy 0.635 0.254) (xy 0.5334 0.254)
				(xy 0.5334 0.2794)
			)
			(stroke
				(width 0)
				(type default)
			)
			(fill no)
			(layer "F.CrtYd")
		)
		(pad "1" smd rect
			(at 0.40005 0 270)
			(size 0.4572 0.508)
			(layers "F.Cu" "F.Mask" "F.Paste")
			(net "N52998345")
		)
		(pad "2" smd rect
			(at -0.40005 0 270)
			(size 0.4572 0.508)
			(layers "F.Cu" "F.Mask" "F.Paste")
			(net "N52998343")
		)
	)
	(footprint ""
		(layer "F.Cu")
		(at 131.30276 -188.126624 -90)
		(property "Reference" "R992"
			(at -4.949444 0.837438 90)
			(unlocked yes)
			(layer "F.SilkS")
			(effects
				(font
					(size 0.7874 0.5842)
					(thickness 0.1524)
				)
				(justify left)
			)
		)
		(property "Value" ""
			(at 0 0 270)
			(layer "F.Fab")
			(effects
				(font
					(size 1.27 1.27)
				)
			)
		)
		(duplicate_pad_numbers_are_jumpers no)
		(fp_line
			(start -0.7874 0.4064)
			(end -0.7874 -0.4064)
			(stroke
				(width 0.1524)
				(type default)
			)
			(layer "F.SilkS")
		)
		(fp_line
			(start 0.7874 0.4064)
			(end -0.7874 0.4064)
			(stroke
				(width 0.1524)
				(type default)
			)
			(layer "F.SilkS")
		)
		(fp_line
			(start -0.7874 -0.4064)
			(end 0.7874 -0.4064)
			(stroke
				(width 0.1524)
				(type default)
			)
			(layer "F.SilkS")
		)
		(fp_line
			(start 0.7874 -0.4064)
			(end 0.7874 0.4064)
			(stroke
				(width 0.1524)
				(type default)
			)
			(layer "F.SilkS")
		)
		(fp_poly
			(pts
				(xy -0.508 0.2794) (xy -0.508 0.2286) (xy -0.635 0.2286) (xy -0.635 -0.254) (xy -0.5334 -0.254)
				(xy -0.5334 -0.2794) (xy 0.5334 -0.2794) (xy 0.5334 -0.254) (xy 0.635 -0.254) (xy 0.635 0.254) (xy 0.5334 0.254)
				(xy 0.5334 0.2794)
			)
			(stroke
				(width 0)
				(type default)
			)
			(fill no)
			(layer "F.CrtYd")
		)
		(pad "1" smd rect
			(at 0.40005 0 270)
			(size 0.4572 0.508)
			(layers "F.Cu" "F.Mask" "F.Paste")
			(net "UART_T10_NODE3_RXD")
		)
		(pad "2" smd rect
			(at -0.40005 0 270)
			(size 0.4572 0.508)
			(layers "F.Cu" "F.Mask" "F.Paste")
			(net "UART_T10_NODE3_RXD_R")
		)
	)
	(footprint ""
		(layer "F.Cu")
		(at 67.67576 -185.205624 -90)
		(property "Reference" "R874"
			(at -4.006088 0.786892 90)
			(unlocked yes)
			(layer "F.SilkS")
			(effects
				(font
					(size 0.7874 0.5842)
					(thickness 0.1524)
				)
				(justify left)
			)
		)
		(property "Value" ""
			(at 0 0 270)
			(layer "F.Fab")
			(effects
				(font
					(size 1.27 1.27)
				)
			)
		)
		(duplicate_pad_numbers_are_jumpers no)
		(fp_line
			(start -0.7874 0.4064)
			(end -0.7874 -0.4064)
			(stroke
				(width 0.1524)
				(type default)
			)
			(layer "F.SilkS")
		)
		(fp_line
			(start 0.7874 0.4064)
			(end -0.7874 0.4064)
			(stroke
				(width 0.1524)
				(type default)
			)
			(layer "F.SilkS")
		)
		(fp_line
			(start -0.7874 -0.4064)
			(end 0.7874 -0.4064)
			(stroke
				(width 0.1524)
				(type default)
			)
			(layer "F.SilkS")
		)
		(fp_line
			(start 0.7874 -0.4064)
			(end 0.7874 0.4064)
			(stroke
				(width 0.1524)
				(type default)
			)
			(layer "F.SilkS")
		)
		(fp_poly
			(pts
				(xy -0.508 0.2794) (xy -0.508 0.2286) (xy -0.635 0.2286) (xy -0.635 -0.254) (xy -0.5334 -0.254)
				(xy -0.5334 -0.2794) (xy 0.5334 -0.2794) (xy 0.5334 -0.254) (xy 0.635 -0.254) (xy 0.635 0.254) (xy 0.5334 0.254)
				(xy 0.5334 0.2794)
			)
			(stroke
				(width 0)
				(type default)
			)
			(fill no)
			(layer "F.CrtYd")
		)
		(pad "1" smd rect
			(at 0.40005 0 270)
			(size 0.4572 0.508)
			(layers "F.Cu" "F.Mask" "F.Paste")
			(net "T2_NODE2_EN")
		)
		(pad "2" smd rect
			(at -0.40005 0 270)
			(size 0.4572 0.508)
			(layers "F.Cu" "F.Mask" "F.Paste")
			(net "T2_NODE2_EN_R")
		)
	)
	(footprint ""
		(layer "F.Cu")
		(at 137.076688 -66.893948)
		(property "Reference" "Q12"
			(at -1.456436 -2.032254 0)
			(unlocked yes)
			(layer "F.SilkS")
			(effects
				(font
					(size 0.7874 0.5842)
					(thickness 0.1524)
				)
			)
		)
		(property "Value" ""
			(at 0 0 0)
			(layer "F.Fab")
			(effects
				(font
					(size 1.27 1.27)
				)
			)
		)
		(duplicate_pad_numbers_are_jumpers no)
		(fp_line
			(start -1.488186 -1.500124)
			(end 1.488186 -1.500124)
			(stroke
				(width 0.1524)
				(type default)
			)
			(layer "F.SilkS")
		)
		(fp_line
			(start -1.488186 1.500124)
			(end -1.488186 -1.500124)
			(stroke
				(width 0.1524)
				(type default)
			)
			(layer "F.SilkS")
		)
		(fp_line
			(start 1.488186 -1.500124)
			(end 1.488186 1.500124)
			(stroke
				(width 0.1524)
				(type default)
			)
			(layer "F.SilkS")
		)
		(fp_line
			(start 1.488186 1.500124)
			(end -1.488186 1.500124)
			(stroke
				(width 0.1524)
				(type default)
			)
			(layer "F.SilkS")
		)
		(fp_poly
			(pts
				(xy -0.700024 1.500124) (xy 0.700024 1.500124) (xy 0.700024 0.3556) (xy 1.4224 0.3556) (xy 1.4224 -0.3556)
				(xy 0.700024 -0.3556) (xy 0.700024 -1.500124) (xy -0.700024 -1.500124) (xy -0.700024 -1.3208) (xy -1.4224 -1.3208)
				(xy -1.4224 -0.5842) (xy -0.700024 -0.5842) (xy -0.700024 0.5842) (xy -1.4224 0.5842) (xy -1.4224 1.3208)
				(xy -0.700024 1.3208)
			)
			(stroke
				(width 0)
				(type default)
			)
			(fill no)
			(layer "F.CrtYd")
		)
		(fp_line
			(start -0.700024 -1.500124)
			(end 0.700024 -1.500124)
			(stroke
				(width 0.1)
				(type default)
			)
			(layer "F.Fab")
		)
		(fp_line
			(start -0.700024 1.500124)
			(end -0.700024 -1.500124)
			(stroke
				(width 0.1)
				(type default)
			)
			(layer "F.Fab")
		)
		(fp_line
			(start 0.700024 -1.500124)
			(end 0.700024 1.500124)
			(stroke
				(width 0.1)
				(type default)
			)
			(layer "F.Fab")
		)
		(fp_line
			(start 0.700024 1.500124)
			(end -0.700024 1.500124)
			(stroke
				(width 0.1)
				(type default)
			)
			(layer "F.Fab")
		)
		(fp_text user "1"
			(at -1.784604 -0.378714 0)
			(unlocked yes)
			(layer "F.SilkS")
			(effects
				(font
					(size 0.7874 0.5842)
					(thickness 0.1524)
				)
			)
		)
		(fp_text user "2"
			(at 1.745234 1.965706 90)
			(unlocked yes)
			(layer "F.SilkS")
			(effects
				(font
					(size 0.7874 0.5842)
					(thickness 0.1524)
				)
			)
		)
		(fp_text user "3"
			(at 1.972564 0.468376 0)
			(unlocked yes)
			(layer "F.SilkS")
			(effects
				(font
					(size 0.7874 0.5842)
					(thickness 0.1524)
				)
			)
		)
		(fp_text user "1"
			(at -0.90805 -1.8034 270)
			(unlocked yes)
			(layer "F.Fab")
			(effects
				(font
					(size 0.7874 0.5842)
					(thickness 0.000001)
				)
			)
		)
		(fp_text user "2"
			(at -0.90805 1.8542 270)
			(unlocked yes)
			(layer "F.Fab")
			(effects
				(font
					(size 0.7874 0.5842)
					(thickness 0.000001)
				)
			)
		)
		(fp_text user "3"
			(at 2.15773 0 270)
			(unlocked yes)
			(layer "F.Fab")
			(effects
				(font
					(size 0.7874 0.5842)
					(thickness 0.000001)
				)
			)
		)
		(pad "1" smd rect
			(at -0.999998 -0.94996 270)
			(size 0.6096 0.7112)
			(layers "F.Cu" "F.Mask" "F.Paste")
			(net "SATA_VCONT_NODE1")
		)
		(pad "2" smd rect
			(at -0.999998 0.94996 270)
			(size 0.6096 0.7112)
			(layers "F.Cu" "F.Mask" "F.Paste")
			(net "P1V8_NODE1")
		)
		(pad "3" smd rect
			(at 0.999998 0 270)
			(size 0.6096 0.7112)
			(layers "F.Cu" "F.Mask" "F.Paste")
			(net "P1V0_SATA")
		)
	)
	(footprint ""
		(layer "F.Cu")
		(at 53.017166 -96.709992 90)
		(property "Reference" "R84"
			(at -54.98719 28.429712 90)
			(unlocked yes)
			(layer "F.SilkS")
			(effects
				(font
					(size 0.7874 0.5842)
					(thickness 0.1524)
				)
				(justify left)
			)
		)
		(property "Value" ""
			(at 0 0 90)
			(layer "F.Fab")
			(effects
				(font
					(size 1.27 1.27)
				)
			)
		)
		(duplicate_pad_numbers_are_jumpers no)
		(fp_line
			(start 0.7874 -0.4064)
			(end 0.7874 0.4064)
			(stroke
				(width 0.1524)
				(type default)
			)
			(layer "F.SilkS")
		)
		(fp_line
			(start -0.7874 -0.4064)
			(end 0.7874 -0.4064)
			(stroke
				(width 0.1524)
				(type default)
			)
			(layer "F.SilkS")
		)
		(fp_line
			(start 0.7874 0.4064)
			(end -0.7874 0.4064)
			(stroke
				(width 0.1524)
				(type default)
			)
			(layer "F.SilkS")
		)
		(fp_line
			(start -0.7874 0.4064)
			(end -0.7874 -0.4064)
			(stroke
				(width 0.1524)
				(type default)
			)
			(layer "F.SilkS")
		)
		(fp_poly
			(pts
				(xy -0.508 0.2794) (xy -0.508 0.2286) (xy -0.635 0.2286) (xy -0.635 -0.254) (xy -0.5334 -0.254)
				(xy -0.5334 -0.2794) (xy 0.5334 -0.2794) (xy 0.5334 -0.254) (xy 0.635 -0.254) (xy 0.635 0.254) (xy 0.5334 0.254)
				(xy 0.5334 0.2794)
			)
			(stroke
				(width 0)
				(type default)
			)
			(fill no)
			(layer "F.CrtYd")
		)
		(pad "1" smd rect
			(at 0.40005 0 90)
			(size 0.4572 0.508)
			(layers "F.Cu" "F.Mask" "F.Paste")
			(net "GND")
		)
		(pad "2" smd rect
			(at -0.40005 0 90)
			(size 0.4572 0.508)
			(layers "F.Cu" "F.Mask" "F.Paste")
			(net "PD_CPU_NODE1_DFX_GPIO_GRP0_1")
		)
	)
	(footprint ""
		(layer "F.Cu")
		(at 30.549088 -132.850382 180)
		(property "Reference" "C833"
			(at 1.261872 3.138424 0)
			(unlocked yes)
			(layer "F.SilkS")
			(effects
				(font
					(size 0.7874 0.5842)
					(thickness 0.1524)
				)
				(justify left)
			)
		)
		(property "Value" ""
			(at 0 0 180)
			(layer "F.Fab")
			(effects
				(font
					(size 1.27 1.27)
				)
			)
		)
		(duplicate_pad_numbers_are_jumpers no)
		(fp_line
			(start 0.7874 0.4064)
			(end -0.7874 0.4064)
			(stroke
				(width 0.1524)
				(type default)
			)
			(layer "F.SilkS")
		)
		(fp_line
			(start 0.7874 -0.4064)
			(end 0.7874 0.4064)
			(stroke
				(width 0.1524)
				(type default)
			)
			(layer "F.SilkS")
		)
		(fp_line
			(start 0 0.381)
			(end 0 -0.381)
			(stroke
				(width 0.1524)
				(type default)
			)
			(layer "F.SilkS")
		)
		(fp_line
			(start -0.7874 0.4064)
			(end -0.7874 -0.4064)
			(stroke
				(width 0.1524)
				(type default)
			)
			(layer "F.SilkS")
		)
		(fp_line
			(start -0.7874 -0.4064)
			(end 0.7874 -0.4064)
			(stroke
				(width 0.1524)
				(type default)
			)
			(layer "F.SilkS")
		)
		(fp_poly
			(pts
				(xy -0.5334 0.254) (xy -0.635 0.254) (xy -0.635 0.2286) (xy -0.635 -0.254) (xy -0.5334 -0.254) (xy -0.5334 -0.2794)
				(xy 0.5334 -0.2794) (xy 0.5334 -0.254) (xy 0.635 -0.254) (xy 0.635 0.254) (xy 0.5334 0.254) (xy 0.5334 0.2794)
				(xy -0.508 0.2794) (xy -0.5334 0.2794)
			)
			(stroke
				(width 0)
				(type default)
			)
			(fill no)
			(layer "F.CrtYd")
		)
		(pad "1" smd rect
			(at 0.40005 0 180)
			(size 0.4572 0.508)
			(layers "F.Cu" "F.Mask" "F.Paste")
			(net "P1V538_BMC_NODE1_ADJ")
		)
		(pad "2" smd rect
			(at -0.40005 0 180)
			(size 0.4572 0.508)
			(layers "F.Cu" "F.Mask" "F.Paste")
			(net "P1V538_STB_NODE1_ADJ_S")
		)
	)
	(footprint ""
		(layer "F.Cu")
		(at 161.489898 -72.400668)
		(property "Reference" "R1218"
			(at -6.716776 -1.069594 0)
			(unlocked yes)
			(layer "F.SilkS")
			(effects
				(font
					(size 0.7874 0.5842)
					(thickness 0.1524)
				)
				(justify left)
			)
		)
		(property "Value" ""
			(at 0 0 0)
			(layer "F.Fab")
			(effects
				(font
					(size 1.27 1.27)
				)
			)
		)
		(duplicate_pad_numbers_are_jumpers no)
		(fp_line
			(start -0.7874 -0.4064)
			(end 0.7874 -0.4064)
			(stroke
				(width 0.1524)
				(type default)
			)
			(layer "F.SilkS")
		)
		(fp_line
			(start -0.7874 0.4064)
			(end -0.7874 -0.4064)
			(stroke
				(width 0.1524)
				(type default)
			)
			(layer "F.SilkS")
		)
		(fp_line
			(start 0.7874 -0.4064)
			(end 0.7874 0.4064)
			(stroke
				(width 0.1524)
				(type default)
			)
			(layer "F.SilkS")
		)
		(fp_line
			(start 0.7874 0.4064)
			(end -0.7874 0.4064)
			(stroke
				(width 0.1524)
				(type default)
			)
			(layer "F.SilkS")
		)
		(fp_poly
			(pts
				(xy -0.508 0.2794) (xy -0.508 0.2286) (xy -0.635 0.2286) (xy -0.635 -0.254) (xy -0.5334 -0.254)
				(xy -0.5334 -0.2794) (xy 0.5334 -0.2794) (xy 0.5334 -0.254) (xy 0.635 -0.254) (xy 0.635 0.254) (xy 0.5334 0.254)
				(xy 0.5334 0.2794)
			)
			(stroke
				(width 0)
				(type default)
			)
			(fill no)
			(layer "F.CrtYd")
		)
		(pad "1" smd rect
			(at 0.40005 0)
			(size 0.4572 0.508)
			(layers "F.Cu" "F.Mask" "F.Paste")
			(net "P3V3_STB_NODE1")
		)
		(pad "2" smd rect
			(at -0.40005 0)
			(size 0.4572 0.508)
			(layers "F.Cu" "F.Mask" "F.Paste")
			(net "PWRGD_NODE1_P1V0")
		)
	)
	(footprint ""
		(layer "F.Cu")
		(at 174.411894 -130.63982 90)
		(property "Reference" "R1036"
			(at -1.213866 12.029948 90)
			(unlocked yes)
			(layer "F.SilkS")
			(effects
				(font
					(size 0.7874 0.5842)
					(thickness 0.1524)
				)
				(justify left)
			)
		)
		(property "Value" ""
			(at 0 0 90)
			(layer "F.Fab")
			(effects
				(font
					(size 1.27 1.27)
				)
			)
		)
		(duplicate_pad_numbers_are_jumpers no)
		(fp_line
			(start 0.7874 -0.4064)
			(end 0.7874 0.4064)
			(stroke
				(width 0.1524)
				(type default)
			)
			(layer "F.SilkS")
		)
		(fp_line
			(start -0.7874 -0.4064)
			(end 0.7874 -0.4064)
			(stroke
				(width 0.1524)
				(type default)
			)
			(layer "F.SilkS")
		)
		(fp_line
			(start 0.7874 0.4064)
			(end -0.7874 0.4064)
			(stroke
				(width 0.1524)
				(type default)
			)
			(layer "F.SilkS")
		)
		(fp_line
			(start -0.7874 0.4064)
			(end -0.7874 -0.4064)
			(stroke
				(width 0.1524)
				(type default)
			)
			(layer "F.SilkS")
		)
		(fp_poly
			(pts
				(xy -0.508 0.2794) (xy -0.508 0.2286) (xy -0.635 0.2286) (xy -0.635 -0.254) (xy -0.5334 -0.254)
				(xy -0.5334 -0.2794) (xy 0.5334 -0.2794) (xy 0.5334 -0.254) (xy 0.635 -0.254) (xy 0.635 0.254) (xy 0.5334 0.254)
				(xy 0.5334 0.2794)
			)
			(stroke
				(width 0)
				(type default)
			)
			(fill no)
			(layer "F.CrtYd")
		)
		(pad "1" smd rect
			(at 0.40005 0 90)
			(size 0.4572 0.508)
			(layers "F.Cu" "F.Mask" "F.Paste")
			(net "P3V3_STB_NODE1")
		)
		(pad "2" smd rect
			(at -0.40005 0 90)
			(size 0.4572 0.508)
			(layers "F.Cu" "F.Mask" "F.Paste")
			(net "FM_CPLD_NODE1_DEBUG_MODE")
		)
	)
	(footprint ""
		(layer "F.Cu")
		(at 20.413472 -128.92913 -90)
		(property "Reference" "PR23"
			(at 2.648712 -4.882642 90)
			(unlocked yes)
			(layer "F.SilkS")
			(effects
				(font
					(size 0.7874 0.5842)
					(thickness 0.1524)
				)
				(justify left)
			)
		)
		(property "Value" ""
			(at 0 0 270)
			(layer "F.Fab")
			(effects
				(font
					(size 1.27 1.27)
				)
			)
		)
		(duplicate_pad_numbers_are_jumpers no)
		(fp_line
			(start -0.7874 0.4064)
			(end -0.7874 -0.4064)
			(stroke
				(width 0.1524)
				(type default)
			)
			(layer "F.SilkS")
		)
		(fp_line
			(start 0.7874 0.4064)
			(end -0.7874 0.4064)
			(stroke
				(width 0.1524)
				(type default)
			)
			(layer "F.SilkS")
		)
		(fp_line
			(start -0.7874 -0.4064)
			(end 0.7874 -0.4064)
			(stroke
				(width 0.1524)
				(type default)
			)
			(layer "F.SilkS")
		)
		(fp_line
			(start 0.7874 -0.4064)
			(end 0.7874 0.4064)
			(stroke
				(width 0.1524)
				(type default)
			)
			(layer "F.SilkS")
		)
		(fp_poly
			(pts
				(xy -0.508 0.2794) (xy -0.508 0.2286) (xy -0.635 0.2286) (xy -0.635 -0.254) (xy -0.5334 -0.254)
				(xy -0.5334 -0.2794) (xy 0.5334 -0.2794) (xy 0.5334 -0.254) (xy 0.635 -0.254) (xy 0.635 0.254) (xy 0.5334 0.254)
				(xy 0.5334 0.2794)
			)
			(stroke
				(width 0)
				(type default)
			)
			(fill no)
			(layer "F.CrtYd")
		)
		(pad "1" smd rect
			(at 0.40005 0 270)
			(size 0.4572 0.508)
			(layers "F.Cu" "F.Mask" "F.Paste")
			(net "P3V3_NODE1")
		)
		(pad "2" smd rect
			(at -0.40005 0 270)
			(size 0.4572 0.508)
			(layers "F.Cu" "F.Mask" "F.Paste")
			(net "P1V05_NODE1_EN")
		)
	)
	(footprint ""
		(layer "F.Cu")
		(at 64.899286 -118.758462 90)
		(property "Reference" "R338"
			(at -4.988306 -0.717042 90)
			(unlocked yes)
			(layer "F.SilkS")
			(effects
				(font
					(size 0.7874 0.5842)
					(thickness 0.1524)
				)
				(justify left)
			)
		)
		(property "Value" ""
			(at 0 0 90)
			(layer "F.Fab")
			(effects
				(font
					(size 1.27 1.27)
				)
			)
		)
		(duplicate_pad_numbers_are_jumpers no)
		(fp_line
			(start 0.7874 -0.4064)
			(end 0.7874 0.4064)
			(stroke
				(width 0.1524)
				(type default)
			)
			(layer "F.SilkS")
		)
		(fp_line
			(start -0.7874 -0.4064)
			(end 0.7874 -0.4064)
			(stroke
				(width 0.1524)
				(type default)
			)
			(layer "F.SilkS")
		)
		(fp_line
			(start 0.7874 0.4064)
			(end -0.7874 0.4064)
			(stroke
				(width 0.1524)
				(type default)
			)
			(layer "F.SilkS")
		)
		(fp_line
			(start -0.7874 0.4064)
			(end -0.7874 -0.4064)
			(stroke
				(width 0.1524)
				(type default)
			)
			(layer "F.SilkS")
		)
		(fp_poly
			(pts
				(xy -0.508 0.2794) (xy -0.508 0.2286) (xy -0.635 0.2286) (xy -0.635 -0.254) (xy -0.5334 -0.254)
				(xy -0.5334 -0.2794) (xy 0.5334 -0.2794) (xy 0.5334 -0.254) (xy 0.635 -0.254) (xy 0.635 0.254) (xy 0.5334 0.254)
				(xy 0.5334 0.2794)
			)
			(stroke
				(width 0)
				(type default)
			)
			(fill no)
			(layer "F.CrtYd")
		)
		(pad "1" smd rect
			(at 0.40005 0 90)
			(size 0.4572 0.508)
			(layers "F.Cu" "F.Mask" "F.Paste")
			(net "P3V3_NODE1")
		)
		(pad "2" smd rect
			(at -0.40005 0 90)
			(size 0.4572 0.508)
			(layers "F.Cu" "F.Mask" "F.Paste")
			(net "BMC_ROMA22")
		)
	)
	(footprint ""
		(layer "F.Cu")
		(at 109.766608 -142.410942 90)
		(property "Reference" "PR61"
			(at 1.927352 0.092964 90)
			(unlocked yes)
			(layer "F.SilkS")
			(effects
				(font
					(size 0.635 0.4064)
					(thickness 0.1524)
				)
				(justify left)
			)
		)
		(property "Value" ""
			(at 0 0 90)
			(layer "F.Fab")
			(effects
				(font
					(size 1.27 1.27)
				)
			)
		)
		(duplicate_pad_numbers_are_jumpers no)
		(fp_line
			(start 0.7874 -0.4064)
			(end 0.7874 0.4064)
			(stroke
				(width 0.1524)
				(type default)
			)
			(layer "F.SilkS")
		)
		(fp_line
			(start -0.7874 -0.4064)
			(end 0.7874 -0.4064)
			(stroke
				(width 0.1524)
				(type default)
			)
			(layer "F.SilkS")
		)
		(fp_line
			(start 0.7874 0.4064)
			(end -0.7874 0.4064)
			(stroke
				(width 0.1524)
				(type default)
			)
			(layer "F.SilkS")
		)
		(fp_line
			(start -0.7874 0.4064)
			(end -0.7874 -0.4064)
			(stroke
				(width 0.1524)
				(type default)
			)
			(layer "F.SilkS")
		)
		(fp_poly
			(pts
				(xy -0.508 0.2794) (xy -0.508 0.2286) (xy -0.635 0.2286) (xy -0.635 -0.254) (xy -0.5334 -0.254)
				(xy -0.5334 -0.2794) (xy 0.5334 -0.2794) (xy 0.5334 -0.254) (xy 0.635 -0.254) (xy 0.635 0.254) (xy 0.5334 0.254)
				(xy 0.5334 0.2794)
			)
			(stroke
				(width 0)
				(type default)
			)
			(fill no)
			(layer "F.CrtYd")
		)
		(pad "1" smd rect
			(at 0.40005 0 90)
			(size 0.4572 0.508)
			(layers "F.Cu" "F.Mask" "F.Paste")
			(net "VR_PVCCP_NODE1_VCC")
		)
		(pad "2" smd rect
			(at -0.40005 0 90)
			(size 0.4572 0.508)
			(layers "F.Cu" "F.Mask" "F.Paste")
			(net "VR_PVCCP_NODE1_TEMPMAX")
		)
	)
	(footprint ""
		(layer "F.Cu")
		(at 83.472782 -89.865454)
		(property "Reference" "R138"
			(at -1.36017 -1.038606 0)
			(unlocked yes)
			(layer "F.SilkS")
			(effects
				(font
					(size 0.635 0.4064)
					(thickness 0.1524)
				)
				(justify left)
			)
		)
		(property "Value" ""
			(at 0 0 0)
			(layer "F.Fab")
			(effects
				(font
					(size 1.27 1.27)
				)
			)
		)
		(duplicate_pad_numbers_are_jumpers no)
		(fp_line
			(start -0.7874 -0.4064)
			(end 0.7874 -0.4064)
			(stroke
				(width 0.1524)
				(type default)
			)
			(layer "F.SilkS")
		)
		(fp_line
			(start -0.7874 0.4064)
			(end -0.7874 -0.4064)
			(stroke
				(width 0.1524)
				(type default)
			)
			(layer "F.SilkS")
		)
		(fp_line
			(start 0.7874 -0.4064)
			(end 0.7874 0.4064)
			(stroke
				(width 0.1524)
				(type default)
			)
			(layer "F.SilkS")
		)
		(fp_line
			(start 0.7874 0.4064)
			(end -0.7874 0.4064)
			(stroke
				(width 0.1524)
				(type default)
			)
			(layer "F.SilkS")
		)
		(fp_poly
			(pts
				(xy -0.508 0.2794) (xy -0.508 0.2286) (xy -0.635 0.2286) (xy -0.635 -0.254) (xy -0.5334 -0.254)
				(xy -0.5334 -0.2794) (xy 0.5334 -0.2794) (xy 0.5334 -0.254) (xy 0.635 -0.254) (xy 0.635 0.254) (xy 0.5334 0.254)
				(xy 0.5334 0.2794)
			)
			(stroke
				(width 0)
				(type default)
			)
			(fill no)
			(layer "F.CrtYd")
		)
		(pad "1" smd rect
			(at 0.40005 0)
			(size 0.4572 0.508)
			(layers "F.Cu" "F.Mask" "F.Paste")
			(net "P3V3_SUS_NODE1")
		)
		(pad "2" smd rect
			(at -0.40005 0)
			(size 0.4572 0.508)
			(layers "F.Cu" "F.Mask" "F.Paste")
			(net "FM_CPU_NODE1_RSTRDY_L")
		)
	)
	(footprint ""
		(layer "F.Cu")
		(at 123.372626 -70.572884 90)
		(property "Reference" "R147"
			(at -3.886962 0.577596 90)
			(unlocked yes)
			(layer "F.SilkS")
			(effects
				(font
					(size 0.7874 0.5842)
					(thickness 0.1524)
				)
				(justify left)
			)
		)
		(property "Value" ""
			(at 0 0 90)
			(layer "F.Fab")
			(effects
				(font
					(size 1.27 1.27)
				)
			)
		)
		(duplicate_pad_numbers_are_jumpers no)
		(fp_line
			(start 0.7874 -0.4064)
			(end 0.7874 0.4064)
			(stroke
				(width 0.1524)
				(type default)
			)
			(layer "F.SilkS")
		)
		(fp_line
			(start -0.7874 -0.4064)
			(end 0.7874 -0.4064)
			(stroke
				(width 0.1524)
				(type default)
			)
			(layer "F.SilkS")
		)
		(fp_line
			(start 0.7874 0.4064)
			(end -0.7874 0.4064)
			(stroke
				(width 0.1524)
				(type default)
			)
			(layer "F.SilkS")
		)
		(fp_line
			(start -0.7874 0.4064)
			(end -0.7874 -0.4064)
			(stroke
				(width 0.1524)
				(type default)
			)
			(layer "F.SilkS")
		)
		(fp_poly
			(pts
				(xy -0.508 0.2794) (xy -0.508 0.2286) (xy -0.635 0.2286) (xy -0.635 -0.254) (xy -0.5334 -0.254)
				(xy -0.5334 -0.2794) (xy 0.5334 -0.2794) (xy 0.5334 -0.254) (xy 0.635 -0.254) (xy 0.635 0.254) (xy 0.5334 0.254)
				(xy 0.5334 0.2794)
			)
			(stroke
				(width 0)
				(type default)
			)
			(fill no)
			(layer "F.CrtYd")
		)
		(pad "1" smd rect
			(at 0.40005 0 90)
			(size 0.4572 0.508)
			(layers "F.Cu" "F.Mask" "F.Paste")
			(net "P3V_COIN_CELL")
		)
		(pad "2" smd rect
			(at -0.40005 0 90)
			(size 0.4572 0.508)
			(layers "F.Cu" "F.Mask" "F.Paste")
			(net "P3V0_BAT_NODE1_R")
		)
	)
	(footprint ""
		(layer "F.Cu")
		(at 69.755004 -164.621718 180)
		(property "Reference" "R678"
			(at 4.49072 0.046228 0)
			(unlocked yes)
			(layer "F.SilkS")
			(effects
				(font
					(size 0.7874 0.5842)
					(thickness 0.1524)
				)
				(justify left)
			)
		)
		(property "Value" ""
			(at 0 0 180)
			(layer "F.Fab")
			(effects
				(font
					(size 1.27 1.27)
				)
			)
		)
		(duplicate_pad_numbers_are_jumpers no)
		(fp_line
			(start 0.7874 0.4064)
			(end -0.7874 0.4064)
			(stroke
				(width 0.1524)
				(type default)
			)
			(layer "F.SilkS")
		)
		(fp_line
			(start 0.7874 -0.4064)
			(end 0.7874 0.4064)
			(stroke
				(width 0.1524)
				(type default)
			)
			(layer "F.SilkS")
		)
		(fp_line
			(start -0.7874 0.4064)
			(end -0.7874 -0.4064)
			(stroke
				(width 0.1524)
				(type default)
			)
			(layer "F.SilkS")
		)
		(fp_line
			(start -0.7874 -0.4064)
			(end 0.7874 -0.4064)
			(stroke
				(width 0.1524)
				(type default)
			)
			(layer "F.SilkS")
		)
		(fp_poly
			(pts
				(xy -0.508 0.2794) (xy -0.508 0.2286) (xy -0.635 0.2286) (xy -0.635 -0.254) (xy -0.5334 -0.254)
				(xy -0.5334 -0.2794) (xy 0.5334 -0.2794) (xy 0.5334 -0.254) (xy 0.635 -0.254) (xy 0.635 0.254) (xy 0.5334 0.254)
				(xy 0.5334 0.2794)
			)
			(stroke
				(width 0)
				(type default)
			)
			(fill no)
			(layer "F.CrtYd")
		)
		(pad "1" smd rect
			(at 0.40005 0 180)
			(size 0.4572 0.508)
			(layers "F.Cu" "F.Mask" "F.Paste")
			(net "CPLD123_RSV3")
		)
		(pad "2" smd rect
			(at -0.40005 0 180)
			(size 0.4572 0.508)
			(layers "F.Cu" "F.Mask" "F.Paste")
			(net "CPLD2_RSV3")
		)
	)
	(footprint ""
		(layer "F.Cu")
		(at 131.30657 -26.569416 -90)
		(property "Reference" "R1145"
			(at 5.325618 -0.127508 90)
			(unlocked yes)
			(layer "F.SilkS")
			(effects
				(font
					(size 0.7874 0.5842)
					(thickness 0.1524)
				)
				(justify left)
			)
		)
		(property "Value" ""
			(at 0 0 270)
			(layer "F.Fab")
			(effects
				(font
					(size 1.27 1.27)
				)
			)
		)
		(duplicate_pad_numbers_are_jumpers no)
		(fp_line
			(start -0.7874 0.4064)
			(end -0.7874 -0.4064)
			(stroke
				(width 0.1524)
				(type default)
			)
			(layer "F.SilkS")
		)
		(fp_line
			(start 0.7874 0.4064)
			(end -0.7874 0.4064)
			(stroke
				(width 0.1524)
				(type default)
			)
			(layer "F.SilkS")
		)
		(fp_line
			(start -0.7874 -0.4064)
			(end 0.7874 -0.4064)
			(stroke
				(width 0.1524)
				(type default)
			)
			(layer "F.SilkS")
		)
		(fp_line
			(start 0.7874 -0.4064)
			(end 0.7874 0.4064)
			(stroke
				(width 0.1524)
				(type default)
			)
			(layer "F.SilkS")
		)
		(fp_poly
			(pts
				(xy -0.508 0.2794) (xy -0.508 0.2286) (xy -0.635 0.2286) (xy -0.635 -0.254) (xy -0.5334 -0.254)
				(xy -0.5334 -0.2794) (xy 0.5334 -0.2794) (xy 0.5334 -0.254) (xy 0.635 -0.254) (xy 0.635 0.254) (xy 0.5334 0.254)
				(xy 0.5334 0.2794)
			)
			(stroke
				(width 0)
				(type default)
			)
			(fill no)
			(layer "F.CrtYd")
		)
		(pad "1" smd rect
			(at 0.40005 0 270)
			(size 0.4572 0.508)
			(layers "F.Cu" "F.Mask" "F.Paste")
			(net "P3V3_STB_NODE1")
		)
		(pad "2" smd rect
			(at -0.40005 0 270)
			(size 0.4572 0.508)
			(layers "F.Cu" "F.Mask" "F.Paste")
			(net "SIO_PIN80")
		)
	)
	(footprint ""
		(layer "F.Cu")
		(at 122.03176 -179.363624 -90)
		(property "Reference" "D15"
			(at -3.39344 -5.986272 90)
			(unlocked yes)
			(layer "F.SilkS")
			(effects
				(font
					(size 0.635 0.4064)
					(thickness 0.1524)
				)
				(justify left)
			)
		)
		(property "Value" ""
			(at 0 0 270)
			(layer "F.Fab")
			(effects
				(font
					(size 1.27 1.27)
				)
			)
		)
		(duplicate_pad_numbers_are_jumpers no)
		(fp_line
			(start -1.3208 0.5588)
			(end -1.3208 -0.5588)
			(stroke
				(width 0.1524)
				(type default)
			)
			(layer "F.SilkS")
		)
		(fp_line
			(start 1.3208 0.5588)
			(end -1.3208 0.5588)
			(stroke
				(width 0.1524)
				(type default)
			)
			(layer "F.SilkS")
		)
		(fp_line
			(start 1.6256 0.5588)
			(end 1.6256 -0.5588)
			(stroke
				(width 0.1524)
				(type default)
			)
			(layer "F.SilkS")
		)
		(fp_line
			(start 1.778 0.5588)
			(end 1.3208 0.5588)
			(stroke
				(width 0.1524)
				(type default)
			)
			(layer "F.SilkS")
		)
		(fp_line
			(start -1.3208 -0.5588)
			(end 1.3208 -0.5588)
			(stroke
				(width 0.1524)
				(type default)
			)
			(layer "F.SilkS")
		)
		(fp_line
			(start 1.3208 -0.5588)
			(end 1.3208 0.5588)
			(stroke
				(width 0.1524)
				(type default)
			)
			(layer "F.SilkS")
		)
		(fp_line
			(start 1.4732 -0.5588)
			(end 1.4732 0.5588)
			(stroke
				(width 0.1524)
				(type default)
			)
			(layer "F.SilkS")
		)
		(fp_line
			(start 1.778 -0.5588)
			(end 1.778 0.5588)
			(stroke
				(width 0.1524)
				(type default)
			)
			(layer "F.SilkS")
		)
		(fp_line
			(start 1.778 -0.5588)
			(end 1.3208 -0.5588)
			(stroke
				(width 0.1524)
				(type default)
			)
			(layer "F.SilkS")
		)
		(fp_rect
			(start -1.1684 0.508)
			(end 1.1684 -0.508)
			(stroke
				(width 0)
				(type default)
			)
			(fill no)
			(layer "F.CrtYd")
		)
		(pad "A" smd rect
			(at -0.750062 0 270)
			(size 0.8128 0.8128)
			(layers "F.Cu" "F.Mask" "F.Paste")
			(net "UART_SW_S0_N")
		)
		(pad "C" smd rect
			(at 0.750062 0 270)
			(size 0.8128 0.8128)
			(layers "F.Cu" "F.Mask" "F.Paste")
			(net "N31328106")
		)
	)
	(footprint ""
		(layer "F.Cu")
		(at 153.541222 -91.32951 -90)
		(property "Reference" "R531"
			(at -0.411988 3.409188 0)
			(unlocked yes)
			(layer "F.SilkS")
			(effects
				(font
					(size 0.7874 0.5842)
					(thickness 0.1524)
				)
				(justify left)
			)
		)
		(property "Value" ""
			(at 0 0 270)
			(layer "F.Fab")
			(effects
				(font
					(size 1.27 1.27)
				)
			)
		)
		(duplicate_pad_numbers_are_jumpers no)
		(fp_line
			(start -0.7874 0.4064)
			(end -0.7874 -0.4064)
			(stroke
				(width 0.1524)
				(type default)
			)
			(layer "F.SilkS")
		)
		(fp_line
			(start 0.7874 0.4064)
			(end -0.7874 0.4064)
			(stroke
				(width 0.1524)
				(type default)
			)
			(layer "F.SilkS")
		)
		(fp_line
			(start -0.7874 -0.4064)
			(end 0.7874 -0.4064)
			(stroke
				(width 0.1524)
				(type default)
			)
			(layer "F.SilkS")
		)
		(fp_line
			(start 0.7874 -0.4064)
			(end 0.7874 0.4064)
			(stroke
				(width 0.1524)
				(type default)
			)
			(layer "F.SilkS")
		)
		(fp_poly
			(pts
				(xy -0.508 0.2794) (xy -0.508 0.2286) (xy -0.635 0.2286) (xy -0.635 -0.254) (xy -0.5334 -0.254)
				(xy -0.5334 -0.2794) (xy 0.5334 -0.2794) (xy 0.5334 -0.254) (xy 0.635 -0.254) (xy 0.635 0.254) (xy 0.5334 0.254)
				(xy 0.5334 0.2794)
			)
			(stroke
				(width 0)
				(type default)
			)
			(fill no)
			(layer "F.CrtYd")
		)
		(pad "1" smd rect
			(at 0.40005 0 270)
			(size 0.4572 0.508)
			(layers "F.Cu" "F.Mask" "F.Paste")
			(net "SPI_USB_NODE1_SI")
		)
		(pad "2" smd rect
			(at -0.40005 0 270)
			(size 0.4572 0.508)
			(layers "F.Cu" "F.Mask" "F.Paste")
			(net "P3V3_NODE1")
		)
	)
	(footprint ""
		(layer "F.Cu")
		(at 71.305166 -96.709992 90)
		(property "Reference" "R71"
			(at -54.98719 28.34005 90)
			(unlocked yes)
			(layer "F.SilkS")
			(effects
				(font
					(size 0.7874 0.5842)
					(thickness 0.1524)
				)
				(justify left)
			)
		)
		(property "Value" ""
			(at 0 0 90)
			(layer "F.Fab")
			(effects
				(font
					(size 1.27 1.27)
				)
			)
		)
		(duplicate_pad_numbers_are_jumpers no)
		(fp_line
			(start 0.7874 -0.4064)
			(end 0.7874 0.4064)
			(stroke
				(width 0.1524)
				(type default)
			)
			(layer "F.SilkS")
		)
		(fp_line
			(start -0.7874 -0.4064)
			(end 0.7874 -0.4064)
			(stroke
				(width 0.1524)
				(type default)
			)
			(layer "F.SilkS")
		)
		(fp_line
			(start 0.7874 0.4064)
			(end -0.7874 0.4064)
			(stroke
				(width 0.1524)
				(type default)
			)
			(layer "F.SilkS")
		)
		(fp_line
			(start -0.7874 0.4064)
			(end -0.7874 -0.4064)
			(stroke
				(width 0.1524)
				(type default)
			)
			(layer "F.SilkS")
		)
		(fp_poly
			(pts
				(xy -0.508 0.2794) (xy -0.508 0.2286) (xy -0.635 0.2286) (xy -0.635 -0.254) (xy -0.5334 -0.254)
				(xy -0.5334 -0.2794) (xy 0.5334 -0.2794) (xy 0.5334 -0.254) (xy 0.635 -0.254) (xy 0.635 0.254) (xy 0.5334 0.254)
				(xy 0.5334 0.2794)
			)
			(stroke
				(width 0)
				(type default)
			)
			(fill no)
			(layer "F.CrtYd")
		)
		(pad "1" smd rect
			(at 0.40005 0 90)
			(size 0.4572 0.508)
			(layers "F.Cu" "F.Mask" "F.Paste")
			(net "SPC_CPU_NODE1_RTS_L")
		)
		(pad "2" smd rect
			(at -0.40005 0 90)
			(size 0.4572 0.508)
			(layers "F.Cu" "F.Mask" "F.Paste")
			(net "SPC_CPU_NODE1_CTS_L")
		)
	)
	(footprint ""
		(layer "F.Cu")
		(at 21.30679 -59.146694 180)
		(property "Reference" "C509"
			(at -11.60399 -3.004566 0)
			(unlocked yes)
			(layer "F.SilkS")
			(effects
				(font
					(size 0.7874 0.5842)
					(thickness 0.1524)
				)
				(justify left)
			)
		)
		(property "Value" ""
			(at 0 0 180)
			(layer "F.Fab")
			(effects
				(font
					(size 1.27 1.27)
				)
			)
		)
		(duplicate_pad_numbers_are_jumpers no)
		(fp_line
			(start 0.7874 0.4064)
			(end -0.7874 0.4064)
			(stroke
				(width 0.1524)
				(type default)
			)
			(layer "F.SilkS")
		)
		(fp_line
			(start 0.7874 -0.4064)
			(end 0.7874 0.4064)
			(stroke
				(width 0.1524)
				(type default)
			)
			(layer "F.SilkS")
		)
		(fp_line
			(start 0 0.381)
			(end 0 -0.381)
			(stroke
				(width 0.1524)
				(type default)
			)
			(layer "F.SilkS")
		)
		(fp_line
			(start -0.7874 0.4064)
			(end -0.7874 -0.4064)
			(stroke
				(width 0.1524)
				(type default)
			)
			(layer "F.SilkS")
		)
		(fp_line
			(start -0.7874 -0.4064)
			(end 0.7874 -0.4064)
			(stroke
				(width 0.1524)
				(type default)
			)
			(layer "F.SilkS")
		)
		(fp_poly
			(pts
				(xy -0.5334 0.254) (xy -0.635 0.254) (xy -0.635 0.2286) (xy -0.635 -0.254) (xy -0.5334 -0.254) (xy -0.5334 -0.2794)
				(xy 0.5334 -0.2794) (xy 0.5334 -0.254) (xy 0.635 -0.254) (xy 0.635 0.254) (xy 0.5334 0.254) (xy 0.5334 0.2794)
				(xy -0.508 0.2794) (xy -0.5334 0.2794)
			)
			(stroke
				(width 0)
				(type default)
			)
			(fill no)
			(layer "F.CrtYd")
		)
		(pad "1" smd rect
			(at 0.40005 0 180)
			(size 0.4572 0.508)
			(layers "F.Cu" "F.Mask" "F.Paste")
			(net "GND")
		)
		(pad "2" smd rect
			(at -0.40005 0 180)
			(size 0.4572 0.508)
			(layers "F.Cu" "F.Mask" "F.Paste")
			(net "P5V_CRT")
		)
	)
	(footprint ""
		(layer "F.Cu")
		(at 52.223162 -149.578822)
		(property "Reference" "R560"
			(at -2.1336 5.265928 0)
			(unlocked yes)
			(layer "F.SilkS")
			(effects
				(font
					(size 0.7874 0.5842)
					(thickness 0.1524)
				)
				(justify left)
			)
		)
		(property "Value" ""
			(at 0 0 0)
			(layer "F.Fab")
			(effects
				(font
					(size 1.27 1.27)
				)
			)
		)
		(duplicate_pad_numbers_are_jumpers no)
		(fp_line
			(start -0.7874 -0.4064)
			(end 0.7874 -0.4064)
			(stroke
				(width 0.1524)
				(type default)
			)
			(layer "F.SilkS")
		)
		(fp_line
			(start -0.7874 0.4064)
			(end -0.7874 -0.4064)
			(stroke
				(width 0.1524)
				(type default)
			)
			(layer "F.SilkS")
		)
		(fp_line
			(start 0.7874 -0.4064)
			(end 0.7874 0.4064)
			(stroke
				(width 0.1524)
				(type default)
			)
			(layer "F.SilkS")
		)
		(fp_line
			(start 0.7874 0.4064)
			(end -0.7874 0.4064)
			(stroke
				(width 0.1524)
				(type default)
			)
			(layer "F.SilkS")
		)
		(fp_poly
			(pts
				(xy -0.508 0.2794) (xy -0.508 0.2286) (xy -0.635 0.2286) (xy -0.635 -0.254) (xy -0.5334 -0.254)
				(xy -0.5334 -0.2794) (xy 0.5334 -0.2794) (xy 0.5334 -0.254) (xy 0.635 -0.254) (xy 0.635 0.254) (xy 0.5334 0.254)
				(xy 0.5334 0.2794)
			)
			(stroke
				(width 0)
				(type default)
			)
			(fill no)
			(layer "F.CrtYd")
		)
		(pad "1" smd rect
			(at 0.40005 0)
			(size 0.4572 0.508)
			(layers "F.Cu" "F.Mask" "F.Paste")
			(net "FM_CPLD_NODE1_CPU_RESET_L")
		)
		(pad "2" smd rect
			(at -0.40005 0)
			(size 0.4572 0.508)
			(layers "F.Cu" "F.Mask" "F.Paste")
			(net "PLT_RST_LAN1_N")
		)
	)
	(footprint ""
		(layer "F.Cu")
		(at 163.565078 -12.4714 90)
		(property "Reference" "R1214"
			(at -0.888238 -2.014728 90)
			(unlocked yes)
			(layer "F.SilkS")
			(effects
				(font
					(size 0.7874 0.5842)
					(thickness 0.1524)
				)
				(justify left)
			)
		)
		(property "Value" ""
			(at 0 0 90)
			(layer "F.Fab")
			(effects
				(font
					(size 1.27 1.27)
				)
			)
		)
		(duplicate_pad_numbers_are_jumpers no)
		(fp_line
			(start 0.7874 -0.4064)
			(end 0.7874 0.4064)
			(stroke
				(width 0.1524)
				(type default)
			)
			(layer "F.SilkS")
		)
		(fp_line
			(start -0.7874 -0.4064)
			(end 0.7874 -0.4064)
			(stroke
				(width 0.1524)
				(type default)
			)
			(layer "F.SilkS")
		)
		(fp_line
			(start 0.7874 0.4064)
			(end -0.7874 0.4064)
			(stroke
				(width 0.1524)
				(type default)
			)
			(layer "F.SilkS")
		)
		(fp_line
			(start -0.7874 0.4064)
			(end -0.7874 -0.4064)
			(stroke
				(width 0.1524)
				(type default)
			)
			(layer "F.SilkS")
		)
		(fp_poly
			(pts
				(xy -0.508 0.2794) (xy -0.508 0.2286) (xy -0.635 0.2286) (xy -0.635 -0.254) (xy -0.5334 -0.254)
				(xy -0.5334 -0.2794) (xy 0.5334 -0.2794) (xy 0.5334 -0.254) (xy 0.635 -0.254) (xy 0.635 0.254) (xy 0.5334 0.254)
				(xy 0.5334 0.2794)
			)
			(stroke
				(width 0)
				(type default)
			)
			(fill no)
			(layer "F.CrtYd")
		)
		(pad "1" smd rect
			(at 0.40005 0 90)
			(size 0.4572 0.508)
			(layers "F.Cu" "F.Mask" "F.Paste")
			(net "P3V3_NODE1")
		)
		(pad "2" smd rect
			(at -0.40005 0 90)
			(size 0.4572 0.508)
			(layers "F.Cu" "F.Mask" "F.Paste")
			(net "JTAG_CPLD3_TDI")
		)
	)
	(footprint ""
		(layer "F.Cu")
		(at 78.123796 -162.099752 90)
		(property "Reference" "C580"
			(at -1.914652 -1.18999 90)
			(unlocked yes)
			(layer "F.SilkS")
			(effects
				(font
					(size 0.7874 0.5842)
					(thickness 0.1524)
				)
				(justify left)
			)
		)
		(property "Value" ""
			(at 0 0 90)
			(layer "F.Fab")
			(effects
				(font
					(size 1.27 1.27)
				)
			)
		)
		(duplicate_pad_numbers_are_jumpers no)
		(fp_line
			(start 0.7874 -0.4064)
			(end 0.7874 0.4064)
			(stroke
				(width 0.1524)
				(type default)
			)
			(layer "F.SilkS")
		)
		(fp_line
			(start -0.7874 -0.4064)
			(end 0.7874 -0.4064)
			(stroke
				(width 0.1524)
				(type default)
			)
			(layer "F.SilkS")
		)
		(fp_line
			(start 0 0.381)
			(end 0 -0.381)
			(stroke
				(width 0.1524)
				(type default)
			)
			(layer "F.SilkS")
		)
		(fp_line
			(start 0.7874 0.4064)
			(end -0.7874 0.4064)
			(stroke
				(width 0.1524)
				(type default)
			)
			(layer "F.SilkS")
		)
		(fp_line
			(start -0.7874 0.4064)
			(end -0.7874 -0.4064)
			(stroke
				(width 0.1524)
				(type default)
			)
			(layer "F.SilkS")
		)
		(fp_poly
			(pts
				(xy -0.5334 0.254) (xy -0.635 0.254) (xy -0.635 0.2286) (xy -0.635 -0.254) (xy -0.5334 -0.254) (xy -0.5334 -0.2794)
				(xy 0.5334 -0.2794) (xy 0.5334 -0.254) (xy 0.635 -0.254) (xy 0.635 0.254) (xy 0.5334 0.254) (xy 0.5334 0.2794)
				(xy -0.508 0.2794) (xy -0.5334 0.2794)
			)
			(stroke
				(width 0)
				(type default)
			)
			(fill no)
			(layer "F.CrtYd")
		)
		(pad "1" smd rect
			(at 0.40005 0 90)
			(size 0.4572 0.508)
			(layers "F.Cu" "F.Mask" "F.Paste")
			(net "P3V3_NODE1")
		)
		(pad "2" smd rect
			(at -0.40005 0 90)
			(size 0.4572 0.508)
			(layers "F.Cu" "F.Mask" "F.Paste")
			(net "GND")
		)
	)
	(footprint ""
		(layer "F.Cu")
		(at 47.60976 -178.804824 180)
		(property "Reference" "U99"
			(at 0.799084 -132.66293 90)
			(unlocked yes)
			(layer "F.SilkS")
			(effects
				(font
					(size 0.7874 0.5842)
					(thickness 0.1524)
				)
			)
		)
		(property "Value" ""
			(at 0 0 180)
			(layer "F.Fab")
			(effects
				(font
					(size 1.27 1.27)
				)
			)
		)
		(duplicate_pad_numbers_are_jumpers no)
		(fp_line
			(start 1.651 1.905)
			(end -1.651 1.905)
			(stroke
				(width 0.1524)
				(type default)
			)
			(layer "F.SilkS")
		)
		(fp_line
			(start 1.651 -1.905)
			(end 1.651 1.905)
			(stroke
				(width 0.1524)
				(type default)
			)
			(layer "F.SilkS")
		)
		(fp_line
			(start -1.651 1.905)
			(end -1.651 -1.905)
			(stroke
				(width 0.1524)
				(type default)
			)
			(layer "F.SilkS")
		)
		(fp_line
			(start -1.651 -1.905)
			(end 1.651 -1.905)
			(stroke
				(width 0.1524)
				(type default)
			)
			(layer "F.SilkS")
		)
		(fp_poly
			(pts
				(xy -1.524 0.7112) (xy -1.524 1.7526) (xy -0.508 1.7526) (xy -0.508 0.6985) (xy 0.508 0.6985) (xy 0.508 1.7526)
				(xy 1.524 1.7526) (xy 1.524 0.6985) (xy 1.524 -0.6985) (xy 0.508 -0.6985) (xy 0.508 -1.7526) (xy -0.508 -1.7526)
				(xy -0.508 -0.6985) (xy -1.524 -0.6985) (xy -1.524 0.6985)
			)
			(stroke
				(width 0)
				(type default)
			)
			(fill no)
			(layer "F.CrtYd")
		)
		(fp_text user "S"
			(at 1.988566 1.008634 0)
			(unlocked yes)
			(layer "F.SilkS")
			(effects
				(font
					(size 0.635 0.4064)
					(thickness 0.1524)
				)
			)
		)
		(fp_text user "G"
			(at -1.110742 2.328418 90)
			(unlocked yes)
			(layer "F.SilkS")
			(effects
				(font
					(size 0.635 0.4064)
					(thickness 0.1524)
				)
			)
		)
		(fp_text user "D"
			(at -1.253744 -2.37744 0)
			(unlocked yes)
			(layer "F.SilkS")
			(effects
				(font
					(size 0.635 0.4064)
					(thickness 0.1524)
				)
			)
		)
		(pad "D" smd rect
			(at 0 -1.1176 180)
			(size 1.016 1.27)
			(layers "F.Cu" "F.Mask" "F.Paste")
			(net "PSU_DC_OK_N")
		)
		(pad "G" smd rect
			(at -1.016 1.1176 180)
			(size 1.016 1.27)
			(layers "F.Cu" "F.Mask" "F.Paste")
			(net "PSU6_DC_OK_R_BUF")
		)
		(pad "S" smd rect
			(at 1.016 1.1176 180)
			(size 1.016 1.27)
			(layers "F.Cu" "F.Mask" "F.Paste")
			(net "GND")
		)
	)
	(footprint ""
		(layer "F.Cu")
		(at 115.43538 -130.40614 180)
		(property "Reference" "PR59"
			(at -0.512572 -3.68046 90)
			(unlocked yes)
			(layer "F.SilkS")
			(effects
				(font
					(size 0.7874 0.5842)
					(thickness 0.1524)
				)
				(justify left)
			)
		)
		(property "Value" ""
			(at 0 0 180)
			(layer "F.Fab")
			(effects
				(font
					(size 1.27 1.27)
				)
			)
		)
		(duplicate_pad_numbers_are_jumpers no)
		(fp_line
			(start 0.7874 0.4064)
			(end -0.7874 0.4064)
			(stroke
				(width 0.1524)
				(type default)
			)
			(layer "F.SilkS")
		)
		(fp_line
			(start 0.7874 -0.4064)
			(end 0.7874 0.4064)
			(stroke
				(width 0.1524)
				(type default)
			)
			(layer "F.SilkS")
		)
		(fp_line
			(start -0.7874 0.4064)
			(end -0.7874 -0.4064)
			(stroke
				(width 0.1524)
				(type default)
			)
			(layer "F.SilkS")
		)
		(fp_line
			(start -0.7874 -0.4064)
			(end 0.7874 -0.4064)
			(stroke
				(width 0.1524)
				(type default)
			)
			(layer "F.SilkS")
		)
		(fp_poly
			(pts
				(xy -0.508 0.2794) (xy -0.508 0.2286) (xy -0.635 0.2286) (xy -0.635 -0.254) (xy -0.5334 -0.254)
				(xy -0.5334 -0.2794) (xy 0.5334 -0.2794) (xy 0.5334 -0.254) (xy 0.635 -0.254) (xy 0.635 0.254) (xy 0.5334 0.254)
				(xy 0.5334 0.2794)
			)
			(stroke
				(width 0)
				(type default)
			)
			(fill no)
			(layer "F.CrtYd")
		)
		(pad "1" smd rect
			(at 0.40005 0 180)
			(size 0.4572 0.508)
			(layers "F.Cu" "F.Mask" "F.Paste")
			(net "VR_PVCCP_NODE1_ISEN1P_RR")
		)
		(pad "2" smd rect
			(at -0.40005 0 180)
			(size 0.4572 0.508)
			(layers "F.Cu" "F.Mask" "F.Paste")
			(net "ISENSE_PVCCP_NODE1_ISEN1N")
		)
	)
	(footprint ""
		(layer "F.Cu")
		(at 106.192066 -163.767516)
		(property "Reference" "R769"
			(at 85.291168 69.771768 0)
			(unlocked yes)
			(layer "F.SilkS")
			(effects
				(font
					(size 0.7874 0.5842)
					(thickness 0.1524)
				)
				(justify left)
			)
		)
		(property "Value" ""
			(at 0 0 0)
			(layer "F.Fab")
			(effects
				(font
					(size 1.27 1.27)
				)
			)
		)
		(duplicate_pad_numbers_are_jumpers no)
		(fp_line
			(start -0.7874 -0.4064)
			(end 0.7874 -0.4064)
			(stroke
				(width 0.1524)
				(type default)
			)
			(layer "F.SilkS")
		)
		(fp_line
			(start -0.7874 0.4064)
			(end -0.7874 -0.4064)
			(stroke
				(width 0.1524)
				(type default)
			)
			(layer "F.SilkS")
		)
		(fp_line
			(start 0.7874 -0.4064)
			(end 0.7874 0.4064)
			(stroke
				(width 0.1524)
				(type default)
			)
			(layer "F.SilkS")
		)
		(fp_line
			(start 0.7874 0.4064)
			(end -0.7874 0.4064)
			(stroke
				(width 0.1524)
				(type default)
			)
			(layer "F.SilkS")
		)
		(fp_poly
			(pts
				(xy -0.508 0.2794) (xy -0.508 0.2286) (xy -0.635 0.2286) (xy -0.635 -0.254) (xy -0.5334 -0.254)
				(xy -0.5334 -0.2794) (xy 0.5334 -0.2794) (xy 0.5334 -0.254) (xy 0.635 -0.254) (xy 0.635 0.254) (xy 0.5334 0.254)
				(xy 0.5334 0.2794)
			)
			(stroke
				(width 0)
				(type default)
			)
			(fill no)
			(layer "F.CrtYd")
		)
		(pad "1" smd rect
			(at 0.40005 0)
			(size 0.4572 0.508)
			(layers "F.Cu" "F.Mask" "F.Paste")
			(net "P3V3_NODE1")
		)
		(pad "2" smd rect
			(at -0.40005 0)
			(size 0.4572 0.508)
			(layers "F.Cu" "F.Mask" "F.Paste")
			(net "PU_FAN_TACH")
		)
	)
	(footprint ""
		(layer "F.Cu")
		(at 85.390228 -133.213094 -90)
		(property "Reference" "D34"
			(at 5.3213 3.152902 90)
			(unlocked yes)
			(layer "F.SilkS")
			(effects
				(font
					(size 0.7874 0.5842)
					(thickness 0.1524)
				)
				(justify left)
			)
		)
		(property "Value" ""
			(at 0 0 270)
			(layer "F.Fab")
			(effects
				(font
					(size 1.27 1.27)
				)
			)
		)
		(duplicate_pad_numbers_are_jumpers no)
		(fp_line
			(start -1.3208 0.5588)
			(end -1.3208 -0.5588)
			(stroke
				(width 0.1524)
				(type default)
			)
			(layer "F.SilkS")
		)
		(fp_line
			(start 1.3208 0.5588)
			(end -1.3208 0.5588)
			(stroke
				(width 0.1524)
				(type default)
			)
			(layer "F.SilkS")
		)
		(fp_line
			(start 1.6256 0.5588)
			(end 1.6256 -0.5588)
			(stroke
				(width 0.1524)
				(type default)
			)
			(layer "F.SilkS")
		)
		(fp_line
			(start 1.778 0.5588)
			(end 1.3208 0.5588)
			(stroke
				(width 0.1524)
				(type default)
			)
			(layer "F.SilkS")
		)
		(fp_line
			(start -1.3208 -0.5588)
			(end 1.3208 -0.5588)
			(stroke
				(width 0.1524)
				(type default)
			)
			(layer "F.SilkS")
		)
		(fp_line
			(start 1.3208 -0.5588)
			(end 1.3208 0.5588)
			(stroke
				(width 0.1524)
				(type default)
			)
			(layer "F.SilkS")
		)
		(fp_line
			(start 1.4732 -0.5588)
			(end 1.4732 0.5588)
			(stroke
				(width 0.1524)
				(type default)
			)
			(layer "F.SilkS")
		)
		(fp_line
			(start 1.778 -0.5588)
			(end 1.778 0.5588)
			(stroke
				(width 0.1524)
				(type default)
			)
			(layer "F.SilkS")
		)
		(fp_line
			(start 1.778 -0.5588)
			(end 1.3208 -0.5588)
			(stroke
				(width 0.1524)
				(type default)
			)
			(layer "F.SilkS")
		)
		(fp_circle
			(center 2.4384 0)
			(end 2.4384 -0.413512)
			(stroke
				(width 0.1524)
				(type default)
			)
			(fill no)
			(layer "F.SilkS")
		)
		(fp_rect
			(start -1.1684 0.508)
			(end 1.1684 -0.508)
			(stroke
				(width 0)
				(type default)
			)
			(fill no)
			(layer "F.CrtYd")
		)
		(fp_text user "-"
			(at 2.218182 0.635 270)
			(unlocked yes)
			(layer "F.SilkS")
			(effects
				(font
					(size 0.7874 0.5842)
					(thickness 0.1524)
				)
				(justify left)
			)
		)
		(pad "A" smd rect
			(at -0.750062 0 270)
			(size 0.8128 0.8128)
			(layers "F.Cu" "F.Mask" "F.Paste")
			(net "P3V3_NODE1")
		)
		(pad "C" smd rect
			(at 0.750062 0 270)
			(size 0.8128 0.8128)
			(layers "F.Cu" "F.Mask" "F.Paste")
			(net "N53313501")
		)
	)
	(footprint ""
		(layer "F.Cu")
		(at 33.566608 -127.363728 90)
		(property "Reference" "C830"
			(at -1.219708 1.625346 90)
			(unlocked yes)
			(layer "F.SilkS")
			(effects
				(font
					(size 0.7874 0.5842)
					(thickness 0.1524)
				)
				(justify left)
			)
		)
		(property "Value" ""
			(at 0 0 90)
			(layer "F.Fab")
			(effects
				(font
					(size 1.27 1.27)
				)
			)
		)
		(duplicate_pad_numbers_are_jumpers no)
		(fp_line
			(start 1.905 -0.8636)
			(end 1.905 0.8636)
			(stroke
				(width 0.1524)
				(type default)
			)
			(layer "F.SilkS")
		)
		(fp_line
			(start -1.905 -0.8636)
			(end 1.905 -0.8636)
			(stroke
				(width 0.1524)
				(type default)
			)
			(layer "F.SilkS")
		)
		(fp_line
			(start 0 0.8382)
			(end 0 -0.8382)
			(stroke
				(width 0.1524)
				(type default)
			)
			(layer "F.SilkS")
		)
		(fp_line
			(start 1.905 0.8636)
			(end -1.905 0.8636)
			(stroke
				(width 0.1524)
				(type default)
			)
			(layer "F.SilkS")
		)
		(fp_line
			(start -1.905 0.8636)
			(end -1.905 -0.8636)
			(stroke
				(width 0.1524)
				(type default)
			)
			(layer "F.SilkS")
		)
		(fp_rect
			(start -1.524 0.7366)
			(end 1.524 -0.7366)
			(stroke
				(width 0)
				(type default)
			)
			(fill no)
			(layer "F.CrtYd")
		)
		(pad "1" smd rect
			(at 0.94996 0 90)
			(size 1.1176 1.3716)
			(layers "F.Cu" "F.Mask" "F.Paste")
			(net "P1V538_BMC_NODE1")
		)
		(pad "2" smd rect
			(at -0.94996 0 90)
			(size 1.1176 1.3716)
			(layers "F.Cu" "F.Mask" "F.Paste")
			(net "GND")
		)
	)
	(footprint ""
		(layer "F.Cu")
		(at 133.46176 -188.126624 -90)
		(property "Reference" "R986"
			(at -4.949444 1.084072 90)
			(unlocked yes)
			(layer "F.SilkS")
			(effects
				(font
					(size 0.7874 0.5842)
					(thickness 0.1524)
				)
				(justify left)
			)
		)
		(property "Value" ""
			(at 0 0 270)
			(layer "F.Fab")
			(effects
				(font
					(size 1.27 1.27)
				)
			)
		)
		(duplicate_pad_numbers_are_jumpers no)
		(fp_line
			(start -0.7874 0.4064)
			(end -0.7874 -0.4064)
			(stroke
				(width 0.1524)
				(type default)
			)
			(layer "F.SilkS")
		)
		(fp_line
			(start 0.7874 0.4064)
			(end -0.7874 0.4064)
			(stroke
				(width 0.1524)
				(type default)
			)
			(layer "F.SilkS")
		)
		(fp_line
			(start -0.7874 -0.4064)
			(end 0.7874 -0.4064)
			(stroke
				(width 0.1524)
				(type default)
			)
			(layer "F.SilkS")
		)
		(fp_line
			(start 0.7874 -0.4064)
			(end 0.7874 0.4064)
			(stroke
				(width 0.1524)
				(type default)
			)
			(layer "F.SilkS")
		)
		(fp_poly
			(pts
				(xy -0.508 0.2794) (xy -0.508 0.2286) (xy -0.635 0.2286) (xy -0.635 -0.254) (xy -0.5334 -0.254)
				(xy -0.5334 -0.2794) (xy 0.5334 -0.2794) (xy 0.5334 -0.254) (xy 0.635 -0.254) (xy 0.635 0.254) (xy 0.5334 0.254)
				(xy 0.5334 0.2794)
			)
			(stroke
				(width 0)
				(type default)
			)
			(fill no)
			(layer "F.CrtYd")
		)
		(pad "1" smd rect
			(at 0.40005 0 270)
			(size 0.4572 0.508)
			(layers "F.Cu" "F.Mask" "F.Paste")
			(net "UART_T10_NODE2_RXD")
		)
		(pad "2" smd rect
			(at -0.40005 0 270)
			(size 0.4572 0.508)
			(layers "F.Cu" "F.Mask" "F.Paste")
			(net "UART_T10_NODE2_RXD_R")
		)
	)
	(footprint ""
		(layer "F.Cu")
		(at 49.38776 -182.238142 90)
		(property "Reference" "C608"
			(at -133.313932 -3.637788 90)
			(unlocked yes)
			(layer "F.SilkS")
			(effects
				(font
					(size 0.7874 0.5842)
					(thickness 0.1524)
				)
				(justify left)
			)
		)
		(property "Value" ""
			(at 0 0 90)
			(layer "F.Fab")
			(effects
				(font
					(size 1.27 1.27)
				)
			)
		)
		(duplicate_pad_numbers_are_jumpers no)
		(fp_line
			(start 0.7874 -0.4064)
			(end 0.7874 0.4064)
			(stroke
				(width 0.1524)
				(type default)
			)
			(layer "F.SilkS")
		)
		(fp_line
			(start -0.7874 -0.4064)
			(end 0.7874 -0.4064)
			(stroke
				(width 0.1524)
				(type default)
			)
			(layer "F.SilkS")
		)
		(fp_line
			(start 0 0.381)
			(end 0 -0.381)
			(stroke
				(width 0.1524)
				(type default)
			)
			(layer "F.SilkS")
		)
		(fp_line
			(start 0.7874 0.4064)
			(end -0.7874 0.4064)
			(stroke
				(width 0.1524)
				(type default)
			)
			(layer "F.SilkS")
		)
		(fp_line
			(start -0.7874 0.4064)
			(end -0.7874 -0.4064)
			(stroke
				(width 0.1524)
				(type default)
			)
			(layer "F.SilkS")
		)
		(fp_poly
			(pts
				(xy -0.5334 0.254) (xy -0.635 0.254) (xy -0.635 0.2286) (xy -0.635 -0.254) (xy -0.5334 -0.254) (xy -0.5334 -0.2794)
				(xy 0.5334 -0.2794) (xy 0.5334 -0.254) (xy 0.635 -0.254) (xy 0.635 0.254) (xy 0.5334 0.254) (xy 0.5334 0.2794)
				(xy -0.508 0.2794) (xy -0.5334 0.2794)
			)
			(stroke
				(width 0)
				(type default)
			)
			(fill no)
			(layer "F.CrtYd")
		)
		(pad "1" smd rect
			(at 0.40005 0 90)
			(size 0.4572 0.508)
			(layers "F.Cu" "F.Mask" "F.Paste")
			(net "PSU4_AC_OK")
		)
		(pad "2" smd rect
			(at -0.40005 0 90)
			(size 0.4572 0.508)
			(layers "F.Cu" "F.Mask" "F.Paste")
			(net "GND")
		)
	)
	(footprint ""
		(layer "F.Cu")
		(at 162.696906 -116.303552)
		(property "Reference" "R175"
			(at -4.639564 0.997204 0)
			(unlocked yes)
			(layer "F.SilkS")
			(effects
				(font
					(size 0.7874 0.5842)
					(thickness 0.1524)
				)
				(justify left)
			)
		)
		(property "Value" ""
			(at 0 0 0)
			(layer "F.Fab")
			(effects
				(font
					(size 1.27 1.27)
				)
			)
		)
		(duplicate_pad_numbers_are_jumpers no)
		(fp_line
			(start -0.7874 -0.4064)
			(end 0.7874 -0.4064)
			(stroke
				(width 0.1524)
				(type default)
			)
			(layer "F.SilkS")
		)
		(fp_line
			(start -0.7874 0.4064)
			(end -0.7874 -0.4064)
			(stroke
				(width 0.1524)
				(type default)
			)
			(layer "F.SilkS")
		)
		(fp_line
			(start 0.7874 -0.4064)
			(end 0.7874 0.4064)
			(stroke
				(width 0.1524)
				(type default)
			)
			(layer "F.SilkS")
		)
		(fp_line
			(start 0.7874 0.4064)
			(end -0.7874 0.4064)
			(stroke
				(width 0.1524)
				(type default)
			)
			(layer "F.SilkS")
		)
		(fp_poly
			(pts
				(xy -0.508 0.2794) (xy -0.508 0.2286) (xy -0.635 0.2286) (xy -0.635 -0.254) (xy -0.5334 -0.254)
				(xy -0.5334 -0.2794) (xy 0.5334 -0.2794) (xy 0.5334 -0.254) (xy 0.635 -0.254) (xy 0.635 0.254) (xy 0.5334 0.254)
				(xy 0.5334 0.2794)
			)
			(stroke
				(width 0)
				(type default)
			)
			(fill no)
			(layer "F.CrtYd")
		)
		(pad "1" smd rect
			(at 0.40005 0)
			(size 0.4572 0.508)
			(layers "F.Cu" "F.Mask" "F.Paste")
			(net "RST_CPU_NODE1_SRTCRST_L")
		)
		(pad "2" smd rect
			(at -0.40005 0)
			(size 0.4572 0.508)
			(layers "F.Cu" "F.Mask" "F.Paste")
			(net "P3V3_RTC_NODE1")
		)
	)
	(footprint ""
		(layer "F.Cu")
		(at 179.364894 -130.36042 180)
		(property "Reference" "R1041"
			(at -9.945624 -0.306832 0)
			(unlocked yes)
			(layer "F.SilkS")
			(effects
				(font
					(size 0.7874 0.5842)
					(thickness 0.1524)
				)
				(justify left)
			)
		)
		(property "Value" ""
			(at 0 0 180)
			(layer "F.Fab")
			(effects
				(font
					(size 1.27 1.27)
				)
			)
		)
		(duplicate_pad_numbers_are_jumpers no)
		(fp_line
			(start 0.7874 0.4064)
			(end -0.7874 0.4064)
			(stroke
				(width 0.1524)
				(type default)
			)
			(layer "F.SilkS")
		)
		(fp_line
			(start 0.7874 -0.4064)
			(end 0.7874 0.4064)
			(stroke
				(width 0.1524)
				(type default)
			)
			(layer "F.SilkS")
		)
		(fp_line
			(start -0.7874 0.4064)
			(end -0.7874 -0.4064)
			(stroke
				(width 0.1524)
				(type default)
			)
			(layer "F.SilkS")
		)
		(fp_line
			(start -0.7874 -0.4064)
			(end 0.7874 -0.4064)
			(stroke
				(width 0.1524)
				(type default)
			)
			(layer "F.SilkS")
		)
		(fp_poly
			(pts
				(xy -0.508 0.2794) (xy -0.508 0.2286) (xy -0.635 0.2286) (xy -0.635 -0.254) (xy -0.5334 -0.254)
				(xy -0.5334 -0.2794) (xy 0.5334 -0.2794) (xy 0.5334 -0.254) (xy 0.635 -0.254) (xy 0.635 0.254) (xy 0.5334 0.254)
				(xy 0.5334 0.2794)
			)
			(stroke
				(width 0)
				(type default)
			)
			(fill no)
			(layer "F.CrtYd")
		)
		(pad "1" smd rect
			(at 0.40005 0 180)
			(size 0.4572 0.508)
			(layers "F.Cu" "F.Mask" "F.Paste")
			(net "FM_CPLD_NODE1_WDT")
		)
		(pad "2" smd rect
			(at -0.40005 0 180)
			(size 0.4572 0.508)
			(layers "F.Cu" "F.Mask" "F.Paste")
			(net "P3V3_STB_NODE1")
		)
	)
	(footprint ""
		(layer "F.Cu")
		(at 133.33857 -26.569416 -90)
		(property "Reference" "R1147"
			(at 5.325618 -0.231648 90)
			(unlocked yes)
			(layer "F.SilkS")
			(effects
				(font
					(size 0.7874 0.5842)
					(thickness 0.1524)
				)
				(justify left)
			)
		)
		(property "Value" ""
			(at 0 0 270)
			(layer "F.Fab")
			(effects
				(font
					(size 1.27 1.27)
				)
			)
		)
		(duplicate_pad_numbers_are_jumpers no)
		(fp_line
			(start -0.7874 0.4064)
			(end -0.7874 -0.4064)
			(stroke
				(width 0.1524)
				(type default)
			)
			(layer "F.SilkS")
		)
		(fp_line
			(start 0.7874 0.4064)
			(end -0.7874 0.4064)
			(stroke
				(width 0.1524)
				(type default)
			)
			(layer "F.SilkS")
		)
		(fp_line
			(start -0.7874 -0.4064)
			(end 0.7874 -0.4064)
			(stroke
				(width 0.1524)
				(type default)
			)
			(layer "F.SilkS")
		)
		(fp_line
			(start 0.7874 -0.4064)
			(end 0.7874 0.4064)
			(stroke
				(width 0.1524)
				(type default)
			)
			(layer "F.SilkS")
		)
		(fp_poly
			(pts
				(xy -0.508 0.2794) (xy -0.508 0.2286) (xy -0.635 0.2286) (xy -0.635 -0.254) (xy -0.5334 -0.254)
				(xy -0.5334 -0.2794) (xy 0.5334 -0.2794) (xy 0.5334 -0.254) (xy 0.635 -0.254) (xy 0.635 0.254) (xy 0.5334 0.254)
				(xy 0.5334 0.2794)
			)
			(stroke
				(width 0)
				(type default)
			)
			(fill no)
			(layer "F.CrtYd")
		)
		(pad "1" smd rect
			(at 0.40005 0 270)
			(size 0.4572 0.508)
			(layers "F.Cu" "F.Mask" "F.Paste")
			(net "P3V3_STB_NODE1")
		)
		(pad "2" smd rect
			(at -0.40005 0 270)
			(size 0.4572 0.508)
			(layers "F.Cu" "F.Mask" "F.Paste")
			(net "SIO_PIN82")
		)
	)
	(footprint ""
		(layer "F.Cu")
		(at 53.76164 -99.105212 -90)
		(property "Reference" "C137"
			(at 0.63373 -1.409954 90)
			(unlocked yes)
			(layer "F.SilkS")
			(effects
				(font
					(size 0.7874 0.5842)
					(thickness 0.1524)
				)
				(justify left)
			)
		)
		(property "Value" ""
			(at 0 0 270)
			(layer "F.Fab")
			(effects
				(font
					(size 1.27 1.27)
				)
			)
		)
		(duplicate_pad_numbers_are_jumpers no)
		(fp_line
			(start -0.7874 0.4064)
			(end -0.7874 -0.4064)
			(stroke
				(width 0.1524)
				(type default)
			)
			(layer "F.SilkS")
		)
		(fp_line
			(start 0.7874 0.4064)
			(end -0.7874 0.4064)
			(stroke
				(width 0.1524)
				(type default)
			)
			(layer "F.SilkS")
		)
		(fp_line
			(start 0 0.381)
			(end 0 -0.381)
			(stroke
				(width 0.1524)
				(type default)
			)
			(layer "F.SilkS")
		)
		(fp_line
			(start -0.7874 -0.4064)
			(end 0.7874 -0.4064)
			(stroke
				(width 0.1524)
				(type default)
			)
			(layer "F.SilkS")
		)
		(fp_line
			(start 0.7874 -0.4064)
			(end 0.7874 0.4064)
			(stroke
				(width 0.1524)
				(type default)
			)
			(layer "F.SilkS")
		)
		(fp_poly
			(pts
				(xy -0.5334 0.254) (xy -0.635 0.254) (xy -0.635 0.2286) (xy -0.635 -0.254) (xy -0.5334 -0.254) (xy -0.5334 -0.2794)
				(xy 0.5334 -0.2794) (xy 0.5334 -0.254) (xy 0.635 -0.254) (xy 0.635 0.254) (xy 0.5334 0.254) (xy 0.5334 0.2794)
				(xy -0.508 0.2794) (xy -0.5334 0.2794)
			)
			(stroke
				(width 0)
				(type default)
			)
			(fill no)
			(layer "F.CrtYd")
		)
		(pad "1" smd rect
			(at 0.40005 0 270)
			(size 0.4572 0.508)
			(layers "F.Cu" "F.Mask" "F.Paste")
			(net "A_CPU0_NODE1_THERMDA")
		)
		(pad "2" smd rect
			(at -0.40005 0 270)
			(size 0.4572 0.508)
			(layers "F.Cu" "F.Mask" "F.Paste")
			(net "A_CPU0_NODE1_THERMDC")
		)
	)
	(footprint ""
		(layer "F.Cu")
		(at 168.258744 -93.866208)
		(property "Reference" "C366"
			(at 5.086096 0.54991 90)
			(unlocked yes)
			(layer "F.SilkS")
			(effects
				(font
					(size 0.7874 0.5842)
					(thickness 0.1524)
				)
				(justify left)
			)
		)
		(property "Value" ""
			(at 0 0 0)
			(layer "F.Fab")
			(effects
				(font
					(size 1.27 1.27)
				)
			)
		)
		(duplicate_pad_numbers_are_jumpers no)
		(fp_line
			(start -0.7874 -0.4064)
			(end 0.7874 -0.4064)
			(stroke
				(width 0.1524)
				(type default)
			)
			(layer "F.SilkS")
		)
		(fp_line
			(start -0.7874 0.4064)
			(end -0.7874 -0.4064)
			(stroke
				(width 0.1524)
				(type default)
			)
			(layer "F.SilkS")
		)
		(fp_line
			(start 0 0.381)
			(end 0 -0.381)
			(stroke
				(width 0.1524)
				(type default)
			)
			(layer "F.SilkS")
		)
		(fp_line
			(start 0.7874 -0.4064)
			(end 0.7874 0.4064)
			(stroke
				(width 0.1524)
				(type default)
			)
			(layer "F.SilkS")
		)
		(fp_line
			(start 0.7874 0.4064)
			(end -0.7874 0.4064)
			(stroke
				(width 0.1524)
				(type default)
			)
			(layer "F.SilkS")
		)
		(fp_poly
			(pts
				(xy -0.5334 0.254) (xy -0.635 0.254) (xy -0.635 0.2286) (xy -0.635 -0.254) (xy -0.5334 -0.254) (xy -0.5334 -0.2794)
				(xy 0.5334 -0.2794) (xy 0.5334 -0.254) (xy 0.635 -0.254) (xy 0.635 0.254) (xy 0.5334 0.254) (xy 0.5334 0.2794)
				(xy -0.508 0.2794) (xy -0.5334 0.2794)
			)
			(stroke
				(width 0)
				(type default)
			)
			(fill no)
			(layer "F.CrtYd")
		)
		(pad "1" smd rect
			(at 0.40005 0)
			(size 0.4572 0.508)
			(layers "F.Cu" "F.Mask" "F.Paste")
			(net "USB_NODE1_XTA2")
		)
		(pad "2" smd rect
			(at -0.40005 0)
			(size 0.4572 0.508)
			(layers "F.Cu" "F.Mask" "F.Paste")
			(net "GND")
		)
	)
	(footprint ""
		(layer "F.Cu")
		(at 137.52576 -181.506622 -90)
		(property "Reference" "C903"
			(at 0.169926 1.011174 90)
			(unlocked yes)
			(layer "F.SilkS")
			(effects
				(font
					(size 0.7874 0.5842)
					(thickness 0.1524)
				)
				(justify left)
			)
		)
		(property "Value" ""
			(at 0 0 270)
			(layer "F.Fab")
			(effects
				(font
					(size 1.27 1.27)
				)
			)
		)
		(duplicate_pad_numbers_are_jumpers no)
		(fp_line
			(start -0.7874 0.4064)
			(end -0.7874 -0.4064)
			(stroke
				(width 0.1524)
				(type default)
			)
			(layer "F.SilkS")
		)
		(fp_line
			(start 0.7874 0.4064)
			(end -0.7874 0.4064)
			(stroke
				(width 0.1524)
				(type default)
			)
			(layer "F.SilkS")
		)
		(fp_line
			(start 0 0.381)
			(end 0 -0.381)
			(stroke
				(width 0.1524)
				(type default)
			)
			(layer "F.SilkS")
		)
		(fp_line
			(start -0.7874 -0.4064)
			(end 0.7874 -0.4064)
			(stroke
				(width 0.1524)
				(type default)
			)
			(layer "F.SilkS")
		)
		(fp_line
			(start 0.7874 -0.4064)
			(end 0.7874 0.4064)
			(stroke
				(width 0.1524)
				(type default)
			)
			(layer "F.SilkS")
		)
		(fp_poly
			(pts
				(xy -0.5334 0.254) (xy -0.635 0.254) (xy -0.635 0.2286) (xy -0.635 -0.254) (xy -0.5334 -0.254) (xy -0.5334 -0.2794)
				(xy 0.5334 -0.2794) (xy 0.5334 -0.254) (xy 0.635 -0.254) (xy 0.635 0.254) (xy 0.5334 0.254) (xy 0.5334 0.2794)
				(xy -0.508 0.2794) (xy -0.5334 0.2794)
			)
			(stroke
				(width 0)
				(type default)
			)
			(fill no)
			(layer "F.CrtYd")
		)
		(pad "1" smd rect
			(at 0.40005 0 270)
			(size 0.4572 0.508)
			(layers "F.Cu" "F.Mask" "F.Paste")
			(net "P3V3_NODE1")
		)
		(pad "2" smd rect
			(at -0.40005 0 270)
			(size 0.4572 0.508)
			(layers "F.Cu" "F.Mask" "F.Paste")
			(net "GND")
		)
	)
	(footprint ""
		(layer "F.Cu")
		(at 15.997174 -16.260572 90)
		(property "Reference" "C543"
			(at -1.500124 -6.16966 90)
			(unlocked yes)
			(layer "F.SilkS")
			(effects
				(font
					(size 0.7874 0.5842)
					(thickness 0.1524)
				)
				(justify left)
			)
		)
		(property "Value" ""
			(at 0 0 90)
			(layer "F.Fab")
			(effects
				(font
					(size 1.27 1.27)
				)
			)
		)
		(duplicate_pad_numbers_are_jumpers no)
		(fp_line
			(start 0.7874 -0.4064)
			(end 0.7874 0.4064)
			(stroke
				(width 0.1524)
				(type default)
			)
			(layer "F.SilkS")
		)
		(fp_line
			(start -0.7874 -0.4064)
			(end 0.7874 -0.4064)
			(stroke
				(width 0.1524)
				(type default)
			)
			(layer "F.SilkS")
		)
		(fp_line
			(start 0 0.381)
			(end 0 -0.381)
			(stroke
				(width 0.1524)
				(type default)
			)
			(layer "F.SilkS")
		)
		(fp_line
			(start 0.7874 0.4064)
			(end -0.7874 0.4064)
			(stroke
				(width 0.1524)
				(type default)
			)
			(layer "F.SilkS")
		)
		(fp_line
			(start -0.7874 0.4064)
			(end -0.7874 -0.4064)
			(stroke
				(width 0.1524)
				(type default)
			)
			(layer "F.SilkS")
		)
		(fp_poly
			(pts
				(xy -0.5334 0.254) (xy -0.635 0.254) (xy -0.635 0.2286) (xy -0.635 -0.254) (xy -0.5334 -0.254) (xy -0.5334 -0.2794)
				(xy 0.5334 -0.2794) (xy 0.5334 -0.254) (xy 0.635 -0.254) (xy 0.635 0.254) (xy 0.5334 0.254) (xy 0.5334 0.2794)
				(xy -0.508 0.2794) (xy -0.5334 0.2794)
			)
			(stroke
				(width 0)
				(type default)
			)
			(fill no)
			(layer "F.CrtYd")
		)
		(pad "1" smd rect
			(at 0.40005 0 90)
			(size 0.4572 0.508)
			(layers "F.Cu" "F.Mask" "F.Paste")
			(net "P3V3_NODE1")
		)
		(pad "2" smd rect
			(at -0.40005 0 90)
			(size 0.4572 0.508)
			(layers "F.Cu" "F.Mask" "F.Paste")
			(net "GND")
		)
	)
	(footprint ""
		(layer "F.Cu")
		(at 38.699948 -3.086354 180)
		(property "Reference" "R1241"
			(at 15.15618 -1.703578 0)
			(unlocked yes)
			(layer "F.SilkS")
			(effects
				(font
					(size 0.7874 0.5842)
					(thickness 0.1524)
				)
				(justify left)
			)
		)
		(property "Value" ""
			(at 0 0 180)
			(layer "F.Fab")
			(effects
				(font
					(size 1.27 1.27)
				)
			)
		)
		(duplicate_pad_numbers_are_jumpers no)
		(fp_line
			(start 0.7874 0.4064)
			(end -0.7874 0.4064)
			(stroke
				(width 0.1524)
				(type default)
			)
			(layer "F.SilkS")
		)
		(fp_line
			(start 0.7874 -0.4064)
			(end 0.7874 0.4064)
			(stroke
				(width 0.1524)
				(type default)
			)
			(layer "F.SilkS")
		)
		(fp_line
			(start -0.7874 0.4064)
			(end -0.7874 -0.4064)
			(stroke
				(width 0.1524)
				(type default)
			)
			(layer "F.SilkS")
		)
		(fp_line
			(start -0.7874 -0.4064)
			(end 0.7874 -0.4064)
			(stroke
				(width 0.1524)
				(type default)
			)
			(layer "F.SilkS")
		)
		(fp_poly
			(pts
				(xy -0.508 0.2794) (xy -0.508 0.2286) (xy -0.635 0.2286) (xy -0.635 -0.254) (xy -0.5334 -0.254)
				(xy -0.5334 -0.2794) (xy 0.5334 -0.2794) (xy 0.5334 -0.254) (xy 0.635 -0.254) (xy 0.635 0.254) (xy 0.5334 0.254)
				(xy 0.5334 0.2794)
			)
			(stroke
				(width 0)
				(type default)
			)
			(fill no)
			(layer "F.CrtYd")
		)
		(pad "1" smd rect
			(at 0.40005 0 180)
			(size 0.4572 0.508)
			(layers "F.Cu" "F.Mask" "F.Paste")
			(net "GND")
		)
		(pad "2" smd rect
			(at -0.40005 0 180)
			(size 0.4572 0.508)
			(layers "F.Cu" "F.Mask" "F.Paste")
			(net "FM_CPLD_NODE1_PVDDR_STB_EN")
		)
	)
	(footprint ""
		(layer "F.Cu")
		(at 94.211394 -184.774586)
		(property "Reference" "C690"
			(at -1.182878 -7.195566 0)
			(unlocked yes)
			(layer "F.SilkS")
			(effects
				(font
					(size 0.7874 0.5842)
					(thickness 0.1524)
				)
				(justify left)
			)
		)
		(property "Value" ""
			(at 0 0 0)
			(layer "F.Fab")
			(effects
				(font
					(size 1.27 1.27)
				)
			)
		)
		(duplicate_pad_numbers_are_jumpers no)
		(fp_line
			(start -0.7874 -0.4064)
			(end 0.7874 -0.4064)
			(stroke
				(width 0.1524)
				(type default)
			)
			(layer "F.SilkS")
		)
		(fp_line
			(start -0.7874 0.4064)
			(end -0.7874 -0.4064)
			(stroke
				(width 0.1524)
				(type default)
			)
			(layer "F.SilkS")
		)
		(fp_line
			(start 0 0.381)
			(end 0 -0.381)
			(stroke
				(width 0.1524)
				(type default)
			)
			(layer "F.SilkS")
		)
		(fp_line
			(start 0.7874 -0.4064)
			(end 0.7874 0.4064)
			(stroke
				(width 0.1524)
				(type default)
			)
			(layer "F.SilkS")
		)
		(fp_line
			(start 0.7874 0.4064)
			(end -0.7874 0.4064)
			(stroke
				(width 0.1524)
				(type default)
			)
			(layer "F.SilkS")
		)
		(fp_poly
			(pts
				(xy -0.5334 0.254) (xy -0.635 0.254) (xy -0.635 0.2286) (xy -0.635 -0.254) (xy -0.5334 -0.254) (xy -0.5334 -0.2794)
				(xy 0.5334 -0.2794) (xy 0.5334 -0.254) (xy 0.635 -0.254) (xy 0.635 0.254) (xy 0.5334 0.254) (xy 0.5334 0.2794)
				(xy -0.508 0.2794) (xy -0.5334 0.2794)
			)
			(stroke
				(width 0)
				(type default)
			)
			(fill no)
			(layer "F.CrtYd")
		)
		(pad "1" smd rect
			(at 0.40005 0)
			(size 0.4572 0.508)
			(layers "F.Cu" "F.Mask" "F.Paste")
			(net "UART_T5_NODE4_RXD")
		)
		(pad "2" smd rect
			(at -0.40005 0)
			(size 0.4572 0.508)
			(layers "F.Cu" "F.Mask" "F.Paste")
			(net "GND")
		)
	)
	(footprint ""
		(layer "F.Cu")
		(at 155.476956 -20.568412 90)
		(property "Reference" "J5"
			(at -1.866138 3.43154 90)
			(unlocked yes)
			(layer "F.SilkS")
			(effects
				(font
					(size 0.7874 0.5842)
					(thickness 0.1524)
				)
				(justify left)
			)
		)
		(property "Value" ""
			(at 0 0 90)
			(layer "F.Fab")
			(effects
				(font
					(size 1.27 1.27)
				)
			)
		)
		(duplicate_pad_numbers_are_jumpers no)
		(fp_line
			(start 4.99999 -2.100072)
			(end -4.99999 -2.100072)
			(stroke
				(width 0.1524)
				(type default)
			)
			(layer "F.SilkS")
		)
		(fp_line
			(start -4.99999 -2.100072)
			(end -4.99999 0)
			(stroke
				(width 0.1524)
				(type default)
			)
			(layer "F.SilkS")
		)
		(fp_line
			(start 4.500118 -1.599946)
			(end 4.500118 2.100072)
			(stroke
				(width 0.1524)
				(type default)
			)
			(layer "F.SilkS")
		)
		(fp_line
			(start -2.3876 -1.599946)
			(end 4.500118 -1.599946)
			(stroke
				(width 0.1524)
				(type default)
			)
			(layer "F.SilkS")
		)
		(fp_line
			(start -4.500118 -1.599946)
			(end -3.6068 -1.599946)
			(stroke
				(width 0.1524)
				(type default)
			)
			(layer "F.SilkS")
		)
		(fp_line
			(start -4.99999 0)
			(end -4.99999 2.599944)
			(stroke
				(width 0.1524)
				(type default)
			)
			(layer "F.SilkS")
		)
		(fp_line
			(start 4.500118 2.100072)
			(end 1.999996 2.100072)
			(stroke
				(width 0.1524)
				(type default)
			)
			(layer "F.SilkS")
		)
		(fp_line
			(start 1.999996 2.100072)
			(end 1.999996 2.599944)
			(stroke
				(width 0.1524)
				(type default)
			)
			(layer "F.SilkS")
		)
		(fp_line
			(start -1.999996 2.100072)
			(end -4.500118 2.100072)
			(stroke
				(width 0.1524)
				(type default)
			)
			(layer "F.SilkS")
		)
		(fp_line
			(start -4.500118 2.100072)
			(end -4.500118 -1.599946)
			(stroke
				(width 0.1524)
				(type default)
			)
			(layer "F.SilkS")
		)
		(fp_line
			(start 4.99999 2.599944)
			(end 4.99999 -2.100072)
			(stroke
				(width 0.1524)
				(type default)
			)
			(layer "F.SilkS")
		)
		(fp_line
			(start -1.999996 2.599944)
			(end -1.999996 2.100072)
			(stroke
				(width 0.1524)
				(type default)
			)
			(layer "F.SilkS")
		)
		(fp_line
			(start -4.99999 2.599944)
			(end 4.99999 2.599944)
			(stroke
				(width 0.1524)
				(type default)
			)
			(layer "F.SilkS")
		)
		(fp_poly
			(pts
				(xy 2.959354 4.18084) (xy 3.721354 5.70484) (xy 2.197354 5.70484)
			)
			(stroke
				(width 0)
				(type default)
			)
			(fill yes)
			(layer "F.SilkS")
		)
		(fp_poly
			(pts
				(xy -3.7084 0.1778) (xy 3.683 0.1778) (xy 3.683 1.6256) (xy -3.7084 1.6256)
			)
			(stroke
				(width 0)
				(type default)
			)
			(fill no)
			(layer "B.CrtYd")
		)
		(fp_poly
			(pts
				(arc
					(start -2.9972 -1.7526)
					(mid -3.607857 -1.499657)
					(end -3.8608 -0.889)
				)
				(arc
					(start -3.8608 -0.889)
					(mid -3.615297 -0.296303)
					(end -3.0226 -0.0508)
				)
				(arc
					(start -2.9972 -0.0508)
					(mid -2.1463 -0.9017)
					(end -2.9972 -1.7526)
				)
			)
			(stroke
				(width 0)
				(type default)
			)
			(fill no)
			(layer "B.CrtYd")
		)
		(fp_rect
			(start -4.99999 2.599944)
			(end 4.99999 -2.100072)
			(stroke
				(width 0)
				(type default)
			)
			(fill no)
			(layer "F.CrtYd")
		)
		(fp_line
			(start 4.99999 -2.100072)
			(end -4.99999 -2.100072)
			(stroke
				(width 0.1)
				(type default)
			)
			(layer "F.Fab")
		)
		(fp_line
			(start -4.99999 -2.100072)
			(end -4.99999 0)
			(stroke
				(width 0.1)
				(type default)
			)
			(layer "F.Fab")
		)
		(fp_line
			(start 4.500118 -1.599946)
			(end 4.500118 2.100072)
			(stroke
				(width 0.1)
				(type default)
			)
			(layer "F.Fab")
		)
		(fp_line
			(start -3.6576 -1.599946)
			(end 4.500118 -1.599946)
			(stroke
				(width 0.1)
				(type default)
			)
			(layer "F.Fab")
		)
		(fp_line
			(start -4.500118 -1.599946)
			(end -3.6068 -1.599946)
			(stroke
				(width 0.1)
				(type default)
			)
			(layer "F.Fab")
		)
		(fp_line
			(start -4.99999 0)
			(end -4.99999 2.599944)
			(stroke
				(width 0.1)
				(type default)
			)
			(layer "F.Fab")
		)
		(fp_line
			(start 4.500118 2.100072)
			(end 1.999996 2.100072)
			(stroke
				(width 0.1)
				(type default)
			)
			(layer "F.Fab")
		)
		(fp_line
			(start 1.999996 2.100072)
			(end 1.999996 2.599944)
			(stroke
				(width 0.1)
				(type default)
			)
			(layer "F.Fab")
		)
		(fp_line
			(start -1.999996 2.100072)
			(end -4.500118 2.100072)
			(stroke
				(width 0.1)
				(type default)
			)
			(layer "F.Fab")
		)
		(fp_line
			(start -4.500118 2.100072)
			(end -4.500118 -1.599946)
			(stroke
				(width 0.1)
				(type default)
			)
			(layer "F.Fab")
		)
		(fp_line
			(start 4.99999 2.599944)
			(end 4.99999 -2.100072)
			(stroke
				(width 0.1)
				(type default)
			)
			(layer "F.Fab")
		)
		(fp_line
			(start -1.999996 2.599944)
			(end -1.999996 2.100072)
			(stroke
				(width 0.1)
				(type default)
			)
			(layer "F.Fab")
		)
		(fp_line
			(start -4.99999 2.599944)
			(end 4.99999 2.599944)
			(stroke
				(width 0.1)
				(type default)
			)
			(layer "F.Fab")
		)
		(fp_poly
			(pts
				(xy 5.715 0.899922) (xy 7.239 0.137922) (xy 7.239 1.661922)
			)
			(stroke
				(width 0)
				(type default)
			)
			(fill yes)
			(layer "F.Fab")
		)
		(fp_text user "1"
			(at 4.197096 -2.834132 0)
			(unlocked yes)
			(layer "F.SilkS")
			(effects
				(font
					(size 0.7874 0.5842)
					(thickness 0.1524)
				)
				(justify left)
			)
		)
		(fp_text user "4"
			(at -5.793994 1.24079 90)
			(unlocked yes)
			(layer "F.SilkS")
			(effects
				(font
					(size 0.7874 0.5842)
					(thickness 0.1524)
				)
				(justify left)
			)
		)
		(fp_text user "4"
			(at -4.571746 1.43383 0)
			(unlocked yes)
			(layer "B.SilkS")
			(effects
				(font
					(size 0.7874 0.5842)
					(thickness 0.1524)
				)
				(justify left mirror)
			)
		)
		(fp_text user "1"
			(at 4.340606 1.547622 0)
			(unlocked yes)
			(layer "B.SilkS")
			(effects
				(font
					(size 0.7874 0.5842)
					(thickness 0.1524)
				)
				(justify left mirror)
			)
		)
		(fp_text user "1"
			(at 4.4831 0.808203 90)
			(unlocked yes)
			(layer "B.Fab")
			(effects
				(font
					(size 0.786892 0.583946)
					(thickness 0.000001)
				)
				(justify left mirror)
			)
		)
		(fp_text user "4"
			(at -3.8989 0.808203 90)
			(unlocked yes)
			(layer "B.Fab")
			(effects
				(font
					(size 0.786892 0.583946)
					(thickness 0.000001)
				)
				(justify left mirror)
			)
		)
		(fp_text user "1"
			(at 5.0419 0.808203 90)
			(unlocked yes)
			(layer "F.Fab")
			(effects
				(font
					(size 0.786892 0.583946)
					(thickness 0.000001)
				)
				(justify left)
			)
		)
		(fp_text user "4"
			(at -6.0071 0.808203 90)
			(unlocked yes)
			(layer "F.Fab")
			(effects
				(font
					(size 0.786892 0.583946)
					(thickness 0.000001)
				)
				(justify left)
			)
		)
		(pad "" np_thru_hole circle
			(at -2.999994 -0.899922 90)
			(size 1.1938 1.1938)
			(drill 1.1938)
			(layers "*.Cu" "*.Mask")
			(clearance 0.381)
			(thermal_gap 0.381)
		)
		(pad "1" thru_hole rect
			(at 2.999994 0.899922 90)
			(size 1.3208 1.3208)
			(drill 0.9144)
			(layers "*.Cu" "*.Mask")
			(remove_unused_layers no)
			(net "P3V3_NODE1")
			(clearance 0.0508)
			(thermal_gap 0.0508)
			(padstack
				(mode front_inner_back)
				(layer "Inner"
					(shape circle)
					(size 1.3208 1.3208)
					(clearance 0.0508)
				)
				(layer "B.Cu"
					(shape rect)
					(size 1.3208 1.3208)
					(clearance 0.0508)
				)
			)
		)
		(pad "2" thru_hole circle
			(at 0.999998 0.899922 90)
			(size 1.3208 1.3208)
			(drill 0.9144)
			(layers "*.Cu" "*.Mask")
			(remove_unused_layers no)
			(net "UART_TX_P3")
			(clearance 0.0508)
			(thermal_gap 0.0508)
		)
		(pad "3" thru_hole circle
			(at -0.999998 0.899922 90)
			(size 1.3208 1.3208)
			(drill 0.9144)
			(layers "*.Cu" "*.Mask")
			(remove_unused_layers no)
			(net "UART_RX_P3")
			(clearance 0.0508)
			(thermal_gap 0.0508)
		)
		(pad "4" thru_hole circle
			(at -2.999994 0.899922 90)
			(size 1.3208 1.3208)
			(drill 0.9144)
			(layers "*.Cu" "*.Mask")
			(remove_unused_layers no)
			(net "GND")
			(clearance 0.0508)
			(thermal_gap 0.0508)
		)
		(zone
			(layers "F.Cu" "B.Cu" "In1.Cu" "In2.Cu" "In3.Cu" "In4.Cu" "In5.Cu" "In6.Cu"
				"In7.Cu" "In8.Cu"
			)
			(hatch none 0.5)
			(connect_pads
				(clearance 0)
			)
			(min_thickness 0.25)
			(keepout
				(tracks not_allowed)
				(vias allowed)
				(pads allowed)
				(copperpour not_allowed)
				(footprints allowed)
			)
			(placement
				(enabled no)
				(sheetname "")
			)
			(fill
				(thermal_gap 0.5)
				(thermal_bridge_width 0.5)
				(island_removal_mode 0)
			)
			(polygon
				(pts
					(arc
						(start 153.571956 -17.571212)
						(mid 153.869536 -16.852792)
						(end 154.587956 -16.555212)
					)
					(arc
						(start 154.587956 -16.555212)
						(mid 155.288416 -16.845352)
						(end 155.578556 -17.545812)
					)
					(arc
						(start 155.578556 -17.571212)
						(mid 154.575256 -18.574512)
						(end 153.571956 -17.571212)
					)
				)
			)
		)
	)
	(footprint ""
		(layer "F.Cu")
		(at 83.425538 -136.337294 -90)
		(property "Reference" "J23"
			(at -3.184652 -4.199128 90)
			(unlocked yes)
			(layer "F.SilkS")
			(effects
				(font
					(size 0.7874 0.5842)
					(thickness 0.1524)
				)
				(justify left)
			)
		)
		(property "Value" ""
			(at 0 0 270)
			(layer "F.Fab")
			(effects
				(font
					(size 1.27 1.27)
				)
			)
		)
		(duplicate_pad_numbers_are_jumpers no)
		(fp_poly
			(pts
				(xy 0.2794 0.907796) (xy 0.254 0.907796) (xy 0.254 1.0414) (xy -0.254 1.0414) (xy -0.254 1.034796)
				(xy -0.254 0.933196) (xy -0.2794 0.933196) (xy -0.2794 -0.133604) (xy -0.254 -0.133604) (xy -0.254 -0.235204)
				(xy 0.254 -0.235204) (xy 0.254 -0.133604) (xy 0.2794 -0.133604)
			)
			(stroke
				(width 0)
				(type default)
			)
			(fill no)
			(layer "F.CrtYd")
		)
		(pad "1" smd custom
			(at 0 -0.000254 270)
			(size 0.127 0.127)
			(layers "F.Cu" "F.Mask" "F.Paste")
			(net "P1V26_STB_NODE1_ADJ_S")
			(options
				(clearance outline)
				(anchor circle)
			)
			(primitives
				(gr_poly
					(pts
						(xy -0.127 0.508) (xy -0.127 -0.0508) (xy -0.254 -0.0508) (xy -0.254 -0.508) (xy 0.254 -0.508)
						(xy 0.254 -0.0508) (xy 0.127 -0.0508) (xy 0.127 0.508)
					)
					(width 0)
					(fill yes)
				)
			)
		)
		(pad "2" smd rect
			(at 0 0.799846)
			(size 0.4572 0.508)
			(layers "F.Cu" "F.Mask" "F.Paste")
			(net "P1V26_BMC_NODE1")
		)
		(zone
			(layer "F.Cu")
			(hatch none 0.5)
			(connect_pads
				(clearance 0)
			)
			(min_thickness 0.25)
			(keepout
				(tracks allowed)
				(vias not_allowed)
				(pads allowed)
				(copperpour not_allowed)
				(footprints allowed)
			)
			(placement
				(enabled no)
				(sheetname "")
			)
			(fill
				(thermal_gap 0.5)
				(thermal_bridge_width 0.5)
				(island_removal_mode 0)
			)
			(polygon
				(pts
					(xy 82.339942 -136.642094) (xy 82.339942 -136.032494) (xy 83.711542 -136.032494) (xy 83.711542 -136.642094)
				)
			)
		)
	)
	(footprint ""
		(layer "F.Cu")
		(at 64.622172 -156.431234)
		(property "Reference" "PC6"
			(at -32.142684 -4.459224 0)
			(unlocked yes)
			(layer "F.SilkS")
			(effects
				(font
					(size 0.7874 0.5842)
					(thickness 0.1524)
				)
				(justify left)
			)
		)
		(property "Value" ""
			(at 0 0 0)
			(layer "F.Fab")
			(effects
				(font
					(size 1.27 1.27)
				)
			)
		)
		(duplicate_pad_numbers_are_jumpers no)
		(fp_line
			(start -1.905 -0.8636)
			(end 1.905 -0.8636)
			(stroke
				(width 0.1524)
				(type default)
			)
			(layer "F.SilkS")
		)
		(fp_line
			(start -1.905 0.8636)
			(end -1.905 -0.8636)
			(stroke
				(width 0.1524)
				(type default)
			)
			(layer "F.SilkS")
		)
		(fp_line
			(start 0 0.8382)
			(end 0 -0.8382)
			(stroke
				(width 0.1524)
				(type default)
			)
			(layer "F.SilkS")
		)
		(fp_line
			(start 1.905 -0.8636)
			(end 1.905 0.8636)
			(stroke
				(width 0.1524)
				(type default)
			)
			(layer "F.SilkS")
		)
		(fp_line
			(start 1.905 0.8636)
			(end -1.905 0.8636)
			(stroke
				(width 0.1524)
				(type default)
			)
			(layer "F.SilkS")
		)
		(fp_rect
			(start -1.524 0.7366)
			(end 1.524 -0.7366)
			(stroke
				(width 0)
				(type default)
			)
			(fill no)
			(layer "F.CrtYd")
		)
		(pad "1" smd rect
			(at 0.94996 0)
			(size 1.1176 1.3716)
			(layers "F.Cu" "F.Mask" "F.Paste")
			(net "P5V_STB_NODE1")
		)
		(pad "2" smd rect
			(at -0.94996 0)
			(size 1.1176 1.3716)
			(layers "F.Cu" "F.Mask" "F.Paste")
			(net "GND")
		)
	)
	(footprint ""
		(layer "F.Cu")
		(at 38.39083 -118.112286 90)
		(property "Reference" "R1115"
			(at 0.167132 1.236472 90)
			(unlocked yes)
			(layer "F.SilkS")
			(effects
				(font
					(size 0.7874 0.5842)
					(thickness 0.1524)
				)
				(justify left)
			)
		)
		(property "Value" ""
			(at 0 0 90)
			(layer "F.Fab")
			(effects
				(font
					(size 1.27 1.27)
				)
			)
		)
		(duplicate_pad_numbers_are_jumpers no)
		(fp_line
			(start 0.7874 -0.4064)
			(end 0.7874 0.4064)
			(stroke
				(width 0.1524)
				(type default)
			)
			(layer "F.SilkS")
		)
		(fp_line
			(start -0.7874 -0.4064)
			(end 0.7874 -0.4064)
			(stroke
				(width 0.1524)
				(type default)
			)
			(layer "F.SilkS")
		)
		(fp_line
			(start 0.7874 0.4064)
			(end -0.7874 0.4064)
			(stroke
				(width 0.1524)
				(type default)
			)
			(layer "F.SilkS")
		)
		(fp_line
			(start -0.7874 0.4064)
			(end -0.7874 -0.4064)
			(stroke
				(width 0.1524)
				(type default)
			)
			(layer "F.SilkS")
		)
		(fp_poly
			(pts
				(xy -0.508 0.2794) (xy -0.508 0.2286) (xy -0.635 0.2286) (xy -0.635 -0.254) (xy -0.5334 -0.254)
				(xy -0.5334 -0.2794) (xy 0.5334 -0.2794) (xy 0.5334 -0.254) (xy 0.635 -0.254) (xy 0.635 0.254) (xy 0.5334 0.254)
				(xy 0.5334 0.2794)
			)
			(stroke
				(width 0)
				(type default)
			)
			(fill no)
			(layer "F.CrtYd")
		)
		(pad "1" smd rect
			(at 0.40005 0 90)
			(size 0.4572 0.508)
			(layers "F.Cu" "F.Mask" "F.Paste")
			(net "P5V_STB_NODE1")
		)
		(pad "2" smd rect
			(at -0.40005 0 90)
			(size 0.4572 0.508)
			(layers "F.Cu" "F.Mask" "F.Paste")
			(net "FM_CPLD_NODE1_P1V5_EN_LV")
		)
	)
	(footprint ""
		(layer "F.Cu")
		(at 44.49572 -173.717966)
		(property "Reference" "U92"
			(at 1.411224 132.150612 90)
			(unlocked yes)
			(layer "F.SilkS")
			(effects
				(font
					(size 0.7874 0.5842)
					(thickness 0.1524)
				)
			)
		)
		(property "Value" ""
			(at 0 0 0)
			(layer "F.Fab")
			(effects
				(font
					(size 1.27 1.27)
				)
			)
		)
		(duplicate_pad_numbers_are_jumpers no)
		(fp_line
			(start -1.651 -1.905)
			(end 1.651 -1.905)
			(stroke
				(width 0.1524)
				(type default)
			)
			(layer "F.SilkS")
		)
		(fp_line
			(start -1.651 1.905)
			(end -1.651 -1.905)
			(stroke
				(width 0.1524)
				(type default)
			)
			(layer "F.SilkS")
		)
		(fp_line
			(start 1.651 -1.905)
			(end 1.651 1.905)
			(stroke
				(width 0.1524)
				(type default)
			)
			(layer "F.SilkS")
		)
		(fp_line
			(start 1.651 1.905)
			(end -1.651 1.905)
			(stroke
				(width 0.1524)
				(type default)
			)
			(layer "F.SilkS")
		)
		(fp_poly
			(pts
				(xy -1.524 0.7112) (xy -1.524 1.7526) (xy -0.508 1.7526) (xy -0.508 0.6985) (xy 0.508 0.6985) (xy 0.508 1.7526)
				(xy 1.524 1.7526) (xy 1.524 0.6985) (xy 1.524 -0.6985) (xy 0.508 -0.6985) (xy 0.508 -1.7526) (xy -0.508 -1.7526)
				(xy -0.508 -0.6985) (xy -1.524 -0.6985) (xy -1.524 0.6985)
			)
			(stroke
				(width 0)
				(type default)
			)
			(fill no)
			(layer "F.CrtYd")
		)
		(fp_text user "G"
			(at -2.196846 1.442466 0)
			(unlocked yes)
			(layer "F.SilkS")
			(effects
				(font
					(size 0.635 0.4064)
					(thickness 0.1524)
				)
			)
		)
		(fp_text user "D"
			(at -0.823468 -2.367026 0)
			(unlocked yes)
			(layer "F.SilkS")
			(effects
				(font
					(size 0.635 0.4064)
					(thickness 0.1524)
				)
			)
		)
		(fp_text user "S"
			(at 1.830578 1.30175 0)
			(unlocked yes)
			(layer "F.SilkS")
			(effects
				(font
					(size 0.635 0.4064)
					(thickness 0.1524)
				)
			)
		)
		(pad "D" smd rect
			(at 0 -1.1176)
			(size 1.016 1.27)
			(layers "F.Cu" "F.Mask" "F.Paste")
			(net "P12V_AUX_EN")
		)
		(pad "G" smd rect
			(at -1.016 1.1176)
			(size 1.016 1.27)
			(layers "F.Cu" "F.Mask" "F.Paste")
			(net "PSU_DC_OK_N")
		)
		(pad "S" smd rect
			(at 1.016 1.1176)
			(size 1.016 1.27)
			(layers "F.Cu" "F.Mask" "F.Paste")
			(net "GND")
		)
	)
	(footprint ""
		(layer "F.Cu")
		(at 133.26745 -60.930282 -90)
		(property "Reference" "R653"
			(at 0.706882 -2.11582 90)
			(unlocked yes)
			(layer "F.SilkS")
			(effects
				(font
					(size 0.7874 0.5842)
					(thickness 0.1524)
				)
				(justify left)
			)
		)
		(property "Value" ""
			(at 0 0 270)
			(layer "F.Fab")
			(effects
				(font
					(size 1.27 1.27)
				)
			)
		)
		(duplicate_pad_numbers_are_jumpers no)
		(fp_line
			(start -0.7874 0.4064)
			(end -0.7874 -0.4064)
			(stroke
				(width 0.1524)
				(type default)
			)
			(layer "F.SilkS")
		)
		(fp_line
			(start 0.7874 0.4064)
			(end -0.7874 0.4064)
			(stroke
				(width 0.1524)
				(type default)
			)
			(layer "F.SilkS")
		)
		(fp_line
			(start -0.7874 -0.4064)
			(end 0.7874 -0.4064)
			(stroke
				(width 0.1524)
				(type default)
			)
			(layer "F.SilkS")
		)
		(fp_line
			(start 0.7874 -0.4064)
			(end 0.7874 0.4064)
			(stroke
				(width 0.1524)
				(type default)
			)
			(layer "F.SilkS")
		)
		(fp_poly
			(pts
				(xy -0.508 0.2794) (xy -0.508 0.2286) (xy -0.635 0.2286) (xy -0.635 -0.254) (xy -0.5334 -0.254)
				(xy -0.5334 -0.2794) (xy 0.5334 -0.2794) (xy 0.5334 -0.254) (xy 0.635 -0.254) (xy 0.635 0.254) (xy 0.5334 0.254)
				(xy 0.5334 0.2794)
			)
			(stroke
				(width 0)
				(type default)
			)
			(fill no)
			(layer "F.CrtYd")
		)
		(pad "1" smd rect
			(at 0.40005 0 270)
			(size 0.4572 0.508)
			(layers "F.Cu" "F.Mask" "F.Paste")
			(net "P3V3_NODE1")
		)
		(pad "2" smd rect
			(at -0.40005 0 270)
			(size 0.4572 0.508)
			(layers "F.Cu" "F.Mask" "F.Paste")
			(net "N21116716")
		)
	)
	(footprint ""
		(layer "F.Cu")
		(at 87.73668 -77.200252 180)
		(property "Reference" "C60"
			(at -3.937 0.021336 0)
			(unlocked yes)
			(layer "F.SilkS")
			(effects
				(font
					(size 0.7874 0.5842)
					(thickness 0.1524)
				)
			)
		)
		(property "Value" ""
			(at 0 0 180)
			(layer "F.Fab")
			(effects
				(font
					(size 1.27 1.27)
				)
			)
		)
		(duplicate_pad_numbers_are_jumpers no)
		(fp_line
			(start 1.2954 0.5842)
			(end -1.2954 0.5842)
			(stroke
				(width 0.1524)
				(type default)
			)
			(layer "F.SilkS")
		)
		(fp_line
			(start 1.2954 -0.5842)
			(end 1.2954 0.5842)
			(stroke
				(width 0.1524)
				(type default)
			)
			(layer "F.SilkS")
		)
		(fp_line
			(start 0 -0.5842)
			(end 0 0.5842)
			(stroke
				(width 0.1524)
				(type default)
			)
			(layer "F.SilkS")
		)
		(fp_line
			(start -1.2954 0.5842)
			(end -1.2954 -0.5842)
			(stroke
				(width 0.1524)
				(type default)
			)
			(layer "F.SilkS")
		)
		(fp_line
			(start -1.2954 -0.5842)
			(end 1.2954 -0.5842)
			(stroke
				(width 0.1524)
				(type default)
			)
			(layer "F.SilkS")
		)
		(fp_poly
			(pts
				(xy 0.8636 -0.4572) (xy 0.8636 -0.3556) (xy 1.143 -0.3556) (xy 1.143 0.3556) (xy 0.8636 0.3556)
				(xy 0.8636 0.4572) (xy -0.8636 0.4572) (xy -0.8636 0.3556) (xy -1.143 0.3556) (xy -1.143 -0.3556)
				(xy -0.8636 -0.3556) (xy -0.8636 -0.4572)
			)
			(stroke
				(width 0)
				(type default)
			)
			(fill no)
			(layer "F.CrtYd")
		)
		(fp_line
			(start 0.884936 0.504952)
			(end -0.884936 0.504952)
			(stroke
				(width 0.1)
				(type default)
			)
			(layer "F.Fab")
		)
		(fp_line
			(start 0.884936 -0.504952)
			(end 0.884936 0.504952)
			(stroke
				(width 0.1)
				(type default)
			)
			(layer "F.Fab")
		)
		(fp_line
			(start -0.884936 0.504952)
			(end -0.884936 -0.504952)
			(stroke
				(width 0.1)
				(type default)
			)
			(layer "F.Fab")
		)
		(fp_line
			(start -0.884936 -0.504952)
			(end 0.884936 -0.504952)
			(stroke
				(width 0.1)
				(type default)
			)
			(layer "F.Fab")
		)
		(pad "1" smd rect
			(at 0.7366 0 270)
			(size 0.7112 0.8128)
			(layers "F.Cu" "F.Mask" "F.Paste")
			(net "P1V05_VCCPLLCPU0SIO_NODE1")
		)
		(pad "2" smd rect
			(at -0.7366 0 270)
			(size 0.7112 0.8128)
			(layers "F.Cu" "F.Mask" "F.Paste")
			(net "GND")
		)
	)
	(footprint ""
		(layer "F.Cu")
		(at 148.07184 -175.28032 180)
		(property "Reference" "R794"
			(at 1.07442 2.382012 0)
			(unlocked yes)
			(layer "F.SilkS")
			(effects
				(font
					(size 0.7874 0.5842)
					(thickness 0.1524)
				)
				(justify left)
			)
		)
		(property "Value" ""
			(at 0 0 180)
			(layer "F.Fab")
			(effects
				(font
					(size 1.27 1.27)
				)
			)
		)
		(duplicate_pad_numbers_are_jumpers no)
		(fp_line
			(start 0.7874 0.4064)
			(end -0.7874 0.4064)
			(stroke
				(width 0.1524)
				(type default)
			)
			(layer "F.SilkS")
		)
		(fp_line
			(start 0.7874 -0.4064)
			(end 0.7874 0.4064)
			(stroke
				(width 0.1524)
				(type default)
			)
			(layer "F.SilkS")
		)
		(fp_line
			(start -0.7874 0.4064)
			(end -0.7874 -0.4064)
			(stroke
				(width 0.1524)
				(type default)
			)
			(layer "F.SilkS")
		)
		(fp_line
			(start -0.7874 -0.4064)
			(end 0.7874 -0.4064)
			(stroke
				(width 0.1524)
				(type default)
			)
			(layer "F.SilkS")
		)
		(fp_poly
			(pts
				(xy -0.508 0.2794) (xy -0.508 0.2286) (xy -0.635 0.2286) (xy -0.635 -0.254) (xy -0.5334 -0.254)
				(xy -0.5334 -0.2794) (xy 0.5334 -0.2794) (xy 0.5334 -0.254) (xy 0.635 -0.254) (xy 0.635 0.254) (xy 0.5334 0.254)
				(xy 0.5334 0.2794)
			)
			(stroke
				(width 0)
				(type default)
			)
			(fill no)
			(layer "F.CrtYd")
		)
		(pad "1" smd rect
			(at 0.40005 0 180)
			(size 0.4572 0.508)
			(layers "F.Cu" "F.Mask" "F.Paste")
			(net "CPLD_UART_RTS_P3_N")
		)
		(pad "2" smd rect
			(at -0.40005 0 180)
			(size 0.4572 0.508)
			(layers "F.Cu" "F.Mask" "F.Paste")
			(net "GND")
		)
	)
	(footprint ""
		(layer "F.Cu")
		(at 118.183914 -136.24814 -90)
		(property "Reference" "PR70"
			(at -2.32664 -5.267452 90)
			(unlocked yes)
			(layer "F.SilkS")
			(effects
				(font
					(size 0.635 0.4064)
					(thickness 0.1524)
				)
				(justify left)
			)
		)
		(property "Value" ""
			(at 0 0 270)
			(layer "F.Fab")
			(effects
				(font
					(size 1.27 1.27)
				)
			)
		)
		(duplicate_pad_numbers_are_jumpers no)
		(fp_line
			(start -0.7874 0.4064)
			(end -0.7874 -0.4064)
			(stroke
				(width 0.1524)
				(type default)
			)
			(layer "F.SilkS")
		)
		(fp_line
			(start 0.7874 0.4064)
			(end -0.7874 0.4064)
			(stroke
				(width 0.1524)
				(type default)
			)
			(layer "F.SilkS")
		)
		(fp_line
			(start -0.7874 -0.4064)
			(end 0.7874 -0.4064)
			(stroke
				(width 0.1524)
				(type default)
			)
			(layer "F.SilkS")
		)
		(fp_line
			(start 0.7874 -0.4064)
			(end 0.7874 0.4064)
			(stroke
				(width 0.1524)
				(type default)
			)
			(layer "F.SilkS")
		)
		(fp_poly
			(pts
				(xy -0.508 0.2794) (xy -0.508 0.2286) (xy -0.635 0.2286) (xy -0.635 -0.254) (xy -0.5334 -0.254)
				(xy -0.5334 -0.2794) (xy 0.5334 -0.2794) (xy 0.5334 -0.254) (xy 0.635 -0.254) (xy 0.635 0.254) (xy 0.5334 0.254)
				(xy 0.5334 0.2794)
			)
			(stroke
				(width 0)
				(type default)
			)
			(fill no)
			(layer "F.CrtYd")
		)
		(pad "1" smd rect
			(at 0.40005 0 270)
			(size 0.4572 0.508)
			(layers "F.Cu" "F.Mask" "F.Paste")
			(net "VR_PVCCP_NODE1_FB_RR")
		)
		(pad "2" smd rect
			(at -0.40005 0 270)
			(size 0.4572 0.508)
			(layers "F.Cu" "F.Mask" "F.Paste")
			(net "VR_PVCCP_NODE1_VSEN")
		)
	)
	(footprint ""
		(layer "F.Cu")
		(at 61.444886 -121.044462 -90)
		(property "Reference" "R323"
			(at 4.642612 -8.319516 90)
			(unlocked yes)
			(layer "F.SilkS")
			(effects
				(font
					(size 0.7874 0.5842)
					(thickness 0.1524)
				)
				(justify left)
			)
		)
		(property "Value" ""
			(at 0 0 270)
			(layer "F.Fab")
			(effects
				(font
					(size 1.27 1.27)
				)
			)
		)
		(duplicate_pad_numbers_are_jumpers no)
		(fp_line
			(start -0.7874 0.4064)
			(end -0.7874 -0.4064)
			(stroke
				(width 0.1524)
				(type default)
			)
			(layer "F.SilkS")
		)
		(fp_line
			(start 0.7874 0.4064)
			(end -0.7874 0.4064)
			(stroke
				(width 0.1524)
				(type default)
			)
			(layer "F.SilkS")
		)
		(fp_line
			(start -0.7874 -0.4064)
			(end 0.7874 -0.4064)
			(stroke
				(width 0.1524)
				(type default)
			)
			(layer "F.SilkS")
		)
		(fp_line
			(start 0.7874 -0.4064)
			(end 0.7874 0.4064)
			(stroke
				(width 0.1524)
				(type default)
			)
			(layer "F.SilkS")
		)
		(fp_poly
			(pts
				(xy -0.508 0.2794) (xy -0.508 0.2286) (xy -0.635 0.2286) (xy -0.635 -0.254) (xy -0.5334 -0.254)
				(xy -0.5334 -0.2794) (xy 0.5334 -0.2794) (xy 0.5334 -0.254) (xy 0.635 -0.254) (xy 0.635 0.254) (xy 0.5334 0.254)
				(xy 0.5334 0.2794)
			)
			(stroke
				(width 0)
				(type default)
			)
			(fill no)
			(layer "F.CrtYd")
		)
		(pad "1" smd rect
			(at 0.40005 0 270)
			(size 0.4572 0.508)
			(layers "F.Cu" "F.Mask" "F.Paste")
			(net "P3V3_NODE1")
		)
		(pad "2" smd rect
			(at -0.40005 0 270)
			(size 0.4572 0.508)
			(layers "F.Cu" "F.Mask" "F.Paste")
			(net "BMC_ROMA7")
		)
	)
	(footprint ""
		(layer "F.Cu")
		(at 19.99996 -7.799832)
		(property "Reference" "D18"
			(at -3.796284 4.463288 90)
			(unlocked yes)
			(layer "F.SilkS")
			(effects
				(font
					(size 0.7874 0.5842)
					(thickness 0.1524)
				)
				(justify left)
			)
		)
		(property "Value" ""
			(at 0 0 0)
			(layer "F.Fab")
			(effects
				(font
					(size 1.27 1.27)
				)
			)
		)
		(duplicate_pad_numbers_are_jumpers no)
		(fp_line
			(start -3.109976 -1.400048)
			(end -3.109976 1.1938)
			(stroke
				(width 0.1524)
				(type default)
			)
			(layer "F.SilkS")
		)
		(fp_line
			(start -3.109976 0.8128)
			(end -3.109976 7.739888)
			(stroke
				(width 0.1524)
				(type default)
			)
			(layer "F.SilkS")
		)
		(fp_line
			(start -3.109976 7.739888)
			(end -2.499868 7.739888)
			(stroke
				(width 0.1524)
				(type default)
			)
			(layer "F.SilkS")
		)
		(fp_line
			(start -2.499868 7.739888)
			(end -2.499868 10.24001)
			(stroke
				(width 0.1524)
				(type default)
			)
			(layer "F.SilkS")
		)
		(fp_line
			(start 2.499868 7.739888)
			(end 3.109976 7.739888)
			(stroke
				(width 0.1524)
				(type default)
			)
			(layer "F.SilkS")
		)
		(fp_line
			(start 2.499868 10.24001)
			(end 2.499868 7.739888)
			(stroke
				(width 0.1524)
				(type default)
			)
			(layer "F.SilkS")
		)
		(fp_line
			(start 3.109976 -1.400048)
			(end -3.109976 -1.400048)
			(stroke
				(width 0.1524)
				(type default)
			)
			(layer "F.SilkS")
		)
		(fp_line
			(start 3.109976 1.4478)
			(end 3.109976 -1.400048)
			(stroke
				(width 0.1524)
				(type default)
			)
			(layer "F.SilkS")
		)
		(fp_line
			(start 3.109976 7.739888)
			(end 3.109976 0.6096)
			(stroke
				(width 0.1524)
				(type default)
			)
			(layer "F.SilkS")
		)
		(fp_arc
			(start 2.499868 10.24001)
			(mid 0 12.739878)
			(end -2.499868 10.24001)
			(stroke
				(width 0.1524)
				(type default)
			)
			(layer "F.SilkS")
		)
		(fp_poly
			(pts
				(xy -1.27 -1.5494) (xy -1.778 -2.5654) (xy -0.762 -2.5654)
			)
			(stroke
				(width 0)
				(type default)
			)
			(fill yes)
			(layer "F.SilkS")
		)
		(fp_poly
			(pts
				(xy -2.0828 3.354832) (xy -2.0828 1.729232) (xy -1.4478 1.729232) (xy -1.4478 1.725168) (xy -0.4572 1.725168)
				(xy -0.4572 3.3528) (xy -1.388872 3.3528) (xy -1.388872 3.354832)
			)
			(stroke
				(width 0)
				(type default)
			)
			(fill no)
			(layer "B.CrtYd")
		)
		(fp_poly
			(pts
				(arc
					(start 0 0.8128)
					(mid 0 -0.8128)
					(end 0 0.8128)
				)
			)
			(stroke
				(width 0)
				(type default)
			)
			(fill no)
			(layer "B.CrtYd")
		)
		(fp_poly
			(pts
				(arc
					(start 1.27 3.3528)
					(mid 1.27 1.7272)
					(end 1.27 3.3528)
				)
			)
			(stroke
				(width 0)
				(type default)
			)
			(fill no)
			(layer "B.CrtYd")
		)
		(fp_poly
			(pts
				(xy -2.499868 7.739888)
				(arc
					(start -2.499868 10.24001)
					(mid 0 12.739878)
					(end 2.499868 10.24001)
				)
				(xy 2.499868 7.739888) (xy 3.109976 7.739888) (xy 3.109976 -1.400048) (xy -3.109976 -1.400048) (xy -3.109976 7.739888)
			)
			(stroke
				(width 0)
				(type default)
			)
			(fill no)
			(layer "F.CrtYd")
		)
		(fp_line
			(start -3.109976 -1.400048)
			(end -3.109976 7.739888)
			(stroke
				(width 0.1)
				(type default)
			)
			(layer "F.Fab")
		)
		(fp_line
			(start -3.109976 -1.400048)
			(end -3.109976 7.739888)
			(stroke
				(width 0.1)
				(type default)
			)
			(layer "F.Fab")
		)
		(fp_line
			(start -3.109976 7.739888)
			(end -2.499868 7.739888)
			(stroke
				(width 0.1)
				(type default)
			)
			(layer "F.Fab")
		)
		(fp_line
			(start -3.109976 7.739888)
			(end -2.499868 7.739888)
			(stroke
				(width 0.1)
				(type default)
			)
			(layer "F.Fab")
		)
		(fp_line
			(start -2.499868 7.739888)
			(end -2.499868 10.24001)
			(stroke
				(width 0.1)
				(type default)
			)
			(layer "F.Fab")
		)
		(fp_line
			(start -2.499868 7.739888)
			(end -2.499868 10.24001)
			(stroke
				(width 0.1)
				(type default)
			)
			(layer "F.Fab")
		)
		(fp_line
			(start 2.499868 7.739888)
			(end 3.109976 7.739888)
			(stroke
				(width 0.1)
				(type default)
			)
			(layer "F.Fab")
		)
		(fp_line
			(start 2.499868 7.739888)
			(end 3.109976 7.739888)
			(stroke
				(width 0.1)
				(type default)
			)
			(layer "F.Fab")
		)
		(fp_line
			(start 2.499868 10.24001)
			(end 2.499868 7.739888)
			(stroke
				(width 0.1)
				(type default)
			)
			(layer "F.Fab")
		)
		(fp_line
			(start 2.499868 10.24001)
			(end 2.499868 7.739888)
			(stroke
				(width 0.1)
				(type default)
			)
			(layer "F.Fab")
		)
		(fp_line
			(start 3.109976 -1.400048)
			(end -3.109976 -1.400048)
			(stroke
				(width 0.1)
				(type default)
			)
			(layer "F.Fab")
		)
		(fp_line
			(start 3.109976 -1.400048)
			(end -3.109976 -1.400048)
			(stroke
				(width 0.1)
				(type default)
			)
			(layer "F.Fab")
		)
		(fp_line
			(start 3.109976 7.739888)
			(end 3.109976 -1.400048)
			(stroke
				(width 0.1)
				(type default)
			)
			(layer "F.Fab")
		)
		(fp_line
			(start 3.109976 7.739888)
			(end 3.109976 -1.400048)
			(stroke
				(width 0.1)
				(type default)
			)
			(layer "F.Fab")
		)
		(fp_arc
			(start 2.499868 10.24001)
			(mid 0 12.739878)
			(end -2.499868 10.24001)
			(stroke
				(width 0.1)
				(type default)
			)
			(layer "F.Fab")
		)
		(fp_arc
			(start 2.499868 10.24001)
			(mid 0 12.739878)
			(end -2.499868 10.24001)
			(stroke
				(width 0.1)
				(type default)
			)
			(layer "F.Fab")
		)
		(fp_poly
			(pts
				(xy -1.27 -1.5494) (xy -1.778 -2.5654) (xy -0.762 -2.5654)
			)
			(stroke
				(width 0)
				(type default)
			)
			(fill yes)
			(layer "F.Fab")
		)
		(fp_text user "1"
			(at -3.782568 0.37719 0)
			(unlocked yes)
			(layer "F.SilkS")
			(effects
				(font
					(size 0.7874 0.5842)
					(thickness 0.1524)
				)
				(justify left)
			)
		)
		(fp_text user "3"
			(at 3.218942 3.372358 0)
			(unlocked yes)
			(layer "F.SilkS")
			(effects
				(font
					(size 0.7874 0.5842)
					(thickness 0.1524)
				)
				(justify left)
			)
		)
		(fp_text user "2"
			(at 3.241548 -0.785876 0)
			(unlocked yes)
			(layer "F.SilkS")
			(effects
				(font
					(size 0.7874 0.5842)
					(thickness 0.1524)
				)
				(justify left)
			)
		)
		(fp_text user "1"
			(at -3.282696 2.342134 0)
			(unlocked yes)
			(layer "B.SilkS")
			(effects
				(font
					(size 0.7874 0.5842)
					(thickness 0.1524)
				)
				(justify left mirror)
			)
		)
		(fp_text user "2"
			(at 0.574294 -2.155698 0)
			(unlocked yes)
			(layer "B.SilkS")
			(effects
				(font
					(size 0.7874 0.5842)
					(thickness 0.1524)
				)
				(justify left mirror)
			)
		)
		(fp_text user "3"
			(at 3.208528 2.271522 0)
			(unlocked yes)
			(layer "B.SilkS")
			(effects
				(font
					(size 0.7874 0.5842)
					(thickness 0.1524)
				)
				(justify left mirror)
			)
		)
		(fp_text user "1"
			(at -0.9779 1.330706 0)
			(unlocked yes)
			(layer "B.Fab")
			(effects
				(font
					(size 0.7874 0.5842)
					(thickness 0.000001)
				)
				(justify left mirror)
			)
		)
		(fp_text user "2"
			(at 0.2921 1.254506 0)
			(unlocked yes)
			(layer "B.Fab")
			(effects
				(font
					(size 0.7874 0.5842)
					(thickness 0.000001)
				)
				(justify left mirror)
			)
		)
		(fp_text user "3"
			(at 1.5621 1.330706 0)
			(unlocked yes)
			(layer "B.Fab")
			(effects
				(font
					(size 0.7874 0.5842)
					(thickness 0.000001)
				)
				(justify left mirror)
			)
		)
		(fp_text user "1"
			(at -2.1717 -2.022094 0)
			(unlocked yes)
			(layer "F.Fab")
			(effects
				(font
					(size 0.7874 0.5842)
					(thickness 0.000001)
				)
				(justify left)
			)
		)
		(fp_text user "2"
			(at -0.2921 -2.022094 0)
			(unlocked yes)
			(layer "F.Fab")
			(effects
				(font
					(size 0.7874 0.5842)
					(thickness 0.000001)
				)
				(justify left)
			)
		)
		(fp_text user "3"
			(at 0.9779 -1.996694 0)
			(unlocked yes)
			(layer "F.Fab")
			(effects
				(font
					(size 0.7874 0.5842)
					(thickness 0.000001)
				)
				(justify left)
			)
		)
		(pad "1" thru_hole rect
			(at -1.27 2.54)
			(size 1.524 1.524)
			(drill 1.016)
			(layers "*.Cu" "*.Mask")
			(remove_unused_layers no)
			(net "ATTENTION_LED_R")
			(clearance 0)
			(padstack
				(mode front_inner_back)
				(layer "Inner"
					(shape circle)
					(size 1.524 1.524)
					(clearance 0)
				)
				(layer "B.Cu"
					(shape rect)
					(size 1.524 1.524)
					(clearance 0)
				)
			)
		)
		(pad "2" thru_hole circle
			(at 0 0)
			(size 1.524 1.524)
			(drill 1.016)
			(layers "*.Cu" "*.Mask")
			(remove_unused_layers no)
			(net "N53608934")
			(clearance 0)
		)
		(pad "3" thru_hole circle
			(at 1.27 2.54)
			(size 1.524 1.524)
			(drill 1.016)
			(layers "*.Cu" "*.Mask")
			(remove_unused_layers no)
			(net "GND")
			(clearance 0)
		)
	)
	(footprint ""
		(layer "F.Cu")
		(at 171.151042 -137.351008)
		(property "Reference" "C797"
			(at -2.942082 -9.370314 0)
			(unlocked yes)
			(layer "F.SilkS")
			(effects
				(font
					(size 0.7874 0.5842)
					(thickness 0.1524)
				)
				(justify left)
			)
		)
		(property "Value" ""
			(at 0 0 0)
			(layer "F.Fab")
			(effects
				(font
					(size 1.27 1.27)
				)
			)
		)
		(duplicate_pad_numbers_are_jumpers no)
		(fp_line
			(start -0.7874 -0.4064)
			(end 0.7874 -0.4064)
			(stroke
				(width 0.1524)
				(type default)
			)
			(layer "F.SilkS")
		)
		(fp_line
			(start -0.7874 0.4064)
			(end -0.7874 -0.4064)
			(stroke
				(width 0.1524)
				(type default)
			)
			(layer "F.SilkS")
		)
		(fp_line
			(start 0 0.381)
			(end 0 -0.381)
			(stroke
				(width 0.1524)
				(type default)
			)
			(layer "F.SilkS")
		)
		(fp_line
			(start 0.7874 -0.4064)
			(end 0.7874 0.4064)
			(stroke
				(width 0.1524)
				(type default)
			)
			(layer "F.SilkS")
		)
		(fp_line
			(start 0.7874 0.4064)
			(end -0.7874 0.4064)
			(stroke
				(width 0.1524)
				(type default)
			)
			(layer "F.SilkS")
		)
		(fp_poly
			(pts
				(xy -0.5334 0.254) (xy -0.635 0.254) (xy -0.635 0.2286) (xy -0.635 -0.254) (xy -0.5334 -0.254) (xy -0.5334 -0.2794)
				(xy 0.5334 -0.2794) (xy 0.5334 -0.254) (xy 0.635 -0.254) (xy 0.635 0.254) (xy 0.5334 0.254) (xy 0.5334 0.2794)
				(xy -0.508 0.2794) (xy -0.5334 0.2794)
			)
			(stroke
				(width 0)
				(type default)
			)
			(fill no)
			(layer "F.CrtYd")
		)
		(pad "1" smd rect
			(at 0.40005 0)
			(size 0.4572 0.508)
			(layers "F.Cu" "F.Mask" "F.Paste")
			(net "GND")
		)
		(pad "2" smd rect
			(at -0.40005 0)
			(size 0.4572 0.508)
			(layers "F.Cu" "F.Mask" "F.Paste")
			(net "PWR_BTN_NODE1_L")
		)
	)
	(footprint ""
		(layer "F.Cu")
		(at 82.051144 -156.359352 90)
		(property "Reference" "PC9"
			(at -0.276098 0.648716 0)
			(unlocked yes)
			(layer "F.SilkS")
			(effects
				(font
					(size 0.7874 0.5842)
					(thickness 0.1524)
				)
				(justify left)
			)
		)
		(property "Value" ""
			(at 0 0 90)
			(layer "F.Fab")
			(effects
				(font
					(size 1.27 1.27)
				)
			)
		)
		(duplicate_pad_numbers_are_jumpers no)
		(fp_line
			(start 0.7874 -0.4064)
			(end 0.7874 0.4064)
			(stroke
				(width 0.1524)
				(type default)
			)
			(layer "F.SilkS")
		)
		(fp_line
			(start -0.7874 -0.4064)
			(end 0.7874 -0.4064)
			(stroke
				(width 0.1524)
				(type default)
			)
			(layer "F.SilkS")
		)
		(fp_line
			(start 0 0.381)
			(end 0 -0.381)
			(stroke
				(width 0.1524)
				(type default)
			)
			(layer "F.SilkS")
		)
		(fp_line
			(start 0.7874 0.4064)
			(end -0.7874 0.4064)
			(stroke
				(width 0.1524)
				(type default)
			)
			(layer "F.SilkS")
		)
		(fp_line
			(start -0.7874 0.4064)
			(end -0.7874 -0.4064)
			(stroke
				(width 0.1524)
				(type default)
			)
			(layer "F.SilkS")
		)
		(fp_poly
			(pts
				(xy -0.5334 0.254) (xy -0.635 0.254) (xy -0.635 0.2286) (xy -0.635 -0.254) (xy -0.5334 -0.254) (xy -0.5334 -0.2794)
				(xy 0.5334 -0.2794) (xy 0.5334 -0.254) (xy 0.635 -0.254) (xy 0.635 0.254) (xy 0.5334 0.254) (xy 0.5334 0.2794)
				(xy -0.508 0.2794) (xy -0.5334 0.2794)
			)
			(stroke
				(width 0)
				(type default)
			)
			(fill no)
			(layer "F.CrtYd")
		)
		(pad "1" smd rect
			(at 0.40005 0 90)
			(size 0.4572 0.508)
			(layers "F.Cu" "F.Mask" "F.Paste")
			(net "GND")
		)
		(pad "2" smd rect
			(at -0.40005 0 90)
			(size 0.4572 0.508)
			(layers "F.Cu" "F.Mask" "F.Paste")
			(net "P5V_STB_NODE1_SS")
		)
	)
	(footprint ""
		(layer "F.Cu")
		(at 179.622704 -11.53668 -90)
		(property "Reference" "R813"
			(at 0.8636 2.071624 90)
			(unlocked yes)
			(layer "F.SilkS")
			(effects
				(font
					(size 0.7874 0.5842)
					(thickness 0.1524)
				)
				(justify left)
			)
		)
		(property "Value" ""
			(at 0 0 270)
			(layer "F.Fab")
			(effects
				(font
					(size 1.27 1.27)
				)
			)
		)
		(duplicate_pad_numbers_are_jumpers no)
		(fp_line
			(start -0.7874 0.4064)
			(end -0.7874 -0.4064)
			(stroke
				(width 0.1524)
				(type default)
			)
			(layer "F.SilkS")
		)
		(fp_line
			(start 0.7874 0.4064)
			(end -0.7874 0.4064)
			(stroke
				(width 0.1524)
				(type default)
			)
			(layer "F.SilkS")
		)
		(fp_line
			(start -0.7874 -0.4064)
			(end 0.7874 -0.4064)
			(stroke
				(width 0.1524)
				(type default)
			)
			(layer "F.SilkS")
		)
		(fp_line
			(start 0.7874 -0.4064)
			(end 0.7874 0.4064)
			(stroke
				(width 0.1524)
				(type default)
			)
			(layer "F.SilkS")
		)
		(fp_poly
			(pts
				(xy -0.508 0.2794) (xy -0.508 0.2286) (xy -0.635 0.2286) (xy -0.635 -0.254) (xy -0.5334 -0.254)
				(xy -0.5334 -0.2794) (xy 0.5334 -0.2794) (xy 0.5334 -0.254) (xy 0.635 -0.254) (xy 0.635 0.254) (xy 0.5334 0.254)
				(xy 0.5334 0.2794)
			)
			(stroke
				(width 0)
				(type default)
			)
			(fill no)
			(layer "F.CrtYd")
		)
		(pad "1" smd rect
			(at 0.40005 0 270)
			(size 0.4572 0.508)
			(layers "F.Cu" "F.Mask" "F.Paste")
			(net "N53608970")
		)
		(pad "2" smd rect
			(at -0.40005 0 270)
			(size 0.4572 0.508)
			(layers "F.Cu" "F.Mask" "F.Paste")
			(net "GND")
		)
	)
	(footprint ""
		(layer "F.Cu")
		(at 125.07976 -185.205624 -90)
		(property "Reference" "C737"
			(at -4.725416 -0.073152 90)
			(unlocked yes)
			(layer "F.SilkS")
			(effects
				(font
					(size 0.7874 0.5842)
					(thickness 0.1524)
				)
				(justify left)
			)
		)
		(property "Value" ""
			(at 0 0 270)
			(layer "F.Fab")
			(effects
				(font
					(size 1.27 1.27)
				)
			)
		)
		(duplicate_pad_numbers_are_jumpers no)
		(fp_line
			(start -0.7874 0.4064)
			(end -0.7874 -0.4064)
			(stroke
				(width 0.1524)
				(type default)
			)
			(layer "F.SilkS")
		)
		(fp_line
			(start 0.7874 0.4064)
			(end -0.7874 0.4064)
			(stroke
				(width 0.1524)
				(type default)
			)
			(layer "F.SilkS")
		)
		(fp_line
			(start 0 0.381)
			(end 0 -0.381)
			(stroke
				(width 0.1524)
				(type default)
			)
			(layer "F.SilkS")
		)
		(fp_line
			(start -0.7874 -0.4064)
			(end 0.7874 -0.4064)
			(stroke
				(width 0.1524)
				(type default)
			)
			(layer "F.SilkS")
		)
		(fp_line
			(start 0.7874 -0.4064)
			(end 0.7874 0.4064)
			(stroke
				(width 0.1524)
				(type default)
			)
			(layer "F.SilkS")
		)
		(fp_poly
			(pts
				(xy -0.5334 0.254) (xy -0.635 0.254) (xy -0.635 0.2286) (xy -0.635 -0.254) (xy -0.5334 -0.254) (xy -0.5334 -0.2794)
				(xy 0.5334 -0.2794) (xy 0.5334 -0.254) (xy 0.635 -0.254) (xy 0.635 0.254) (xy 0.5334 0.254) (xy 0.5334 0.2794)
				(xy -0.508 0.2794) (xy -0.5334 0.2794)
			)
			(stroke
				(width 0)
				(type default)
			)
			(fill no)
			(layer "F.CrtYd")
		)
		(pad "1" smd rect
			(at 0.40005 0 270)
			(size 0.4572 0.508)
			(layers "F.Cu" "F.Mask" "F.Paste")
			(net "UART_T9_NODE4_RXD")
		)
		(pad "2" smd rect
			(at -0.40005 0 270)
			(size 0.4572 0.508)
			(layers "F.Cu" "F.Mask" "F.Paste")
			(net "GND")
		)
	)
	(footprint ""
		(layer "F.Cu")
		(at 36.280598 -76.35875)
		(property "Reference" "C112"
			(at -5.19938 -0.53594 0)
			(unlocked yes)
			(layer "F.SilkS")
			(effects
				(font
					(size 0.7874 0.5842)
					(thickness 0.1524)
				)
				(justify left)
			)
		)
		(property "Value" ""
			(at 0 0 0)
			(layer "F.Fab")
			(effects
				(font
					(size 1.27 1.27)
				)
			)
		)
		(duplicate_pad_numbers_are_jumpers no)
		(fp_line
			(start -0.7874 -0.4064)
			(end 0.7874 -0.4064)
			(stroke
				(width 0.1524)
				(type default)
			)
			(layer "F.SilkS")
		)
		(fp_line
			(start -0.7874 0.4064)
			(end -0.7874 -0.4064)
			(stroke
				(width 0.1524)
				(type default)
			)
			(layer "F.SilkS")
		)
		(fp_line
			(start 0 0.381)
			(end 0 -0.381)
			(stroke
				(width 0.1524)
				(type default)
			)
			(layer "F.SilkS")
		)
		(fp_line
			(start 0.7874 -0.4064)
			(end 0.7874 0.4064)
			(stroke
				(width 0.1524)
				(type default)
			)
			(layer "F.SilkS")
		)
		(fp_line
			(start 0.7874 0.4064)
			(end -0.7874 0.4064)
			(stroke
				(width 0.1524)
				(type default)
			)
			(layer "F.SilkS")
		)
		(fp_poly
			(pts
				(xy -0.5334 0.254) (xy -0.635 0.254) (xy -0.635 0.2286) (xy -0.635 -0.254) (xy -0.5334 -0.254) (xy -0.5334 -0.2794)
				(xy 0.5334 -0.2794) (xy 0.5334 -0.254) (xy 0.635 -0.254) (xy 0.635 0.254) (xy 0.5334 0.254) (xy 0.5334 0.2794)
				(xy -0.508 0.2794) (xy -0.5334 0.2794)
			)
			(stroke
				(width 0)
				(type default)
			)
			(fill no)
			(layer "F.CrtYd")
		)
		(pad "1" smd rect
			(at 0.40005 0)
			(size 0.4572 0.508)
			(layers "F.Cu" "F.Mask" "F.Paste")
			(net "P1V8_VCCASFRHPLL_NODE1")
		)
		(pad "2" smd rect
			(at -0.40005 0)
			(size 0.4572 0.508)
			(layers "F.Cu" "F.Mask" "F.Paste")
			(net "GND")
		)
	)
	(footprint ""
		(layer "F.Cu")
		(at 61.38418 -164.510212 -90)
		(property "Reference" "R1109"
			(at -1.53416 -0.204724 90)
			(unlocked yes)
			(layer "F.SilkS")
			(effects
				(font
					(size 0.7874 0.5842)
					(thickness 0.1524)
				)
				(justify left)
			)
		)
		(property "Value" ""
			(at 0 0 270)
			(layer "F.Fab")
			(effects
				(font
					(size 1.27 1.27)
				)
			)
		)
		(duplicate_pad_numbers_are_jumpers no)
		(fp_line
			(start -0.7874 0.4064)
			(end -0.7874 -0.4064)
			(stroke
				(width 0.1524)
				(type default)
			)
			(layer "F.SilkS")
		)
		(fp_line
			(start 0.7874 0.4064)
			(end -0.7874 0.4064)
			(stroke
				(width 0.1524)
				(type default)
			)
			(layer "F.SilkS")
		)
		(fp_line
			(start -0.7874 -0.4064)
			(end 0.7874 -0.4064)
			(stroke
				(width 0.1524)
				(type default)
			)
			(layer "F.SilkS")
		)
		(fp_line
			(start 0.7874 -0.4064)
			(end 0.7874 0.4064)
			(stroke
				(width 0.1524)
				(type default)
			)
			(layer "F.SilkS")
		)
		(fp_poly
			(pts
				(xy -0.508 0.2794) (xy -0.508 0.2286) (xy -0.635 0.2286) (xy -0.635 -0.254) (xy -0.5334 -0.254)
				(xy -0.5334 -0.2794) (xy 0.5334 -0.2794) (xy 0.5334 -0.254) (xy 0.635 -0.254) (xy 0.635 0.254) (xy 0.5334 0.254)
				(xy 0.5334 0.2794)
			)
			(stroke
				(width 0)
				(type default)
			)
			(fill no)
			(layer "F.CrtYd")
		)
		(pad "1" smd rect
			(at 0.40005 0 270)
			(size 0.4572 0.508)
			(layers "F.Cu" "F.Mask" "F.Paste")
			(net "FM_CPLD_NODE1_P5V_NODE1_EN_G")
		)
		(pad "2" smd rect
			(at -0.40005 0 270)
			(size 0.4572 0.508)
			(layers "F.Cu" "F.Mask" "F.Paste")
			(net "P3V3_STB_NODE1")
		)
	)
	(footprint ""
		(layer "F.Cu")
		(at 110.51032 -151.381968 -90)
		(property "Reference" "Q45"
			(at 4.080002 -0.417576 0)
			(unlocked yes)
			(layer "F.SilkS")
			(effects
				(font
					(size 0.7874 0.5842)
					(thickness 0.1524)
				)
			)
		)
		(property "Value" ""
			(at 0 0 270)
			(layer "F.Fab")
			(effects
				(font
					(size 1.27 1.27)
				)
			)
		)
		(duplicate_pad_numbers_are_jumpers no)
		(fp_line
			(start -1.488186 1.500124)
			(end -1.488186 -1.500124)
			(stroke
				(width 0.1524)
				(type default)
			)
			(layer "F.SilkS")
		)
		(fp_line
			(start 1.488186 1.500124)
			(end -1.488186 1.500124)
			(stroke
				(width 0.1524)
				(type default)
			)
			(layer "F.SilkS")
		)
		(fp_line
			(start -1.488186 -1.500124)
			(end 1.488186 -1.500124)
			(stroke
				(width 0.1524)
				(type default)
			)
			(layer "F.SilkS")
		)
		(fp_line
			(start 1.488186 -1.500124)
			(end 1.488186 1.500124)
			(stroke
				(width 0.1524)
				(type default)
			)
			(layer "F.SilkS")
		)
		(fp_poly
			(pts
				(xy -0.700024 1.500124) (xy 0.700024 1.500124) (xy 0.700024 0.3556) (xy 1.4224 0.3556) (xy 1.4224 -0.3556)
				(xy 0.700024 -0.3556) (xy 0.700024 -1.500124) (xy -0.700024 -1.500124) (xy -0.700024 -1.3208) (xy -1.4224 -1.3208)
				(xy -1.4224 -0.5842) (xy -0.700024 -0.5842) (xy -0.700024 0.5842) (xy -1.4224 0.5842) (xy -1.4224 1.3208)
				(xy -0.700024 1.3208)
			)
			(stroke
				(width 0)
				(type default)
			)
			(fill no)
			(layer "F.CrtYd")
		)
		(fp_line
			(start -0.700024 1.500124)
			(end -0.700024 -1.500124)
			(stroke
				(width 0.1)
				(type default)
			)
			(layer "F.Fab")
		)
		(fp_line
			(start 0.700024 1.500124)
			(end -0.700024 1.500124)
			(stroke
				(width 0.1)
				(type default)
			)
			(layer "F.Fab")
		)
		(fp_line
			(start -0.700024 -1.500124)
			(end 0.700024 -1.500124)
			(stroke
				(width 0.1)
				(type default)
			)
			(layer "F.Fab")
		)
		(fp_line
			(start 0.700024 -1.500124)
			(end 0.700024 1.500124)
			(stroke
				(width 0.1)
				(type default)
			)
			(layer "F.Fab")
		)
		(fp_text user "1"
			(at -0.439928 0.237744 0)
			(unlocked yes)
			(layer "F.SilkS")
			(effects
				(font
					(size 0.635 0.4064)
					(thickness 0.1524)
				)
			)
		)
		(fp_text user "3"
			(at -0.09779 -1.881378 0)
			(unlocked yes)
			(layer "F.SilkS")
			(effects
				(font
					(size 0.635 0.4064)
					(thickness 0.1524)
				)
			)
		)
		(fp_text user "2"
			(at 1.009396 -1.881378 0)
			(unlocked yes)
			(layer "F.SilkS")
			(effects
				(font
					(size 0.635 0.4064)
					(thickness 0.1524)
				)
			)
		)
		(fp_text user "2"
			(at -0.90805 1.8542 180)
			(unlocked yes)
			(layer "F.Fab")
			(effects
				(font
					(size 0.7874 0.5842)
					(thickness 0.000001)
				)
			)
		)
		(fp_text user "3"
			(at 2.15773 0 180)
			(unlocked yes)
			(layer "F.Fab")
			(effects
				(font
					(size 0.7874 0.5842)
					(thickness 0.000001)
				)
			)
		)
		(fp_text user "1"
			(at -0.90805 -1.8034 180)
			(unlocked yes)
			(layer "F.Fab")
			(effects
				(font
					(size 0.7874 0.5842)
					(thickness 0.000001)
				)
			)
		)
		(pad "1" smd rect
			(at -0.999998 -0.94996 180)
			(size 0.6096 0.7112)
			(layers "F.Cu" "F.Mask" "F.Paste")
			(net "N52411214")
		)
		(pad "2" smd rect
			(at -0.999998 0.94996 180)
			(size 0.6096 0.7112)
			(layers "F.Cu" "F.Mask" "F.Paste")
			(net "N52411159")
		)
		(pad "3" smd rect
			(at 0.999998 0 180)
			(size 0.6096 0.7112)
			(layers "F.Cu" "F.Mask" "F.Paste")
			(net "POWER_SW2_PWR_CTR_12V")
		)
	)
	(footprint ""
		(layer "F.Cu")
		(at 50.53076 -188.126624 90)
		(property "Reference" "R849"
			(at 4.548886 0.205232 90)
			(unlocked yes)
			(layer "F.SilkS")
			(effects
				(font
					(size 0.7874 0.5842)
					(thickness 0.1524)
				)
				(justify left)
			)
		)
		(property "Value" ""
			(at 0 0 90)
			(layer "F.Fab")
			(effects
				(font
					(size 1.27 1.27)
				)
			)
		)
		(duplicate_pad_numbers_are_jumpers no)
		(fp_line
			(start 0.7874 -0.4064)
			(end 0.7874 0.4064)
			(stroke
				(width 0.1524)
				(type default)
			)
			(layer "F.SilkS")
		)
		(fp_line
			(start -0.7874 -0.4064)
			(end 0.7874 -0.4064)
			(stroke
				(width 0.1524)
				(type default)
			)
			(layer "F.SilkS")
		)
		(fp_line
			(start 0.7874 0.4064)
			(end -0.7874 0.4064)
			(stroke
				(width 0.1524)
				(type default)
			)
			(layer "F.SilkS")
		)
		(fp_line
			(start -0.7874 0.4064)
			(end -0.7874 -0.4064)
			(stroke
				(width 0.1524)
				(type default)
			)
			(layer "F.SilkS")
		)
		(fp_poly
			(pts
				(xy -0.508 0.2794) (xy -0.508 0.2286) (xy -0.635 0.2286) (xy -0.635 -0.254) (xy -0.5334 -0.254)
				(xy -0.5334 -0.2794) (xy 0.5334 -0.2794) (xy 0.5334 -0.254) (xy 0.635 -0.254) (xy 0.635 0.254) (xy 0.5334 0.254)
				(xy 0.5334 0.2794)
			)
			(stroke
				(width 0)
				(type default)
			)
			(fill no)
			(layer "F.CrtYd")
		)
		(pad "1" smd rect
			(at 0.40005 0 90)
			(size 0.4572 0.508)
			(layers "F.Cu" "F.Mask" "F.Paste")
			(net "PSU3_AC_OK_R")
		)
		(pad "2" smd rect
			(at -0.40005 0 90)
			(size 0.4572 0.508)
			(layers "F.Cu" "F.Mask" "F.Paste")
			(net "GND")
		)
	)
	(footprint ""
		(layer "F.Cu")
		(at 8.553958 -9.179306 90)
		(property "Reference" "C180"
			(at -2.095246 -2.989834 90)
			(unlocked yes)
			(layer "F.SilkS")
			(effects
				(font
					(size 0.7874 0.5842)
					(thickness 0.1524)
				)
				(justify left)
			)
		)
		(property "Value" ""
			(at 0 0 90)
			(layer "F.Fab")
			(effects
				(font
					(size 1.27 1.27)
				)
			)
		)
		(duplicate_pad_numbers_are_jumpers no)
		(fp_line
			(start 0.7874 -0.4064)
			(end 0.7874 0.4064)
			(stroke
				(width 0.1524)
				(type default)
			)
			(layer "F.SilkS")
		)
		(fp_line
			(start -0.7874 -0.4064)
			(end 0.7874 -0.4064)
			(stroke
				(width 0.1524)
				(type default)
			)
			(layer "F.SilkS")
		)
		(fp_line
			(start 0 0.381)
			(end 0 -0.381)
			(stroke
				(width 0.1524)
				(type default)
			)
			(layer "F.SilkS")
		)
		(fp_line
			(start 0.7874 0.4064)
			(end -0.7874 0.4064)
			(stroke
				(width 0.1524)
				(type default)
			)
			(layer "F.SilkS")
		)
		(fp_line
			(start -0.7874 0.4064)
			(end -0.7874 -0.4064)
			(stroke
				(width 0.1524)
				(type default)
			)
			(layer "F.SilkS")
		)
		(fp_poly
			(pts
				(xy -0.5334 0.254) (xy -0.635 0.254) (xy -0.635 0.2286) (xy -0.635 -0.254) (xy -0.5334 -0.254) (xy -0.5334 -0.2794)
				(xy 0.5334 -0.2794) (xy 0.5334 -0.254) (xy 0.635 -0.254) (xy 0.635 0.254) (xy 0.5334 0.254) (xy 0.5334 0.2794)
				(xy -0.508 0.2794) (xy -0.5334 0.2794)
			)
			(stroke
				(width 0)
				(type default)
			)
			(fill no)
			(layer "F.CrtYd")
		)
		(pad "1" smd rect
			(at 0.40005 0 90)
			(size 0.4572 0.508)
			(layers "F.Cu" "F.Mask" "F.Paste")
			(net "P5V_STB_NODE1")
		)
		(pad "2" smd rect
			(at -0.40005 0 90)
			(size 0.4572 0.508)
			(layers "F.Cu" "F.Mask" "F.Paste")
			(net "GND")
		)
	)
	(footprint ""
		(layer "F.Cu")
		(at 13.965174 -16.260572 -90)
		(property "Reference" "C546"
			(at 1.500124 6.243574 90)
			(unlocked yes)
			(layer "F.SilkS")
			(effects
				(font
					(size 0.7874 0.5842)
					(thickness 0.1524)
				)
				(justify left)
			)
		)
		(property "Value" ""
			(at 0 0 270)
			(layer "F.Fab")
			(effects
				(font
					(size 1.27 1.27)
				)
			)
		)
		(duplicate_pad_numbers_are_jumpers no)
		(fp_line
			(start -0.7874 0.4064)
			(end -0.7874 -0.4064)
			(stroke
				(width 0.1524)
				(type default)
			)
			(layer "F.SilkS")
		)
		(fp_line
			(start 0.7874 0.4064)
			(end -0.7874 0.4064)
			(stroke
				(width 0.1524)
				(type default)
			)
			(layer "F.SilkS")
		)
		(fp_line
			(start 0 0.381)
			(end 0 -0.381)
			(stroke
				(width 0.1524)
				(type default)
			)
			(layer "F.SilkS")
		)
		(fp_line
			(start -0.7874 -0.4064)
			(end 0.7874 -0.4064)
			(stroke
				(width 0.1524)
				(type default)
			)
			(layer "F.SilkS")
		)
		(fp_line
			(start 0.7874 -0.4064)
			(end 0.7874 0.4064)
			(stroke
				(width 0.1524)
				(type default)
			)
			(layer "F.SilkS")
		)
		(fp_poly
			(pts
				(xy -0.5334 0.254) (xy -0.635 0.254) (xy -0.635 0.2286) (xy -0.635 -0.254) (xy -0.5334 -0.254) (xy -0.5334 -0.2794)
				(xy 0.5334 -0.2794) (xy 0.5334 -0.254) (xy 0.635 -0.254) (xy 0.635 0.254) (xy 0.5334 0.254) (xy 0.5334 0.2794)
				(xy -0.508 0.2794) (xy -0.5334 0.2794)
			)
			(stroke
				(width 0)
				(type default)
			)
			(fill no)
			(layer "F.CrtYd")
		)
		(pad "1" smd rect
			(at 0.40005 0 270)
			(size 0.4572 0.508)
			(layers "F.Cu" "F.Mask" "F.Paste")
			(net "N54251517")
		)
		(pad "2" smd rect
			(at -0.40005 0 270)
			(size 0.4572 0.508)
			(layers "F.Cu" "F.Mask" "F.Paste")
			(net "N54251519")
		)
	)
	(footprint ""
		(layer "F.Cu")
		(at 47.60214 -166.43985 90)
		(property "Reference" "R541"
			(at -130.36804 -3.317748 90)
			(unlocked yes)
			(layer "F.SilkS")
			(effects
				(font
					(size 0.7874 0.5842)
					(thickness 0.1524)
				)
				(justify left)
			)
		)
		(property "Value" ""
			(at 0 0 90)
			(layer "F.Fab")
			(effects
				(font
					(size 1.27 1.27)
				)
			)
		)
		(duplicate_pad_numbers_are_jumpers no)
		(fp_line
			(start 0.7874 -0.4064)
			(end 0.7874 0.4064)
			(stroke
				(width 0.1524)
				(type default)
			)
			(layer "F.SilkS")
		)
		(fp_line
			(start -0.7874 -0.4064)
			(end 0.7874 -0.4064)
			(stroke
				(width 0.1524)
				(type default)
			)
			(layer "F.SilkS")
		)
		(fp_line
			(start 0.7874 0.4064)
			(end -0.7874 0.4064)
			(stroke
				(width 0.1524)
				(type default)
			)
			(layer "F.SilkS")
		)
		(fp_line
			(start -0.7874 0.4064)
			(end -0.7874 -0.4064)
			(stroke
				(width 0.1524)
				(type default)
			)
			(layer "F.SilkS")
		)
		(fp_poly
			(pts
				(xy -0.508 0.2794) (xy -0.508 0.2286) (xy -0.635 0.2286) (xy -0.635 -0.254) (xy -0.5334 -0.254)
				(xy -0.5334 -0.2794) (xy 0.5334 -0.2794) (xy 0.5334 -0.254) (xy 0.635 -0.254) (xy 0.635 0.254) (xy 0.5334 0.254)
				(xy 0.5334 0.2794)
			)
			(stroke
				(width 0)
				(type default)
			)
			(fill no)
			(layer "F.CrtYd")
		)
		(pad "1" smd rect
			(at 0.40005 0 90)
			(size 0.4572 0.508)
			(layers "F.Cu" "F.Mask" "F.Paste")
			(net "P3V3_NODE1")
		)
		(pad "2" smd rect
			(at -0.40005 0 90)
			(size 0.4572 0.508)
			(layers "F.Cu" "F.Mask" "F.Paste")
			(net "LAN1_AUX_PWR")
		)
	)
	(footprint ""
		(layer "F.Cu")
		(at 123.89358 -130.473196 -90)
		(property "Reference" ""
			(at 0 0 270)
			(layer "F.SilkS")
			(hide yes)
			(effects
				(font
					(size 1.27 1.27)
				)
			)
		)
		(property "Value" ""
			(at 0 0 270)
			(layer "F.Fab")
			(effects
				(font
					(size 1.27 1.27)
				)
			)
		)
		(duplicate_pad_numbers_are_jumpers no)
		(fp_poly
			(pts
				(arc
					(start 0 -1.4986)
					(mid 0 1.4986)
					(end 0 -1.4986)
				)
			)
			(stroke
				(width 0)
				(type default)
			)
			(fill no)
			(layer "F.CrtYd")
		)
		(pad "1" smd circle
			(at 0 0 270)
			(size 0.9906 0.9906)
			(layers "F.Cu" "F.Mask" "F.Paste")
			(net "Net_34")
		)
		(zone
			(layer "F.Cu")
			(hatch none 0.5)
			(connect_pads
				(clearance 0)
			)
			(min_thickness 0.25)
			(keepout
				(tracks not_allowed)
				(vias allowed)
				(pads allowed)
				(copperpour not_allowed)
				(footprints allowed)
			)
			(placement
				(enabled no)
				(sheetname "")
			)
			(fill
				(thermal_gap 0.5)
				(thermal_bridge_width 0.5)
				(island_removal_mode 0)
			)
			(polygon
				(pts
					(arc
						(start 125.51918 -130.473196)
						(mid 122.26798 -130.473196)
						(end 125.51918 -130.473196)
					)
				)
			)
		)
	)
	(footprint ""
		(layer "F.Cu")
		(at 8.1915 -97.303336 90)
		(property "Reference" "D29"
			(at 3.693668 0.060452 90)
			(unlocked yes)
			(layer "F.SilkS")
			(effects
				(font
					(size 0.7874 0.5842)
					(thickness 0.1524)
				)
				(justify left)
			)
		)
		(property "Value" ""
			(at 0 0 90)
			(layer "F.Fab")
			(effects
				(font
					(size 1.27 1.27)
				)
			)
		)
		(duplicate_pad_numbers_are_jumpers no)
		(fp_line
			(start 3.429 -1.397)
			(end -3.175 -1.397)
			(stroke
				(width 0.1524)
				(type default)
			)
			(layer "F.SilkS")
		)
		(fp_line
			(start 3.302 -1.397)
			(end 3.302 1.397)
			(stroke
				(width 0.1524)
				(type default)
			)
			(layer "F.SilkS")
		)
		(fp_line
			(start -3.175 -1.397)
			(end -3.175 1.397)
			(stroke
				(width 0.1524)
				(type default)
			)
			(layer "F.SilkS")
		)
		(fp_line
			(start 0.299974 -0.500126)
			(end 0.299974 0.500126)
			(stroke
				(width 0.1524)
				(type default)
			)
			(layer "F.SilkS")
		)
		(fp_line
			(start -0.299974 -0.500126)
			(end -0.299974 0.500126)
			(stroke
				(width 0.1524)
				(type default)
			)
			(layer "F.SilkS")
		)
		(fp_line
			(start 0.199898 0)
			(end -0.299974 -0.500126)
			(stroke
				(width 0.1524)
				(type default)
			)
			(layer "F.SilkS")
		)
		(fp_line
			(start -0.299974 0.500126)
			(end 0.199898 0)
			(stroke
				(width 0.1524)
				(type default)
			)
			(layer "F.SilkS")
		)
		(fp_line
			(start 3.429 1.397)
			(end 3.429 -1.397)
			(stroke
				(width 0.1524)
				(type default)
			)
			(layer "F.SilkS")
		)
		(fp_line
			(start 3.302 1.397)
			(end 3.299968 1.400048)
			(stroke
				(width 0.1524)
				(type default)
			)
			(layer "F.SilkS")
		)
		(fp_line
			(start 3.175 1.397)
			(end 3.175 -1.397)
			(stroke
				(width 0.1524)
				(type default)
			)
			(layer "F.SilkS")
		)
		(fp_line
			(start -3.175 1.397)
			(end 3.429 1.397)
			(stroke
				(width 0.1524)
				(type default)
			)
			(layer "F.SilkS")
		)
		(fp_poly
			(pts
				(xy -2.6416 1.397) (xy -2.6416 1.016) (xy -3.0226 1.016) (xy -3.0226 -1.016) (xy -2.667 -1.016)
				(xy -2.667 -1.397) (xy 2.667 -1.397) (xy 2.667 -1.016) (xy 3.0226 -1.016) (xy 3.0226 1.016) (xy 2.667 1.016)
				(xy 2.667 1.397)
			)
			(stroke
				(width 0)
				(type default)
			)
			(fill no)
			(layer "F.CrtYd")
		)
		(pad "1" smd rect
			(at -2.249932 0 270)
			(size 1.524 2.032)
			(layers "F.Cu" "F.Mask" "F.Paste")
			(net "P12V_DBG")
		)
		(pad "2" smd rect
			(at 2.249932 0 90)
			(size 1.524 2.032)
			(layers "F.Cu" "F.Mask" "F.Paste")
			(net "P12V_PDB")
		)
	)
	(footprint ""
		(layer "F.Cu")
		(at 132.95376 -117.514624 90)
		(property "Reference" "U1"
			(at 5.298948 -1.346708 0)
			(unlocked yes)
			(layer "F.SilkS")
			(effects
				(font
					(size 0.7874 0.5842)
					(thickness 0.1524)
				)
				(justify left)
			)
		)
		(property "Value" ""
			(at 0 0 90)
			(layer "F.Fab")
			(effects
				(font
					(size 1.27 1.27)
				)
			)
		)
		(duplicate_pad_numbers_are_jumpers no)
		(fp_line
			(start -0.188976 -4.2037)
			(end -0.188976 -5.0927)
			(stroke
				(width 0.1524)
				(type default)
			)
			(layer "F.SilkS")
		)
		(fp_line
			(start 1.804924 -4.191)
			(end 1.804924 -4.6482)
			(stroke
				(width 0.1524)
				(type default)
			)
			(layer "F.SilkS")
		)
		(fp_line
			(start -2.208276 -4.191)
			(end -2.208276 -4.6482)
			(stroke
				(width 0.1524)
				(type default)
			)
			(layer "F.SilkS")
		)
		(fp_line
			(start 3.549904 -3.549904)
			(end 3.549904 -2.853944)
			(stroke
				(width 0.1524)
				(type default)
			)
			(layer "F.SilkS")
		)
		(fp_line
			(start 2.848356 -3.549904)
			(end 3.549904 -3.549904)
			(stroke
				(width 0.1524)
				(type default)
			)
			(layer "F.SilkS")
		)
		(fp_line
			(start -2.866644 -3.549904)
			(end -3.041904 -3.549904)
			(stroke
				(width 0.1524)
				(type default)
			)
			(layer "F.SilkS")
		)
		(fp_line
			(start -3.041904 -3.549904)
			(end -3.549904 -3.041904)
			(stroke
				(width 0.1524)
				(type default)
			)
			(layer "F.SilkS")
		)
		(fp_line
			(start -3.549904 -3.041904)
			(end -3.549904 -2.879344)
			(stroke
				(width 0.1524)
				(type default)
			)
			(layer "F.SilkS")
		)
		(fp_line
			(start 5.078476 -1.8034)
			(end 4.189476 -1.8034)
			(stroke
				(width 0.1524)
				(type default)
			)
			(layer "F.SilkS")
		)
		(fp_line
			(start -4.164076 -1.016)
			(end -4.621276 -1.016)
			(stroke
				(width 0.1524)
				(type default)
			)
			(layer "F.SilkS")
		)
		(fp_line
			(start 4.646676 0.1778)
			(end 4.189476 0.1778)
			(stroke
				(width 0.1524)
				(type default)
			)
			(layer "F.SilkS")
		)
		(fp_line
			(start -4.164076 1.016)
			(end -5.053076 1.016)
			(stroke
				(width 0.1524)
				(type default)
			)
			(layer "F.SilkS")
		)
		(fp_line
			(start 5.053076 2.1844)
			(end 4.164076 2.1844)
			(stroke
				(width 0.1524)
				(type default)
			)
			(layer "F.SilkS")
		)
		(fp_line
			(start 3.549904 2.861056)
			(end 3.549904 3.549904)
			(stroke
				(width 0.1524)
				(type default)
			)
			(layer "F.SilkS")
		)
		(fp_line
			(start 3.549904 3.549904)
			(end 2.848356 3.549904)
			(stroke
				(width 0.1524)
				(type default)
			)
			(layer "F.SilkS")
		)
		(fp_line
			(start -2.841244 3.549904)
			(end -3.549904 3.549904)
			(stroke
				(width 0.1524)
				(type default)
			)
			(layer "F.SilkS")
		)
		(fp_line
			(start -3.549904 3.549904)
			(end -3.549904 2.835656)
			(stroke
				(width 0.1524)
				(type default)
			)
			(layer "F.SilkS")
		)
		(fp_line
			(start 1.398524 4.6482)
			(end 1.398524 4.191)
			(stroke
				(width 0.1524)
				(type default)
			)
			(layer "F.SilkS")
		)
		(fp_line
			(start -2.614676 4.6736)
			(end -2.614676 4.2164)
			(stroke
				(width 0.1524)
				(type default)
			)
			(layer "F.SilkS")
		)
		(fp_line
			(start -0.595376 5.0927)
			(end -0.595376 4.2037)
			(stroke
				(width 0.1524)
				(type default)
			)
			(layer "F.SilkS")
		)
		(fp_poly
			(pts
				(xy -3.579114 -3.265932) (xy -4.26085 -4.73964) (xy -5.069078 -3.931412)
			)
			(stroke
				(width 0)
				(type default)
			)
			(fill yes)
			(layer "F.SilkS")
		)
		(fp_poly
			(pts
				(xy -3.549904 3.549904) (xy -2.7432 3.549904) (xy -2.7432 4.064) (xy 2.7432 4.064) (xy 2.7432 3.549904)
				(xy 3.549904 3.549904) (xy 3.549904 2.7432) (xy 4.064 2.7432) (xy 4.064 -2.7432) (xy 3.549904 -2.7432)
				(xy 3.549904 -3.549904) (xy 2.7432 -3.549904) (xy 2.7432 -4.064) (xy -2.7432 -4.064) (xy -2.7432 -3.549904)
				(xy -3.549904 -3.549904) (xy -3.549904 -2.7432) (xy -4.064 -2.7432) (xy -4.064 2.7432) (xy -3.549904 2.7432)
			)
			(stroke
				(width 0)
				(type default)
			)
			(fill no)
			(layer "F.CrtYd")
		)
		(fp_line
			(start -0.188976 -4.2037)
			(end -0.188976 -5.0927)
			(stroke
				(width 0.1)
				(type default)
			)
			(layer "F.Fab")
		)
		(fp_line
			(start 1.804924 -4.191)
			(end 1.804924 -4.6482)
			(stroke
				(width 0.1)
				(type default)
			)
			(layer "F.Fab")
		)
		(fp_line
			(start -2.208276 -4.191)
			(end -2.208276 -4.6482)
			(stroke
				(width 0.1)
				(type default)
			)
			(layer "F.Fab")
		)
		(fp_line
			(start 3.549904 -3.549904)
			(end 3.549904 3.549904)
			(stroke
				(width 0.1)
				(type default)
			)
			(layer "F.Fab")
		)
		(fp_line
			(start -3.549904 -3.549904)
			(end 3.549904 -3.549904)
			(stroke
				(width 0.1)
				(type default)
			)
			(layer "F.Fab")
		)
		(fp_line
			(start 5.078476 -1.8034)
			(end 4.189476 -1.8034)
			(stroke
				(width 0.1)
				(type default)
			)
			(layer "F.Fab")
		)
		(fp_line
			(start -4.164076 -1.016)
			(end -4.621276 -1.016)
			(stroke
				(width 0.1)
				(type default)
			)
			(layer "F.Fab")
		)
		(fp_line
			(start 4.646676 0.1778)
			(end 4.189476 0.1778)
			(stroke
				(width 0.1)
				(type default)
			)
			(layer "F.Fab")
		)
		(fp_line
			(start -4.164076 1.016)
			(end -5.053076 1.016)
			(stroke
				(width 0.1)
				(type default)
			)
			(layer "F.Fab")
		)
		(fp_line
			(start 5.053076 2.1844)
			(end 4.164076 2.1844)
			(stroke
				(width 0.1)
				(type default)
			)
			(layer "F.Fab")
		)
		(fp_line
			(start 3.549904 3.549904)
			(end -3.549904 3.549904)
			(stroke
				(width 0.1)
				(type default)
			)
			(layer "F.Fab")
		)
		(fp_line
			(start -3.549904 3.549904)
			(end -3.549904 -3.549904)
			(stroke
				(width 0.1)
				(type default)
			)
			(layer "F.Fab")
		)
		(fp_line
			(start 1.398524 4.6482)
			(end 1.398524 4.191)
			(stroke
				(width 0.1)
				(type default)
			)
			(layer "F.Fab")
		)
		(fp_line
			(start -2.614676 4.6736)
			(end -2.614676 4.2164)
			(stroke
				(width 0.1)
				(type default)
			)
			(layer "F.Fab")
		)
		(fp_line
			(start -0.595376 5.0927)
			(end -0.595376 4.2037)
			(stroke
				(width 0.1)
				(type default)
			)
			(layer "F.Fab")
		)
		(fp_poly
			(pts
				(xy -4.2164 -2.599944) (xy -5.7404 -3.160014) (xy -5.7404 -2.017014)
			)
			(stroke
				(width 0)
				(type default)
			)
			(fill yes)
			(layer "F.Fab")
		)
		(fp_text user "56"
			(at -2.900426 -4.033266 0)
			(unlocked yes)
			(layer "F.SilkS")
			(effects
				(font
					(size 0.635 0.4064)
					(thickness 0.1524)
				)
				(justify right)
			)
		)
		(fp_text user "43"
			(at 3.124708 -3.701796 0)
			(unlocked yes)
			(layer "F.SilkS")
			(effects
				(font
					(size 0.635 0.4064)
					(thickness 0.1524)
				)
				(justify right)
			)
		)
		(fp_text user "1"
			(at -4.144264 -2.817368 0)
			(unlocked yes)
			(layer "F.SilkS")
			(effects
				(font
					(size 0.635 0.4064)
					(thickness 0.1524)
				)
				(justify right)
			)
		)
		(fp_text user "42"
			(at 4.156456 -2.789682 0)
			(unlocked yes)
			(layer "F.SilkS")
			(effects
				(font
					(size 0.635 0.4064)
					(thickness 0.1524)
				)
				(justify right)
			)
		)
		(fp_text user "29"
			(at 4.285742 3.78841 0)
			(unlocked yes)
			(layer "F.SilkS")
			(effects
				(font
					(size 0.635 0.4064)
					(thickness 0.1524)
				)
				(justify right)
			)
		)
		(fp_text user "14"
			(at -4.254754 3.908298 0)
			(unlocked yes)
			(layer "F.SilkS")
			(effects
				(font
					(size 0.635 0.4064)
					(thickness 0.1524)
				)
				(justify right)
			)
		)
		(fp_text user "28"
			(at 3.299968 4.69138 0)
			(unlocked yes)
			(layer "F.SilkS")
			(effects
				(font
					(size 0.635 0.4064)
					(thickness 0.1524)
				)
				(justify right)
			)
		)
		(fp_text user "15"
			(at -3.314954 4.700524 0)
			(unlocked yes)
			(layer "F.SilkS")
			(effects
				(font
					(size 0.635 0.4064)
					(thickness 0.1524)
				)
				(justify right)
			)
		)
		(fp_text user "43"
			(at 3.7846 -4.112768 90)
			(unlocked yes)
			(layer "F.Fab")
			(effects
				(font
					(size 0.635 0.4064)
					(thickness 0.000001)
				)
				(justify right)
			)
		)
		(fp_text user "56"
			(at -2.8448 -4.061968 90)
			(unlocked yes)
			(layer "F.Fab")
			(effects
				(font
					(size 0.635 0.4064)
					(thickness 0.000001)
				)
				(justify right)
			)
		)
		(fp_text user "42"
			(at 4.696714 -3.274568 90)
			(unlocked yes)
			(layer "F.Fab")
			(effects
				(font
					(size 0.635 0.4064)
					(thickness 0.000001)
				)
				(justify right)
			)
		)
		(fp_text user "1"
			(at -3.7973 -3.249168 90)
			(unlocked yes)
			(layer "F.Fab")
			(effects
				(font
					(size 0.635 0.4064)
					(thickness 0.000001)
				)
				(justify right)
			)
		)
		(fp_text user "29"
			(at 4.7498 3.227832 90)
			(unlocked yes)
			(layer "F.Fab")
			(effects
				(font
					(size 0.635 0.4064)
					(thickness 0.000001)
				)
				(justify right)
			)
		)
		(fp_text user "14"
			(at -3.8608 3.304032 90)
			(unlocked yes)
			(layer "F.Fab")
			(effects
				(font
					(size 0.635 0.4064)
					(thickness 0.000001)
				)
				(justify right)
			)
		)
		(fp_text user "28"
			(at 3.81 4.142232 90)
			(unlocked yes)
			(layer "F.Fab")
			(effects
				(font
					(size 0.635 0.4064)
					(thickness 0.000001)
				)
				(justify right)
			)
		)
		(fp_text user "15"
			(at -3.048 4.167632 90)
			(unlocked yes)
			(layer "F.Fab")
			(effects
				(font
					(size 0.635 0.4064)
					(thickness 0.000001)
				)
				(justify right)
			)
		)
		(pad "1" smd rect
			(at -3.549904 -2.599944)
			(size 0.1778 0.889)
			(layers "F.Cu" "F.Mask" "F.Paste")
			(net "XTAL_CLK_NODE1_X2")
		)
		(pad "2" smd rect
			(at -3.549904 -2.199894)
			(size 0.1778 0.889)
			(layers "F.Cu" "F.Mask" "F.Paste")
			(net "XTAL_CLK_NODE1_X1")
		)
		(pad "3" smd rect
			(at -3.549904 -1.800098)
			(size 0.1778 0.889)
			(layers "F.Cu" "F.Mask" "F.Paste")
			(net "P3V3_CLK_NODE1")
		)
		(pad "4" smd rect
			(at -3.549904 -1.400048)
			(size 0.1778 0.889)
			(layers "F.Cu" "F.Mask" "F.Paste")
			(net "CLK_25M_SATA_NODE1_R")
		)
		(pad "5" smd rect
			(at -3.549904 -0.999998)
			(size 0.1778 0.889)
			(layers "F.Cu" "F.Mask" "F.Paste")
			(net "SMB_MUX_CPU_ICS_NODE1_DAT")
		)
		(pad "6" smd rect
			(at -3.549904 -0.599948)
			(size 0.1778 0.889)
			(layers "F.Cu" "F.Mask" "F.Paste")
			(net "SMB_MUX_CPU_ICS_NODE1_CLK")
		)
		(pad "7" smd rect
			(at -3.549904 -0.199898)
			(size 0.1778 0.889)
			(layers "F.Cu" "F.Mask" "F.Paste")
			(net "P3V3_CLK_NODE1")
		)
		(pad "8" smd rect
			(at -3.549904 0.199898)
			(size 0.1778 0.889)
			(layers "F.Cu" "F.Mask" "F.Paste")
			(net "CLP_ITP_EN_NODE1")
		)
		(pad "9" smd rect
			(at -3.549904 0.599948)
			(size 0.1778 0.889)
			(layers "F.Cu" "F.Mask" "F.Paste")
			(net "CLK_FSLB_NODE1")
		)
		(pad "10" smd rect
			(at -3.549904 0.999998)
			(size 0.1778 0.889)
			(layers "F.Cu" "F.Mask" "F.Paste")
			(net "CLKREQA_NODE1_N")
		)
		(pad "11" smd rect
			(at -3.549904 1.400048)
			(size 0.1778 0.889)
			(layers "F.Cu" "F.Mask" "F.Paste")
			(net "GND")
		)
		(pad "12" smd rect
			(at -3.549904 1.800098)
			(size 0.1778 0.889)
			(layers "F.Cu" "F.Mask" "F.Paste")
			(net "GND")
		)
		(pad "13" smd rect
			(at -3.549904 2.199894)
			(size 0.1778 0.889)
			(layers "F.Cu" "F.Mask" "F.Paste")
			(net "CLK_14M_CPU_NODE1_R")
		)
		(pad "14" smd rect
			(at -3.549904 2.599944)
			(size 0.1778 0.889)
			(layers "F.Cu" "F.Mask" "F.Paste")
			(net "P3V3_CLK_NODE1")
		)
		(pad "15" smd rect
			(at -2.599944 3.549904 90)
			(size 0.1778 0.889)
			(layers "F.Cu" "F.Mask" "F.Paste")
			(net "P3V3_CLK_NODE1")
		)
		(pad "16" smd rect
			(at -2.199894 3.549904 90)
			(size 0.1778 0.889)
			(layers "F.Cu" "F.Mask" "F.Paste")
			(net "SEL_DOT_SRC5")
		)
		(pad "17" smd rect
			(at -1.800098 3.549904 90)
			(size 0.1778 0.889)
			(layers "F.Cu" "F.Mask" "F.Paste")
			(net "CLKREQC_NODE1_N")
		)
		(pad "18" smd rect
			(at -1.400048 3.549904 90)
			(size 0.1778 0.889)
			(layers "F.Cu" "F.Mask" "F.Paste")
			(net "GND")
		)
		(pad "19" smd rect
			(at -0.999998 3.549904 90)
			(size 0.1778 0.889)
			(layers "F.Cu" "F.Mask" "F.Paste")
			(net "CLKREQB_NODE1_N")
		)
		(pad "20" smd rect
			(at -0.599948 3.549904 90)
			(size 0.1778 0.889)
			(layers "F.Cu" "F.Mask" "F.Paste")
			(net "P3V3_CLK_NODE1")
		)
		(pad "21" smd rect
			(at -0.199898 3.549904 90)
			(size 0.1778 0.889)
			(layers "F.Cu" "F.Mask" "F.Paste")
			(net "SEL_PCI_27M")
		)
		(pad "22" smd rect
			(at 0.199898 3.549904 90)
			(size 0.1778 0.889)
			(layers "F.Cu" "F.Mask" "F.Paste")
			(net "GND")
		)
		(pad "23" smd rect
			(at 0.599948 3.549904 90)
			(size 0.1778 0.889)
			(layers "F.Cu" "F.Mask" "F.Paste")
			(net "CLK_100M_PCIE_SW_NODE1_DP")
		)
		(pad "24" smd rect
			(at 0.999998 3.549904 90)
			(size 0.1778 0.889)
			(layers "F.Cu" "F.Mask" "F.Paste")
			(net "CLK_100M_PCIE_SW_NODE1_DN")
		)
		(pad "25" smd rect
			(at 1.400048 3.549904 90)
			(size 0.1778 0.889)
			(layers "F.Cu" "F.Mask" "F.Paste")
			(net "P1V5_CLK_NODE1")
		)
		(pad "26" smd rect
			(at 1.800098 3.549904 90)
			(size 0.1778 0.889)
			(layers "F.Cu" "F.Mask" "F.Paste")
			(net "Net_1702")
		)
		(pad "27" smd rect
			(at 2.199894 3.549904 90)
			(size 0.1778 0.889)
			(layers "F.Cu" "F.Mask" "F.Paste")
			(net "Net_1701")
		)
		(pad "28" smd rect
			(at 2.599944 3.549904 90)
			(size 0.1778 0.889)
			(layers "F.Cu" "F.Mask" "F.Paste")
			(net "GND")
		)
		(pad "29" smd rect
			(at 3.549904 2.599944)
			(size 0.1778 0.889)
			(layers "F.Cu" "F.Mask" "F.Paste")
			(net "GND")
		)
		(pad "30" smd rect
			(at 3.549904 2.199894)
			(size 0.1778 0.889)
			(layers "F.Cu" "F.Mask" "F.Paste")
			(net "CLK_100M_SATA_NODE1_DN")
		)
		(pad "31" smd rect
			(at 3.549904 1.800098)
			(size 0.1778 0.889)
			(layers "F.Cu" "F.Mask" "F.Paste")
			(net "CLK_100M_SATA_NODE1_DP")
		)
		(pad "32" smd rect
			(at 3.549904 1.400048)
			(size 0.1778 0.889)
			(layers "F.Cu" "F.Mask" "F.Paste")
			(net "CLK_100M_NIC2_NODE1_DN")
		)
		(pad "33" smd rect
			(at 3.549904 0.999998)
			(size 0.1778 0.889)
			(layers "F.Cu" "F.Mask" "F.Paste")
			(net "CLK_100M_NIC2_NODE1_DP")
		)
		(pad "34" smd rect
			(at 3.549904 0.599948)
			(size 0.1778 0.889)
			(layers "F.Cu" "F.Mask" "F.Paste")
			(net "P1V05_CLK_NODE1")
		)
		(pad "35" smd rect
			(at 3.549904 0.199898)
			(size 0.1778 0.889)
			(layers "F.Cu" "F.Mask" "F.Paste")
			(net "PCI_STP_NODE1")
		)
		(pad "36" smd rect
			(at 3.549904 -0.199898)
			(size 0.1778 0.889)
			(layers "F.Cu" "F.Mask" "F.Paste")
			(net "CLK_100M_NIC1_NODE1_DN")
		)
		(pad "37" smd rect
			(at 3.549904 -0.599948)
			(size 0.1778 0.889)
			(layers "F.Cu" "F.Mask" "F.Paste")
			(net "CLK_100M_NIC1_NODE1_DP")
		)
		(pad "38" smd rect
			(at 3.549904 -0.999998)
			(size 0.1778 0.889)
			(layers "F.Cu" "F.Mask" "F.Paste")
			(net "CLK_100M_USB_NODE1_DN")
		)
		(pad "39" smd rect
			(at 3.549904 -1.400048)
			(size 0.1778 0.889)
			(layers "F.Cu" "F.Mask" "F.Paste")
			(net "CLK_100M_USB_NODE1_DP")
		)
		(pad "40" smd rect
			(at 3.549904 -1.800098)
			(size 0.1778 0.889)
			(layers "F.Cu" "F.Mask" "F.Paste")
			(net "GND")
		)
		(pad "41" smd rect
			(at 3.549904 -2.199894)
			(size 0.1778 0.889)
			(layers "F.Cu" "F.Mask" "F.Paste")
			(net "CLK_100M_PCIE_RP0_NODE1_DN")
		)
		(pad "42" smd rect
			(at 3.549904 -2.599944)
			(size 0.1778 0.889)
			(layers "F.Cu" "F.Mask" "F.Paste")
			(net "CLK_100M_PCIE_RP0_NODE1_DP")
		)
		(pad "43" smd rect
			(at 2.599944 -3.549904 90)
			(size 0.1778 0.889)
			(layers "F.Cu" "F.Mask" "F.Paste")
			(net "CLK_100M_BMC_NODE1_DN")
		)
		(pad "44" smd rect
			(at 2.199894 -3.549904 90)
			(size 0.1778 0.889)
			(layers "F.Cu" "F.Mask" "F.Paste")
			(net "CLK_100M_BMC_NODE1_DP")
		)
		(pad "45" smd rect
			(at 1.800098 -3.549904 90)
			(size 0.1778 0.889)
			(layers "F.Cu" "F.Mask" "F.Paste")
			(net "CPU_STP_NODE1")
		)
		(pad "46" smd rect
			(at 1.400048 -3.549904 90)
			(size 0.1778 0.889)
			(layers "F.Cu" "F.Mask" "F.Paste")
			(net "CLK_100M_XDP_NODE1_DN")
		)
		(pad "47" smd rect
			(at 0.999998 -3.549904 90)
			(size 0.1778 0.889)
			(layers "F.Cu" "F.Mask" "F.Paste")
			(net "CLK_100M_XDP_NODE1_DP")
		)
		(pad "48" smd rect
			(at 0.599948 -3.549904 90)
			(size 0.1778 0.889)
			(layers "F.Cu" "F.Mask" "F.Paste")
			(net "P1V5_CLK_NODE1")
		)
		(pad "49" smd rect
			(at 0.199898 -3.549904 90)
			(size 0.1778 0.889)
			(layers "F.Cu" "F.Mask" "F.Paste")
			(net "P1V05_CLK_NODE1")
		)
		(pad "50" smd rect
			(at -0.199898 -3.549904 90)
			(size 0.1778 0.889)
			(layers "F.Cu" "F.Mask" "F.Paste")
			(net "CLK_100M_CPU_NODE1_DN")
		)
		(pad "51" smd rect
			(at -0.599948 -3.549904 90)
			(size 0.1778 0.889)
			(layers "F.Cu" "F.Mask" "F.Paste")
			(net "CLK_100M_CPU_NODE1_DP")
		)
		(pad "52" smd rect
			(at -0.999998 -3.549904 90)
			(size 0.1778 0.889)
			(layers "F.Cu" "F.Mask" "F.Paste")
			(net "GND")
		)
		(pad "53" smd rect
			(at -1.400048 -3.549904 90)
			(size 0.1778 0.889)
			(layers "F.Cu" "F.Mask" "F.Paste")
			(net "CLK_100M_DDR3_NODE1_DN")
		)
		(pad "54" smd rect
			(at -1.800098 -3.549904 90)
			(size 0.1778 0.889)
			(layers "F.Cu" "F.Mask" "F.Paste")
			(net "CLK_100M_DDR3_NODE1_DP")
		)
		(pad "55" smd rect
			(at -2.199894 -3.549904 90)
			(size 0.1778 0.889)
			(layers "F.Cu" "F.Mask" "F.Paste")
			(net "FM_CPLD_CLK_R_PG_NODE1_R")
		)
		(pad "56" smd rect
			(at -2.599944 -3.549904 90)
			(size 0.1778 0.889)
			(layers "F.Cu" "F.Mask" "F.Paste")
			(net "GND")
		)
		(pad "TH" smd rect
			(at 0 0 90)
			(size 5.7912 5.7912)
			(layers "F.Cu" "F.Mask" "F.Paste")
			(net "GND")
		)
		(zone
			(layer "F.Cu")
			(hatch none 0.5)
			(connect_pads
				(clearance 0)
			)
			(min_thickness 0.25)
			(keepout
				(tracks allowed)
				(vias not_allowed)
				(pads allowed)
				(copperpour not_allowed)
				(footprints allowed)
			)
			(placement
				(enabled no)
				(sheetname "")
			)
			(fill
				(thermal_gap 0.5)
				(thermal_bridge_width 0.5)
				(island_removal_mode 0)
			)
			(polygon
				(pts
					(xy 130.28676 -114.492024) (xy 130.28676 -114.542824) (xy 130.00736 -114.542824) (xy 129.98196 -114.542824)
					(xy 129.98196 -120.461024) (xy 129.98196 -120.486424) (xy 135.92556 -120.486424) (xy 135.92556 -114.542824)
					(xy 130.31216 -114.542824) (xy 130.31216 -114.492024) (xy 130.31216 -114.466624) (xy 136.00176 -114.466624)
					(xy 136.00176 -114.492024) (xy 136.00176 -120.562624) (xy 135.97636 -120.562624) (xy 129.90576 -120.562624)
					(xy 129.90576 -120.537224) (xy 129.90576 -114.466624) (xy 129.93116 -114.466624) (xy 130.28676 -114.466624)
				)
			)
		)
		(zone
			(layer "F.Cu")
			(hatch none 0.5)
			(connect_pads
				(clearance 0)
			)
			(min_thickness 0.25)
			(keepout
				(tracks not_allowed)
				(vias allowed)
				(pads allowed)
				(copperpour not_allowed)
				(footprints allowed)
			)
			(placement
				(enabled no)
				(sheetname "")
			)
			(fill
				(thermal_gap 0.5)
				(thermal_bridge_width 0.5)
				(island_removal_mode 0)
			)
			(polygon
				(pts
					(xy 130.28676 -114.492024) (xy 130.28676 -114.542824) (xy 130.00736 -114.542824) (xy 129.98196 -114.542824)
					(xy 129.98196 -120.461024) (xy 129.98196 -120.486424) (xy 135.92556 -120.486424) (xy 135.92556 -114.542824)
					(xy 130.31216 -114.542824) (xy 130.31216 -114.492024) (xy 130.31216 -114.466624) (xy 136.00176 -114.466624)
					(xy 136.00176 -114.492024) (xy 136.00176 -120.562624) (xy 135.97636 -120.562624) (xy 129.90576 -120.562624)
					(xy 129.90576 -120.537224) (xy 129.90576 -114.466624) (xy 129.93116 -114.466624) (xy 130.28676 -114.466624)
				)
			)
		)
	)
	(footprint ""
		(layer "F.Cu")
		(at 89.13876 -188.126624 -90)
		(property "Reference" "R945"
			(at -4.548886 1.939798 90)
			(unlocked yes)
			(layer "F.SilkS")
			(effects
				(font
					(size 0.7874 0.5842)
					(thickness 0.1524)
				)
				(justify left)
			)
		)
		(property "Value" ""
			(at 0 0 270)
			(layer "F.Fab")
			(effects
				(font
					(size 1.27 1.27)
				)
			)
		)
		(duplicate_pad_numbers_are_jumpers no)
		(fp_line
			(start -0.7874 0.4064)
			(end -0.7874 -0.4064)
			(stroke
				(width 0.1524)
				(type default)
			)
			(layer "F.SilkS")
		)
		(fp_line
			(start 0.7874 0.4064)
			(end -0.7874 0.4064)
			(stroke
				(width 0.1524)
				(type default)
			)
			(layer "F.SilkS")
		)
		(fp_line
			(start -0.7874 -0.4064)
			(end 0.7874 -0.4064)
			(stroke
				(width 0.1524)
				(type default)
			)
			(layer "F.SilkS")
		)
		(fp_line
			(start 0.7874 -0.4064)
			(end 0.7874 0.4064)
			(stroke
				(width 0.1524)
				(type default)
			)
			(layer "F.SilkS")
		)
		(fp_poly
			(pts
				(xy -0.508 0.2794) (xy -0.508 0.2286) (xy -0.635 0.2286) (xy -0.635 -0.254) (xy -0.5334 -0.254)
				(xy -0.5334 -0.2794) (xy 0.5334 -0.2794) (xy 0.5334 -0.254) (xy 0.635 -0.254) (xy 0.635 0.254) (xy 0.5334 0.254)
				(xy 0.5334 0.2794)
			)
			(stroke
				(width 0)
				(type default)
			)
			(fill no)
			(layer "F.CrtYd")
		)
		(pad "1" smd rect
			(at 0.40005 0 270)
			(size 0.4572 0.508)
			(layers "F.Cu" "F.Mask" "F.Paste")
			(net "UART_T6_NODE3_RXD")
		)
		(pad "2" smd rect
			(at -0.40005 0 270)
			(size 0.4572 0.508)
			(layers "F.Cu" "F.Mask" "F.Paste")
			(net "UART_T6_NODE3_RXD_R")
		)
	)
	(footprint ""
		(layer "F.Cu")
		(at 165.811454 -166.388288 180)
		(property "Reference" "R583"
			(at -1.22936 -0.590296 0)
			(unlocked yes)
			(layer "F.SilkS")
			(effects
				(font
					(size 0.7874 0.5842)
					(thickness 0.1524)
				)
				(justify left)
			)
		)
		(property "Value" ""
			(at 0 0 180)
			(layer "F.Fab")
			(effects
				(font
					(size 1.27 1.27)
				)
			)
		)
		(duplicate_pad_numbers_are_jumpers no)
		(fp_line
			(start 0.7874 0.4064)
			(end -0.7874 0.4064)
			(stroke
				(width 0.1524)
				(type default)
			)
			(layer "F.SilkS")
		)
		(fp_line
			(start 0.7874 -0.4064)
			(end 0.7874 0.4064)
			(stroke
				(width 0.1524)
				(type default)
			)
			(layer "F.SilkS")
		)
		(fp_line
			(start -0.7874 0.4064)
			(end -0.7874 -0.4064)
			(stroke
				(width 0.1524)
				(type default)
			)
			(layer "F.SilkS")
		)
		(fp_line
			(start -0.7874 -0.4064)
			(end 0.7874 -0.4064)
			(stroke
				(width 0.1524)
				(type default)
			)
			(layer "F.SilkS")
		)
		(fp_poly
			(pts
				(xy -0.508 0.2794) (xy -0.508 0.2286) (xy -0.635 0.2286) (xy -0.635 -0.254) (xy -0.5334 -0.254)
				(xy -0.5334 -0.2794) (xy 0.5334 -0.2794) (xy 0.5334 -0.254) (xy 0.635 -0.254) (xy 0.635 0.254) (xy 0.5334 0.254)
				(xy 0.5334 0.2794)
			)
			(stroke
				(width 0)
				(type default)
			)
			(fill no)
			(layer "F.CrtYd")
		)
		(pad "1" smd rect
			(at 0.40005 0 180)
			(size 0.4572 0.508)
			(layers "F.Cu" "F.Mask" "F.Paste")
			(net "LAN2_NVM_HOLD_N")
		)
		(pad "2" smd rect
			(at -0.40005 0 180)
			(size 0.4572 0.508)
			(layers "F.Cu" "F.Mask" "F.Paste")
			(net "P3V3_NODE1")
		)
	)
	(footprint ""
		(layer "F.Cu")
		(at 91.102434 -186.826398)
		(property "Reference" "C684"
			(at -1.437894 -7.307072 0)
			(unlocked yes)
			(layer "F.SilkS")
			(effects
				(font
					(size 0.7874 0.5842)
					(thickness 0.1524)
				)
				(justify left)
			)
		)
		(property "Value" ""
			(at 0 0 0)
			(layer "F.Fab")
			(effects
				(font
					(size 1.27 1.27)
				)
			)
		)
		(duplicate_pad_numbers_are_jumpers no)
		(fp_line
			(start -0.7874 -0.4064)
			(end 0.7874 -0.4064)
			(stroke
				(width 0.1524)
				(type default)
			)
			(layer "F.SilkS")
		)
		(fp_line
			(start -0.7874 0.4064)
			(end -0.7874 -0.4064)
			(stroke
				(width 0.1524)
				(type default)
			)
			(layer "F.SilkS")
		)
		(fp_line
			(start 0 0.381)
			(end 0 -0.381)
			(stroke
				(width 0.1524)
				(type default)
			)
			(layer "F.SilkS")
		)
		(fp_line
			(start 0.7874 -0.4064)
			(end 0.7874 0.4064)
			(stroke
				(width 0.1524)
				(type default)
			)
			(layer "F.SilkS")
		)
		(fp_line
			(start 0.7874 0.4064)
			(end -0.7874 0.4064)
			(stroke
				(width 0.1524)
				(type default)
			)
			(layer "F.SilkS")
		)
		(fp_poly
			(pts
				(xy -0.5334 0.254) (xy -0.635 0.254) (xy -0.635 0.2286) (xy -0.635 -0.254) (xy -0.5334 -0.254) (xy -0.5334 -0.2794)
				(xy 0.5334 -0.2794) (xy 0.5334 -0.254) (xy 0.635 -0.254) (xy 0.635 0.254) (xy 0.5334 0.254) (xy 0.5334 0.2794)
				(xy -0.508 0.2794) (xy -0.5334 0.2794)
			)
			(stroke
				(width 0)
				(type default)
			)
			(fill no)
			(layer "F.CrtYd")
		)
		(pad "1" smd rect
			(at 0.40005 0)
			(size 0.4572 0.508)
			(layers "F.Cu" "F.Mask" "F.Paste")
			(net "UART_T5_NODE3_RXD")
		)
		(pad "2" smd rect
			(at -0.40005 0)
			(size 0.4572 0.508)
			(layers "F.Cu" "F.Mask" "F.Paste")
			(net "GND")
		)
	)
	(footprint ""
		(layer "F.Cu")
		(at 165.951408 -72.836532 90)
		(property "Reference" "R1105"
			(at -0.804672 4.841494 90)
			(unlocked yes)
			(layer "F.SilkS")
			(effects
				(font
					(size 0.7874 0.5842)
					(thickness 0.1524)
				)
				(justify left)
			)
		)
		(property "Value" ""
			(at 0 0 90)
			(layer "F.Fab")
			(effects
				(font
					(size 1.27 1.27)
				)
			)
		)
		(duplicate_pad_numbers_are_jumpers no)
		(fp_line
			(start 0.7874 -0.4064)
			(end 0.7874 0.4064)
			(stroke
				(width 0.1524)
				(type default)
			)
			(layer "F.SilkS")
		)
		(fp_line
			(start -0.7874 -0.4064)
			(end 0.7874 -0.4064)
			(stroke
				(width 0.1524)
				(type default)
			)
			(layer "F.SilkS")
		)
		(fp_line
			(start 0.7874 0.4064)
			(end -0.7874 0.4064)
			(stroke
				(width 0.1524)
				(type default)
			)
			(layer "F.SilkS")
		)
		(fp_line
			(start -0.7874 0.4064)
			(end -0.7874 -0.4064)
			(stroke
				(width 0.1524)
				(type default)
			)
			(layer "F.SilkS")
		)
		(fp_poly
			(pts
				(xy -0.508 0.2794) (xy -0.508 0.2286) (xy -0.635 0.2286) (xy -0.635 -0.254) (xy -0.5334 -0.254)
				(xy -0.5334 -0.2794) (xy 0.5334 -0.2794) (xy 0.5334 -0.254) (xy 0.635 -0.254) (xy 0.635 0.254) (xy 0.5334 0.254)
				(xy 0.5334 0.2794)
			)
			(stroke
				(width 0)
				(type default)
			)
			(fill no)
			(layer "F.CrtYd")
		)
		(pad "1" smd rect
			(at 0.40005 0 90)
			(size 0.4572 0.508)
			(layers "F.Cu" "F.Mask" "F.Paste")
			(net "GND")
		)
		(pad "2" smd rect
			(at -0.40005 0 90)
			(size 0.4572 0.508)
			(layers "F.Cu" "F.Mask" "F.Paste")
			(net "N47241340")
		)
	)
	(footprint ""
		(layer "F.Cu")
		(at 100.35032 -15.98549 90)
		(property "Reference" "R193"
			(at -1.79451 -0.909574 90)
			(unlocked yes)
			(layer "F.SilkS")
			(effects
				(font
					(size 0.7874 0.5842)
					(thickness 0.1524)
				)
				(justify left)
			)
		)
		(property "Value" ""
			(at 0 0 90)
			(layer "F.Fab")
			(effects
				(font
					(size 1.27 1.27)
				)
			)
		)
		(duplicate_pad_numbers_are_jumpers no)
		(fp_line
			(start 0.7874 -0.4064)
			(end 0.7874 0.4064)
			(stroke
				(width 0.1524)
				(type default)
			)
			(layer "F.SilkS")
		)
		(fp_line
			(start -0.7874 -0.4064)
			(end 0.7874 -0.4064)
			(stroke
				(width 0.1524)
				(type default)
			)
			(layer "F.SilkS")
		)
		(fp_line
			(start 0.7874 0.4064)
			(end -0.7874 0.4064)
			(stroke
				(width 0.1524)
				(type default)
			)
			(layer "F.SilkS")
		)
		(fp_line
			(start -0.7874 0.4064)
			(end -0.7874 -0.4064)
			(stroke
				(width 0.1524)
				(type default)
			)
			(layer "F.SilkS")
		)
		(fp_poly
			(pts
				(xy -0.508 0.2794) (xy -0.508 0.2286) (xy -0.635 0.2286) (xy -0.635 -0.254) (xy -0.5334 -0.254)
				(xy -0.5334 -0.2794) (xy 0.5334 -0.2794) (xy 0.5334 -0.254) (xy 0.635 -0.254) (xy 0.635 0.254) (xy 0.5334 0.254)
				(xy 0.5334 0.2794)
			)
			(stroke
				(width 0)
				(type default)
			)
			(fill no)
			(layer "F.CrtYd")
		)
		(pad "1" smd rect
			(at 0.40005 0 90)
			(size 0.4572 0.508)
			(layers "F.Cu" "F.Mask" "F.Paste")
			(net "LPC_CPU_NODE1_CLKOUT0")
		)
		(pad "2" smd rect
			(at -0.40005 0 90)
			(size 0.4572 0.508)
			(layers "F.Cu" "F.Mask" "F.Paste")
			(net "N20512395")
		)
	)
	(footprint ""
		(layer "F.Cu")
		(at 159.62376 -188.126624 90)
		(property "Reference" "C588"
			(at 5.519674 -3.78333 90)
			(unlocked yes)
			(layer "F.SilkS")
			(effects
				(font
					(size 0.7874 0.5842)
					(thickness 0.1524)
				)
				(justify left)
			)
		)
		(property "Value" ""
			(at 0 0 90)
			(layer "F.Fab")
			(effects
				(font
					(size 1.27 1.27)
				)
			)
		)
		(duplicate_pad_numbers_are_jumpers no)
		(fp_line
			(start 0.7874 -0.4064)
			(end 0.7874 0.4064)
			(stroke
				(width 0.1524)
				(type default)
			)
			(layer "F.SilkS")
		)
		(fp_line
			(start -0.7874 -0.4064)
			(end 0.7874 -0.4064)
			(stroke
				(width 0.1524)
				(type default)
			)
			(layer "F.SilkS")
		)
		(fp_line
			(start 0 0.381)
			(end 0 -0.381)
			(stroke
				(width 0.1524)
				(type default)
			)
			(layer "F.SilkS")
		)
		(fp_line
			(start 0.7874 0.4064)
			(end -0.7874 0.4064)
			(stroke
				(width 0.1524)
				(type default)
			)
			(layer "F.SilkS")
		)
		(fp_line
			(start -0.7874 0.4064)
			(end -0.7874 -0.4064)
			(stroke
				(width 0.1524)
				(type default)
			)
			(layer "F.SilkS")
		)
		(fp_poly
			(pts
				(xy -0.5334 0.254) (xy -0.635 0.254) (xy -0.635 0.2286) (xy -0.635 -0.254) (xy -0.5334 -0.254) (xy -0.5334 -0.2794)
				(xy 0.5334 -0.2794) (xy 0.5334 -0.254) (xy 0.635 -0.254) (xy 0.635 0.254) (xy 0.5334 0.254) (xy 0.5334 0.2794)
				(xy -0.508 0.2794) (xy -0.5334 0.2794)
			)
			(stroke
				(width 0)
				(type default)
			)
			(fill no)
			(layer "F.CrtYd")
		)
		(pad "1" smd rect
			(at 0.40005 0 90)
			(size 0.4572 0.508)
			(layers "F.Cu" "F.Mask" "F.Paste")
			(net "FAN_PWM_R")
		)
		(pad "2" smd rect
			(at -0.40005 0 90)
			(size 0.4572 0.508)
			(layers "F.Cu" "F.Mask" "F.Paste")
			(net "GND")
		)
	)
	(footprint ""
		(layer "F.Cu")
		(at 20.915376 -46.219618 90)
		(property "Reference" "U47"
			(at -1.723136 3.181604 0)
			(unlocked yes)
			(layer "F.SilkS")
			(effects
				(font
					(size 0.7874 0.5842)
					(thickness 0.1524)
				)
			)
		)
		(property "Value" ""
			(at 0 0 90)
			(layer "F.Fab")
			(effects
				(font
					(size 1.27 1.27)
				)
			)
		)
		(duplicate_pad_numbers_are_jumpers no)
		(fp_line
			(start 1.651 -1.905)
			(end 1.651 1.905)
			(stroke
				(width 0.1524)
				(type default)
			)
			(layer "F.SilkS")
		)
		(fp_line
			(start -1.651 -1.905)
			(end 1.651 -1.905)
			(stroke
				(width 0.1524)
				(type default)
			)
			(layer "F.SilkS")
		)
		(fp_line
			(start 1.651 1.905)
			(end -1.651 1.905)
			(stroke
				(width 0.1524)
				(type default)
			)
			(layer "F.SilkS")
		)
		(fp_line
			(start -1.651 1.905)
			(end -1.651 -1.905)
			(stroke
				(width 0.1524)
				(type default)
			)
			(layer "F.SilkS")
		)
		(fp_poly
			(pts
				(xy -1.524 0.7112) (xy -1.524 1.7526) (xy -0.508 1.7526) (xy -0.508 0.6985) (xy 0.508 0.6985) (xy 0.508 1.7526)
				(xy 1.524 1.7526) (xy 1.524 0.6985) (xy 1.524 -0.6985) (xy 0.508 -0.6985) (xy 0.508 -1.7526) (xy -0.508 -1.7526)
				(xy -0.508 -0.6985) (xy -1.524 -0.6985) (xy -1.524 0.6985)
			)
			(stroke
				(width 0)
				(type default)
			)
			(fill no)
			(layer "F.CrtYd")
		)
		(fp_text user "3"
			(at -1.015492 -1.565402 0)
			(unlocked yes)
			(layer "F.SilkS")
			(effects
				(font
					(size 0.635 0.4064)
					(thickness 0.1524)
				)
			)
		)
		(fp_text user "1"
			(at -1.914906 1.400556 90)
			(unlocked yes)
			(layer "F.SilkS")
			(effects
				(font
					(size 0.635 0.4064)
					(thickness 0.1524)
				)
			)
		)
		(fp_text user "2"
			(at 3.155188 2.46888 90)
			(unlocked yes)
			(layer "F.SilkS")
			(effects
				(font
					(size 0.635 0.4064)
					(thickness 0.1524)
				)
			)
		)
		(pad "1" smd rect
			(at -1.016 1.1176 90)
			(size 1.016 1.27)
			(layers "F.Cu" "F.Mask" "F.Paste")
			(net "GND")
		)
		(pad "2" smd rect
			(at 1.016 1.1176 90)
			(size 1.016 1.27)
			(layers "F.Cu" "F.Mask" "F.Paste")
			(net "P5V_CRT")
		)
		(pad "3" smd rect
			(at 0 -1.1176 90)
			(size 1.016 1.27)
			(layers "F.Cu" "F.Mask" "F.Paste")
			(net "CRT_DDCDATA")
		)
	)
	(footprint ""
		(layer "F.Cu")
		(at 103.498142 -158.277052 -90)
		(property "Reference" "PR14"
			(at 1.77419 -2.89687 90)
			(unlocked yes)
			(layer "F.SilkS")
			(effects
				(font
					(size 0.635 0.4064)
					(thickness 0.1524)
				)
				(justify left)
			)
		)
		(property "Value" ""
			(at 0 0 270)
			(layer "F.Fab")
			(effects
				(font
					(size 1.27 1.27)
				)
			)
		)
		(duplicate_pad_numbers_are_jumpers no)
		(fp_line
			(start -0.7874 0.4064)
			(end -0.7874 -0.4064)
			(stroke
				(width 0.1524)
				(type default)
			)
			(layer "F.SilkS")
		)
		(fp_line
			(start 0.7874 0.4064)
			(end -0.7874 0.4064)
			(stroke
				(width 0.1524)
				(type default)
			)
			(layer "F.SilkS")
		)
		(fp_line
			(start -0.7874 -0.4064)
			(end 0.7874 -0.4064)
			(stroke
				(width 0.1524)
				(type default)
			)
			(layer "F.SilkS")
		)
		(fp_line
			(start 0.7874 -0.4064)
			(end 0.7874 0.4064)
			(stroke
				(width 0.1524)
				(type default)
			)
			(layer "F.SilkS")
		)
		(fp_poly
			(pts
				(xy -0.508 0.2794) (xy -0.508 0.2286) (xy -0.635 0.2286) (xy -0.635 -0.254) (xy -0.5334 -0.254)
				(xy -0.5334 -0.2794) (xy 0.5334 -0.2794) (xy 0.5334 -0.254) (xy 0.635 -0.254) (xy 0.635 0.254) (xy 0.5334 0.254)
				(xy 0.5334 0.2794)
			)
			(stroke
				(width 0)
				(type default)
			)
			(fill no)
			(layer "F.CrtYd")
		)
		(pad "1" smd rect
			(at 0.40005 0 270)
			(size 0.4572 0.508)
			(layers "F.Cu" "F.Mask" "F.Paste")
			(net "PWRGD_NODE1_P1V8_STB_PG")
		)
		(pad "2" smd rect
			(at -0.40005 0 270)
			(size 0.4572 0.508)
			(layers "F.Cu" "F.Mask" "F.Paste")
			(net "GND")
		)
	)
	(footprint ""
		(layer "F.Cu")
		(at 15.194534 -49.95291 -90)
		(property "Reference" "C503"
			(at 3.747008 -14.687296 90)
			(unlocked yes)
			(layer "F.SilkS")
			(effects
				(font
					(size 0.7874 0.5842)
					(thickness 0.1524)
				)
			)
		)
		(property "Value" ""
			(at 0 0 270)
			(layer "F.Fab")
			(effects
				(font
					(size 1.27 1.27)
				)
			)
		)
		(duplicate_pad_numbers_are_jumpers no)
		(fp_line
			(start -1.2954 0.5842)
			(end -1.2954 -0.5842)
			(stroke
				(width 0.1524)
				(type default)
			)
			(layer "F.SilkS")
		)
		(fp_line
			(start 1.2954 0.5842)
			(end -1.2954 0.5842)
			(stroke
				(width 0.1524)
				(type default)
			)
			(layer "F.SilkS")
		)
		(fp_line
			(start -1.2954 -0.5842)
			(end 1.2954 -0.5842)
			(stroke
				(width 0.1524)
				(type default)
			)
			(layer "F.SilkS")
		)
		(fp_line
			(start 0 -0.5842)
			(end 0 0.5842)
			(stroke
				(width 0.1524)
				(type default)
			)
			(layer "F.SilkS")
		)
		(fp_line
			(start 1.2954 -0.5842)
			(end 1.2954 0.5842)
			(stroke
				(width 0.1524)
				(type default)
			)
			(layer "F.SilkS")
		)
		(fp_poly
			(pts
				(xy 0.8636 -0.4572) (xy 0.8636 -0.3556) (xy 1.143 -0.3556) (xy 1.143 0.3556) (xy 0.8636 0.3556)
				(xy 0.8636 0.4572) (xy -0.8636 0.4572) (xy -0.8636 0.3556) (xy -1.143 0.3556) (xy -1.143 -0.3556)
				(xy -0.8636 -0.3556) (xy -0.8636 -0.4572)
			)
			(stroke
				(width 0)
				(type default)
			)
			(fill no)
			(layer "F.CrtYd")
		)
		(fp_line
			(start -0.884936 0.504952)
			(end -0.884936 -0.504952)
			(stroke
				(width 0.1)
				(type default)
			)
			(layer "F.Fab")
		)
		(fp_line
			(start 0.884936 0.504952)
			(end -0.884936 0.504952)
			(stroke
				(width 0.1)
				(type default)
			)
			(layer "F.Fab")
		)
		(fp_line
			(start -0.884936 -0.504952)
			(end 0.884936 -0.504952)
			(stroke
				(width 0.1)
				(type default)
			)
			(layer "F.Fab")
		)
		(fp_line
			(start 0.884936 -0.504952)
			(end 0.884936 0.504952)
			(stroke
				(width 0.1)
				(type default)
			)
			(layer "F.Fab")
		)
		(pad "1" smd rect
			(at 0.7366 0)
			(size 0.7112 0.8128)
			(layers "F.Cu" "F.Mask" "F.Paste")
			(net "CRT_G")
		)
		(pad "2" smd rect
			(at -0.7366 0)
			(size 0.7112 0.8128)
			(layers "F.Cu" "F.Mask" "F.Paste")
			(net "GND")
		)
	)
	(footprint ""
		(layer "F.Cu")
		(at 9.848088 -151.71039 180)
		(property "Reference" "C553"
			(at -3.745992 -2.40157 90)
			(unlocked yes)
			(layer "F.SilkS")
			(effects
				(font
					(size 0.7874 0.5842)
					(thickness 0.1524)
				)
				(justify left)
			)
		)
		(property "Value" ""
			(at 0 0 180)
			(layer "F.Fab")
			(effects
				(font
					(size 1.27 1.27)
				)
			)
		)
		(duplicate_pad_numbers_are_jumpers no)
		(fp_line
			(start 0.7874 0.4064)
			(end -0.7874 0.4064)
			(stroke
				(width 0.1524)
				(type default)
			)
			(layer "F.SilkS")
		)
		(fp_line
			(start 0.7874 -0.4064)
			(end 0.7874 0.4064)
			(stroke
				(width 0.1524)
				(type default)
			)
			(layer "F.SilkS")
		)
		(fp_line
			(start 0 0.381)
			(end 0 -0.381)
			(stroke
				(width 0.1524)
				(type default)
			)
			(layer "F.SilkS")
		)
		(fp_line
			(start -0.7874 0.4064)
			(end -0.7874 -0.4064)
			(stroke
				(width 0.1524)
				(type default)
			)
			(layer "F.SilkS")
		)
		(fp_line
			(start -0.7874 -0.4064)
			(end 0.7874 -0.4064)
			(stroke
				(width 0.1524)
				(type default)
			)
			(layer "F.SilkS")
		)
		(fp_poly
			(pts
				(xy -0.5334 0.254) (xy -0.635 0.254) (xy -0.635 0.2286) (xy -0.635 -0.254) (xy -0.5334 -0.254) (xy -0.5334 -0.2794)
				(xy 0.5334 -0.2794) (xy 0.5334 -0.254) (xy 0.635 -0.254) (xy 0.635 0.254) (xy 0.5334 0.254) (xy 0.5334 0.2794)
				(xy -0.508 0.2794) (xy -0.5334 0.2794)
			)
			(stroke
				(width 0)
				(type default)
			)
			(fill no)
			(layer "F.CrtYd")
		)
		(pad "1" smd rect
			(at 0.40005 0 180)
			(size 0.4572 0.508)
			(layers "F.Cu" "F.Mask" "F.Paste")
			(net "GND")
		)
		(pad "2" smd rect
			(at -0.40005 0 180)
			(size 0.4572 0.508)
			(layers "F.Cu" "F.Mask" "F.Paste")
			(net "N54310606")
		)
	)
	(footprint ""
		(layer "F.Cu")
		(at 123.588018 -56.831484)
		(property "Reference" "R521"
			(at -3.77698 0.058928 0)
			(unlocked yes)
			(layer "F.SilkS")
			(effects
				(font
					(size 0.7874 0.5842)
					(thickness 0.1524)
				)
				(justify left)
			)
		)
		(property "Value" ""
			(at 0 0 0)
			(layer "F.Fab")
			(effects
				(font
					(size 1.27 1.27)
				)
			)
		)
		(duplicate_pad_numbers_are_jumpers no)
		(fp_line
			(start -0.7874 -0.4064)
			(end 0.7874 -0.4064)
			(stroke
				(width 0.1524)
				(type default)
			)
			(layer "F.SilkS")
		)
		(fp_line
			(start -0.7874 0.4064)
			(end -0.7874 -0.4064)
			(stroke
				(width 0.1524)
				(type default)
			)
			(layer "F.SilkS")
		)
		(fp_line
			(start 0.7874 -0.4064)
			(end 0.7874 0.4064)
			(stroke
				(width 0.1524)
				(type default)
			)
			(layer "F.SilkS")
		)
		(fp_line
			(start 0.7874 0.4064)
			(end -0.7874 0.4064)
			(stroke
				(width 0.1524)
				(type default)
			)
			(layer "F.SilkS")
		)
		(fp_poly
			(pts
				(xy -0.508 0.2794) (xy -0.508 0.2286) (xy -0.635 0.2286) (xy -0.635 -0.254) (xy -0.5334 -0.254)
				(xy -0.5334 -0.2794) (xy 0.5334 -0.2794) (xy 0.5334 -0.254) (xy 0.635 -0.254) (xy 0.635 0.254) (xy 0.5334 0.254)
				(xy 0.5334 0.2794)
			)
			(stroke
				(width 0)
				(type default)
			)
			(fill no)
			(layer "F.CrtYd")
		)
		(pad "1" smd rect
			(at 0.40005 0)
			(size 0.4572 0.508)
			(layers "F.Cu" "F.Mask" "F.Paste")
			(net "COM4_EN_N")
		)
		(pad "2" smd rect
			(at -0.40005 0)
			(size 0.4572 0.508)
			(layers "F.Cu" "F.Mask" "F.Paste")
			(net "CPLD_UART_RI_P3_N")
		)
	)
	(footprint ""
		(layer "F.Cu")
		(at -67.821048 -265.408664)
		(property "Reference" "PCB"
			(at -0.5842 -1.31953 0)
			(unlocked yes)
			(layer "B.SilkS")
			(effects
				(font
					(size 0.7874 0.5842)
					(thickness 0.1524)
				)
				(justify left mirror)
			)
		)
		(property "Value" ""
			(at 0 0 0)
			(layer "F.Fab")
			(effects
				(font
					(size 1.27 1.27)
				)
			)
		)
		(duplicate_pad_numbers_are_jumpers no)
		(fp_poly
			(pts
				(arc
					(start 0.3302 0)
					(mid -0.3302 0)
					(end 0.3302 0)
				)
			)
			(stroke
				(width 0)
				(type default)
			)
			(fill no)
			(layer "B.CrtYd")
		)
		(pad "1" thru_hole circle
			(at 0 0)
			(size 0.508 0.508)
			(drill 0.254)
			(layers "*.Cu" "*.Mask")
			(remove_unused_layers no)
			(net "Net_220")
			(clearance 0.127)
			(thermal_gap 0.127)
			(padstack
				(mode front_inner_back)
				(layer "Inner"
					(shape circle)
					(size 0.508 0.508)
					(clearance 0.127)
				)
				(layer "B.Cu"
					(shape circle)
					(size 0.6604 0.6604)
					(clearance 0.0508)
				)
			)
		)
	)
	(footprint ""
		(layer "F.Cu")
		(at 133.53796 -143.575532 90)
		(property "Reference" "U125"
			(at -10.804652 0.525272 0)
			(unlocked yes)
			(layer "F.SilkS")
			(effects
				(font
					(size 0.7874 0.5842)
					(thickness 0.1524)
				)
				(justify left)
			)
		)
		(property "Value" ""
			(at 0 0 90)
			(layer "F.Fab")
			(effects
				(font
					(size 1.27 1.27)
				)
			)
		)
		(duplicate_pad_numbers_are_jumpers no)
		(fp_line
			(start 4.191 -10.1854)
			(end 4.191 -8.6614)
			(stroke
				(width 0.127)
				(type default)
			)
			(layer "F.SilkS")
		)
		(fp_line
			(start -3.7846 -10.1854)
			(end -3.7846 -8.6614)
			(stroke
				(width 0.127)
				(type default)
			)
			(layer "F.SilkS")
		)
		(fp_line
			(start 6.1976 -9.4234)
			(end 6.1976 -8.6614)
			(stroke
				(width 0.127)
				(type default)
			)
			(layer "F.SilkS")
		)
		(fp_line
			(start 2.2098 -9.4234)
			(end 2.2098 -8.6614)
			(stroke
				(width 0.127)
				(type default)
			)
			(layer "F.SilkS")
		)
		(fp_line
			(start -1.8034 -9.4234)
			(end -1.8034 -8.6614)
			(stroke
				(width 0.127)
				(type default)
			)
			(layer "F.SilkS")
		)
		(fp_line
			(start -5.7912 -9.4234)
			(end -5.7912 -8.6614)
			(stroke
				(width 0.127)
				(type default)
			)
			(layer "F.SilkS")
		)
		(fp_line
			(start 0.2032 -9.195308)
			(end 0.2032 -8.6614)
			(stroke
				(width 0.127)
				(type default)
			)
			(layer "F.SilkS")
		)
		(fp_line
			(start 6.8072 -6.8072)
			(end 6.8072 6.8072)
			(stroke
				(width 0.1524)
				(type default)
			)
			(layer "F.SilkS")
		)
		(fp_line
			(start -6.8072 -6.8072)
			(end 6.8072 -6.8072)
			(stroke
				(width 0.1524)
				(type default)
			)
			(layer "F.SilkS")
		)
		(fp_line
			(start -10.1854 -4.9784)
			(end -8.6614 -4.9784)
			(stroke
				(width 0.127)
				(type default)
			)
			(layer "F.SilkS")
		)
		(fp_line
			(start 8.6614 -4.5974)
			(end 10.1854 -4.5974)
			(stroke
				(width 0.127)
				(type default)
			)
			(layer "F.SilkS")
		)
		(fp_line
			(start -9.4234 -2.9972)
			(end -8.6614 -2.9972)
			(stroke
				(width 0.127)
				(type default)
			)
			(layer "F.SilkS")
		)
		(fp_line
			(start 8.6614 -2.5908)
			(end 9.4234 -2.5908)
			(stroke
				(width 0.127)
				(type default)
			)
			(layer "F.SilkS")
		)
		(fp_line
			(start -10.1854 -0.9906)
			(end -8.6614 -0.9906)
			(stroke
				(width 0.127)
				(type default)
			)
			(layer "F.SilkS")
		)
		(fp_line
			(start 8.6614 -0.5842)
			(end 10.1854 -0.5842)
			(stroke
				(width 0.127)
				(type default)
			)
			(layer "F.SilkS")
		)
		(fp_line
			(start -9.4234 1.016)
			(end -8.6614 1.016)
			(stroke
				(width 0.127)
				(type default)
			)
			(layer "F.SilkS")
		)
		(fp_line
			(start 8.6614 1.397)
			(end 9.4234 1.397)
			(stroke
				(width 0.127)
				(type default)
			)
			(layer "F.SilkS")
		)
		(fp_line
			(start -10.1854 2.9972)
			(end -8.6614 2.9972)
			(stroke
				(width 0.127)
				(type default)
			)
			(layer "F.SilkS")
		)
		(fp_line
			(start 8.6614 3.4036)
			(end 10.1854 3.4036)
			(stroke
				(width 0.127)
				(type default)
			)
			(layer "F.SilkS")
		)
		(fp_line
			(start -9.4234 5.0038)
			(end -8.6614 5.0038)
			(stroke
				(width 0.127)
				(type default)
			)
			(layer "F.SilkS")
		)
		(fp_line
			(start 8.6614 5.4102)
			(end 9.4234 5.4102)
			(stroke
				(width 0.127)
				(type default)
			)
			(layer "F.SilkS")
		)
		(fp_line
			(start -6.8072 5.999988)
			(end -6.8072 -6.8072)
			(stroke
				(width 0.1524)
				(type default)
			)
			(layer "F.SilkS")
		)
		(fp_line
			(start 6.8072 6.8072)
			(end -5.999988 6.8072)
			(stroke
				(width 0.1524)
				(type default)
			)
			(layer "F.SilkS")
		)
		(fp_line
			(start -5.999988 6.8072)
			(end -6.8072 5.999988)
			(stroke
				(width 0.1524)
				(type default)
			)
			(layer "F.SilkS")
		)
		(fp_line
			(start 5.4102 8.6614)
			(end 5.4102 10.1854)
			(stroke
				(width 0.127)
				(type default)
			)
			(layer "F.SilkS")
		)
		(fp_line
			(start 3.4036 8.6614)
			(end 3.4036 9.4234)
			(stroke
				(width 0.127)
				(type default)
			)
			(layer "F.SilkS")
		)
		(fp_line
			(start 1.397 8.6614)
			(end 1.397 10.1854)
			(stroke
				(width 0.127)
				(type default)
			)
			(layer "F.SilkS")
		)
		(fp_line
			(start -0.6096 8.6614)
			(end -0.6096 9.4234)
			(stroke
				(width 0.127)
				(type default)
			)
			(layer "F.SilkS")
		)
		(fp_line
			(start -2.5908 8.6614)
			(end -2.5908 10.1854)
			(stroke
				(width 0.127)
				(type default)
			)
			(layer "F.SilkS")
		)
		(fp_line
			(start -4.5974 8.6614)
			(end -4.5974 9.4234)
			(stroke
				(width 0.127)
				(type default)
			)
			(layer "F.SilkS")
		)
		(fp_poly
			(pts
				(xy -6.78053 7.238238) (xy -8.24865 6.713728) (xy -8.24865 7.882128)
			)
			(stroke
				(width 0)
				(type default)
			)
			(fill yes)
			(layer "F.SilkS")
		)
		(fp_poly
			(pts
				(xy -6.999986 6.999986) (xy -6.2992 6.999986) (xy -6.2992 8.5344) (xy 6.2992 8.5344) (xy 6.2992 6.999986)
				(xy 6.999986 6.999986) (xy 6.999986 6.2992) (xy 8.5344 6.2992) (xy 8.5344 -6.2992) (xy 6.999986 -6.2992)
				(xy 6.999986 -6.999986) (xy 6.2992 -6.999986) (xy 6.2992 -8.5344) (xy -6.2992 -8.5344) (xy -6.2992 -6.999986)
				(xy -6.999986 -6.999986) (xy -6.999986 -6.2992) (xy -8.5344 -6.2992) (xy -8.5344 6.2992) (xy -6.999986 6.2992)
			)
			(stroke
				(width 0)
				(type default)
			)
			(fill no)
			(layer "F.CrtYd")
		)
		(fp_line
			(start 6.999986 -6.999986)
			(end 6.999986 6.999986)
			(stroke
				(width 0.1)
				(type default)
			)
			(layer "F.Fab")
		)
		(fp_line
			(start -6.999986 -6.999986)
			(end 6.999986 -6.999986)
			(stroke
				(width 0.1)
				(type default)
			)
			(layer "F.Fab")
		)
		(fp_line
			(start 6.999986 6.999986)
			(end -6.999986 6.999986)
			(stroke
				(width 0.1)
				(type default)
			)
			(layer "F.Fab")
		)
		(fp_line
			(start -6.999986 6.999986)
			(end -6.999986 -6.999986)
			(stroke
				(width 0.1)
				(type default)
			)
			(layer "F.Fab")
		)
		(fp_poly
			(pts
				(xy -6.23189 8.79094) (xy -6.7564 10.25906) (xy -5.588 10.25906)
			)
			(stroke
				(width 0)
				(type default)
			)
			(fill yes)
			(layer "F.Fab")
		)
		(fp_text user "65"
			(at 7.004304 -8.47725 0)
			(unlocked yes)
			(layer "F.SilkS")
			(effects
				(font
					(size 0.635 0.4064)
					(thickness 0.1524)
				)
				(justify left)
			)
		)
		(fp_text user "96"
			(at -7.309612 -8.136382 0)
			(unlocked yes)
			(layer "F.SilkS")
			(effects
				(font
					(size 0.635 0.4064)
					(thickness 0.1524)
				)
				(justify left)
			)
		)
		(fp_text user "97"
			(at -8.726678 -7.550912 0)
			(unlocked yes)
			(layer "F.SilkS")
			(effects
				(font
					(size 0.635 0.4064)
					(thickness 0.1524)
				)
				(justify left)
			)
		)
		(fp_text user "64"
			(at 7.787132 -7.43077 0)
			(unlocked yes)
			(layer "F.SilkS")
			(effects
				(font
					(size 0.635 0.4064)
					(thickness 0.1524)
				)
				(justify left)
			)
		)
		(fp_text user "128"
			(at -9.226296 6.4262 0)
			(unlocked yes)
			(layer "F.SilkS")
			(effects
				(font
					(size 0.635 0.4064)
					(thickness 0.1524)
				)
				(justify left)
			)
		)
		(fp_text user "33"
			(at 7.521702 6.636004 0)
			(unlocked yes)
			(layer "F.SilkS")
			(effects
				(font
					(size 0.635 0.4064)
					(thickness 0.1524)
				)
				(justify left)
			)
		)
		(fp_text user "1"
			(at -7.275322 7.531608 0)
			(unlocked yes)
			(layer "F.SilkS")
			(effects
				(font
					(size 0.635 0.4064)
					(thickness 0.1524)
				)
				(justify left)
			)
		)
		(fp_text user "32"
			(at 7.128256 8.164576 0)
			(unlocked yes)
			(layer "F.SilkS")
			(effects
				(font
					(size 0.635 0.4064)
					(thickness 0.1524)
				)
				(justify left)
			)
		)
		(fp_text user "65"
			(at 6.2992 -9.388348 90)
			(unlocked yes)
			(layer "F.Fab")
			(effects
				(font
					(size 0.7874 0.5842)
					(thickness 0.000001)
				)
				(justify left)
			)
		)
		(fp_text user "96"
			(at -7.366 -9.362948 90)
			(unlocked yes)
			(layer "F.Fab")
			(effects
				(font
					(size 0.7874 0.5842)
					(thickness 0.000001)
				)
				(justify left)
			)
		)
		(fp_text user "64"
			(at 8.8392 -6.441948 90)
			(unlocked yes)
			(layer "F.Fab")
			(effects
				(font
					(size 0.7874 0.5842)
					(thickness 0.000001)
				)
				(justify left)
			)
		)
		(fp_text user "97"
			(at -10.2108 -6.441948 90)
			(unlocked yes)
			(layer "F.Fab")
			(effects
				(font
					(size 0.7874 0.5842)
					(thickness 0.000001)
				)
				(justify left)
			)
		)
		(fp_text user "33"
			(at 8.8392 6.258052 90)
			(unlocked yes)
			(layer "F.Fab")
			(effects
				(font
					(size 0.7874 0.5842)
					(thickness 0.000001)
				)
				(justify left)
			)
		)
		(fp_text user "128"
			(at -11.2395 6.258052 90)
			(unlocked yes)
			(layer "F.Fab")
			(effects
				(font
					(size 0.7874 0.5842)
					(thickness 0.000001)
				)
				(justify left)
			)
		)
		(fp_text user "1"
			(at -7.292086 9.40816 90)
			(unlocked yes)
			(layer "F.Fab")
			(effects
				(font
					(size 0.7874 0.5842)
					(thickness 0.000001)
				)
				(justify left)
			)
		)
		(fp_text user "32"
			(at 5.6642 9.433052 90)
			(unlocked yes)
			(layer "F.Fab")
			(effects
				(font
					(size 0.7874 0.5842)
					(thickness 0.000001)
				)
				(justify left)
			)
		)
		(pad "1" smd rect
			(at -6.199886 7.750048 90)
			(size 0.1778 1.524)
			(layers "F.Cu" "F.Mask" "F.Paste")
			(net "P1V0_NODE1")
		)
		(pad "2" smd rect
			(at -5.80009 7.750048 90)
			(size 0.1778 1.524)
			(layers "F.Cu" "F.Mask" "F.Paste")
			(net "GND")
		)
		(pad "3" smd rect
			(at -5.40004 7.750048 90)
			(size 0.1778 1.524)
			(layers "F.Cu" "F.Mask" "F.Paste")
			(net "GND")
		)
		(pad "4" smd rect
			(at -4.99999 7.750048 90)
			(size 0.1778 1.524)
			(layers "F.Cu" "F.Mask" "F.Paste")
			(net "P1V0_NODE1")
		)
		(pad "5" smd rect
			(at -4.59994 7.750048 90)
			(size 0.1778 1.524)
			(layers "F.Cu" "F.Mask" "F.Paste")
			(net "P3V3_NODE1")
		)
		(pad "6" smd rect
			(at -4.19989 7.750048 90)
			(size 0.1778 1.524)
			(layers "F.Cu" "F.Mask" "F.Paste")
			(net "PCIE_SW_WAKE_N")
		)
		(pad "7" smd rect
			(at -3.800094 7.750048 90)
			(size 0.1778 1.524)
			(layers "F.Cu" "F.Mask" "F.Paste")
			(net "PCIE_SW_PRSNT2")
		)
		(pad "8" smd rect
			(at -3.400044 7.750048 90)
			(size 0.1778 1.524)
			(layers "F.Cu" "F.Mask" "F.Paste")
			(net "P3V3_NODE1")
		)
		(pad "9" smd rect
			(at -2.999994 7.750048 90)
			(size 0.1778 1.524)
			(layers "F.Cu" "F.Mask" "F.Paste")
			(net "Net_2284")
		)
		(pad "10" smd rect
			(at -2.599944 7.750048 90)
			(size 0.1778 1.524)
			(layers "F.Cu" "F.Mask" "F.Paste")
			(net "PCIE_SW_TEST5")
		)
		(pad "11" smd rect
			(at -2.199894 7.750048 90)
			(size 0.1778 1.524)
			(layers "F.Cu" "F.Mask" "F.Paste")
			(net "PCIE_SW_TEST4")
		)
		(pad "12" smd rect
			(at -1.800098 7.750048 90)
			(size 0.1778 1.524)
			(layers "F.Cu" "F.Mask" "F.Paste")
			(net "PCIE_SW_TEST3")
		)
		(pad "13" smd rect
			(at -1.400048 7.750048 90)
			(size 0.1778 1.524)
			(layers "F.Cu" "F.Mask" "F.Paste")
			(net "PCIE_SW_I2C_SCL")
		)
		(pad "14" smd rect
			(at -0.999998 7.750048 90)
			(size 0.1778 1.524)
			(layers "F.Cu" "F.Mask" "F.Paste")
			(net "GND")
		)
		(pad "15" smd rect
			(at -0.599948 7.750048 90)
			(size 0.1778 1.524)
			(layers "F.Cu" "F.Mask" "F.Paste")
			(net "P1V0_NODE1")
		)
		(pad "16" smd rect
			(at -0.199898 7.750048 90)
			(size 0.1778 1.524)
			(layers "F.Cu" "F.Mask" "F.Paste")
			(net "PCIE_SW_I2C_SDA")
		)
		(pad "17" smd rect
			(at 0.199898 7.750048 90)
			(size 0.1778 1.524)
			(layers "F.Cu" "F.Mask" "F.Paste")
			(net "PCIE_SW_PWR_SAV")
		)
		(pad "18" smd rect
			(at 0.599948 7.750048 90)
			(size 0.1778 1.524)
			(layers "F.Cu" "F.Mask" "F.Paste")
			(net "PCIE_SW_P0_CTCDIS")
		)
		(pad "19" smd rect
			(at 0.999998 7.750048 90)
			(size 0.1778 1.524)
			(layers "F.Cu" "F.Mask" "F.Paste")
			(net "GND")
		)
		(pad "20" smd rect
			(at 1.400048 7.750048 90)
			(size 0.1778 1.524)
			(layers "F.Cu" "F.Mask" "F.Paste")
			(net "P3V3_NODE1")
		)
		(pad "21" smd rect
			(at 1.800098 7.750048 90)
			(size 0.1778 1.524)
			(layers "F.Cu" "F.Mask" "F.Paste")
			(net "Net_2292")
		)
		(pad "22" smd rect
			(at 2.199894 7.750048 90)
			(size 0.1778 1.524)
			(layers "F.Cu" "F.Mask" "F.Paste")
			(net "Net_2291")
		)
		(pad "23" smd rect
			(at 2.599944 7.750048 90)
			(size 0.1778 1.524)
			(layers "F.Cu" "F.Mask" "F.Paste")
			(net "Net_2290")
		)
		(pad "24" smd rect
			(at 2.999994 7.750048 90)
			(size 0.1778 1.524)
			(layers "F.Cu" "F.Mask" "F.Paste")
			(net "Net_2289")
		)
		(pad "25" smd rect
			(at 3.400044 7.750048 90)
			(size 0.1778 1.524)
			(layers "F.Cu" "F.Mask" "F.Paste")
			(net "Net_2288")
		)
		(pad "26" smd rect
			(at 3.800094 7.750048 90)
			(size 0.1778 1.524)
			(layers "F.Cu" "F.Mask" "F.Paste")
			(net "PCIE_SW_GPIO5")
		)
		(pad "27" smd rect
			(at 4.19989 7.750048 90)
			(size 0.1778 1.524)
			(layers "F.Cu" "F.Mask" "F.Paste")
			(net "PCIE_SW_GPIO6")
		)
		(pad "28" smd rect
			(at 4.59994 7.750048 90)
			(size 0.1778 1.524)
			(layers "F.Cu" "F.Mask" "F.Paste")
			(net "PCIE_SW_GPIO7")
		)
		(pad "29" smd rect
			(at 4.99999 7.750048 90)
			(size 0.1778 1.524)
			(layers "F.Cu" "F.Mask" "F.Paste")
			(net "P1V0_NODE1")
		)
		(pad "30" smd rect
			(at 5.40004 7.750048 90)
			(size 0.1778 1.524)
			(layers "F.Cu" "F.Mask" "F.Paste")
			(net "GND")
		)
		(pad "31" smd rect
			(at 5.80009 7.750048 90)
			(size 0.1778 1.524)
			(layers "F.Cu" "F.Mask" "F.Paste")
			(net "PCIE_SW_TEST1")
		)
		(pad "32" smd rect
			(at 6.199886 7.750048 90)
			(size 0.1778 1.524)
			(layers "F.Cu" "F.Mask" "F.Paste")
			(net "PCIE_SW_P1_CTCDIS")
		)
		(pad "33" smd rect
			(at 7.750048 6.199886 180)
			(size 0.1778 1.524)
			(layers "F.Cu" "F.Mask" "F.Paste")
			(net "PCIE_SW_P2_CTCDIS")
		)
		(pad "34" smd rect
			(at 7.750048 5.80009 180)
			(size 0.1778 1.524)
			(layers "F.Cu" "F.Mask" "F.Paste")
			(net "GND")
		)
		(pad "35" smd rect
			(at 7.750048 5.40004 180)
			(size 0.1778 1.524)
			(layers "F.Cu" "F.Mask" "F.Paste")
			(net "P3V3_NODE1")
		)
		(pad "36" smd rect
			(at 7.750048 4.99999 180)
			(size 0.1778 1.524)
			(layers "F.Cu" "F.Mask" "F.Paste")
			(net "GND")
		)
		(pad "37" smd rect
			(at 7.750048 4.59994 180)
			(size 0.1778 1.524)
			(layers "F.Cu" "F.Mask" "F.Paste")
			(net "P1V0_NODE1")
		)
		(pad "38" smd rect
			(at 7.750048 4.19989 180)
			(size 0.1778 1.524)
			(layers "F.Cu" "F.Mask" "F.Paste")
			(net "PCIE_SW_TEST7")
		)
		(pad "39" smd rect
			(at 7.750048 3.800094 180)
			(size 0.1778 1.524)
			(layers "F.Cu" "F.Mask" "F.Paste")
			(net "P3V3_NODE1")
		)
		(pad "40" smd rect
			(at 7.750048 3.400044 180)
			(size 0.1778 1.524)
			(layers "F.Cu" "F.Mask" "F.Paste")
			(net "PCIE_SW_EEPROM_CLK")
		)
		(pad "41" smd rect
			(at 7.750048 2.999994 180)
			(size 0.1778 1.524)
			(layers "F.Cu" "F.Mask" "F.Paste")
			(net "PCIE_SW_EEPROM_DAT")
		)
		(pad "42" smd rect
			(at 7.750048 2.599944 180)
			(size 0.1778 1.524)
			(layers "F.Cu" "F.Mask" "F.Paste")
			(net "P1V0_NODE1")
		)
		(pad "43" smd rect
			(at 7.750048 2.199894 180)
			(size 0.1778 1.524)
			(layers "F.Cu" "F.Mask" "F.Paste")
			(net "PCIE_SW_RST_N")
		)
		(pad "44" smd rect
			(at 7.750048 1.800098 180)
			(size 0.1778 1.524)
			(layers "F.Cu" "F.Mask" "F.Paste")
			(net "GND")
		)
		(pad "45" smd rect
			(at 7.750048 1.400048 180)
			(size 0.1778 1.524)
			(layers "F.Cu" "F.Mask" "F.Paste")
			(net "PCIE_SW_P0_ERR_R")
		)
		(pad "46" smd rect
			(at 7.750048 0.999998 180)
			(size 0.1778 1.524)
			(layers "F.Cu" "F.Mask" "F.Paste")
			(net "P1V0_NODE1")
		)
		(pad "47" smd rect
			(at 7.750048 0.599948 180)
			(size 0.1778 1.524)
			(layers "F.Cu" "F.Mask" "F.Paste")
			(net "Net_2282")
		)
		(pad "48" smd rect
			(at 7.750048 0.199898 180)
			(size 0.1778 1.524)
			(layers "F.Cu" "F.Mask" "F.Paste")
			(net "P3V3_NODE1")
		)
		(pad "49" smd rect
			(at 7.750048 -0.199898 180)
			(size 0.1778 1.524)
			(layers "F.Cu" "F.Mask" "F.Paste")
			(net "P1V0_NODE1")
		)
		(pad "50" smd rect
			(at 7.750048 -0.599948 180)
			(size 0.1778 1.524)
			(layers "F.Cu" "F.Mask" "F.Paste")
			(net "GND")
		)
		(pad "51" smd rect
			(at 7.750048 -0.999998 180)
			(size 0.1778 1.524)
			(layers "F.Cu" "F.Mask" "F.Paste")
			(net "Net_2281")
		)
		(pad "52" smd rect
			(at 7.750048 -1.400048 180)
			(size 0.1778 1.524)
			(layers "F.Cu" "F.Mask" "F.Paste")
			(net "P1V0_NODE1")
		)
		(pad "53" smd rect
			(at 7.750048 -1.800098 180)
			(size 0.1778 1.524)
			(layers "F.Cu" "F.Mask" "F.Paste")
			(net "GND")
		)
		(pad "54" smd rect
			(at 7.750048 -2.199894 180)
			(size 0.1778 1.524)
			(layers "F.Cu" "F.Mask" "F.Paste")
			(net "Net_2283")
		)
		(pad "55" smd rect
			(at 7.750048 -2.599944 180)
			(size 0.1778 1.524)
			(layers "F.Cu" "F.Mask" "F.Paste")
			(net "P3V3_NODE1")
		)
		(pad "56" smd rect
			(at 7.750048 -2.999994 180)
			(size 0.1778 1.524)
			(layers "F.Cu" "F.Mask" "F.Paste")
			(net "PCIE_SW_SCAN_EN")
		)
		(pad "57" smd rect
			(at 7.750048 -3.400044 180)
			(size 0.1778 1.524)
			(layers "F.Cu" "F.Mask" "F.Paste")
			(net "GND")
		)
		(pad "58" smd rect
			(at 7.750048 -3.800094 180)
			(size 0.1778 1.524)
			(layers "F.Cu" "F.Mask" "F.Paste")
			(net "Net_2285")
		)
		(pad "59" smd rect
			(at 7.750048 -4.19989 180)
			(size 0.1778 1.524)
			(layers "F.Cu" "F.Mask" "F.Paste")
			(net "Net_2287")
		)
		(pad "60" smd rect
			(at 7.750048 -4.59994 180)
			(size 0.1778 1.524)
			(layers "F.Cu" "F.Mask" "F.Paste")
			(net "GND")
		)
		(pad "61" smd rect
			(at 7.750048 -4.99999 180)
			(size 0.1778 1.524)
			(layers "F.Cu" "F.Mask" "F.Paste")
			(net "P1V0_NODE1")
		)
		(pad "62" smd rect
			(at 7.750048 -5.40004 180)
			(size 0.1778 1.524)
			(layers "F.Cu" "F.Mask" "F.Paste")
			(net "GND")
		)
		(pad "63" smd rect
			(at 7.750048 -5.80009 180)
			(size 0.1778 1.524)
			(layers "F.Cu" "F.Mask" "F.Paste")
			(net "PCIE_SW_TMS")
		)
		(pad "64" smd rect
			(at 7.750048 -6.199886 180)
			(size 0.1778 1.524)
			(layers "F.Cu" "F.Mask" "F.Paste")
			(net "Net_2286")
		)
		(pad "65" smd rect
			(at 6.199886 -7.750048 90)
			(size 0.1778 1.524)
			(layers "F.Cu" "F.Mask" "F.Paste")
			(net "PCIE_SW_TRST")
		)
		(pad "66" smd rect
			(at 5.80009 -7.750048 90)
			(size 0.1778 1.524)
			(layers "F.Cu" "F.Mask" "F.Paste")
			(net "PCIE_SW_TEST2")
		)
		(pad "67" smd rect
			(at 5.40004 -7.750048 90)
			(size 0.1778 1.524)
			(layers "F.Cu" "F.Mask" "F.Paste")
			(net "GND")
		)
		(pad "68" smd rect
			(at 4.99999 -7.750048 90)
			(size 0.1778 1.524)
			(layers "F.Cu" "F.Mask" "F.Paste")
			(net "GND")
		)
		(pad "69" smd rect
			(at 4.59994 -7.750048 90)
			(size 0.1778 1.524)
			(layers "F.Cu" "F.Mask" "F.Paste")
			(net "P2E_CPU_PCIE_SW_NODE1_TX_DN")
		)
		(pad "70" smd rect
			(at 4.19989 -7.750048 90)
			(size 0.1778 1.524)
			(layers "F.Cu" "F.Mask" "F.Paste")
			(net "P2E_CPU_PCIE_SW_NODE1_TX_DP")
		)
		(pad "71" smd rect
			(at 3.800094 -7.750048 90)
			(size 0.1778 1.524)
			(layers "F.Cu" "F.Mask" "F.Paste")
			(net "GND")
		)
		(pad "72" smd rect
			(at 3.400044 -7.750048 90)
			(size 0.1778 1.524)
			(layers "F.Cu" "F.Mask" "F.Paste")
			(net "P1V0_NODE1")
		)
		(pad "73" smd rect
			(at 2.999994 -7.750048 90)
			(size 0.1778 1.524)
			(layers "F.Cu" "F.Mask" "F.Paste")
			(net "P2E_CPU_PCIE_SW_NODE1_RX_C_DP")
		)
		(pad "74" smd rect
			(at 2.599944 -7.750048 90)
			(size 0.1778 1.524)
			(layers "F.Cu" "F.Mask" "F.Paste")
			(net "P2E_CPU_PCIE_SW_NODE1_RX_C_DN")
		)
		(pad "75" smd rect
			(at 2.199894 -7.750048 90)
			(size 0.1778 1.524)
			(layers "F.Cu" "F.Mask" "F.Paste")
			(net "P1V538_BMC_NODE1")
		)
		(pad "76" smd rect
			(at 1.800098 -7.750048 90)
			(size 0.1778 1.524)
			(layers "F.Cu" "F.Mask" "F.Paste")
			(net "P1V0_NODE1")
		)
		(pad "77" smd rect
			(at 1.400048 -7.750048 90)
			(size 0.1778 1.524)
			(layers "F.Cu" "F.Mask" "F.Paste")
			(net "GND")
		)
		(pad "78" smd rect
			(at 0.999998 -7.750048 90)
			(size 0.1778 1.524)
			(layers "F.Cu" "F.Mask" "F.Paste")
			(net "P1V0_PCI_SW_A")
		)
		(pad "79" smd rect
			(at 0.599948 -7.750048 90)
			(size 0.1778 1.524)
			(layers "F.Cu" "F.Mask" "F.Paste")
			(net "P1V0_PCI_SW_A")
		)
		(pad "80" smd rect
			(at 0.199898 -7.750048 90)
			(size 0.1778 1.524)
			(layers "F.Cu" "F.Mask" "F.Paste")
			(net "P1V0_PCI_SW_A")
		)
		(pad "81" smd rect
			(at -0.199898 -7.750048 90)
			(size 0.1778 1.524)
			(layers "F.Cu" "F.Mask" "F.Paste")
			(net "GND")
		)
		(pad "82" smd rect
			(at -0.599948 -7.750048 90)
			(size 0.1778 1.524)
			(layers "F.Cu" "F.Mask" "F.Paste")
			(net "P1V538_BMC_NODE1")
		)
		(pad "83" smd rect
			(at -0.999998 -7.750048 90)
			(size 0.1778 1.524)
			(layers "F.Cu" "F.Mask" "F.Paste")
			(net "P2E_CPU_BMC_NODE1_TX_C_DN")
		)
		(pad "84" smd rect
			(at -1.400048 -7.750048 90)
			(size 0.1778 1.524)
			(layers "F.Cu" "F.Mask" "F.Paste")
			(net "P2E_CPU_BMC_NODE1_TX_C_DP")
		)
		(pad "85" smd rect
			(at -1.800098 -7.750048 90)
			(size 0.1778 1.524)
			(layers "F.Cu" "F.Mask" "F.Paste")
			(net "P1V0_NODE1")
		)
		(pad "86" smd rect
			(at -2.199894 -7.750048 90)
			(size 0.1778 1.524)
			(layers "F.Cu" "F.Mask" "F.Paste")
			(net "GND")
		)
		(pad "87" smd rect
			(at -2.599944 -7.750048 90)
			(size 0.1778 1.524)
			(layers "F.Cu" "F.Mask" "F.Paste")
			(net "P2E_CPU_BMC_NODE1_RX_DP")
		)
		(pad "88" smd rect
			(at -2.999994 -7.750048 90)
			(size 0.1778 1.524)
			(layers "F.Cu" "F.Mask" "F.Paste")
			(net "P2E_CPU_BMC_NODE1_RX_DN")
		)
		(pad "89" smd rect
			(at -3.400044 -7.750048 90)
			(size 0.1778 1.524)
			(layers "F.Cu" "F.Mask" "F.Paste")
			(net "GND")
		)
		(pad "90" smd rect
			(at -3.800094 -7.750048 90)
			(size 0.1778 1.524)
			(layers "F.Cu" "F.Mask" "F.Paste")
			(net "GND")
		)
		(pad "91" smd rect
			(at -4.19989 -7.750048 90)
			(size 0.1778 1.524)
			(layers "F.Cu" "F.Mask" "F.Paste")
			(net "CLK_100M_PCIE_SW_NODE1_C_DP")
		)
		(pad "92" smd rect
			(at -4.59994 -7.750048 90)
			(size 0.1778 1.524)
			(layers "F.Cu" "F.Mask" "F.Paste")
			(net "P1V0_PCI_SW_A")
		)
		(pad "93" smd rect
			(at -4.99999 -7.750048 90)
			(size 0.1778 1.524)
			(layers "F.Cu" "F.Mask" "F.Paste")
			(net "CLK_100M_PCIE_SW_NODE1_C_DN")
		)
		(pad "94" smd rect
			(at -5.40004 -7.750048 90)
			(size 0.1778 1.524)
			(layers "F.Cu" "F.Mask" "F.Paste")
			(net "GND")
		)
		(pad "95" smd rect
			(at -5.80009 -7.750048 90)
			(size 0.1778 1.524)
			(layers "F.Cu" "F.Mask" "F.Paste")
			(net "GND")
		)
		(pad "96" smd rect
			(at -6.199886 -7.750048 90)
			(size 0.1778 1.524)
			(layers "F.Cu" "F.Mask" "F.Paste")
			(net "PE_SW_BMC_PERST_L")
		)
		(pad "97" smd rect
			(at -7.750048 -6.199886 180)
			(size 0.1778 1.524)
			(layers "F.Cu" "F.Mask" "F.Paste")
			(net "PE_SW_USB_PERST_L")
		)
		(pad "98" smd rect
			(at -7.750048 -5.80009 180)
			(size 0.1778 1.524)
			(layers "F.Cu" "F.Mask" "F.Paste")
			(net "Net_2280")
		)
		(pad "99" smd rect
			(at -7.750048 -5.40004 180)
			(size 0.1778 1.524)
			(layers "F.Cu" "F.Mask" "F.Paste")
			(net "P3V3_NODE1")
		)
		(pad "100" smd rect
			(at -7.750048 -4.99999 180)
			(size 0.1778 1.524)
			(layers "F.Cu" "F.Mask" "F.Paste")
			(net "GND")
		)
		(pad "101" smd rect
			(at -7.750048 -4.59994 180)
			(size 0.1778 1.524)
			(layers "F.Cu" "F.Mask" "F.Paste")
			(net "P1V0_NODE1")
		)
		(pad "102" smd rect
			(at -7.750048 -4.19989 180)
			(size 0.1778 1.524)
			(layers "F.Cu" "F.Mask" "F.Paste")
			(net "GND")
		)
		(pad "103" smd rect
			(at -7.750048 -3.800094 180)
			(size 0.1778 1.524)
			(layers "F.Cu" "F.Mask" "F.Paste")
			(net "P2E_CPU_USB_NODE1_RX_DN")
		)
		(pad "104" smd rect
			(at -7.750048 -3.400044 180)
			(size 0.1778 1.524)
			(layers "F.Cu" "F.Mask" "F.Paste")
			(net "P2E_CPU_USB_NODE1_RX_DP")
		)
		(pad "105" smd rect
			(at -7.750048 -2.999994 180)
			(size 0.1778 1.524)
			(layers "F.Cu" "F.Mask" "F.Paste")
			(net "GND")
		)
		(pad "106" smd rect
			(at -7.750048 -2.599944 180)
			(size 0.1778 1.524)
			(layers "F.Cu" "F.Mask" "F.Paste")
			(net "P1V0_NODE1")
		)
		(pad "107" smd rect
			(at -7.750048 -2.199894 180)
			(size 0.1778 1.524)
			(layers "F.Cu" "F.Mask" "F.Paste")
			(net "P2E_CPU_USB_NODE1_TX_C_DP")
		)
		(pad "108" smd rect
			(at -7.750048 -1.800098 180)
			(size 0.1778 1.524)
			(layers "F.Cu" "F.Mask" "F.Paste")
			(net "P2E_CPU_USB_NODE1_TX_C_DN")
		)
		(pad "109" smd rect
			(at -7.750048 -1.400048 180)
			(size 0.1778 1.524)
			(layers "F.Cu" "F.Mask" "F.Paste")
			(net "P1V538_BMC_NODE1")
		)
		(pad "110" smd rect
			(at -7.750048 -0.999998 180)
			(size 0.1778 1.524)
			(layers "F.Cu" "F.Mask" "F.Paste")
			(net "P1V0_NODE1")
		)
		(pad "111" smd rect
			(at -7.750048 -0.599948 180)
			(size 0.1778 1.524)
			(layers "F.Cu" "F.Mask" "F.Paste")
			(net "GND")
		)
		(pad "112" smd rect
			(at -7.750048 -0.199898 180)
			(size 0.1778 1.524)
			(layers "F.Cu" "F.Mask" "F.Paste")
			(net "P1V0_PCI_SW_A")
		)
		(pad "113" smd rect
			(at -7.750048 0.199898 180)
			(size 0.1778 1.524)
			(layers "F.Cu" "F.Mask" "F.Paste")
			(net "P1V0_PCI_SW_A")
		)
		(pad "114" smd rect
			(at -7.750048 0.599948 180)
			(size 0.1778 1.524)
			(layers "F.Cu" "F.Mask" "F.Paste")
			(net "GND")
		)
		(pad "115" smd rect
			(at -7.750048 0.999998 180)
			(size 0.1778 1.524)
			(layers "F.Cu" "F.Mask" "F.Paste")
			(net "P1V538_BMC_NODE1")
		)
		(pad "116" smd rect
			(at -7.750048 1.400048 180)
			(size 0.1778 1.524)
			(layers "F.Cu" "F.Mask" "F.Paste")
			(net "Net_2279")
		)
		(pad "117" smd rect
			(at -7.750048 1.800098 180)
			(size 0.1778 1.524)
			(layers "F.Cu" "F.Mask" "F.Paste")
			(net "Net_2278")
		)
		(pad "118" smd rect
			(at -7.750048 2.199894 180)
			(size 0.1778 1.524)
			(layers "F.Cu" "F.Mask" "F.Paste")
			(net "P1V0_NODE1")
		)
		(pad "119" smd rect
			(at -7.750048 2.599944 180)
			(size 0.1778 1.524)
			(layers "F.Cu" "F.Mask" "F.Paste")
			(net "GND")
		)
		(pad "120" smd rect
			(at -7.750048 2.999994 180)
			(size 0.1778 1.524)
			(layers "F.Cu" "F.Mask" "F.Paste")
			(net "Net_2277")
		)
		(pad "121" smd rect
			(at -7.750048 3.400044 180)
			(size 0.1778 1.524)
			(layers "F.Cu" "F.Mask" "F.Paste")
			(net "Net_2276")
		)
		(pad "122" smd rect
			(at -7.750048 3.800094 180)
			(size 0.1778 1.524)
			(layers "F.Cu" "F.Mask" "F.Paste")
			(net "GND")
		)
		(pad "123" smd rect
			(at -7.750048 4.19989 180)
			(size 0.1778 1.524)
			(layers "F.Cu" "F.Mask" "F.Paste")
			(net "P1V0_NODE1")
		)
		(pad "124" smd rect
			(at -7.750048 4.59994 180)
			(size 0.1778 1.524)
			(layers "F.Cu" "F.Mask" "F.Paste")
			(net "P3V3_NODE1")
		)
		(pad "125" smd rect
			(at -7.750048 4.99999 180)
			(size 0.1778 1.524)
			(layers "F.Cu" "F.Mask" "F.Paste")
			(net "GND")
		)
		(pad "126" smd rect
			(at -7.750048 5.40004 180)
			(size 0.1778 1.524)
			(layers "F.Cu" "F.Mask" "F.Paste")
			(net "PCIE_SW_TEST6")
		)
		(pad "127" smd rect
			(at -7.750048 5.80009 180)
			(size 0.1778 1.524)
			(layers "F.Cu" "F.Mask" "F.Paste")
			(net "PCIE_SW_SLOTCLK")
		)
		(pad "128" smd rect
			(at -7.750048 6.199886 180)
			(size 0.1778 1.524)
			(layers "F.Cu" "F.Mask" "F.Paste")
			(net "PCIE_SW_PRSNT1")
		)
	)
	(footprint ""
		(layer "F.Cu")
		(at 65.77076 -178.804824 180)
		(property "Reference" "U94"
			(at 13.868908 -132.653786 90)
			(unlocked yes)
			(layer "F.SilkS")
			(effects
				(font
					(size 0.7874 0.5842)
					(thickness 0.1524)
				)
			)
		)
		(property "Value" ""
			(at 0 0 180)
			(layer "F.Fab")
			(effects
				(font
					(size 1.27 1.27)
				)
			)
		)
		(duplicate_pad_numbers_are_jumpers no)
		(fp_line
			(start 1.651 1.905)
			(end -1.651 1.905)
			(stroke
				(width 0.1524)
				(type default)
			)
			(layer "F.SilkS")
		)
		(fp_line
			(start 1.651 -1.905)
			(end 1.651 1.905)
			(stroke
				(width 0.1524)
				(type default)
			)
			(layer "F.SilkS")
		)
		(fp_line
			(start -1.651 1.905)
			(end -1.651 -1.905)
			(stroke
				(width 0.1524)
				(type default)
			)
			(layer "F.SilkS")
		)
		(fp_line
			(start -1.651 -1.905)
			(end 1.651 -1.905)
			(stroke
				(width 0.1524)
				(type default)
			)
			(layer "F.SilkS")
		)
		(fp_poly
			(pts
				(xy -1.524 0.7112) (xy -1.524 1.7526) (xy -0.508 1.7526) (xy -0.508 0.6985) (xy 0.508 0.6985) (xy 0.508 1.7526)
				(xy 1.524 1.7526) (xy 1.524 0.6985) (xy 1.524 -0.6985) (xy 0.508 -0.6985) (xy 0.508 -1.7526) (xy -0.508 -1.7526)
				(xy -0.508 -0.6985) (xy -1.524 -0.6985) (xy -1.524 0.6985)
			)
			(stroke
				(width 0)
				(type default)
			)
			(fill no)
			(layer "F.CrtYd")
		)
		(fp_text user "S"
			(at 0.254508 2.360168 0)
			(unlocked yes)
			(layer "F.SilkS")
			(effects
				(font
					(size 0.635 0.4064)
					(thickness 0.1524)
				)
			)
		)
		(fp_text user "D"
			(at -0.83693 -2.441702 0)
			(unlocked yes)
			(layer "F.SilkS")
			(effects
				(font
					(size 0.635 0.4064)
					(thickness 0.1524)
				)
			)
		)
		(fp_text user "G"
			(at -2.285492 1.979168 0)
			(unlocked yes)
			(layer "F.SilkS")
			(effects
				(font
					(size 0.635 0.4064)
					(thickness 0.1524)
				)
			)
		)
		(pad "D" smd rect
			(at 0 -1.1176 180)
			(size 1.016 1.27)
			(layers "F.Cu" "F.Mask" "F.Paste")
			(net "PSU_DC_OK_N")
		)
		(pad "G" smd rect
			(at -1.016 1.1176 180)
			(size 1.016 1.27)
			(layers "F.Cu" "F.Mask" "F.Paste")
			(net "PSU1_DC_OK_R_BUF")
		)
		(pad "S" smd rect
			(at 1.016 1.1176 180)
			(size 1.016 1.27)
			(layers "F.Cu" "F.Mask" "F.Paste")
			(net "GND")
		)
	)
	(footprint ""
		(layer "F.Cu")
		(at 65.38976 -188.126624 90)
		(property "Reference" "C643"
			(at 4.548886 -0.3175 90)
			(unlocked yes)
			(layer "F.SilkS")
			(effects
				(font
					(size 0.7874 0.5842)
					(thickness 0.1524)
				)
				(justify left)
			)
		)
		(property "Value" ""
			(at 0 0 90)
			(layer "F.Fab")
			(effects
				(font
					(size 1.27 1.27)
				)
			)
		)
		(duplicate_pad_numbers_are_jumpers no)
		(fp_line
			(start 0.7874 -0.4064)
			(end 0.7874 0.4064)
			(stroke
				(width 0.1524)
				(type default)
			)
			(layer "F.SilkS")
		)
		(fp_line
			(start -0.7874 -0.4064)
			(end 0.7874 -0.4064)
			(stroke
				(width 0.1524)
				(type default)
			)
			(layer "F.SilkS")
		)
		(fp_line
			(start 0 0.381)
			(end 0 -0.381)
			(stroke
				(width 0.1524)
				(type default)
			)
			(layer "F.SilkS")
		)
		(fp_line
			(start 0.7874 0.4064)
			(end -0.7874 0.4064)
			(stroke
				(width 0.1524)
				(type default)
			)
			(layer "F.SilkS")
		)
		(fp_line
			(start -0.7874 0.4064)
			(end -0.7874 -0.4064)
			(stroke
				(width 0.1524)
				(type default)
			)
			(layer "F.SilkS")
		)
		(fp_poly
			(pts
				(xy -0.5334 0.254) (xy -0.635 0.254) (xy -0.635 0.2286) (xy -0.635 -0.254) (xy -0.5334 -0.254) (xy -0.5334 -0.2794)
				(xy 0.5334 -0.2794) (xy 0.5334 -0.254) (xy 0.635 -0.254) (xy 0.635 0.254) (xy 0.5334 0.254) (xy 0.5334 0.2794)
				(xy -0.508 0.2794) (xy -0.5334 0.2794)
			)
			(stroke
				(width 0)
				(type default)
			)
			(fill no)
			(layer "F.CrtYd")
		)
		(pad "1" smd rect
			(at 0.40005 0 90)
			(size 0.4572 0.508)
			(layers "F.Cu" "F.Mask" "F.Paste")
			(net "T2_NODE4_EN_R")
		)
		(pad "2" smd rect
			(at -0.40005 0 90)
			(size 0.4572 0.508)
			(layers "F.Cu" "F.Mask" "F.Paste")
			(net "GND")
		)
	)
	(footprint ""
		(layer "F.Cu")
		(at 53.95976 -188.126624 90)
		(property "Reference" "C587"
			(at 4.548886 0.375158 90)
			(unlocked yes)
			(layer "F.SilkS")
			(effects
				(font
					(size 0.7874 0.5842)
					(thickness 0.1524)
				)
				(justify left)
			)
		)
		(property "Value" ""
			(at 0 0 90)
			(layer "F.Fab")
			(effects
				(font
					(size 1.27 1.27)
				)
			)
		)
		(duplicate_pad_numbers_are_jumpers no)
		(fp_line
			(start 0.7874 -0.4064)
			(end 0.7874 0.4064)
			(stroke
				(width 0.1524)
				(type default)
			)
			(layer "F.SilkS")
		)
		(fp_line
			(start -0.7874 -0.4064)
			(end 0.7874 -0.4064)
			(stroke
				(width 0.1524)
				(type default)
			)
			(layer "F.SilkS")
		)
		(fp_line
			(start 0 0.381)
			(end 0 -0.381)
			(stroke
				(width 0.1524)
				(type default)
			)
			(layer "F.SilkS")
		)
		(fp_line
			(start 0.7874 0.4064)
			(end -0.7874 0.4064)
			(stroke
				(width 0.1524)
				(type default)
			)
			(layer "F.SilkS")
		)
		(fp_line
			(start -0.7874 0.4064)
			(end -0.7874 -0.4064)
			(stroke
				(width 0.1524)
				(type default)
			)
			(layer "F.SilkS")
		)
		(fp_poly
			(pts
				(xy -0.5334 0.254) (xy -0.635 0.254) (xy -0.635 0.2286) (xy -0.635 -0.254) (xy -0.5334 -0.254) (xy -0.5334 -0.2794)
				(xy 0.5334 -0.2794) (xy 0.5334 -0.254) (xy 0.635 -0.254) (xy 0.635 0.254) (xy 0.5334 0.254) (xy 0.5334 0.2794)
				(xy -0.508 0.2794) (xy -0.5334 0.2794)
			)
			(stroke
				(width 0)
				(type default)
			)
			(fill no)
			(layer "F.CrtYd")
		)
		(pad "1" smd rect
			(at 0.40005 0 90)
			(size 0.4572 0.508)
			(layers "F.Cu" "F.Mask" "F.Paste")
			(net "I2C_PSU1_R_SDA")
		)
		(pad "2" smd rect
			(at -0.40005 0 90)
			(size 0.4572 0.508)
			(layers "F.Cu" "F.Mask" "F.Paste")
			(net "GND")
		)
	)
	(footprint ""
		(layer "F.Cu")
		(at 19.938746 -97.973388 180)
		(property "Reference" "R1153"
			(at 5.192776 0.307086 0)
			(unlocked yes)
			(layer "F.SilkS")
			(effects
				(font
					(size 0.7874 0.5842)
					(thickness 0.1524)
				)
				(justify left)
			)
		)
		(property "Value" ""
			(at 0 0 180)
			(layer "F.Fab")
			(effects
				(font
					(size 1.27 1.27)
				)
			)
		)
		(duplicate_pad_numbers_are_jumpers no)
		(fp_line
			(start 0.7874 0.4064)
			(end -0.7874 0.4064)
			(stroke
				(width 0.1524)
				(type default)
			)
			(layer "F.SilkS")
		)
		(fp_line
			(start 0.7874 -0.4064)
			(end 0.7874 0.4064)
			(stroke
				(width 0.1524)
				(type default)
			)
			(layer "F.SilkS")
		)
		(fp_line
			(start -0.7874 0.4064)
			(end -0.7874 -0.4064)
			(stroke
				(width 0.1524)
				(type default)
			)
			(layer "F.SilkS")
		)
		(fp_line
			(start -0.7874 -0.4064)
			(end 0.7874 -0.4064)
			(stroke
				(width 0.1524)
				(type default)
			)
			(layer "F.SilkS")
		)
		(fp_poly
			(pts
				(xy -0.508 0.2794) (xy -0.508 0.2286) (xy -0.635 0.2286) (xy -0.635 -0.254) (xy -0.5334 -0.254)
				(xy -0.5334 -0.2794) (xy 0.5334 -0.2794) (xy 0.5334 -0.254) (xy 0.635 -0.254) (xy 0.635 0.254) (xy 0.5334 0.254)
				(xy 0.5334 0.2794)
			)
			(stroke
				(width 0)
				(type default)
			)
			(fill no)
			(layer "F.CrtYd")
		)
		(pad "1" smd rect
			(at 0.40005 0 180)
			(size 0.4572 0.508)
			(layers "F.Cu" "F.Mask" "F.Paste")
			(net "GND")
		)
		(pad "2" smd rect
			(at -0.40005 0 180)
			(size 0.4572 0.508)
			(layers "F.Cu" "F.Mask" "F.Paste")
			(net "FRU_SYS_A1")
		)
	)
	(footprint ""
		(layer "F.Cu")
		(at 82.96656 -80.683608 -90)
		(property "Reference" "C88"
			(at 17.592294 -1.189482 90)
			(unlocked yes)
			(layer "F.SilkS")
			(effects
				(font
					(size 0.7874 0.5842)
					(thickness 0.1524)
				)
				(justify left)
			)
		)
		(property "Value" ""
			(at 0 0 270)
			(layer "F.Fab")
			(effects
				(font
					(size 1.27 1.27)
				)
			)
		)
		(duplicate_pad_numbers_are_jumpers no)
		(fp_line
			(start -0.7874 0.4064)
			(end -0.7874 -0.4064)
			(stroke
				(width 0.1524)
				(type default)
			)
			(layer "F.SilkS")
		)
		(fp_line
			(start 0.7874 0.4064)
			(end -0.7874 0.4064)
			(stroke
				(width 0.1524)
				(type default)
			)
			(layer "F.SilkS")
		)
		(fp_line
			(start 0 0.381)
			(end 0 -0.381)
			(stroke
				(width 0.1524)
				(type default)
			)
			(layer "F.SilkS")
		)
		(fp_line
			(start -0.7874 -0.4064)
			(end 0.7874 -0.4064)
			(stroke
				(width 0.1524)
				(type default)
			)
			(layer "F.SilkS")
		)
		(fp_line
			(start 0.7874 -0.4064)
			(end 0.7874 0.4064)
			(stroke
				(width 0.1524)
				(type default)
			)
			(layer "F.SilkS")
		)
		(fp_poly
			(pts
				(xy -0.5334 0.254) (xy -0.635 0.254) (xy -0.635 0.2286) (xy -0.635 -0.254) (xy -0.5334 -0.254) (xy -0.5334 -0.2794)
				(xy 0.5334 -0.2794) (xy 0.5334 -0.254) (xy 0.635 -0.254) (xy 0.635 0.254) (xy 0.5334 0.254) (xy 0.5334 0.2794)
				(xy -0.508 0.2794) (xy -0.5334 0.2794)
			)
			(stroke
				(width 0)
				(type default)
			)
			(fill no)
			(layer "F.CrtYd")
		)
		(pad "1" smd rect
			(at 0.40005 0 270)
			(size 0.4572 0.508)
			(layers "F.Cu" "F.Mask" "F.Paste")
			(net "PV_VCCP_NODE1")
		)
		(pad "2" smd rect
			(at -0.40005 0 270)
			(size 0.4572 0.508)
			(layers "F.Cu" "F.Mask" "F.Paste")
			(net "GND")
		)
	)
	(footprint ""
		(layer "F.Cu")
		(at 174.636684 -41.493186 180)
		(property "Reference" "U53"
			(at -2.365248 0.11176 90)
			(unlocked yes)
			(layer "F.SilkS")
			(effects
				(font
					(size 0.7874 0.5842)
					(thickness 0.1524)
				)
			)
		)
		(property "Value" ""
			(at 0 0 180)
			(layer "F.Fab")
			(effects
				(font
					(size 1.27 1.27)
				)
			)
		)
		(duplicate_pad_numbers_are_jumpers no)
		(fp_line
			(start 1.549908 2.032)
			(end -1.549908 2.032)
			(stroke
				(width 0.1524)
				(type default)
			)
			(layer "F.SilkS")
		)
		(fp_line
			(start 1.549908 -2.032)
			(end 1.549908 2.032)
			(stroke
				(width 0.1524)
				(type default)
			)
			(layer "F.SilkS")
		)
		(fp_line
			(start -1.549908 2.032)
			(end -1.549908 -2.032)
			(stroke
				(width 0.1524)
				(type default)
			)
			(layer "F.SilkS")
		)
		(fp_line
			(start -1.549908 -2.032)
			(end 1.549908 -2.032)
			(stroke
				(width 0.1524)
				(type default)
			)
			(layer "F.SilkS")
		)
		(fp_poly
			(pts
				(xy -0.94996 2.4765) (xy -1.33096 3.6195) (xy -0.56896 3.6195)
			)
			(stroke
				(width 0)
				(type default)
			)
			(fill yes)
			(layer "F.SilkS")
		)
		(fp_poly
			(pts
				(xy -1.1684 1.905) (xy -1.1684 0.8636) (xy -1.5494 0.8636) (xy -1.5494 -0.8636) (xy -1.1684 -0.8636)
				(xy -1.1684 -1.905) (xy 1.1684 -1.905) (xy 1.1684 -0.8636) (xy 1.5494 -0.8636) (xy 1.5494 0.8636)
				(xy 1.1684 0.8636) (xy 1.1684 1.905)
			)
			(stroke
				(width 0)
				(type default)
			)
			(fill no)
			(layer "F.CrtYd")
		)
		(pad "1" smd rect
			(at -0.94996 1.225042 180)
			(size 0.4064 1.3208)
			(layers "F.Cu" "F.Mask" "F.Paste")
			(net "USB1_L_DN")
		)
		(pad "2" smd rect
			(at 0 1.225042 180)
			(size 0.4064 1.3208)
			(layers "F.Cu" "F.Mask" "F.Paste")
			(net "GND")
		)
		(pad "3" smd rect
			(at 0.94996 1.225042 180)
			(size 0.4064 1.3208)
			(layers "F.Cu" "F.Mask" "F.Paste")
			(net "USB1_L_DP")
		)
		(pad "4" smd rect
			(at 0.94996 -1.225042 180)
			(size 0.4064 1.3208)
			(layers "F.Cu" "F.Mask" "F.Paste")
			(net "USB0_L_DP")
		)
		(pad "5" smd rect
			(at 0 -1.225042 180)
			(size 0.4064 1.3208)
			(layers "F.Cu" "F.Mask" "F.Paste")
			(net "USBPWR_P0")
		)
		(pad "6" smd rect
			(at -0.94996 -1.225042 180)
			(size 0.4064 1.3208)
			(layers "F.Cu" "F.Mask" "F.Paste")
			(net "USB0_L_DN")
		)
	)
	(footprint ""
		(layer "F.Cu")
		(at 62.934596 -151.481028 180)
		(property "Reference" "R555"
			(at 30.839664 6.20141 0)
			(unlocked yes)
			(layer "F.SilkS")
			(effects
				(font
					(size 0.7874 0.5842)
					(thickness 0.1524)
				)
				(justify left)
			)
		)
		(property "Value" ""
			(at 0 0 180)
			(layer "F.Fab")
			(effects
				(font
					(size 1.27 1.27)
				)
			)
		)
		(duplicate_pad_numbers_are_jumpers no)
		(fp_line
			(start 0.7874 0.4064)
			(end -0.7874 0.4064)
			(stroke
				(width 0.1524)
				(type default)
			)
			(layer "F.SilkS")
		)
		(fp_line
			(start 0.7874 -0.4064)
			(end 0.7874 0.4064)
			(stroke
				(width 0.1524)
				(type default)
			)
			(layer "F.SilkS")
		)
		(fp_line
			(start -0.7874 0.4064)
			(end -0.7874 -0.4064)
			(stroke
				(width 0.1524)
				(type default)
			)
			(layer "F.SilkS")
		)
		(fp_line
			(start -0.7874 -0.4064)
			(end 0.7874 -0.4064)
			(stroke
				(width 0.1524)
				(type default)
			)
			(layer "F.SilkS")
		)
		(fp_poly
			(pts
				(xy -0.508 0.2794) (xy -0.508 0.2286) (xy -0.635 0.2286) (xy -0.635 -0.254) (xy -0.5334 -0.254)
				(xy -0.5334 -0.2794) (xy 0.5334 -0.2794) (xy 0.5334 -0.254) (xy 0.635 -0.254) (xy 0.635 0.254) (xy 0.5334 0.254)
				(xy 0.5334 0.2794)
			)
			(stroke
				(width 0)
				(type default)
			)
			(fill no)
			(layer "F.CrtYd")
		)
		(pad "1" smd rect
			(at 0.40005 0 180)
			(size 0.4572 0.508)
			(layers "F.Cu" "F.Mask" "F.Paste")
			(net "LAN1_NVM_WP_N")
		)
		(pad "2" smd rect
			(at -0.40005 0 180)
			(size 0.4572 0.508)
			(layers "F.Cu" "F.Mask" "F.Paste")
			(net "P3V3_NODE1")
		)
	)
	(footprint ""
		(layer "F.Cu")
		(at 45.557694 -102.399084 90)
		(property "Reference" "R198"
			(at -2.331212 -2.549652 90)
			(unlocked yes)
			(layer "F.SilkS")
			(effects
				(font
					(size 0.7874 0.5842)
					(thickness 0.1524)
				)
				(justify left)
			)
		)
		(property "Value" ""
			(at 0 0 90)
			(layer "F.Fab")
			(effects
				(font
					(size 1.27 1.27)
				)
			)
		)
		(duplicate_pad_numbers_are_jumpers no)
		(fp_line
			(start 0.7874 -0.4064)
			(end 0.7874 0.4064)
			(stroke
				(width 0.1524)
				(type default)
			)
			(layer "F.SilkS")
		)
		(fp_line
			(start -0.7874 -0.4064)
			(end 0.7874 -0.4064)
			(stroke
				(width 0.1524)
				(type default)
			)
			(layer "F.SilkS")
		)
		(fp_line
			(start 0.7874 0.4064)
			(end -0.7874 0.4064)
			(stroke
				(width 0.1524)
				(type default)
			)
			(layer "F.SilkS")
		)
		(fp_line
			(start -0.7874 0.4064)
			(end -0.7874 -0.4064)
			(stroke
				(width 0.1524)
				(type default)
			)
			(layer "F.SilkS")
		)
		(fp_poly
			(pts
				(xy -0.508 0.2794) (xy -0.508 0.2286) (xy -0.635 0.2286) (xy -0.635 -0.254) (xy -0.5334 -0.254)
				(xy -0.5334 -0.2794) (xy 0.5334 -0.2794) (xy 0.5334 -0.254) (xy 0.635 -0.254) (xy 0.635 0.254) (xy 0.5334 0.254)
				(xy 0.5334 0.2794)
			)
			(stroke
				(width 0)
				(type default)
			)
			(fill no)
			(layer "F.CrtYd")
		)
		(pad "1" smd rect
			(at 0.40005 0 90)
			(size 0.4572 0.508)
			(layers "F.Cu" "F.Mask" "F.Paste")
			(net "P3V3_NODE1")
		)
		(pad "2" smd rect
			(at -0.40005 0 90)
			(size 0.4572 0.508)
			(layers "F.Cu" "F.Mask" "F.Paste")
			(net "SMB_TEMP1_NODE1_ALERT_R_L")
		)
	)
	(footprint ""
		(layer "F.Cu")
		(at 103.589836 -138.90117 90)
		(property "Reference" "PR78"
			(at 4.973828 -1.973834 0)
			(unlocked yes)
			(layer "F.SilkS")
			(effects
				(font
					(size 0.635 0.4064)
					(thickness 0.1524)
				)
				(justify left)
			)
		)
		(property "Value" ""
			(at 0 0 90)
			(layer "F.Fab")
			(effects
				(font
					(size 1.27 1.27)
				)
			)
		)
		(duplicate_pad_numbers_are_jumpers no)
		(fp_line
			(start 0.7874 -0.4064)
			(end 0.7874 0.4064)
			(stroke
				(width 0.1524)
				(type default)
			)
			(layer "F.SilkS")
		)
		(fp_line
			(start -0.7874 -0.4064)
			(end 0.7874 -0.4064)
			(stroke
				(width 0.1524)
				(type default)
			)
			(layer "F.SilkS")
		)
		(fp_line
			(start 0.7874 0.4064)
			(end -0.7874 0.4064)
			(stroke
				(width 0.1524)
				(type default)
			)
			(layer "F.SilkS")
		)
		(fp_line
			(start -0.7874 0.4064)
			(end -0.7874 -0.4064)
			(stroke
				(width 0.1524)
				(type default)
			)
			(layer "F.SilkS")
		)
		(fp_poly
			(pts
				(xy -0.508 0.2794) (xy -0.508 0.2286) (xy -0.635 0.2286) (xy -0.635 -0.254) (xy -0.5334 -0.254)
				(xy -0.5334 -0.2794) (xy 0.5334 -0.2794) (xy 0.5334 -0.254) (xy 0.635 -0.254) (xy 0.635 0.254) (xy 0.5334 0.254)
				(xy 0.5334 0.2794)
			)
			(stroke
				(width 0)
				(type default)
			)
			(fill no)
			(layer "F.CrtYd")
		)
		(pad "1" smd rect
			(at 0.40005 0 90)
			(size 0.4572 0.508)
			(layers "F.Cu" "F.Mask" "F.Paste")
			(net "AGND_PVCCP_NODE1")
		)
		(pad "2" smd rect
			(at -0.40005 0 90)
			(size 0.4572 0.508)
			(layers "F.Cu" "F.Mask" "F.Paste")
			(net "VR_PVCCP_NODE1_IBIAS")
		)
	)
	(footprint ""
		(layer "F.Cu")
		(at 116.074952 -123.297442 90)
		(property "Reference" "PC94"
			(at -0.530352 4.81457 90)
			(unlocked yes)
			(layer "F.SilkS")
			(effects
				(font
					(size 0.7874 0.5842)
					(thickness 0.1524)
				)
				(justify left)
			)
		)
		(property "Value" ""
			(at 0 0 90)
			(layer "F.Fab")
			(effects
				(font
					(size 1.27 1.27)
				)
			)
		)
		(duplicate_pad_numbers_are_jumpers no)
		(fp_line
			(start 2.2098 -0.9398)
			(end 2.2098 0.9398)
			(stroke
				(width 0.1524)
				(type default)
			)
			(layer "F.SilkS")
		)
		(fp_line
			(start 0 -0.9398)
			(end 0 0.9398)
			(stroke
				(width 0.1524)
				(type default)
			)
			(layer "F.SilkS")
		)
		(fp_line
			(start -2.2098 -0.9398)
			(end 2.2098 -0.9398)
			(stroke
				(width 0.1524)
				(type default)
			)
			(layer "F.SilkS")
		)
		(fp_line
			(start 2.2098 0.9398)
			(end -2.2098 0.9398)
			(stroke
				(width 0.1524)
				(type default)
			)
			(layer "F.SilkS")
		)
		(fp_line
			(start -2.2098 0.9398)
			(end -2.2098 -0.9398)
			(stroke
				(width 0.1524)
				(type default)
			)
			(layer "F.SilkS")
		)
		(fp_poly
			(pts
				(xy -1.6764 0.889) (xy -1.6764 0.7874) (xy -2.0574 0.7874) (xy -2.0574 -0.7874) (xy -1.6764 -0.7874)
				(xy -1.6764 -0.9398) (xy 1.6764 -0.9398) (xy 1.6764 -0.7874) (xy 2.0574 -0.7874) (xy 2.0574 0.7874)
				(xy 1.6764 0.7874) (xy 1.6764 0.9398) (xy -1.6764 0.9398)
			)
			(stroke
				(width 0)
				(type default)
			)
			(fill no)
			(layer "F.CrtYd")
		)
		(fp_line
			(start 1.700022 -0.899922)
			(end 1.700022 0.899922)
			(stroke
				(width 0.1)
				(type default)
			)
			(layer "F.Fab")
		)
		(fp_line
			(start -1.700022 -0.899922)
			(end 1.700022 -0.899922)
			(stroke
				(width 0.1)
				(type default)
			)
			(layer "F.Fab")
		)
		(fp_line
			(start 1.700022 0.899922)
			(end -1.700022 0.899922)
			(stroke
				(width 0.1)
				(type default)
			)
			(layer "F.Fab")
		)
		(fp_line
			(start -1.700022 0.899922)
			(end -1.700022 -0.899922)
			(stroke
				(width 0.1)
				(type default)
			)
			(layer "F.Fab")
		)
		(pad "1" smd rect
			(at 1.4732 0 90)
			(size 1.1684 1.5748)
			(layers "F.Cu" "F.Mask" "F.Paste")
			(net "SW_VR_PVCCP_NODE1_VIN_FLT")
		)
		(pad "2" smd rect
			(at -1.4732 0 90)
			(size 1.1684 1.5748)
			(layers "F.Cu" "F.Mask" "F.Paste")
			(net "GND")
		)
	)
	(footprint ""
		(layer "F.Cu")
		(at 127.517652 -133.17855 -90)
		(property "Reference" "R280"
			(at 3.941572 -0.084328 90)
			(unlocked yes)
			(layer "F.SilkS")
			(effects
				(font
					(size 0.7874 0.5842)
					(thickness 0.1524)
				)
				(justify left)
			)
		)
		(property "Value" ""
			(at 0 0 270)
			(layer "F.Fab")
			(effects
				(font
					(size 1.27 1.27)
				)
			)
		)
		(duplicate_pad_numbers_are_jumpers no)
		(fp_line
			(start -0.7874 0.4064)
			(end -0.7874 -0.4064)
			(stroke
				(width 0.1524)
				(type default)
			)
			(layer "F.SilkS")
		)
		(fp_line
			(start 0.7874 0.4064)
			(end -0.7874 0.4064)
			(stroke
				(width 0.1524)
				(type default)
			)
			(layer "F.SilkS")
		)
		(fp_line
			(start -0.7874 -0.4064)
			(end 0.7874 -0.4064)
			(stroke
				(width 0.1524)
				(type default)
			)
			(layer "F.SilkS")
		)
		(fp_line
			(start 0.7874 -0.4064)
			(end 0.7874 0.4064)
			(stroke
				(width 0.1524)
				(type default)
			)
			(layer "F.SilkS")
		)
		(fp_poly
			(pts
				(xy -0.508 0.2794) (xy -0.508 0.2286) (xy -0.635 0.2286) (xy -0.635 -0.254) (xy -0.5334 -0.254)
				(xy -0.5334 -0.2794) (xy 0.5334 -0.2794) (xy 0.5334 -0.254) (xy 0.635 -0.254) (xy 0.635 0.254) (xy 0.5334 0.254)
				(xy 0.5334 0.2794)
			)
			(stroke
				(width 0)
				(type default)
			)
			(fill no)
			(layer "F.CrtYd")
		)
		(pad "1" smd rect
			(at 0.40005 0 270)
			(size 0.4572 0.508)
			(layers "F.Cu" "F.Mask" "F.Paste")
			(net "P3V3_NODE1")
		)
		(pad "2" smd rect
			(at -0.40005 0 270)
			(size 0.4572 0.508)
			(layers "F.Cu" "F.Mask" "F.Paste")
			(net "PE_SW_USB_PERST_L")
		)
	)
	(footprint ""
		(layer "F.Cu")
		(at 64.24676 -185.205624 90)
		(property "Reference" "C694"
			(at 4.006088 -0.795528 90)
			(unlocked yes)
			(layer "F.SilkS")
			(effects
				(font
					(size 0.7874 0.5842)
					(thickness 0.1524)
				)
				(justify left)
			)
		)
		(property "Value" ""
			(at 0 0 90)
			(layer "F.Fab")
			(effects
				(font
					(size 1.27 1.27)
				)
			)
		)
		(duplicate_pad_numbers_are_jumpers no)
		(fp_line
			(start 0.7874 -0.4064)
			(end 0.7874 0.4064)
			(stroke
				(width 0.1524)
				(type default)
			)
			(layer "F.SilkS")
		)
		(fp_line
			(start -0.7874 -0.4064)
			(end 0.7874 -0.4064)
			(stroke
				(width 0.1524)
				(type default)
			)
			(layer "F.SilkS")
		)
		(fp_line
			(start 0 0.381)
			(end 0 -0.381)
			(stroke
				(width 0.1524)
				(type default)
			)
			(layer "F.SilkS")
		)
		(fp_line
			(start 0.7874 0.4064)
			(end -0.7874 0.4064)
			(stroke
				(width 0.1524)
				(type default)
			)
			(layer "F.SilkS")
		)
		(fp_line
			(start -0.7874 0.4064)
			(end -0.7874 -0.4064)
			(stroke
				(width 0.1524)
				(type default)
			)
			(layer "F.SilkS")
		)
		(fp_poly
			(pts
				(xy -0.5334 0.254) (xy -0.635 0.254) (xy -0.635 0.2286) (xy -0.635 -0.254) (xy -0.5334 -0.254) (xy -0.5334 -0.2794)
				(xy 0.5334 -0.2794) (xy 0.5334 -0.254) (xy 0.635 -0.254) (xy 0.635 0.254) (xy 0.5334 0.254) (xy 0.5334 0.2794)
				(xy -0.508 0.2794) (xy -0.5334 0.2794)
			)
			(stroke
				(width 0)
				(type default)
			)
			(fill no)
			(layer "F.CrtYd")
		)
		(pad "1" smd rect
			(at 0.40005 0 90)
			(size 0.4572 0.508)
			(layers "F.Cu" "F.Mask" "F.Paste")
			(net "UART_T2_NODE1_RXD")
		)
		(pad "2" smd rect
			(at -0.40005 0 90)
			(size 0.4572 0.508)
			(layers "F.Cu" "F.Mask" "F.Paste")
			(net "GND")
		)
	)
	(footprint ""
		(layer "F.Cu")
		(at 112.76076 -188.126624 90)
		(property "Reference" "C763"
			(at 5.151882 -0.377698 90)
			(unlocked yes)
			(layer "F.SilkS")
			(effects
				(font
					(size 0.7874 0.5842)
					(thickness 0.1524)
				)
				(justify left)
			)
		)
		(property "Value" ""
			(at 0 0 90)
			(layer "F.Fab")
			(effects
				(font
					(size 1.27 1.27)
				)
			)
		)
		(duplicate_pad_numbers_are_jumpers no)
		(fp_line
			(start 0.7874 -0.4064)
			(end 0.7874 0.4064)
			(stroke
				(width 0.1524)
				(type default)
			)
			(layer "F.SilkS")
		)
		(fp_line
			(start -0.7874 -0.4064)
			(end 0.7874 -0.4064)
			(stroke
				(width 0.1524)
				(type default)
			)
			(layer "F.SilkS")
		)
		(fp_line
			(start 0 0.381)
			(end 0 -0.381)
			(stroke
				(width 0.1524)
				(type default)
			)
			(layer "F.SilkS")
		)
		(fp_line
			(start 0.7874 0.4064)
			(end -0.7874 0.4064)
			(stroke
				(width 0.1524)
				(type default)
			)
			(layer "F.SilkS")
		)
		(fp_line
			(start -0.7874 0.4064)
			(end -0.7874 -0.4064)
			(stroke
				(width 0.1524)
				(type default)
			)
			(layer "F.SilkS")
		)
		(fp_poly
			(pts
				(xy -0.5334 0.254) (xy -0.635 0.254) (xy -0.635 0.2286) (xy -0.635 -0.254) (xy -0.5334 -0.254) (xy -0.5334 -0.2794)
				(xy 0.5334 -0.2794) (xy 0.5334 -0.254) (xy 0.635 -0.254) (xy 0.635 0.254) (xy 0.5334 0.254) (xy 0.5334 0.2794)
				(xy -0.508 0.2794) (xy -0.5334 0.2794)
			)
			(stroke
				(width 0)
				(type default)
			)
			(fill no)
			(layer "F.CrtYd")
		)
		(pad "1" smd rect
			(at 0.40005 0 90)
			(size 0.4572 0.508)
			(layers "F.Cu" "F.Mask" "F.Paste")
			(net "UART_T8_NODE4_TXD_R")
		)
		(pad "2" smd rect
			(at -0.40005 0 90)
			(size 0.4572 0.508)
			(layers "F.Cu" "F.Mask" "F.Paste")
			(net "GND")
		)
	)
	(footprint ""
		(layer "F.Cu")
		(at 160.008062 -98.343212 180)
		(property "Reference" "R533"
			(at 3.956304 -0.569468 0)
			(unlocked yes)
			(layer "F.SilkS")
			(effects
				(font
					(size 0.7874 0.5842)
					(thickness 0.1524)
				)
				(justify left)
			)
		)
		(property "Value" ""
			(at 0 0 180)
			(layer "F.Fab")
			(effects
				(font
					(size 1.27 1.27)
				)
			)
		)
		(duplicate_pad_numbers_are_jumpers no)
		(fp_line
			(start 0.7874 0.4064)
			(end -0.7874 0.4064)
			(stroke
				(width 0.1524)
				(type default)
			)
			(layer "F.SilkS")
		)
		(fp_line
			(start 0.7874 -0.4064)
			(end 0.7874 0.4064)
			(stroke
				(width 0.1524)
				(type default)
			)
			(layer "F.SilkS")
		)
		(fp_line
			(start -0.7874 0.4064)
			(end -0.7874 -0.4064)
			(stroke
				(width 0.1524)
				(type default)
			)
			(layer "F.SilkS")
		)
		(fp_line
			(start -0.7874 -0.4064)
			(end 0.7874 -0.4064)
			(stroke
				(width 0.1524)
				(type default)
			)
			(layer "F.SilkS")
		)
		(fp_poly
			(pts
				(xy -0.508 0.2794) (xy -0.508 0.2286) (xy -0.635 0.2286) (xy -0.635 -0.254) (xy -0.5334 -0.254)
				(xy -0.5334 -0.2794) (xy 0.5334 -0.2794) (xy 0.5334 -0.254) (xy 0.635 -0.254) (xy 0.635 0.254) (xy 0.5334 0.254)
				(xy 0.5334 0.2794)
			)
			(stroke
				(width 0)
				(type default)
			)
			(fill no)
			(layer "F.CrtYd")
		)
		(pad "1" smd rect
			(at 0.40005 0 180)
			(size 0.4572 0.508)
			(layers "F.Cu" "F.Mask" "F.Paste")
			(net "P3V3_NODE1")
		)
		(pad "2" smd rect
			(at -0.40005 0 180)
			(size 0.4572 0.508)
			(layers "F.Cu" "F.Mask" "F.Paste")
			(net "USB_NODE1_PECREQ_L")
		)
	)
	(footprint ""
		(layer "F.Cu")
		(at 44.207176 -180.333904 180)
		(property "Reference" "C775"
			(at 0.986028 -132.587492 0)
			(unlocked yes)
			(layer "F.SilkS")
			(effects
				(font
					(size 0.7874 0.5842)
					(thickness 0.1524)
				)
				(justify left)
			)
		)
		(property "Value" ""
			(at 0 0 180)
			(layer "F.Fab")
			(effects
				(font
					(size 1.27 1.27)
				)
			)
		)
		(duplicate_pad_numbers_are_jumpers no)
		(fp_line
			(start 0.7874 0.4064)
			(end -0.7874 0.4064)
			(stroke
				(width 0.1524)
				(type default)
			)
			(layer "F.SilkS")
		)
		(fp_line
			(start 0.7874 -0.4064)
			(end 0.7874 0.4064)
			(stroke
				(width 0.1524)
				(type default)
			)
			(layer "F.SilkS")
		)
		(fp_line
			(start 0 0.381)
			(end 0 -0.381)
			(stroke
				(width 0.1524)
				(type default)
			)
			(layer "F.SilkS")
		)
		(fp_line
			(start -0.7874 0.4064)
			(end -0.7874 -0.4064)
			(stroke
				(width 0.1524)
				(type default)
			)
			(layer "F.SilkS")
		)
		(fp_line
			(start -0.7874 -0.4064)
			(end 0.7874 -0.4064)
			(stroke
				(width 0.1524)
				(type default)
			)
			(layer "F.SilkS")
		)
		(fp_poly
			(pts
				(xy -0.5334 0.254) (xy -0.635 0.254) (xy -0.635 0.2286) (xy -0.635 -0.254) (xy -0.5334 -0.254) (xy -0.5334 -0.2794)
				(xy 0.5334 -0.2794) (xy 0.5334 -0.254) (xy 0.635 -0.254) (xy 0.635 0.254) (xy 0.5334 0.254) (xy 0.5334 0.2794)
				(xy -0.508 0.2794) (xy -0.5334 0.2794)
			)
			(stroke
				(width 0)
				(type default)
			)
			(fill no)
			(layer "F.CrtYd")
		)
		(pad "1" smd rect
			(at 0.40005 0 180)
			(size 0.4572 0.508)
			(layers "F.Cu" "F.Mask" "F.Paste")
			(net "P12V_AUX")
		)
		(pad "2" smd rect
			(at -0.40005 0 180)
			(size 0.4572 0.508)
			(layers "F.Cu" "F.Mask" "F.Paste")
			(net "GND")
		)
	)
	(footprint ""
		(layer "F.Cu")
		(at 159.545782 -106.368596 180)
		(property "Reference" "R525"
			(at 1.36779 1.011682 0)
			(unlocked yes)
			(layer "F.SilkS")
			(effects
				(font
					(size 0.7874 0.5842)
					(thickness 0.1524)
				)
				(justify left)
			)
		)
		(property "Value" ""
			(at 0 0 180)
			(layer "F.Fab")
			(effects
				(font
					(size 1.27 1.27)
				)
			)
		)
		(duplicate_pad_numbers_are_jumpers no)
		(fp_line
			(start 0.7874 0.4064)
			(end -0.7874 0.4064)
			(stroke
				(width 0.1524)
				(type default)
			)
			(layer "F.SilkS")
		)
		(fp_line
			(start 0.7874 -0.4064)
			(end 0.7874 0.4064)
			(stroke
				(width 0.1524)
				(type default)
			)
			(layer "F.SilkS")
		)
		(fp_line
			(start -0.7874 0.4064)
			(end -0.7874 -0.4064)
			(stroke
				(width 0.1524)
				(type default)
			)
			(layer "F.SilkS")
		)
		(fp_line
			(start -0.7874 -0.4064)
			(end 0.7874 -0.4064)
			(stroke
				(width 0.1524)
				(type default)
			)
			(layer "F.SilkS")
		)
		(fp_poly
			(pts
				(xy -0.508 0.2794) (xy -0.508 0.2286) (xy -0.635 0.2286) (xy -0.635 -0.254) (xy -0.5334 -0.254)
				(xy -0.5334 -0.2794) (xy 0.5334 -0.2794) (xy 0.5334 -0.254) (xy 0.635 -0.254) (xy 0.635 0.254) (xy 0.5334 0.254)
				(xy 0.5334 0.2794)
			)
			(stroke
				(width 0)
				(type default)
			)
			(fill no)
			(layer "F.CrtYd")
		)
		(pad "1" smd rect
			(at 0.40005 0 180)
			(size 0.4572 0.508)
			(layers "F.Cu" "F.Mask" "F.Paste")
			(net "P3V3_NODE1")
		)
		(pad "2" smd rect
			(at -0.40005 0 180)
			(size 0.4572 0.508)
			(layers "F.Cu" "F.Mask" "F.Paste")
			(net "USB_NODE1_SMI_L")
		)
	)
	(footprint ""
		(layer "F.Cu")
		(at 66.46799 -6.332728)
		(property "Reference" "PC51"
			(at -1.426718 -4.301744 0)
			(unlocked yes)
			(layer "F.SilkS")
			(effects
				(font
					(size 0.7874 0.5842)
					(thickness 0.1524)
				)
				(justify left)
			)
		)
		(property "Value" ""
			(at 0 0 0)
			(layer "F.Fab")
			(effects
				(font
					(size 1.27 1.27)
				)
			)
		)
		(duplicate_pad_numbers_are_jumpers no)
		(fp_line
			(start -0.7874 -0.4064)
			(end 0.7874 -0.4064)
			(stroke
				(width 0.1524)
				(type default)
			)
			(layer "F.SilkS")
		)
		(fp_line
			(start -0.7874 0.4064)
			(end -0.7874 -0.4064)
			(stroke
				(width 0.1524)
				(type default)
			)
			(layer "F.SilkS")
		)
		(fp_line
			(start 0 0.381)
			(end 0 -0.381)
			(stroke
				(width 0.1524)
				(type default)
			)
			(layer "F.SilkS")
		)
		(fp_line
			(start 0.7874 -0.4064)
			(end 0.7874 0.4064)
			(stroke
				(width 0.1524)
				(type default)
			)
			(layer "F.SilkS")
		)
		(fp_line
			(start 0.7874 0.4064)
			(end -0.7874 0.4064)
			(stroke
				(width 0.1524)
				(type default)
			)
			(layer "F.SilkS")
		)
		(fp_poly
			(pts
				(xy -0.5334 0.254) (xy -0.635 0.254) (xy -0.635 0.2286) (xy -0.635 -0.254) (xy -0.5334 -0.254) (xy -0.5334 -0.2794)
				(xy 0.5334 -0.2794) (xy 0.5334 -0.254) (xy 0.635 -0.254) (xy 0.635 0.254) (xy 0.5334 0.254) (xy 0.5334 0.2794)
				(xy -0.508 0.2794) (xy -0.5334 0.2794)
			)
			(stroke
				(width 0)
				(type default)
			)
			(fill no)
			(layer "F.CrtYd")
		)
		(pad "1" smd rect
			(at 0.40005 0)
			(size 0.4572 0.508)
			(layers "F.Cu" "F.Mask" "F.Paste")
			(net "P3V3_NODE1_VREG5")
		)
		(pad "2" smd rect
			(at -0.40005 0)
			(size 0.4572 0.508)
			(layers "F.Cu" "F.Mask" "F.Paste")
			(net "GND")
		)
	)
	(footprint ""
		(layer "F.Cu")
		(at 152.755854 -135.155432 180)
		(property "Reference" "C801"
			(at 5.190236 -1.942084 0)
			(unlocked yes)
			(layer "F.SilkS")
			(effects
				(font
					(size 0.7874 0.5842)
					(thickness 0.1524)
				)
				(justify left)
			)
		)
		(property "Value" ""
			(at 0 0 180)
			(layer "F.Fab")
			(effects
				(font
					(size 1.27 1.27)
				)
			)
		)
		(duplicate_pad_numbers_are_jumpers no)
		(fp_line
			(start 0.7874 0.4064)
			(end -0.7874 0.4064)
			(stroke
				(width 0.1524)
				(type default)
			)
			(layer "F.SilkS")
		)
		(fp_line
			(start 0.7874 -0.4064)
			(end 0.7874 0.4064)
			(stroke
				(width 0.1524)
				(type default)
			)
			(layer "F.SilkS")
		)
		(fp_line
			(start 0 0.381)
			(end 0 -0.381)
			(stroke
				(width 0.1524)
				(type default)
			)
			(layer "F.SilkS")
		)
		(fp_line
			(start -0.7874 0.4064)
			(end -0.7874 -0.4064)
			(stroke
				(width 0.1524)
				(type default)
			)
			(layer "F.SilkS")
		)
		(fp_line
			(start -0.7874 -0.4064)
			(end 0.7874 -0.4064)
			(stroke
				(width 0.1524)
				(type default)
			)
			(layer "F.SilkS")
		)
		(fp_poly
			(pts
				(xy -0.5334 0.254) (xy -0.635 0.254) (xy -0.635 0.2286) (xy -0.635 -0.254) (xy -0.5334 -0.254) (xy -0.5334 -0.2794)
				(xy 0.5334 -0.2794) (xy 0.5334 -0.254) (xy 0.635 -0.254) (xy 0.635 0.254) (xy 0.5334 0.254) (xy 0.5334 0.2794)
				(xy -0.508 0.2794) (xy -0.5334 0.2794)
			)
			(stroke
				(width 0)
				(type default)
			)
			(fill no)
			(layer "F.CrtYd")
		)
		(pad "1" smd rect
			(at 0.40005 0 180)
			(size 0.4572 0.508)
			(layers "F.Cu" "F.Mask" "F.Paste")
			(net "GND")
		)
		(pad "2" smd rect
			(at -0.40005 0 180)
			(size 0.4572 0.508)
			(layers "F.Cu" "F.Mask" "F.Paste")
			(net "RST_BTN_L")
		)
	)
	(footprint ""
		(layer "F.Cu")
		(at 44.702222 -106.475784 90)
		(property "Reference" "PR6"
			(at -2.327148 -3.184144 90)
			(unlocked yes)
			(layer "F.SilkS")
			(effects
				(font
					(size 0.7874 0.5842)
					(thickness 0.1524)
				)
				(justify left)
			)
		)
		(property "Value" ""
			(at 0 0 90)
			(layer "F.Fab")
			(effects
				(font
					(size 1.27 1.27)
				)
			)
		)
		(duplicate_pad_numbers_are_jumpers no)
		(fp_line
			(start 0.7874 -0.4064)
			(end 0.7874 0.4064)
			(stroke
				(width 0.1524)
				(type default)
			)
			(layer "F.SilkS")
		)
		(fp_line
			(start -0.7874 -0.4064)
			(end 0.7874 -0.4064)
			(stroke
				(width 0.1524)
				(type default)
			)
			(layer "F.SilkS")
		)
		(fp_line
			(start 0.7874 0.4064)
			(end -0.7874 0.4064)
			(stroke
				(width 0.1524)
				(type default)
			)
			(layer "F.SilkS")
		)
		(fp_line
			(start -0.7874 0.4064)
			(end -0.7874 -0.4064)
			(stroke
				(width 0.1524)
				(type default)
			)
			(layer "F.SilkS")
		)
		(fp_poly
			(pts
				(xy -0.508 0.2794) (xy -0.508 0.2286) (xy -0.635 0.2286) (xy -0.635 -0.254) (xy -0.5334 -0.254)
				(xy -0.5334 -0.2794) (xy 0.5334 -0.2794) (xy 0.5334 -0.254) (xy 0.635 -0.254) (xy 0.635 0.254) (xy 0.5334 0.254)
				(xy 0.5334 0.2794)
			)
			(stroke
				(width 0)
				(type default)
			)
			(fill no)
			(layer "F.CrtYd")
		)
		(pad "1" smd rect
			(at 0.40005 0 90)
			(size 0.4572 0.508)
			(layers "F.Cu" "F.Mask" "F.Paste")
			(net "PWRGD_NODE1_P3V3_STB_PG")
		)
		(pad "2" smd rect
			(at -0.40005 0 90)
			(size 0.4572 0.508)
			(layers "F.Cu" "F.Mask" "F.Paste")
			(net "GND")
		)
	)
	(footprint ""
		(layer "F.Cu")
		(at 169.77868 -61.181742 90)
		(property "Reference" "L45"
			(at 1.256792 -0.940308 90)
			(unlocked yes)
			(layer "F.SilkS")
			(effects
				(font
					(size 0.7874 0.5842)
					(thickness 0.1524)
				)
				(justify left)
			)
		)
		(property "Value" ""
			(at 0 0 90)
			(layer "F.Fab")
			(effects
				(font
					(size 1.27 1.27)
				)
			)
		)
		(duplicate_pad_numbers_are_jumpers no)
		(fp_line
			(start 0.989838 -2.0066)
			(end 0.989838 2.0066)
			(stroke
				(width 0.1524)
				(type default)
			)
			(layer "F.SilkS")
		)
		(fp_line
			(start -1.015238 -2.0066)
			(end 0.989838 -2.0066)
			(stroke
				(width 0.1524)
				(type default)
			)
			(layer "F.SilkS")
		)
		(fp_line
			(start 0.989838 2.0066)
			(end -1.015238 2.0066)
			(stroke
				(width 0.1524)
				(type default)
			)
			(layer "F.SilkS")
		)
		(fp_line
			(start -1.015238 2.0066)
			(end -1.015238 -2.0066)
			(stroke
				(width 0.1524)
				(type default)
			)
			(layer "F.SilkS")
		)
		(fp_poly
			(pts
				(xy -0.899922 -1.700022) (xy -0.899922 1.700022) (xy -0.8636 1.700022) (xy -0.8636 1.9304) (xy -0.127 1.9304)
				(xy -0.127 1.700022) (xy 0.127 1.700022) (xy 0.127 1.9304) (xy 0.8636 1.9304) (xy 0.8636 1.700022)
				(xy 0.899922 1.700022) (xy 0.899922 -1.700022) (xy 0.8636 -1.700022) (xy 0.8636 -1.9304) (xy 0.127 -1.9304)
				(xy 0.127 -1.700022) (xy -0.127 -1.700022) (xy -0.127 -1.9304) (xy -0.8636 -1.9304) (xy -0.8636 -1.700022)
			)
			(stroke
				(width 0)
				(type default)
			)
			(fill no)
			(layer "F.CrtYd")
		)
		(fp_line
			(start 0.899922 -1.700022)
			(end 0.899922 1.700022)
			(stroke
				(width 0.1)
				(type default)
			)
			(layer "F.Fab")
		)
		(fp_line
			(start -0.899922 -1.700022)
			(end 0.899922 -1.700022)
			(stroke
				(width 0.1)
				(type default)
			)
			(layer "F.Fab")
		)
		(fp_line
			(start 0.899922 1.700022)
			(end -0.899922 1.700022)
			(stroke
				(width 0.1)
				(type default)
			)
			(layer "F.Fab")
		)
		(fp_line
			(start -0.899922 1.700022)
			(end -0.899922 -1.700022)
			(stroke
				(width 0.1)
				(type default)
			)
			(layer "F.Fab")
		)
		(pad "1" smd rect
			(at -0.499872 -1.400048 90)
			(size 0.6096 0.9144)
			(layers "F.Cu" "F.Mask" "F.Paste")
			(net "USB3_DN")
		)
		(pad "2" smd rect
			(at -0.499872 1.400048 90)
			(size 0.6096 0.9144)
			(layers "F.Cu" "F.Mask" "F.Paste")
			(net "USB3_L_DN")
		)
		(pad "3" smd rect
			(at 0.499872 1.400048 90)
			(size 0.6096 0.9144)
			(layers "F.Cu" "F.Mask" "F.Paste")
			(net "USB3_L_DP")
		)
		(pad "4" smd rect
			(at 0.499872 -1.400048 90)
			(size 0.6096 0.9144)
			(layers "F.Cu" "F.Mask" "F.Paste")
			(net "USB3_DP")
		)
	)
	(footprint ""
		(layer "F.Cu")
		(at 38.379654 -112.650016 -90)
		(property "Reference" "R1118"
			(at 4.552696 0.892048 90)
			(unlocked yes)
			(layer "F.SilkS")
			(effects
				(font
					(size 0.7874 0.5842)
					(thickness 0.1524)
				)
				(justify left)
			)
		)
		(property "Value" ""
			(at 0 0 270)
			(layer "F.Fab")
			(effects
				(font
					(size 1.27 1.27)
				)
			)
		)
		(duplicate_pad_numbers_are_jumpers no)
		(fp_line
			(start -0.7874 0.4064)
			(end -0.7874 -0.4064)
			(stroke
				(width 0.1524)
				(type default)
			)
			(layer "F.SilkS")
		)
		(fp_line
			(start 0.7874 0.4064)
			(end -0.7874 0.4064)
			(stroke
				(width 0.1524)
				(type default)
			)
			(layer "F.SilkS")
		)
		(fp_line
			(start -0.7874 -0.4064)
			(end 0.7874 -0.4064)
			(stroke
				(width 0.1524)
				(type default)
			)
			(layer "F.SilkS")
		)
		(fp_line
			(start 0.7874 -0.4064)
			(end 0.7874 0.4064)
			(stroke
				(width 0.1524)
				(type default)
			)
			(layer "F.SilkS")
		)
		(fp_poly
			(pts
				(xy -0.508 0.2794) (xy -0.508 0.2286) (xy -0.635 0.2286) (xy -0.635 -0.254) (xy -0.5334 -0.254)
				(xy -0.5334 -0.2794) (xy 0.5334 -0.2794) (xy 0.5334 -0.254) (xy 0.635 -0.254) (xy 0.635 0.254) (xy 0.5334 0.254)
				(xy 0.5334 0.2794)
			)
			(stroke
				(width 0)
				(type default)
			)
			(fill no)
			(layer "F.CrtYd")
		)
		(pad "1" smd rect
			(at 0.40005 0 270)
			(size 0.4572 0.508)
			(layers "F.Cu" "F.Mask" "F.Paste")
			(net "GND")
		)
		(pad "2" smd rect
			(at -0.40005 0 270)
			(size 0.4572 0.508)
			(layers "F.Cu" "F.Mask" "F.Paste")
			(net "P1V5_NODE1")
		)
	)
	(footprint ""
		(layer "F.Cu")
		(at 71.888604 -9.343898 180)
		(property "Reference" "PC44"
			(at -3.495548 0.070104 0)
			(unlocked yes)
			(layer "F.SilkS")
			(effects
				(font
					(size 0.7874 0.5842)
					(thickness 0.1524)
				)
				(justify left)
			)
		)
		(property "Value" ""
			(at 0 0 180)
			(layer "F.Fab")
			(effects
				(font
					(size 1.27 1.27)
				)
			)
		)
		(duplicate_pad_numbers_are_jumpers no)
		(fp_line
			(start 0.7874 0.4064)
			(end -0.7874 0.4064)
			(stroke
				(width 0.1524)
				(type default)
			)
			(layer "F.SilkS")
		)
		(fp_line
			(start 0.7874 -0.4064)
			(end 0.7874 0.4064)
			(stroke
				(width 0.1524)
				(type default)
			)
			(layer "F.SilkS")
		)
		(fp_line
			(start 0 0.381)
			(end 0 -0.381)
			(stroke
				(width 0.1524)
				(type default)
			)
			(layer "F.SilkS")
		)
		(fp_line
			(start -0.7874 0.4064)
			(end -0.7874 -0.4064)
			(stroke
				(width 0.1524)
				(type default)
			)
			(layer "F.SilkS")
		)
		(fp_line
			(start -0.7874 -0.4064)
			(end 0.7874 -0.4064)
			(stroke
				(width 0.1524)
				(type default)
			)
			(layer "F.SilkS")
		)
		(fp_poly
			(pts
				(xy -0.5334 0.254) (xy -0.635 0.254) (xy -0.635 0.2286) (xy -0.635 -0.254) (xy -0.5334 -0.254) (xy -0.5334 -0.2794)
				(xy 0.5334 -0.2794) (xy 0.5334 -0.254) (xy 0.635 -0.254) (xy 0.635 0.254) (xy 0.5334 0.254) (xy 0.5334 0.2794)
				(xy -0.508 0.2794) (xy -0.5334 0.2794)
			)
			(stroke
				(width 0)
				(type default)
			)
			(fill no)
			(layer "F.CrtYd")
		)
		(pad "1" smd rect
			(at 0.40005 0 180)
			(size 0.4572 0.508)
			(layers "F.Cu" "F.Mask" "F.Paste")
			(net "P12V_AUX")
		)
		(pad "2" smd rect
			(at -0.40005 0 180)
			(size 0.4572 0.508)
			(layers "F.Cu" "F.Mask" "F.Paste")
			(net "GND")
		)
	)
	(footprint ""
		(layer "F.Cu")
		(at 90.753692 -160.942528 180)
		(property "Reference" "U104"
			(at -87.894414 -71.801228 90)
			(unlocked yes)
			(layer "F.SilkS")
			(effects
				(font
					(size 0.7874 0.5842)
					(thickness 0.1524)
				)
			)
		)
		(property "Value" ""
			(at 0 0 180)
			(layer "F.Fab")
			(effects
				(font
					(size 1.27 1.27)
				)
			)
		)
		(duplicate_pad_numbers_are_jumpers no)
		(fp_line
			(start 1.651 1.905)
			(end -1.651 1.905)
			(stroke
				(width 0.1524)
				(type default)
			)
			(layer "F.SilkS")
		)
		(fp_line
			(start 1.651 -1.905)
			(end 1.651 1.905)
			(stroke
				(width 0.1524)
				(type default)
			)
			(layer "F.SilkS")
		)
		(fp_line
			(start -1.651 1.905)
			(end -1.651 -1.905)
			(stroke
				(width 0.1524)
				(type default)
			)
			(layer "F.SilkS")
		)
		(fp_line
			(start -1.651 -1.905)
			(end 1.651 -1.905)
			(stroke
				(width 0.1524)
				(type default)
			)
			(layer "F.SilkS")
		)
		(fp_poly
			(pts
				(xy -1.524 0.7112) (xy -1.524 1.7526) (xy -0.508 1.7526) (xy -0.508 0.6985) (xy 0.508 0.6985) (xy 0.508 1.7526)
				(xy 1.524 1.7526) (xy 1.524 0.6985) (xy 1.524 -0.6985) (xy 0.508 -0.6985) (xy 0.508 -1.7526) (xy -0.508 -1.7526)
				(xy -0.508 -0.6985) (xy -1.524 -0.6985) (xy -1.524 0.6985)
			)
			(stroke
				(width 0)
				(type default)
			)
			(fill no)
			(layer "F.CrtYd")
		)
		(fp_text user "S"
			(at 1.998726 1.213358 0)
			(unlocked yes)
			(layer "F.SilkS")
			(effects
				(font
					(size 0.635 0.4064)
					(thickness 0.1524)
				)
			)
		)
		(fp_text user "D"
			(at 1.92913 -0.415544 0)
			(unlocked yes)
			(layer "F.SilkS")
			(effects
				(font
					(size 0.635 0.4064)
					(thickness 0.1524)
				)
			)
		)
		(fp_text user "G"
			(at -1.477264 2.459228 0)
			(unlocked yes)
			(layer "F.SilkS")
			(effects
				(font
					(size 0.635 0.4064)
					(thickness 0.1524)
				)
			)
		)
		(pad "D" smd rect
			(at 0 -1.1176 180)
			(size 1.016 1.27)
			(layers "F.Cu" "F.Mask" "F.Paste")
			(net "N52410998")
		)
		(pad "G" smd rect
			(at -1.016 1.1176 180)
			(size 1.016 1.27)
			(layers "F.Cu" "F.Mask" "F.Paste")
			(net "POWER_SW1_PWR_CTR_N")
		)
		(pad "S" smd rect
			(at 1.016 1.1176 180)
			(size 1.016 1.27)
			(layers "F.Cu" "F.Mask" "F.Paste")
			(net "GND")
		)
	)
	(footprint ""
		(layer "F.Cu")
		(at -71.458328 -265.390884)
		(property "Reference" "BT1_BATTERY1"
			(at 9.578848 0.097282 0)
			(unlocked yes)
			(layer "B.SilkS")
			(effects
				(font
					(size 0.7874 0.5842)
					(thickness 0.1524)
				)
				(justify left mirror)
			)
		)
		(property "Value" ""
			(at 0 0 0)
			(layer "F.Fab")
			(effects
				(font
					(size 1.27 1.27)
				)
			)
		)
		(duplicate_pad_numbers_are_jumpers no)
		(fp_poly
			(pts
				(arc
					(start 0.3302 0)
					(mid -0.3302 0)
					(end 0.3302 0)
				)
			)
			(stroke
				(width 0)
				(type default)
			)
			(fill no)
			(layer "B.CrtYd")
		)
		(pad "1" thru_hole circle
			(at 0 0)
			(size 0.508 0.508)
			(drill 0.254)
			(layers "*.Cu" "*.Mask")
			(remove_unused_layers no)
			(net "Net_1677")
			(clearance 0.127)
			(thermal_gap 0.127)
			(padstack
				(mode front_inner_back)
				(layer "Inner"
					(shape circle)
					(size 0.508 0.508)
					(clearance 0.127)
				)
				(layer "B.Cu"
					(shape circle)
					(size 0.6604 0.6604)
					(clearance 0.0508)
				)
			)
		)
	)
	(footprint ""
		(layer "F.Cu")
		(at 41.316402 -145.804382 -90)
		(property "Reference" "R550"
			(at 0.86106 6.618732 90)
			(unlocked yes)
			(layer "F.SilkS")
			(effects
				(font
					(size 0.7874 0.5842)
					(thickness 0.1524)
				)
				(justify left)
			)
		)
		(property "Value" ""
			(at 0 0 270)
			(layer "F.Fab")
			(effects
				(font
					(size 1.27 1.27)
				)
			)
		)
		(duplicate_pad_numbers_are_jumpers no)
		(fp_line
			(start -0.7874 0.4064)
			(end -0.7874 -0.4064)
			(stroke
				(width 0.1524)
				(type default)
			)
			(layer "F.SilkS")
		)
		(fp_line
			(start 0.7874 0.4064)
			(end -0.7874 0.4064)
			(stroke
				(width 0.1524)
				(type default)
			)
			(layer "F.SilkS")
		)
		(fp_line
			(start -0.7874 -0.4064)
			(end 0.7874 -0.4064)
			(stroke
				(width 0.1524)
				(type default)
			)
			(layer "F.SilkS")
		)
		(fp_line
			(start 0.7874 -0.4064)
			(end 0.7874 0.4064)
			(stroke
				(width 0.1524)
				(type default)
			)
			(layer "F.SilkS")
		)
		(fp_poly
			(pts
				(xy -0.508 0.2794) (xy -0.508 0.2286) (xy -0.635 0.2286) (xy -0.635 -0.254) (xy -0.5334 -0.254)
				(xy -0.5334 -0.2794) (xy 0.5334 -0.2794) (xy 0.5334 -0.254) (xy 0.635 -0.254) (xy 0.635 0.254) (xy 0.5334 0.254)
				(xy 0.5334 0.2794)
			)
			(stroke
				(width 0)
				(type default)
			)
			(fill no)
			(layer "F.CrtYd")
		)
		(pad "1" smd rect
			(at 0.40005 0 270)
			(size 0.4572 0.508)
			(layers "F.Cu" "F.Mask" "F.Paste")
			(net "P3V3_NODE1")
		)
		(pad "2" smd rect
			(at -0.40005 0 270)
			(size 0.4572 0.508)
			(layers "F.Cu" "F.Mask" "F.Paste")
			(net "LAN1_NC_SI_RXD1")
		)
	)
	(footprint ""
		(layer "F.Cu")
		(at 68.594732 -9.513062)
		(property "Reference" "PC46"
			(at 0.119634 -1.117092 90)
			(unlocked yes)
			(layer "F.SilkS")
			(effects
				(font
					(size 0.7874 0.5842)
					(thickness 0.1524)
				)
				(justify left)
			)
		)
		(property "Value" ""
			(at 0 0 0)
			(layer "F.Fab")
			(effects
				(font
					(size 1.27 1.27)
				)
			)
		)
		(duplicate_pad_numbers_are_jumpers no)
		(fp_line
			(start -0.7874 -0.4064)
			(end 0.7874 -0.4064)
			(stroke
				(width 0.1524)
				(type default)
			)
			(layer "F.SilkS")
		)
		(fp_line
			(start -0.7874 0.4064)
			(end -0.7874 -0.4064)
			(stroke
				(width 0.1524)
				(type default)
			)
			(layer "F.SilkS")
		)
		(fp_line
			(start 0 0.381)
			(end 0 -0.381)
			(stroke
				(width 0.1524)
				(type default)
			)
			(layer "F.SilkS")
		)
		(fp_line
			(start 0.7874 -0.4064)
			(end 0.7874 0.4064)
			(stroke
				(width 0.1524)
				(type default)
			)
			(layer "F.SilkS")
		)
		(fp_line
			(start 0.7874 0.4064)
			(end -0.7874 0.4064)
			(stroke
				(width 0.1524)
				(type default)
			)
			(layer "F.SilkS")
		)
		(fp_poly
			(pts
				(xy -0.5334 0.254) (xy -0.635 0.254) (xy -0.635 0.2286) (xy -0.635 -0.254) (xy -0.5334 -0.254) (xy -0.5334 -0.2794)
				(xy 0.5334 -0.2794) (xy 0.5334 -0.254) (xy 0.635 -0.254) (xy 0.635 0.254) (xy 0.5334 0.254) (xy 0.5334 0.2794)
				(xy -0.508 0.2794) (xy -0.5334 0.2794)
			)
			(stroke
				(width 0)
				(type default)
			)
			(fill no)
			(layer "F.CrtYd")
		)
		(pad "1" smd rect
			(at 0.40005 0)
			(size 0.4572 0.508)
			(layers "F.Cu" "F.Mask" "F.Paste")
			(net "P5V_STB_NODE1")
		)
		(pad "2" smd rect
			(at -0.40005 0)
			(size 0.4572 0.508)
			(layers "F.Cu" "F.Mask" "F.Paste")
			(net "GND")
		)
	)
	(footprint ""
		(layer "F.Cu")
		(at 14.885416 -65.290446)
		(property "Reference" "C508"
			(at -2.683256 -1.039368 0)
			(unlocked yes)
			(layer "F.SilkS")
			(effects
				(font
					(size 0.7874 0.5842)
					(thickness 0.1524)
				)
				(justify left)
			)
		)
		(property "Value" ""
			(at 0 0 0)
			(layer "F.Fab")
			(effects
				(font
					(size 1.27 1.27)
				)
			)
		)
		(duplicate_pad_numbers_are_jumpers no)
		(fp_line
			(start -0.7874 -0.4064)
			(end 0.7874 -0.4064)
			(stroke
				(width 0.1524)
				(type default)
			)
			(layer "F.SilkS")
		)
		(fp_line
			(start -0.7874 0.4064)
			(end -0.7874 -0.4064)
			(stroke
				(width 0.1524)
				(type default)
			)
			(layer "F.SilkS")
		)
		(fp_line
			(start 0 0.381)
			(end 0 -0.381)
			(stroke
				(width 0.1524)
				(type default)
			)
			(layer "F.SilkS")
		)
		(fp_line
			(start 0.7874 -0.4064)
			(end 0.7874 0.4064)
			(stroke
				(width 0.1524)
				(type default)
			)
			(layer "F.SilkS")
		)
		(fp_line
			(start 0.7874 0.4064)
			(end -0.7874 0.4064)
			(stroke
				(width 0.1524)
				(type default)
			)
			(layer "F.SilkS")
		)
		(fp_poly
			(pts
				(xy -0.5334 0.254) (xy -0.635 0.254) (xy -0.635 0.2286) (xy -0.635 -0.254) (xy -0.5334 -0.254) (xy -0.5334 -0.2794)
				(xy 0.5334 -0.2794) (xy 0.5334 -0.254) (xy 0.635 -0.254) (xy 0.635 0.254) (xy 0.5334 0.254) (xy 0.5334 0.2794)
				(xy -0.508 0.2794) (xy -0.5334 0.2794)
			)
			(stroke
				(width 0)
				(type default)
			)
			(fill no)
			(layer "F.CrtYd")
		)
		(pad "1" smd rect
			(at 0.40005 0)
			(size 0.4572 0.508)
			(layers "F.Cu" "F.Mask" "F.Paste")
			(net "CRT_DDCCLK")
		)
		(pad "2" smd rect
			(at -0.40005 0)
			(size 0.4572 0.508)
			(layers "F.Cu" "F.Mask" "F.Paste")
			(net "GND")
		)
	)
	(footprint ""
		(layer "F.Cu")
		(at 87.617554 -78.416658)
		(property "Reference" "L4"
			(at 2.681986 0.21717 0)
			(unlocked yes)
			(layer "F.SilkS")
			(effects
				(font
					(size 0.7874 0.5842)
					(thickness 0.1524)
				)
				(justify left)
			)
		)
		(property "Value" ""
			(at 0 0 0)
			(layer "F.Fab")
			(effects
				(font
					(size 1.27 1.27)
				)
			)
		)
		(duplicate_pad_numbers_are_jumpers no)
		(fp_line
			(start -0.7874 -0.4064)
			(end 0.7874 -0.4064)
			(stroke
				(width 0.1524)
				(type default)
			)
			(layer "F.SilkS")
		)
		(fp_line
			(start -0.7874 0.4064)
			(end -0.7874 -0.4064)
			(stroke
				(width 0.1524)
				(type default)
			)
			(layer "F.SilkS")
		)
		(fp_line
			(start -0.0889 0.4064)
			(end -0.0889 -0.4064)
			(stroke
				(width 0.1524)
				(type default)
			)
			(layer "F.SilkS")
		)
		(fp_line
			(start 0.0889 0.4064)
			(end 0.0889 -0.4064)
			(stroke
				(width 0.1524)
				(type default)
			)
			(layer "F.SilkS")
		)
		(fp_line
			(start 0.7874 -0.4064)
			(end 0.7874 0.4064)
			(stroke
				(width 0.1524)
				(type default)
			)
			(layer "F.SilkS")
		)
		(fp_line
			(start 0.7874 0.4064)
			(end -0.7874 0.4064)
			(stroke
				(width 0.1524)
				(type default)
			)
			(layer "F.SilkS")
		)
		(fp_poly
			(pts
				(xy -0.5334 0.254) (xy -0.635 0.254) (xy -0.635 0.2286) (xy -0.635 -0.254) (xy -0.5334 -0.254) (xy -0.5334 -0.2794)
				(xy 0.5334 -0.2794) (xy 0.5334 -0.254) (xy 0.635 -0.254) (xy 0.635 0.254) (xy 0.5334 0.254) (xy 0.5334 0.2794)
				(xy -0.508 0.2794) (xy -0.5334 0.2794)
			)
			(stroke
				(width 0)
				(type default)
			)
			(fill no)
			(layer "F.CrtYd")
		)
		(pad "1" smd rect
			(at 0.40005 0)
			(size 0.4572 0.508)
			(layers "F.Cu" "F.Mask" "F.Paste")
			(net "P1V05_NODE1")
		)
		(pad "2" smd rect
			(at -0.40005 0)
			(size 0.4572 0.508)
			(layers "F.Cu" "F.Mask" "F.Paste")
			(net "P1V05_VCCPLLCPU0SIO_NODE1")
		)
	)
	(footprint ""
		(layer "F.Cu")
		(at 15.88516 -41.795192)
		(property "Reference" "C499"
			(at -0.470916 7.61111 0)
			(unlocked yes)
			(layer "F.SilkS")
			(effects
				(font
					(size 0.7874 0.5842)
					(thickness 0.1524)
				)
			)
		)
		(property "Value" ""
			(at 0 0 0)
			(layer "F.Fab")
			(effects
				(font
					(size 1.27 1.27)
				)
			)
		)
		(duplicate_pad_numbers_are_jumpers no)
		(fp_line
			(start -1.2954 -0.5842)
			(end 1.2954 -0.5842)
			(stroke
				(width 0.1524)
				(type default)
			)
			(layer "F.SilkS")
		)
		(fp_line
			(start -1.2954 0.5842)
			(end -1.2954 -0.5842)
			(stroke
				(width 0.1524)
				(type default)
			)
			(layer "F.SilkS")
		)
		(fp_line
			(start 0 -0.5842)
			(end 0 0.5842)
			(stroke
				(width 0.1524)
				(type default)
			)
			(layer "F.SilkS")
		)
		(fp_line
			(start 1.2954 -0.5842)
			(end 1.2954 0.5842)
			(stroke
				(width 0.1524)
				(type default)
			)
			(layer "F.SilkS")
		)
		(fp_line
			(start 1.2954 0.5842)
			(end -1.2954 0.5842)
			(stroke
				(width 0.1524)
				(type default)
			)
			(layer "F.SilkS")
		)
		(fp_poly
			(pts
				(xy 0.8636 -0.4572) (xy 0.8636 -0.3556) (xy 1.143 -0.3556) (xy 1.143 0.3556) (xy 0.8636 0.3556)
				(xy 0.8636 0.4572) (xy -0.8636 0.4572) (xy -0.8636 0.3556) (xy -1.143 0.3556) (xy -1.143 -0.3556)
				(xy -0.8636 -0.3556) (xy -0.8636 -0.4572)
			)
			(stroke
				(width 0)
				(type default)
			)
			(fill no)
			(layer "F.CrtYd")
		)
		(fp_line
			(start -0.884936 -0.504952)
			(end 0.884936 -0.504952)
			(stroke
				(width 0.1)
				(type default)
			)
			(layer "F.Fab")
		)
		(fp_line
			(start -0.884936 0.504952)
			(end -0.884936 -0.504952)
			(stroke
				(width 0.1)
				(type default)
			)
			(layer "F.Fab")
		)
		(fp_line
			(start 0.884936 -0.504952)
			(end 0.884936 0.504952)
			(stroke
				(width 0.1)
				(type default)
			)
			(layer "F.Fab")
		)
		(fp_line
			(start 0.884936 0.504952)
			(end -0.884936 0.504952)
			(stroke
				(width 0.1)
				(type default)
			)
			(layer "F.Fab")
		)
		(pad "1" smd rect
			(at 0.7366 0 90)
			(size 0.7112 0.8128)
			(layers "F.Cu" "F.Mask" "F.Paste")
			(net "BMC_NODE1_GFX_RED")
		)
		(pad "2" smd rect
			(at -0.7366 0 90)
			(size 0.7112 0.8128)
			(layers "F.Cu" "F.Mask" "F.Paste")
			(net "GND")
		)
	)
	(footprint ""
		(layer "F.Cu")
		(at 73.39076 -185.205624 90)
		(property "Reference" "C707"
			(at 4.006088 -1.175258 90)
			(unlocked yes)
			(layer "F.SilkS")
			(effects
				(font
					(size 0.7874 0.5842)
					(thickness 0.1524)
				)
				(justify left)
			)
		)
		(property "Value" ""
			(at 0 0 90)
			(layer "F.Fab")
			(effects
				(font
					(size 1.27 1.27)
				)
			)
		)
		(duplicate_pad_numbers_are_jumpers no)
		(fp_line
			(start 0.7874 -0.4064)
			(end 0.7874 0.4064)
			(stroke
				(width 0.1524)
				(type default)
			)
			(layer "F.SilkS")
		)
		(fp_line
			(start -0.7874 -0.4064)
			(end 0.7874 -0.4064)
			(stroke
				(width 0.1524)
				(type default)
			)
			(layer "F.SilkS")
		)
		(fp_line
			(start 0 0.381)
			(end 0 -0.381)
			(stroke
				(width 0.1524)
				(type default)
			)
			(layer "F.SilkS")
		)
		(fp_line
			(start 0.7874 0.4064)
			(end -0.7874 0.4064)
			(stroke
				(width 0.1524)
				(type default)
			)
			(layer "F.SilkS")
		)
		(fp_line
			(start -0.7874 0.4064)
			(end -0.7874 -0.4064)
			(stroke
				(width 0.1524)
				(type default)
			)
			(layer "F.SilkS")
		)
		(fp_poly
			(pts
				(xy -0.5334 0.254) (xy -0.635 0.254) (xy -0.635 0.2286) (xy -0.635 -0.254) (xy -0.5334 -0.254) (xy -0.5334 -0.2794)
				(xy 0.5334 -0.2794) (xy 0.5334 -0.254) (xy 0.635 -0.254) (xy 0.635 0.254) (xy 0.5334 0.254) (xy 0.5334 0.2794)
				(xy -0.508 0.2794) (xy -0.5334 0.2794)
			)
			(stroke
				(width 0)
				(type default)
			)
			(fill no)
			(layer "F.CrtYd")
		)
		(pad "1" smd rect
			(at 0.40005 0 90)
			(size 0.4572 0.508)
			(layers "F.Cu" "F.Mask" "F.Paste")
			(net "UART_T4_NODE3_RXD")
		)
		(pad "2" smd rect
			(at -0.40005 0 90)
			(size 0.4572 0.508)
			(layers "F.Cu" "F.Mask" "F.Paste")
			(net "GND")
		)
	)
	(footprint ""
		(layer "F.Cu")
		(at 98.354134 -135.340852 90)
		(property "Reference" "C814"
			(at -2.155952 1.137412 90)
			(unlocked yes)
			(layer "F.SilkS")
			(effects
				(font
					(size 0.7874 0.5842)
					(thickness 0.1524)
				)
				(justify left)
			)
		)
		(property "Value" ""
			(at 0 0 90)
			(layer "F.Fab")
			(effects
				(font
					(size 1.27 1.27)
				)
			)
		)
		(duplicate_pad_numbers_are_jumpers no)
		(fp_line
			(start 0.7874 -0.4064)
			(end 0.7874 0.4064)
			(stroke
				(width 0.1524)
				(type default)
			)
			(layer "F.SilkS")
		)
		(fp_line
			(start -0.7874 -0.4064)
			(end 0.7874 -0.4064)
			(stroke
				(width 0.1524)
				(type default)
			)
			(layer "F.SilkS")
		)
		(fp_line
			(start 0 0.381)
			(end 0 -0.381)
			(stroke
				(width 0.1524)
				(type default)
			)
			(layer "F.SilkS")
		)
		(fp_line
			(start 0.7874 0.4064)
			(end -0.7874 0.4064)
			(stroke
				(width 0.1524)
				(type default)
			)
			(layer "F.SilkS")
		)
		(fp_line
			(start -0.7874 0.4064)
			(end -0.7874 -0.4064)
			(stroke
				(width 0.1524)
				(type default)
			)
			(layer "F.SilkS")
		)
		(fp_poly
			(pts
				(xy -0.5334 0.254) (xy -0.635 0.254) (xy -0.635 0.2286) (xy -0.635 -0.254) (xy -0.5334 -0.254) (xy -0.5334 -0.2794)
				(xy 0.5334 -0.2794) (xy 0.5334 -0.254) (xy 0.635 -0.254) (xy 0.635 0.254) (xy 0.5334 0.254) (xy 0.5334 0.2794)
				(xy -0.508 0.2794) (xy -0.5334 0.2794)
			)
			(stroke
				(width 0)
				(type default)
			)
			(fill no)
			(layer "F.CrtYd")
		)
		(pad "1" smd rect
			(at 0.40005 0 90)
			(size 0.4572 0.508)
			(layers "F.Cu" "F.Mask" "F.Paste")
			(net "P1V05_SUS_NODE1")
		)
		(pad "2" smd rect
			(at -0.40005 0 90)
			(size 0.4572 0.508)
			(layers "F.Cu" "F.Mask" "F.Paste")
			(net "GND")
		)
	)
	(footprint ""
		(layer "F.Cu")
		(at 128.25476 -185.205624 90)
		(property "Reference" "C761"
			(at 4.731258 0.173482 90)
			(unlocked yes)
			(layer "F.SilkS")
			(effects
				(font
					(size 0.7874 0.5842)
					(thickness 0.1524)
				)
				(justify left)
			)
		)
		(property "Value" ""
			(at 0 0 90)
			(layer "F.Fab")
			(effects
				(font
					(size 1.27 1.27)
				)
			)
		)
		(duplicate_pad_numbers_are_jumpers no)
		(fp_line
			(start 0.7874 -0.4064)
			(end 0.7874 0.4064)
			(stroke
				(width 0.1524)
				(type default)
			)
			(layer "F.SilkS")
		)
		(fp_line
			(start -0.7874 -0.4064)
			(end 0.7874 -0.4064)
			(stroke
				(width 0.1524)
				(type default)
			)
			(layer "F.SilkS")
		)
		(fp_line
			(start 0 0.381)
			(end 0 -0.381)
			(stroke
				(width 0.1524)
				(type default)
			)
			(layer "F.SilkS")
		)
		(fp_line
			(start 0.7874 0.4064)
			(end -0.7874 0.4064)
			(stroke
				(width 0.1524)
				(type default)
			)
			(layer "F.SilkS")
		)
		(fp_line
			(start -0.7874 0.4064)
			(end -0.7874 -0.4064)
			(stroke
				(width 0.1524)
				(type default)
			)
			(layer "F.SilkS")
		)
		(fp_poly
			(pts
				(xy -0.5334 0.254) (xy -0.635 0.254) (xy -0.635 0.2286) (xy -0.635 -0.254) (xy -0.5334 -0.254) (xy -0.5334 -0.2794)
				(xy 0.5334 -0.2794) (xy 0.5334 -0.254) (xy 0.635 -0.254) (xy 0.635 0.254) (xy 0.5334 0.254) (xy 0.5334 0.2794)
				(xy -0.508 0.2794) (xy -0.5334 0.2794)
			)
			(stroke
				(width 0)
				(type default)
			)
			(fill no)
			(layer "F.CrtYd")
		)
		(pad "1" smd rect
			(at 0.40005 0 90)
			(size 0.4572 0.508)
			(layers "F.Cu" "F.Mask" "F.Paste")
			(net "UART_T10_NODE4_RXD")
		)
		(pad "2" smd rect
			(at -0.40005 0 90)
			(size 0.4572 0.508)
			(layers "F.Cu" "F.Mask" "F.Paste")
			(net "GND")
		)
	)
	(footprint ""
		(layer "F.Cu")
		(at 46.573694 -102.399084 90)
		(property "Reference" "R199"
			(at -2.351532 -2.51841 90)
			(unlocked yes)
			(layer "F.SilkS")
			(effects
				(font
					(size 0.7874 0.5842)
					(thickness 0.1524)
				)
				(justify left)
			)
		)
		(property "Value" ""
			(at 0 0 90)
			(layer "F.Fab")
			(effects
				(font
					(size 1.27 1.27)
				)
			)
		)
		(duplicate_pad_numbers_are_jumpers no)
		(fp_line
			(start 0.7874 -0.4064)
			(end 0.7874 0.4064)
			(stroke
				(width 0.1524)
				(type default)
			)
			(layer "F.SilkS")
		)
		(fp_line
			(start -0.7874 -0.4064)
			(end 0.7874 -0.4064)
			(stroke
				(width 0.1524)
				(type default)
			)
			(layer "F.SilkS")
		)
		(fp_line
			(start 0.7874 0.4064)
			(end -0.7874 0.4064)
			(stroke
				(width 0.1524)
				(type default)
			)
			(layer "F.SilkS")
		)
		(fp_line
			(start -0.7874 0.4064)
			(end -0.7874 -0.4064)
			(stroke
				(width 0.1524)
				(type default)
			)
			(layer "F.SilkS")
		)
		(fp_poly
			(pts
				(xy -0.508 0.2794) (xy -0.508 0.2286) (xy -0.635 0.2286) (xy -0.635 -0.254) (xy -0.5334 -0.254)
				(xy -0.5334 -0.2794) (xy 0.5334 -0.2794) (xy 0.5334 -0.254) (xy 0.635 -0.254) (xy 0.635 0.254) (xy 0.5334 0.254)
				(xy 0.5334 0.2794)
			)
			(stroke
				(width 0)
				(type default)
			)
			(fill no)
			(layer "F.CrtYd")
		)
		(pad "1" smd rect
			(at 0.40005 0 90)
			(size 0.4572 0.508)
			(layers "F.Cu" "F.Mask" "F.Paste")
			(net "SMB_TEMP1_NODE1_ALERT_L")
		)
		(pad "2" smd rect
			(at -0.40005 0 90)
			(size 0.4572 0.508)
			(layers "F.Cu" "F.Mask" "F.Paste")
			(net "SMB_TEMP1_NODE1_ALERT_R_L")
		)
	)
	(footprint ""
		(layer "F.Cu")
		(at 139.236704 -71.254112)
		(property "Reference" "D5"
			(at -1.487932 -1.19634 0)
			(unlocked yes)
			(layer "F.SilkS")
			(effects
				(font
					(size 0.7874 0.5842)
					(thickness 0.1524)
				)
				(justify left)
			)
		)
		(property "Value" ""
			(at 0 0 0)
			(layer "F.Fab")
			(effects
				(font
					(size 1.27 1.27)
				)
			)
		)
		(duplicate_pad_numbers_are_jumpers no)
		(fp_line
			(start -1.3208 -0.5588)
			(end 1.3208 -0.5588)
			(stroke
				(width 0.1524)
				(type default)
			)
			(layer "F.SilkS")
		)
		(fp_line
			(start -1.3208 0.5588)
			(end -1.3208 -0.5588)
			(stroke
				(width 0.1524)
				(type default)
			)
			(layer "F.SilkS")
		)
		(fp_line
			(start 1.3208 -0.5588)
			(end 1.3208 0.5588)
			(stroke
				(width 0.1524)
				(type default)
			)
			(layer "F.SilkS")
		)
		(fp_line
			(start 1.3208 0.5588)
			(end -1.3208 0.5588)
			(stroke
				(width 0.1524)
				(type default)
			)
			(layer "F.SilkS")
		)
		(fp_line
			(start 1.4732 -0.5588)
			(end 1.4732 0.5588)
			(stroke
				(width 0.1524)
				(type default)
			)
			(layer "F.SilkS")
		)
		(fp_line
			(start 1.6256 0.5588)
			(end 1.6256 -0.5588)
			(stroke
				(width 0.1524)
				(type default)
			)
			(layer "F.SilkS")
		)
		(fp_line
			(start 1.778 -0.5588)
			(end 1.3208 -0.5588)
			(stroke
				(width 0.1524)
				(type default)
			)
			(layer "F.SilkS")
		)
		(fp_line
			(start 1.778 -0.5588)
			(end 1.778 0.5588)
			(stroke
				(width 0.1524)
				(type default)
			)
			(layer "F.SilkS")
		)
		(fp_line
			(start 1.778 0.5588)
			(end 1.3208 0.5588)
			(stroke
				(width 0.1524)
				(type default)
			)
			(layer "F.SilkS")
		)
		(fp_rect
			(start -1.1684 0.508)
			(end 1.1684 -0.508)
			(stroke
				(width 0)
				(type default)
			)
			(fill no)
			(layer "F.CrtYd")
		)
		(fp_text user "-"
			(at 2.606548 0.03937 0)
			(unlocked yes)
			(layer "F.SilkS")
			(effects
				(font
					(size 1.27 0.9652)
					(thickness 0.1524)
				)
				(justify left)
			)
		)
		(pad "A" smd rect
			(at -0.750062 0)
			(size 0.8128 0.8128)
			(layers "F.Cu" "F.Mask" "F.Paste")
			(net "LED_SATA_NODE1_R")
		)
		(pad "C" smd rect
			(at 0.750062 0)
			(size 0.8128 0.8128)
			(layers "F.Cu" "F.Mask" "F.Paste")
			(net "LED_SATA_NODE1_GPIO0")
		)
	)
	(footprint ""
		(layer "F.Cu")
		(at 43.551602 -165.971982)
		(property "Reference" "Y4"
			(at -4.964938 -0.075438 0)
			(unlocked yes)
			(layer "F.SilkS")
			(effects
				(font
					(size 0.7874 0.5842)
					(thickness 0.1524)
				)
				(justify left)
			)
		)
		(property "Value" ""
			(at 0 0 0)
			(layer "F.Fab")
			(effects
				(font
					(size 1.27 1.27)
				)
			)
		)
		(duplicate_pad_numbers_are_jumpers no)
		(fp_line
			(start -3.3528 -1.700022)
			(end 3.3528 -1.700022)
			(stroke
				(width 0.1524)
				(type default)
			)
			(layer "F.SilkS")
		)
		(fp_line
			(start -3.3528 1.700022)
			(end -3.3528 -1.700022)
			(stroke
				(width 0.1524)
				(type default)
			)
			(layer "F.SilkS")
		)
		(fp_line
			(start 3.3528 -1.700022)
			(end 3.3528 1.700022)
			(stroke
				(width 0.1524)
				(type default)
			)
			(layer "F.SilkS")
		)
		(fp_line
			(start 3.3528 1.700022)
			(end -3.3528 1.700022)
			(stroke
				(width 0.1524)
				(type default)
			)
			(layer "F.SilkS")
		)
		(fp_poly
			(pts
				(xy -2.599944 1.700022) (xy 2.599944 1.700022) (xy 2.599944 1.1176) (xy 3.2258 1.1176) (xy 3.2258 -1.1176)
				(xy 2.599944 -1.1176) (xy 2.599944 -1.700022) (xy -2.599944 -1.700022) (xy -2.599944 -1.1176) (xy -3.2258 -1.1176)
				(xy -3.2258 1.1176) (xy -2.599944 1.1176)
			)
			(stroke
				(width 0)
				(type default)
			)
			(fill no)
			(layer "F.CrtYd")
		)
		(fp_line
			(start -2.599944 -1.700022)
			(end 2.599944 -1.700022)
			(stroke
				(width 0.1)
				(type default)
			)
			(layer "F.Fab")
		)
		(fp_line
			(start -2.599944 1.700022)
			(end -2.599944 -1.700022)
			(stroke
				(width 0.1)
				(type default)
			)
			(layer "F.Fab")
		)
		(fp_line
			(start 2.599944 -1.700022)
			(end 2.599944 1.700022)
			(stroke
				(width 0.1)
				(type default)
			)
			(layer "F.Fab")
		)
		(fp_line
			(start 2.599944 1.700022)
			(end -2.599944 1.700022)
			(stroke
				(width 0.1)
				(type default)
			)
			(layer "F.Fab")
		)
		(pad "1" smd rect
			(at -2.100072 0)
			(size 2.2098 2.2098)
			(layers "F.Cu" "F.Mask" "F.Paste")
			(net "LAN1_XTAL_IN")
		)
		(pad "2" smd rect
			(at 2.100072 0)
			(size 2.2098 2.2098)
			(layers "F.Cu" "F.Mask" "F.Paste")
			(net "LAN1_XTAL_OUT")
		)
	)
	(footprint ""
		(layer "F.Cu")
		(at 176.90465 -55.084472 180)
		(property "Reference" "C560"
			(at 3.75666 2.276094 0)
			(unlocked yes)
			(layer "F.SilkS")
			(effects
				(font
					(size 0.7874 0.5842)
					(thickness 0.1524)
				)
				(justify left)
			)
		)
		(property "Value" ""
			(at 0 0 180)
			(layer "F.Fab")
			(effects
				(font
					(size 1.27 1.27)
				)
			)
		)
		(duplicate_pad_numbers_are_jumpers no)
		(fp_line
			(start 0.7874 0.4064)
			(end -0.7874 0.4064)
			(stroke
				(width 0.1524)
				(type default)
			)
			(layer "F.SilkS")
		)
		(fp_line
			(start 0.7874 -0.4064)
			(end 0.7874 0.4064)
			(stroke
				(width 0.1524)
				(type default)
			)
			(layer "F.SilkS")
		)
		(fp_line
			(start 0 0.381)
			(end 0 -0.381)
			(stroke
				(width 0.1524)
				(type default)
			)
			(layer "F.SilkS")
		)
		(fp_line
			(start -0.7874 0.4064)
			(end -0.7874 -0.4064)
			(stroke
				(width 0.1524)
				(type default)
			)
			(layer "F.SilkS")
		)
		(fp_line
			(start -0.7874 -0.4064)
			(end 0.7874 -0.4064)
			(stroke
				(width 0.1524)
				(type default)
			)
			(layer "F.SilkS")
		)
		(fp_poly
			(pts
				(xy -0.5334 0.254) (xy -0.635 0.254) (xy -0.635 0.2286) (xy -0.635 -0.254) (xy -0.5334 -0.254) (xy -0.5334 -0.2794)
				(xy 0.5334 -0.2794) (xy 0.5334 -0.254) (xy 0.635 -0.254) (xy 0.635 0.254) (xy 0.5334 0.254) (xy 0.5334 0.2794)
				(xy -0.508 0.2794) (xy -0.5334 0.2794)
			)
			(stroke
				(width 0)
				(type default)
			)
			(fill no)
			(layer "F.CrtYd")
		)
		(pad "1" smd rect
			(at 0.40005 0 180)
			(size 0.4572 0.508)
			(layers "F.Cu" "F.Mask" "F.Paste")
			(net "USBPWR_P1")
		)
		(pad "2" smd rect
			(at -0.40005 0 180)
			(size 0.4572 0.508)
			(layers "F.Cu" "F.Mask" "F.Paste")
			(net "GND")
		)
	)
	(footprint ""
		(layer "F.Cu")
		(at 106.07421 -141.990318)
		(property "Reference" "PR74"
			(at -1.350518 -3.101594 0)
			(unlocked yes)
			(layer "F.SilkS")
			(effects
				(font
					(size 0.635 0.4064)
					(thickness 0.1524)
				)
				(justify left)
			)
		)
		(property "Value" ""
			(at 0 0 0)
			(layer "F.Fab")
			(effects
				(font
					(size 1.27 1.27)
				)
			)
		)
		(duplicate_pad_numbers_are_jumpers no)
		(fp_line
			(start -0.7874 -0.4064)
			(end 0.7874 -0.4064)
			(stroke
				(width 0.1524)
				(type default)
			)
			(layer "F.SilkS")
		)
		(fp_line
			(start -0.7874 0.4064)
			(end -0.7874 -0.4064)
			(stroke
				(width 0.1524)
				(type default)
			)
			(layer "F.SilkS")
		)
		(fp_line
			(start 0.7874 -0.4064)
			(end 0.7874 0.4064)
			(stroke
				(width 0.1524)
				(type default)
			)
			(layer "F.SilkS")
		)
		(fp_line
			(start 0.7874 0.4064)
			(end -0.7874 0.4064)
			(stroke
				(width 0.1524)
				(type default)
			)
			(layer "F.SilkS")
		)
		(fp_poly
			(pts
				(xy -0.508 0.2794) (xy -0.508 0.2286) (xy -0.635 0.2286) (xy -0.635 -0.254) (xy -0.5334 -0.254)
				(xy -0.5334 -0.2794) (xy 0.5334 -0.2794) (xy 0.5334 -0.254) (xy 0.635 -0.254) (xy 0.635 0.254) (xy 0.5334 0.254)
				(xy 0.5334 0.2794)
			)
			(stroke
				(width 0)
				(type default)
			)
			(fill no)
			(layer "F.CrtYd")
		)
		(pad "1" smd rect
			(at 0.40005 0)
			(size 0.4572 0.508)
			(layers "F.Cu" "F.Mask" "F.Paste")
			(net "VR_PVCCP_NODE1_TSEN")
		)
		(pad "2" smd rect
			(at -0.40005 0)
			(size 0.4572 0.508)
			(layers "F.Cu" "F.Mask" "F.Paste")
			(net "AGND_PVCCP_NODE1")
		)
	)
	(footprint ""
		(layer "F.Cu")
		(at 123.248674 -161.238184 180)
		(property "Reference" "R643"
			(at -27.988006 -46.909736 0)
			(unlocked yes)
			(layer "F.SilkS")
			(effects
				(font
					(size 0.7874 0.5842)
					(thickness 0.1524)
				)
				(justify left)
			)
		)
		(property "Value" ""
			(at 0 0 180)
			(layer "F.Fab")
			(effects
				(font
					(size 1.27 1.27)
				)
			)
		)
		(duplicate_pad_numbers_are_jumpers no)
		(fp_line
			(start 0.7874 0.4064)
			(end -0.7874 0.4064)
			(stroke
				(width 0.1524)
				(type default)
			)
			(layer "F.SilkS")
		)
		(fp_line
			(start 0.7874 -0.4064)
			(end 0.7874 0.4064)
			(stroke
				(width 0.1524)
				(type default)
			)
			(layer "F.SilkS")
		)
		(fp_line
			(start -0.7874 0.4064)
			(end -0.7874 -0.4064)
			(stroke
				(width 0.1524)
				(type default)
			)
			(layer "F.SilkS")
		)
		(fp_line
			(start -0.7874 -0.4064)
			(end 0.7874 -0.4064)
			(stroke
				(width 0.1524)
				(type default)
			)
			(layer "F.SilkS")
		)
		(fp_poly
			(pts
				(xy -0.508 0.2794) (xy -0.508 0.2286) (xy -0.635 0.2286) (xy -0.635 -0.254) (xy -0.5334 -0.254)
				(xy -0.5334 -0.2794) (xy 0.5334 -0.2794) (xy 0.5334 -0.254) (xy 0.635 -0.254) (xy 0.635 0.254) (xy 0.5334 0.254)
				(xy 0.5334 0.2794)
			)
			(stroke
				(width 0)
				(type default)
			)
			(fill no)
			(layer "F.CrtYd")
		)
		(pad "1" smd rect
			(at 0.40005 0 180)
			(size 0.4572 0.508)
			(layers "F.Cu" "F.Mask" "F.Paste")
			(net "I2C_PSU1_SCL")
		)
		(pad "2" smd rect
			(at -0.40005 0 180)
			(size 0.4572 0.508)
			(layers "F.Cu" "F.Mask" "F.Paste")
			(net "I2C_PSU1_SCL_MOS")
		)
	)
	(footprint ""
		(layer "F.Cu")
		(at 139.02436 -121.070624 -90)
		(property "Reference" "C6"
			(at -2.198116 -0.025146 90)
			(unlocked yes)
			(layer "F.SilkS")
			(effects
				(font
					(size 0.7874 0.5842)
					(thickness 0.1524)
				)
			)
		)
		(property "Value" ""
			(at 0 0 270)
			(layer "F.Fab")
			(effects
				(font
					(size 1.27 1.27)
				)
			)
		)
		(duplicate_pad_numbers_are_jumpers no)
		(fp_line
			(start -1.2954 0.5842)
			(end -1.2954 -0.5842)
			(stroke
				(width 0.1524)
				(type default)
			)
			(layer "F.SilkS")
		)
		(fp_line
			(start 1.2954 0.5842)
			(end -1.2954 0.5842)
			(stroke
				(width 0.1524)
				(type default)
			)
			(layer "F.SilkS")
		)
		(fp_line
			(start -1.2954 -0.5842)
			(end 1.2954 -0.5842)
			(stroke
				(width 0.1524)
				(type default)
			)
			(layer "F.SilkS")
		)
		(fp_line
			(start 0 -0.5842)
			(end 0 0.5842)
			(stroke
				(width 0.1524)
				(type default)
			)
			(layer "F.SilkS")
		)
		(fp_line
			(start 1.2954 -0.5842)
			(end 1.2954 0.5842)
			(stroke
				(width 0.1524)
				(type default)
			)
			(layer "F.SilkS")
		)
		(fp_poly
			(pts
				(xy 0.8636 -0.4572) (xy 0.8636 -0.3556) (xy 1.143 -0.3556) (xy 1.143 0.3556) (xy 0.8636 0.3556)
				(xy 0.8636 0.4572) (xy -0.8636 0.4572) (xy -0.8636 0.3556) (xy -1.143 0.3556) (xy -1.143 -0.3556)
				(xy -0.8636 -0.3556) (xy -0.8636 -0.4572)
			)
			(stroke
				(width 0)
				(type default)
			)
			(fill no)
			(layer "F.CrtYd")
		)
		(fp_line
			(start -0.884936 0.504952)
			(end -0.884936 -0.504952)
			(stroke
				(width 0.1)
				(type default)
			)
			(layer "F.Fab")
		)
		(fp_line
			(start 0.884936 0.504952)
			(end -0.884936 0.504952)
			(stroke
				(width 0.1)
				(type default)
			)
			(layer "F.Fab")
		)
		(fp_line
			(start -0.884936 -0.504952)
			(end 0.884936 -0.504952)
			(stroke
				(width 0.1)
				(type default)
			)
			(layer "F.Fab")
		)
		(fp_line
			(start 0.884936 -0.504952)
			(end 0.884936 0.504952)
			(stroke
				(width 0.1)
				(type default)
			)
			(layer "F.Fab")
		)
		(pad "1" smd rect
			(at 0.7366 0)
			(size 0.7112 0.8128)
			(layers "F.Cu" "F.Mask" "F.Paste")
			(net "P1V5_CLK_NODE1")
		)
		(pad "2" smd rect
			(at -0.7366 0)
			(size 0.7112 0.8128)
			(layers "F.Cu" "F.Mask" "F.Paste")
			(net "GND")
		)
	)
	(footprint ""
		(layer "F.Cu")
		(at 63.0047 -170.630088)
		(property "Reference" "C619"
			(at -9.834626 131.070096 0)
			(unlocked yes)
			(layer "F.SilkS")
			(effects
				(font
					(size 0.7874 0.5842)
					(thickness 0.1524)
				)
				(justify left)
			)
		)
		(property "Value" ""
			(at 0 0 0)
			(layer "F.Fab")
			(effects
				(font
					(size 1.27 1.27)
				)
			)
		)
		(duplicate_pad_numbers_are_jumpers no)
		(fp_line
			(start -0.7874 -0.4064)
			(end 0.7874 -0.4064)
			(stroke
				(width 0.1524)
				(type default)
			)
			(layer "F.SilkS")
		)
		(fp_line
			(start -0.7874 0.4064)
			(end -0.7874 -0.4064)
			(stroke
				(width 0.1524)
				(type default)
			)
			(layer "F.SilkS")
		)
		(fp_line
			(start 0 0.381)
			(end 0 -0.381)
			(stroke
				(width 0.1524)
				(type default)
			)
			(layer "F.SilkS")
		)
		(fp_line
			(start 0.7874 -0.4064)
			(end 0.7874 0.4064)
			(stroke
				(width 0.1524)
				(type default)
			)
			(layer "F.SilkS")
		)
		(fp_line
			(start 0.7874 0.4064)
			(end -0.7874 0.4064)
			(stroke
				(width 0.1524)
				(type default)
			)
			(layer "F.SilkS")
		)
		(fp_poly
			(pts
				(xy -0.5334 0.254) (xy -0.635 0.254) (xy -0.635 0.2286) (xy -0.635 -0.254) (xy -0.5334 -0.254) (xy -0.5334 -0.2794)
				(xy 0.5334 -0.2794) (xy 0.5334 -0.254) (xy 0.635 -0.254) (xy 0.635 0.254) (xy 0.5334 0.254) (xy 0.5334 0.2794)
				(xy -0.508 0.2794) (xy -0.5334 0.2794)
			)
			(stroke
				(width 0)
				(type default)
			)
			(fill no)
			(layer "F.CrtYd")
		)
		(pad "1" smd rect
			(at 0.40005 0)
			(size 0.4572 0.508)
			(layers "F.Cu" "F.Mask" "F.Paste")
			(net "P3V3_NODE1")
		)
		(pad "2" smd rect
			(at -0.40005 0)
			(size 0.4572 0.508)
			(layers "F.Cu" "F.Mask" "F.Paste")
			(net "GND")
		)
	)
	(footprint ""
		(layer "F.Cu")
		(at 82.342228 -133.213094 -90)
		(property "Reference" "D32"
			(at 5.3213 2.271522 90)
			(unlocked yes)
			(layer "F.SilkS")
			(effects
				(font
					(size 0.7874 0.5842)
					(thickness 0.1524)
				)
				(justify left)
			)
		)
		(property "Value" ""
			(at 0 0 270)
			(layer "F.Fab")
			(effects
				(font
					(size 1.27 1.27)
				)
			)
		)
		(duplicate_pad_numbers_are_jumpers no)
		(fp_line
			(start -1.3208 0.5588)
			(end -1.3208 -0.5588)
			(stroke
				(width 0.1524)
				(type default)
			)
			(layer "F.SilkS")
		)
		(fp_line
			(start 1.3208 0.5588)
			(end -1.3208 0.5588)
			(stroke
				(width 0.1524)
				(type default)
			)
			(layer "F.SilkS")
		)
		(fp_line
			(start 1.6256 0.5588)
			(end 1.6256 -0.5588)
			(stroke
				(width 0.1524)
				(type default)
			)
			(layer "F.SilkS")
		)
		(fp_line
			(start 1.778 0.5588)
			(end 1.3208 0.5588)
			(stroke
				(width 0.1524)
				(type default)
			)
			(layer "F.SilkS")
		)
		(fp_line
			(start -1.3208 -0.5588)
			(end 1.3208 -0.5588)
			(stroke
				(width 0.1524)
				(type default)
			)
			(layer "F.SilkS")
		)
		(fp_line
			(start 1.3208 -0.5588)
			(end 1.3208 0.5588)
			(stroke
				(width 0.1524)
				(type default)
			)
			(layer "F.SilkS")
		)
		(fp_line
			(start 1.4732 -0.5588)
			(end 1.4732 0.5588)
			(stroke
				(width 0.1524)
				(type default)
			)
			(layer "F.SilkS")
		)
		(fp_line
			(start 1.778 -0.5588)
			(end 1.778 0.5588)
			(stroke
				(width 0.1524)
				(type default)
			)
			(layer "F.SilkS")
		)
		(fp_line
			(start 1.778 -0.5588)
			(end 1.3208 -0.5588)
			(stroke
				(width 0.1524)
				(type default)
			)
			(layer "F.SilkS")
		)
		(fp_circle
			(center 2.4384 0)
			(end 2.4384 -0.413512)
			(stroke
				(width 0.1524)
				(type default)
			)
			(fill no)
			(layer "F.SilkS")
		)
		(fp_rect
			(start -1.1684 0.508)
			(end 1.1684 -0.508)
			(stroke
				(width 0)
				(type default)
			)
			(fill no)
			(layer "F.CrtYd")
		)
		(fp_text user "-"
			(at 2.687574 -0.35052 270)
			(unlocked yes)
			(layer "F.SilkS")
			(effects
				(font
					(size 0.7874 0.5842)
					(thickness 0.1524)
				)
				(justify left)
			)
		)
		(pad "A" smd rect
			(at -0.750062 0 270)
			(size 0.8128 0.8128)
			(layers "F.Cu" "F.Mask" "F.Paste")
			(net "P3V3_NODE1")
		)
		(pad "C" smd rect
			(at 0.750062 0 270)
			(size 0.8128 0.8128)
			(layers "F.Cu" "F.Mask" "F.Paste")
			(net "N53313464")
		)
	)
	(footprint ""
		(layer "F.Cu")
		(at 18.21942 -45.508926 -90)
		(property "Reference" "R634"
			(at 7.797038 0.840994 90)
			(unlocked yes)
			(layer "F.SilkS")
			(effects
				(font
					(size 0.7874 0.5842)
					(thickness 0.1524)
				)
				(justify left)
			)
		)
		(property "Value" ""
			(at 0 0 270)
			(layer "F.Fab")
			(effects
				(font
					(size 1.27 1.27)
				)
			)
		)
		(duplicate_pad_numbers_are_jumpers no)
		(fp_line
			(start -0.7874 0.4064)
			(end -0.7874 -0.4064)
			(stroke
				(width 0.1524)
				(type default)
			)
			(layer "F.SilkS")
		)
		(fp_line
			(start 0.7874 0.4064)
			(end -0.7874 0.4064)
			(stroke
				(width 0.1524)
				(type default)
			)
			(layer "F.SilkS")
		)
		(fp_line
			(start -0.7874 -0.4064)
			(end 0.7874 -0.4064)
			(stroke
				(width 0.1524)
				(type default)
			)
			(layer "F.SilkS")
		)
		(fp_line
			(start 0.7874 -0.4064)
			(end 0.7874 0.4064)
			(stroke
				(width 0.1524)
				(type default)
			)
			(layer "F.SilkS")
		)
		(fp_poly
			(pts
				(xy -0.508 0.2794) (xy -0.508 0.2286) (xy -0.635 0.2286) (xy -0.635 -0.254) (xy -0.5334 -0.254)
				(xy -0.5334 -0.2794) (xy 0.5334 -0.2794) (xy 0.5334 -0.254) (xy 0.635 -0.254) (xy 0.635 0.254) (xy 0.5334 0.254)
				(xy 0.5334 0.2794)
			)
			(stroke
				(width 0)
				(type default)
			)
			(fill no)
			(layer "F.CrtYd")
		)
		(pad "1" smd rect
			(at 0.40005 0 270)
			(size 0.4572 0.508)
			(layers "F.Cu" "F.Mask" "F.Paste")
			(net "P5V_CRT")
		)
		(pad "2" smd rect
			(at -0.40005 0 270)
			(size 0.4572 0.508)
			(layers "F.Cu" "F.Mask" "F.Paste")
			(net "I2C_VIDREAR_5V_SDA")
		)
	)
	(footprint ""
		(layer "F.Cu")
		(at 58.097166 -96.709992 -90)
		(property "Reference" "R47"
			(at 54.98719 -28.440888 90)
			(unlocked yes)
			(layer "F.SilkS")
			(effects
				(font
					(size 0.7874 0.5842)
					(thickness 0.1524)
				)
				(justify left)
			)
		)
		(property "Value" ""
			(at 0 0 270)
			(layer "F.Fab")
			(effects
				(font
					(size 1.27 1.27)
				)
			)
		)
		(duplicate_pad_numbers_are_jumpers no)
		(fp_line
			(start -0.7874 0.4064)
			(end -0.7874 -0.4064)
			(stroke
				(width 0.1524)
				(type default)
			)
			(layer "F.SilkS")
		)
		(fp_line
			(start 0.7874 0.4064)
			(end -0.7874 0.4064)
			(stroke
				(width 0.1524)
				(type default)
			)
			(layer "F.SilkS")
		)
		(fp_line
			(start -0.7874 -0.4064)
			(end 0.7874 -0.4064)
			(stroke
				(width 0.1524)
				(type default)
			)
			(layer "F.SilkS")
		)
		(fp_line
			(start 0.7874 -0.4064)
			(end 0.7874 0.4064)
			(stroke
				(width 0.1524)
				(type default)
			)
			(layer "F.SilkS")
		)
		(fp_poly
			(pts
				(xy -0.508 0.2794) (xy -0.508 0.2286) (xy -0.635 0.2286) (xy -0.635 -0.254) (xy -0.5334 -0.254)
				(xy -0.5334 -0.2794) (xy 0.5334 -0.2794) (xy 0.5334 -0.254) (xy 0.635 -0.254) (xy 0.635 0.254) (xy 0.5334 0.254)
				(xy 0.5334 0.2794)
			)
			(stroke
				(width 0)
				(type default)
			)
			(fill no)
			(layer "F.CrtYd")
		)
		(pad "1" smd rect
			(at 0.40005 0 270)
			(size 0.4572 0.508)
			(layers "F.Cu" "F.Mask" "F.Paste")
			(net "PU_CPU_NODE1_DFX_GPIO_GRP1_6")
		)
		(pad "2" smd rect
			(at -0.40005 0 270)
			(size 0.4572 0.508)
			(layers "F.Cu" "F.Mask" "F.Paste")
			(net "P1V8_NODE1")
		)
	)
	(footprint ""
		(layer "F.Cu")
		(at 149.8092 -174.112936 90)
		(property "Reference" "R1261"
			(at 0.637032 0.956564 90)
			(unlocked yes)
			(layer "F.SilkS")
			(effects
				(font
					(size 0.7874 0.5842)
					(thickness 0.1524)
				)
				(justify left)
			)
		)
		(property "Value" ""
			(at 0 0 90)
			(layer "F.Fab")
			(effects
				(font
					(size 1.27 1.27)
				)
			)
		)
		(duplicate_pad_numbers_are_jumpers no)
		(fp_line
			(start 0.7874 -0.4064)
			(end 0.7874 0.4064)
			(stroke
				(width 0.1524)
				(type default)
			)
			(layer "F.SilkS")
		)
		(fp_line
			(start -0.7874 -0.4064)
			(end 0.7874 -0.4064)
			(stroke
				(width 0.1524)
				(type default)
			)
			(layer "F.SilkS")
		)
		(fp_line
			(start 0.7874 0.4064)
			(end -0.7874 0.4064)
			(stroke
				(width 0.1524)
				(type default)
			)
			(layer "F.SilkS")
		)
		(fp_line
			(start -0.7874 0.4064)
			(end -0.7874 -0.4064)
			(stroke
				(width 0.1524)
				(type default)
			)
			(layer "F.SilkS")
		)
		(fp_poly
			(pts
				(xy -0.508 0.2794) (xy -0.508 0.2286) (xy -0.635 0.2286) (xy -0.635 -0.254) (xy -0.5334 -0.254)
				(xy -0.5334 -0.2794) (xy 0.5334 -0.2794) (xy 0.5334 -0.254) (xy 0.635 -0.254) (xy 0.635 0.254) (xy 0.5334 0.254)
				(xy 0.5334 0.2794)
			)
			(stroke
				(width 0)
				(type default)
			)
			(fill no)
			(layer "F.CrtYd")
		)
		(pad "1" smd rect
			(at 0.40005 0 90)
			(size 0.4572 0.508)
			(layers "F.Cu" "F.Mask" "F.Paste")
			(net "CPLD_UART_RI_P3_N")
		)
		(pad "2" smd rect
			(at -0.40005 0 90)
			(size 0.4572 0.508)
			(layers "F.Cu" "F.Mask" "F.Paste")
			(net "P3V3_NODE1")
		)
	)
	(footprint ""
		(layer "F.Cu")
		(at 84.350352 -137.033762 -90)
		(property "Reference" "R1097"
			(at -2.512314 -4.28879 90)
			(unlocked yes)
			(layer "F.SilkS")
			(effects
				(font
					(size 0.7874 0.5842)
					(thickness 0.1524)
				)
				(justify left)
			)
		)
		(property "Value" ""
			(at 0 0 270)
			(layer "F.Fab")
			(effects
				(font
					(size 1.27 1.27)
				)
			)
		)
		(duplicate_pad_numbers_are_jumpers no)
		(fp_line
			(start -0.7874 0.4064)
			(end -0.7874 -0.4064)
			(stroke
				(width 0.1524)
				(type default)
			)
			(layer "F.SilkS")
		)
		(fp_line
			(start 0.7874 0.4064)
			(end -0.7874 0.4064)
			(stroke
				(width 0.1524)
				(type default)
			)
			(layer "F.SilkS")
		)
		(fp_line
			(start -0.7874 -0.4064)
			(end 0.7874 -0.4064)
			(stroke
				(width 0.1524)
				(type default)
			)
			(layer "F.SilkS")
		)
		(fp_line
			(start 0.7874 -0.4064)
			(end 0.7874 0.4064)
			(stroke
				(width 0.1524)
				(type default)
			)
			(layer "F.SilkS")
		)
		(fp_poly
			(pts
				(xy -0.508 0.2794) (xy -0.508 0.2286) (xy -0.635 0.2286) (xy -0.635 -0.254) (xy -0.5334 -0.254)
				(xy -0.5334 -0.2794) (xy 0.5334 -0.2794) (xy 0.5334 -0.254) (xy 0.635 -0.254) (xy 0.635 0.254) (xy 0.5334 0.254)
				(xy 0.5334 0.2794)
			)
			(stroke
				(width 0)
				(type default)
			)
			(fill no)
			(layer "F.CrtYd")
		)
		(pad "1" smd rect
			(at 0.40005 0 270)
			(size 0.4572 0.508)
			(layers "F.Cu" "F.Mask" "F.Paste")
			(net "P1V26_STB_NODE1_ADJ_S")
		)
		(pad "2" smd rect
			(at -0.40005 0 270)
			(size 0.4572 0.508)
			(layers "F.Cu" "F.Mask" "F.Paste")
			(net "P1V26_BMC_NODE1_ADJ")
		)
	)
	(footprint ""
		(layer "F.Cu")
		(at 24.6761 -143.307308 180)
		(property "Reference" "Q15"
			(at -3.94462 -2.02438 0)
			(unlocked yes)
			(layer "F.SilkS")
			(effects
				(font
					(size 0.7874 0.5842)
					(thickness 0.1524)
				)
				(justify left)
			)
		)
		(property "Value" ""
			(at 0 0 180)
			(layer "F.Fab")
			(effects
				(font
					(size 1.27 1.27)
				)
			)
		)
		(duplicate_pad_numbers_are_jumpers no)
		(fp_line
			(start 3.3528 1.651)
			(end 3.3528 -1.651)
			(stroke
				(width 0.1524)
				(type default)
			)
			(layer "F.SilkS")
		)
		(fp_line
			(start 3.3528 -1.651)
			(end -3.3528 -1.651)
			(stroke
				(width 0.1524)
				(type default)
			)
			(layer "F.SilkS")
		)
		(fp_line
			(start -3.3528 1.651)
			(end 3.3528 1.651)
			(stroke
				(width 0.1524)
				(type default)
			)
			(layer "F.SilkS")
		)
		(fp_line
			(start -3.3528 -1.651)
			(end -3.3528 1.651)
			(stroke
				(width 0.1524)
				(type default)
			)
			(layer "F.SilkS")
		)
		(fp_poly
			(pts
				(xy -3.048 3.8354) (xy -3.048 1.8796) (xy -3.3528 1.8796) (xy -3.3528 -1.8796) (xy -1.905 -1.8796)
				(xy -1.905 -3.8354) (xy 1.905 -3.8354) (xy 1.905 -1.8796) (xy 3.3528 -1.8796) (xy 3.3528 1.8796)
				(xy 3.048 1.8796) (xy 3.048 3.8354)
			)
			(stroke
				(width 0)
				(type default)
			)
			(fill no)
			(layer "F.CrtYd")
		)
		(pad "1" smd rect
			(at -2.286 2.8321 180)
			(size 1.4986 2.0066)
			(layers "F.Cu" "F.Mask" "F.Paste")
			(net "LAN1_CTRL_P1V9")
		)
		(pad "2" smd rect
			(at 0 2.8321 180)
			(size 1.4986 2.0066)
			(layers "F.Cu" "F.Mask" "F.Paste")
			(net "P1V9_LAN1")
		)
		(pad "3" smd rect
			(at 2.286 2.8321 180)
			(size 1.4986 2.0066)
			(layers "F.Cu" "F.Mask" "F.Paste")
			(net "P3V3_NODE1")
		)
		(pad "4" smd rect
			(at 0 -2.8321 270)
			(size 2.0066 3.81)
			(layers "F.Cu" "F.Mask" "F.Paste")
			(net "P1V9_LAN1")
		)
	)
	(footprint ""
		(layer "F.Cu")
		(at 23.84171 -108.443522 180)
		(property "Reference" "PC66"
			(at -2.78511 0.012446 0)
			(unlocked yes)
			(layer "F.SilkS")
			(effects
				(font
					(size 0.7874 0.5842)
					(thickness 0.1524)
				)
				(justify left)
			)
		)
		(property "Value" ""
			(at 0 0 180)
			(layer "F.Fab")
			(effects
				(font
					(size 1.27 1.27)
				)
			)
		)
		(duplicate_pad_numbers_are_jumpers no)
		(fp_line
			(start 1.905 0.8636)
			(end -1.905 0.8636)
			(stroke
				(width 0.1524)
				(type default)
			)
			(layer "F.SilkS")
		)
		(fp_line
			(start 1.905 -0.8636)
			(end 1.905 0.8636)
			(stroke
				(width 0.1524)
				(type default)
			)
			(layer "F.SilkS")
		)
		(fp_line
			(start 0 0.8382)
			(end 0 -0.8382)
			(stroke
				(width 0.1524)
				(type default)
			)
			(layer "F.SilkS")
		)
		(fp_line
			(start -1.905 0.8636)
			(end -1.905 -0.8636)
			(stroke
				(width 0.1524)
				(type default)
			)
			(layer "F.SilkS")
		)
		(fp_line
			(start -1.905 -0.8636)
			(end 1.905 -0.8636)
			(stroke
				(width 0.1524)
				(type default)
			)
			(layer "F.SilkS")
		)
		(fp_rect
			(start -1.524 0.7366)
			(end 1.524 -0.7366)
			(stroke
				(width 0)
				(type default)
			)
			(fill no)
			(layer "F.CrtYd")
		)
		(pad "1" smd rect
			(at 0.94996 0 180)
			(size 1.1176 1.3716)
			(layers "F.Cu" "F.Mask" "F.Paste")
			(net "P1V05_NODE1")
		)
		(pad "2" smd rect
			(at -0.94996 0 180)
			(size 1.1176 1.3716)
			(layers "F.Cu" "F.Mask" "F.Paste")
			(net "GND")
		)
	)
	(footprint ""
		(layer "F.Cu")
		(at 126.90729 -167.685212)
		(property "Reference" "C902"
			(at -1.617218 -4.22402 0)
			(unlocked yes)
			(layer "F.SilkS")
			(effects
				(font
					(size 0.7874 0.5842)
					(thickness 0.1524)
				)
				(justify left)
			)
		)
		(property "Value" ""
			(at 0 0 0)
			(layer "F.Fab")
			(effects
				(font
					(size 1.27 1.27)
				)
			)
		)
		(duplicate_pad_numbers_are_jumpers no)
		(fp_line
			(start -0.7874 -0.4064)
			(end 0.7874 -0.4064)
			(stroke
				(width 0.1524)
				(type default)
			)
			(layer "F.SilkS")
		)
		(fp_line
			(start -0.7874 0.4064)
			(end -0.7874 -0.4064)
			(stroke
				(width 0.1524)
				(type default)
			)
			(layer "F.SilkS")
		)
		(fp_line
			(start 0 0.381)
			(end 0 -0.381)
			(stroke
				(width 0.1524)
				(type default)
			)
			(layer "F.SilkS")
		)
		(fp_line
			(start 0.7874 -0.4064)
			(end 0.7874 0.4064)
			(stroke
				(width 0.1524)
				(type default)
			)
			(layer "F.SilkS")
		)
		(fp_line
			(start 0.7874 0.4064)
			(end -0.7874 0.4064)
			(stroke
				(width 0.1524)
				(type default)
			)
			(layer "F.SilkS")
		)
		(fp_poly
			(pts
				(xy -0.5334 0.254) (xy -0.635 0.254) (xy -0.635 0.2286) (xy -0.635 -0.254) (xy -0.5334 -0.254) (xy -0.5334 -0.2794)
				(xy 0.5334 -0.2794) (xy 0.5334 -0.254) (xy 0.635 -0.254) (xy 0.635 0.254) (xy 0.5334 0.254) (xy 0.5334 0.2794)
				(xy -0.508 0.2794) (xy -0.5334 0.2794)
			)
			(stroke
				(width 0)
				(type default)
			)
			(fill no)
			(layer "F.CrtYd")
		)
		(pad "1" smd rect
			(at 0.40005 0)
			(size 0.4572 0.508)
			(layers "F.Cu" "F.Mask" "F.Paste")
			(net "P3V3_NODE1")
		)
		(pad "2" smd rect
			(at -0.40005 0)
			(size 0.4572 0.508)
			(layers "F.Cu" "F.Mask" "F.Paste")
			(net "GND")
		)
	)
	(footprint ""
		(layer "F.Cu")
		(at 179.000404 -135.991346)
		(property "Reference" "R1043"
			(at 4.535678 0.127762 0)
			(unlocked yes)
			(layer "F.SilkS")
			(effects
				(font
					(size 0.7874 0.5842)
					(thickness 0.1524)
				)
				(justify left)
			)
		)
		(property "Value" ""
			(at 0 0 0)
			(layer "F.Fab")
			(effects
				(font
					(size 1.27 1.27)
				)
			)
		)
		(duplicate_pad_numbers_are_jumpers no)
		(fp_line
			(start -0.7874 -0.4064)
			(end 0.7874 -0.4064)
			(stroke
				(width 0.1524)
				(type default)
			)
			(layer "F.SilkS")
		)
		(fp_line
			(start -0.7874 0.4064)
			(end -0.7874 -0.4064)
			(stroke
				(width 0.1524)
				(type default)
			)
			(layer "F.SilkS")
		)
		(fp_line
			(start 0.7874 -0.4064)
			(end 0.7874 0.4064)
			(stroke
				(width 0.1524)
				(type default)
			)
			(layer "F.SilkS")
		)
		(fp_line
			(start 0.7874 0.4064)
			(end -0.7874 0.4064)
			(stroke
				(width 0.1524)
				(type default)
			)
			(layer "F.SilkS")
		)
		(fp_poly
			(pts
				(xy -0.508 0.2794) (xy -0.508 0.2286) (xy -0.635 0.2286) (xy -0.635 -0.254) (xy -0.5334 -0.254)
				(xy -0.5334 -0.2794) (xy 0.5334 -0.2794) (xy 0.5334 -0.254) (xy 0.635 -0.254) (xy 0.635 0.254) (xy 0.5334 0.254)
				(xy 0.5334 0.2794)
			)
			(stroke
				(width 0)
				(type default)
			)
			(fill no)
			(layer "F.CrtYd")
		)
		(pad "1" smd rect
			(at 0.40005 0)
			(size 0.4572 0.508)
			(layers "F.Cu" "F.Mask" "F.Paste")
			(net "FM_CPLD_NODE1_WDT_R")
		)
		(pad "2" smd rect
			(at -0.40005 0)
			(size 0.4572 0.508)
			(layers "F.Cu" "F.Mask" "F.Paste")
			(net "P1V05_NODE1")
		)
	)
	(footprint ""
		(layer "F.Cu")
		(at 42.662602 -163.558982)
		(property "Reference" "C399"
			(at -1.90119 1.071118 0)
			(unlocked yes)
			(layer "F.SilkS")
			(effects
				(font
					(size 0.7874 0.5842)
					(thickness 0.1524)
				)
				(justify left)
			)
		)
		(property "Value" ""
			(at 0 0 0)
			(layer "F.Fab")
			(effects
				(font
					(size 1.27 1.27)
				)
			)
		)
		(duplicate_pad_numbers_are_jumpers no)
		(fp_line
			(start -0.7874 -0.4064)
			(end 0.7874 -0.4064)
			(stroke
				(width 0.1524)
				(type default)
			)
			(layer "F.SilkS")
		)
		(fp_line
			(start -0.7874 0.4064)
			(end -0.7874 -0.4064)
			(stroke
				(width 0.1524)
				(type default)
			)
			(layer "F.SilkS")
		)
		(fp_line
			(start 0 0.381)
			(end 0 -0.381)
			(stroke
				(width 0.1524)
				(type default)
			)
			(layer "F.SilkS")
		)
		(fp_line
			(start 0.7874 -0.4064)
			(end 0.7874 0.4064)
			(stroke
				(width 0.1524)
				(type default)
			)
			(layer "F.SilkS")
		)
		(fp_line
			(start 0.7874 0.4064)
			(end -0.7874 0.4064)
			(stroke
				(width 0.1524)
				(type default)
			)
			(layer "F.SilkS")
		)
		(fp_poly
			(pts
				(xy -0.5334 0.254) (xy -0.635 0.254) (xy -0.635 0.2286) (xy -0.635 -0.254) (xy -0.5334 -0.254) (xy -0.5334 -0.2794)
				(xy 0.5334 -0.2794) (xy 0.5334 -0.254) (xy 0.635 -0.254) (xy 0.635 0.254) (xy 0.5334 0.254) (xy 0.5334 0.2794)
				(xy -0.508 0.2794) (xy -0.5334 0.2794)
			)
			(stroke
				(width 0)
				(type default)
			)
			(fill no)
			(layer "F.CrtYd")
		)
		(pad "1" smd rect
			(at 0.40005 0)
			(size 0.4572 0.508)
			(layers "F.Cu" "F.Mask" "F.Paste")
			(net "LAN1_XTAL_IN")
		)
		(pad "2" smd rect
			(at -0.40005 0)
			(size 0.4572 0.508)
			(layers "F.Cu" "F.Mask" "F.Paste")
			(net "GND")
		)
	)
	(footprint ""
		(layer "F.Cu")
		(at 166.73322 -119.39651)
		(property "Reference" "R1030"
			(at -2.81559 8.725408 0)
			(unlocked yes)
			(layer "F.SilkS")
			(effects
				(font
					(size 0.7874 0.5842)
					(thickness 0.1524)
				)
				(justify left)
			)
		)
		(property "Value" ""
			(at 0 0 0)
			(layer "F.Fab")
			(effects
				(font
					(size 1.27 1.27)
				)
			)
		)
		(duplicate_pad_numbers_are_jumpers no)
		(fp_line
			(start -0.7874 -0.4064)
			(end 0.7874 -0.4064)
			(stroke
				(width 0.1524)
				(type default)
			)
			(layer "F.SilkS")
		)
		(fp_line
			(start -0.7874 0.4064)
			(end -0.7874 -0.4064)
			(stroke
				(width 0.1524)
				(type default)
			)
			(layer "F.SilkS")
		)
		(fp_line
			(start 0.7874 -0.4064)
			(end 0.7874 0.4064)
			(stroke
				(width 0.1524)
				(type default)
			)
			(layer "F.SilkS")
		)
		(fp_line
			(start 0.7874 0.4064)
			(end -0.7874 0.4064)
			(stroke
				(width 0.1524)
				(type default)
			)
			(layer "F.SilkS")
		)
		(fp_poly
			(pts
				(xy -0.508 0.2794) (xy -0.508 0.2286) (xy -0.635 0.2286) (xy -0.635 -0.254) (xy -0.5334 -0.254)
				(xy -0.5334 -0.2794) (xy 0.5334 -0.2794) (xy 0.5334 -0.254) (xy 0.635 -0.254) (xy 0.635 0.254) (xy 0.5334 0.254)
				(xy 0.5334 0.2794)
			)
			(stroke
				(width 0)
				(type default)
			)
			(fill no)
			(layer "F.CrtYd")
		)
		(pad "1" smd rect
			(at 0.40005 0)
			(size 0.4572 0.508)
			(layers "F.Cu" "F.Mask" "F.Paste")
			(net "FM_CPLD_NODE1_BMC_SRST_L")
		)
		(pad "2" smd rect
			(at -0.40005 0)
			(size 0.4572 0.508)
			(layers "F.Cu" "F.Mask" "F.Paste")
			(net "FM_BMC_NODE1_RESET_L")
		)
	)
	(footprint ""
		(layer "F.Cu")
		(at 130.60807 -110.92815 180)
		(property "Reference" "C12"
			(at 5.280406 0.023368 0)
			(unlocked yes)
			(layer "F.SilkS")
			(effects
				(font
					(size 0.7874 0.5842)
					(thickness 0.1524)
				)
				(justify left)
			)
		)
		(property "Value" ""
			(at 0 0 180)
			(layer "F.Fab")
			(effects
				(font
					(size 1.27 1.27)
				)
			)
		)
		(duplicate_pad_numbers_are_jumpers no)
		(fp_line
			(start 0.7874 0.4064)
			(end -0.7874 0.4064)
			(stroke
				(width 0.1524)
				(type default)
			)
			(layer "F.SilkS")
		)
		(fp_line
			(start 0.7874 -0.4064)
			(end 0.7874 0.4064)
			(stroke
				(width 0.1524)
				(type default)
			)
			(layer "F.SilkS")
		)
		(fp_line
			(start 0 0.381)
			(end 0 -0.381)
			(stroke
				(width 0.1524)
				(type default)
			)
			(layer "F.SilkS")
		)
		(fp_line
			(start -0.7874 0.4064)
			(end -0.7874 -0.4064)
			(stroke
				(width 0.1524)
				(type default)
			)
			(layer "F.SilkS")
		)
		(fp_line
			(start -0.7874 -0.4064)
			(end 0.7874 -0.4064)
			(stroke
				(width 0.1524)
				(type default)
			)
			(layer "F.SilkS")
		)
		(fp_poly
			(pts
				(xy -0.5334 0.254) (xy -0.635 0.254) (xy -0.635 0.2286) (xy -0.635 -0.254) (xy -0.5334 -0.254) (xy -0.5334 -0.2794)
				(xy 0.5334 -0.2794) (xy 0.5334 -0.254) (xy 0.635 -0.254) (xy 0.635 0.254) (xy 0.5334 0.254) (xy 0.5334 0.2794)
				(xy -0.508 0.2794) (xy -0.5334 0.2794)
			)
			(stroke
				(width 0)
				(type default)
			)
			(fill no)
			(layer "F.CrtYd")
		)
		(pad "1" smd rect
			(at 0.40005 0 180)
			(size 0.4572 0.508)
			(layers "F.Cu" "F.Mask" "F.Paste")
			(net "XTAL_CLK_NODE1_X1")
		)
		(pad "2" smd rect
			(at -0.40005 0 180)
			(size 0.4572 0.508)
			(layers "F.Cu" "F.Mask" "F.Paste")
			(net "GND")
		)
	)
	(footprint ""
		(layer "F.Cu")
		(at 59.957208 -148.241258)
		(property "Reference" "C262"
			(at -29.678122 -7.053834 0)
			(unlocked yes)
			(layer "F.SilkS")
			(effects
				(font
					(size 0.7874 0.5842)
					(thickness 0.1524)
				)
			)
		)
		(property "Value" ""
			(at 0 0 0)
			(layer "F.Fab")
			(effects
				(font
					(size 1.27 1.27)
				)
			)
		)
		(duplicate_pad_numbers_are_jumpers no)
		(fp_line
			(start -1.2954 -0.5842)
			(end 1.2954 -0.5842)
			(stroke
				(width 0.1524)
				(type default)
			)
			(layer "F.SilkS")
		)
		(fp_line
			(start -1.2954 0.5842)
			(end -1.2954 -0.5842)
			(stroke
				(width 0.1524)
				(type default)
			)
			(layer "F.SilkS")
		)
		(fp_line
			(start 0 -0.5842)
			(end 0 0.5842)
			(stroke
				(width 0.1524)
				(type default)
			)
			(layer "F.SilkS")
		)
		(fp_line
			(start 1.2954 -0.5842)
			(end 1.2954 0.5842)
			(stroke
				(width 0.1524)
				(type default)
			)
			(layer "F.SilkS")
		)
		(fp_line
			(start 1.2954 0.5842)
			(end -1.2954 0.5842)
			(stroke
				(width 0.1524)
				(type default)
			)
			(layer "F.SilkS")
		)
		(fp_poly
			(pts
				(xy 0.8636 -0.4572) (xy 0.8636 -0.3556) (xy 1.143 -0.3556) (xy 1.143 0.3556) (xy 0.8636 0.3556)
				(xy 0.8636 0.4572) (xy -0.8636 0.4572) (xy -0.8636 0.3556) (xy -1.143 0.3556) (xy -1.143 -0.3556)
				(xy -0.8636 -0.3556) (xy -0.8636 -0.4572)
			)
			(stroke
				(width 0)
				(type default)
			)
			(fill no)
			(layer "F.CrtYd")
		)
		(fp_line
			(start -0.884936 -0.504952)
			(end 0.884936 -0.504952)
			(stroke
				(width 0.1)
				(type default)
			)
			(layer "F.Fab")
		)
		(fp_line
			(start -0.884936 0.504952)
			(end -0.884936 -0.504952)
			(stroke
				(width 0.1)
				(type default)
			)
			(layer "F.Fab")
		)
		(fp_line
			(start 0.884936 -0.504952)
			(end 0.884936 0.504952)
			(stroke
				(width 0.1)
				(type default)
			)
			(layer "F.Fab")
		)
		(fp_line
			(start 0.884936 0.504952)
			(end -0.884936 0.504952)
			(stroke
				(width 0.1)
				(type default)
			)
			(layer "F.Fab")
		)
		(pad "1" smd rect
			(at 0.7366 0 90)
			(size 0.7112 0.8128)
			(layers "F.Cu" "F.Mask" "F.Paste")
			(net "BMC_NODE1_DACAV33")
		)
		(pad "2" smd rect
			(at -0.7366 0 90)
			(size 0.7112 0.8128)
			(layers "F.Cu" "F.Mask" "F.Paste")
			(net "GND")
		)
	)
	(footprint ""
		(layer "F.Cu")
		(at 131.81076 -185.053224 90)
		(property "Reference" "C755"
			(at 4.663186 -0.954278 90)
			(unlocked yes)
			(layer "F.SilkS")
			(effects
				(font
					(size 0.7874 0.5842)
					(thickness 0.1524)
				)
				(justify left)
			)
		)
		(property "Value" ""
			(at 0 0 90)
			(layer "F.Fab")
			(effects
				(font
					(size 1.27 1.27)
				)
			)
		)
		(duplicate_pad_numbers_are_jumpers no)
		(fp_line
			(start 0.7874 -0.4064)
			(end 0.7874 0.4064)
			(stroke
				(width 0.1524)
				(type default)
			)
			(layer "F.SilkS")
		)
		(fp_line
			(start -0.7874 -0.4064)
			(end 0.7874 -0.4064)
			(stroke
				(width 0.1524)
				(type default)
			)
			(layer "F.SilkS")
		)
		(fp_line
			(start 0 0.381)
			(end 0 -0.381)
			(stroke
				(width 0.1524)
				(type default)
			)
			(layer "F.SilkS")
		)
		(fp_line
			(start 0.7874 0.4064)
			(end -0.7874 0.4064)
			(stroke
				(width 0.1524)
				(type default)
			)
			(layer "F.SilkS")
		)
		(fp_line
			(start -0.7874 0.4064)
			(end -0.7874 -0.4064)
			(stroke
				(width 0.1524)
				(type default)
			)
			(layer "F.SilkS")
		)
		(fp_poly
			(pts
				(xy -0.5334 0.254) (xy -0.635 0.254) (xy -0.635 0.2286) (xy -0.635 -0.254) (xy -0.5334 -0.254) (xy -0.5334 -0.2794)
				(xy 0.5334 -0.2794) (xy 0.5334 -0.254) (xy 0.635 -0.254) (xy 0.635 0.254) (xy 0.5334 0.254) (xy 0.5334 0.2794)
				(xy -0.508 0.2794) (xy -0.5334 0.2794)
			)
			(stroke
				(width 0)
				(type default)
			)
			(fill no)
			(layer "F.CrtYd")
		)
		(pad "1" smd rect
			(at 0.40005 0 90)
			(size 0.4572 0.508)
			(layers "F.Cu" "F.Mask" "F.Paste")
			(net "UART_T10_NODE3_RXD")
		)
		(pad "2" smd rect
			(at -0.40005 0 90)
			(size 0.4572 0.508)
			(layers "F.Cu" "F.Mask" "F.Paste")
			(net "GND")
		)
	)
	(footprint ""
		(layer "F.Cu")
		(at 141.08176 -188.126624 90)
		(property "Reference" "C636"
			(at 5.519674 -0.479552 90)
			(unlocked yes)
			(layer "F.SilkS")
			(effects
				(font
					(size 0.7874 0.5842)
					(thickness 0.1524)
				)
				(justify left)
			)
		)
		(property "Value" ""
			(at 0 0 90)
			(layer "F.Fab")
			(effects
				(font
					(size 1.27 1.27)
				)
			)
		)
		(duplicate_pad_numbers_are_jumpers no)
		(fp_line
			(start 0.7874 -0.4064)
			(end 0.7874 0.4064)
			(stroke
				(width 0.1524)
				(type default)
			)
			(layer "F.SilkS")
		)
		(fp_line
			(start -0.7874 -0.4064)
			(end 0.7874 -0.4064)
			(stroke
				(width 0.1524)
				(type default)
			)
			(layer "F.SilkS")
		)
		(fp_line
			(start 0 0.381)
			(end 0 -0.381)
			(stroke
				(width 0.1524)
				(type default)
			)
			(layer "F.SilkS")
		)
		(fp_line
			(start 0.7874 0.4064)
			(end -0.7874 0.4064)
			(stroke
				(width 0.1524)
				(type default)
			)
			(layer "F.SilkS")
		)
		(fp_line
			(start -0.7874 0.4064)
			(end -0.7874 -0.4064)
			(stroke
				(width 0.1524)
				(type default)
			)
			(layer "F.SilkS")
		)
		(fp_poly
			(pts
				(xy -0.5334 0.254) (xy -0.635 0.254) (xy -0.635 0.2286) (xy -0.635 -0.254) (xy -0.5334 -0.254) (xy -0.5334 -0.2794)
				(xy 0.5334 -0.2794) (xy 0.5334 -0.254) (xy 0.635 -0.254) (xy 0.635 0.254) (xy 0.5334 0.254) (xy 0.5334 0.2794)
				(xy -0.508 0.2794) (xy -0.5334 0.2794)
			)
			(stroke
				(width 0)
				(type default)
			)
			(fill no)
			(layer "F.CrtYd")
		)
		(pad "1" smd rect
			(at 0.40005 0 90)
			(size 0.4572 0.508)
			(layers "F.Cu" "F.Mask" "F.Paste")
			(net "T10_NODE1_EN_R")
		)
		(pad "2" smd rect
			(at -0.40005 0 90)
			(size 0.4572 0.508)
			(layers "F.Cu" "F.Mask" "F.Paste")
			(net "GND")
		)
	)
	(footprint ""
		(layer "F.Cu")
		(at 174.676562 -138.00455 90)
		(property "Reference" "U106"
			(at 2.306574 -0.515366 0)
			(unlocked yes)
			(layer "F.SilkS")
			(effects
				(font
					(size 0.7874 0.5842)
					(thickness 0.1524)
				)
				(justify left)
			)
		)
		(property "Value" ""
			(at 0 0 90)
			(layer "F.Fab")
			(effects
				(font
					(size 1.27 1.27)
				)
			)
		)
		(duplicate_pad_numbers_are_jumpers no)
		(fp_line
			(start 1.549908 -2.032)
			(end 1.549908 2.032)
			(stroke
				(width 0.1524)
				(type default)
			)
			(layer "F.SilkS")
		)
		(fp_line
			(start -1.549908 -2.032)
			(end 1.549908 -2.032)
			(stroke
				(width 0.1524)
				(type default)
			)
			(layer "F.SilkS")
		)
		(fp_line
			(start 1.549908 2.032)
			(end -1.549908 2.032)
			(stroke
				(width 0.1524)
				(type default)
			)
			(layer "F.SilkS")
		)
		(fp_line
			(start -1.549908 2.032)
			(end -1.549908 -2.032)
			(stroke
				(width 0.1524)
				(type default)
			)
			(layer "F.SilkS")
		)
		(fp_poly
			(pts
				(xy -2.9464 1.016) (xy -2.9464 1.524) (xy -2.1844 1.27)
			)
			(stroke
				(width 0)
				(type default)
			)
			(fill yes)
			(layer "F.SilkS")
		)
		(fp_poly
			(pts
				(xy -1.549908 0.849884) (xy -1.2319 0.849884) (xy -1.2319 1.9431) (xy -1.1811 1.9431) (xy 1.1811 1.9431)
				(xy 1.2319 1.9431) (xy 1.2319 0.849884) (xy 1.549908 0.849884) (xy 1.549908 -0.849884) (xy 1.2319 -0.849884)
				(xy 1.2319 -1.9431) (xy 1.1811 -1.9431) (xy -1.1811 -1.9431) (xy -1.2319 -1.9431) (xy -1.2319 -0.849884)
				(xy -1.549908 -0.849884)
			)
			(stroke
				(width 0)
				(type default)
			)
			(fill no)
			(layer "F.CrtYd")
		)
		(fp_line
			(start 1.549908 -0.849884)
			(end -1.549908 -0.849884)
			(stroke
				(width 0.1)
				(type default)
			)
			(layer "F.Fab")
		)
		(fp_line
			(start -1.549908 -0.849884)
			(end -1.549908 0.849884)
			(stroke
				(width 0.1)
				(type default)
			)
			(layer "F.Fab")
		)
		(fp_line
			(start 1.549908 0.849884)
			(end 1.549908 -0.849884)
			(stroke
				(width 0.1)
				(type default)
			)
			(layer "F.Fab")
		)
		(fp_line
			(start -1.549908 0.849884)
			(end 1.549908 0.849884)
			(stroke
				(width 0.1)
				(type default)
			)
			(layer "F.Fab")
		)
		(fp_text user "4"
			(at 2.184908 -1.922272 0)
			(unlocked yes)
			(layer "F.SilkS")
			(effects
				(font
					(size 0.635 0.4064)
					(thickness 0.1524)
				)
				(justify left)
			)
		)
		(fp_text user "5"
			(at -2.2352 -1.04775 90)
			(unlocked yes)
			(layer "F.SilkS")
			(effects
				(font
					(size 0.635 0.4064)
					(thickness 0.1524)
				)
				(justify left)
			)
		)
		(fp_text user "1"
			(at -2.0955 1.373632 90)
			(unlocked yes)
			(layer "F.SilkS")
			(effects
				(font
					(size 0.635 0.4064)
					(thickness 0.1524)
				)
				(justify left)
			)
		)
		(fp_text user "3"
			(at 1.232916 2.408428 0)
			(unlocked yes)
			(layer "F.SilkS")
			(effects
				(font
					(size 0.635 0.4064)
					(thickness 0.1524)
				)
				(justify left)
			)
		)
		(pad "1" smd rect
			(at -0.94996 1.225042 90)
			(size 0.4572 1.3208)
			(layers "F.Cu" "F.Mask" "F.Paste")
			(net "Net_1703")
		)
		(pad "2" smd rect
			(at 0 1.225042 90)
			(size 0.4572 1.3208)
			(layers "F.Cu" "F.Mask" "F.Paste")
			(net "PWR_BTN_NODE1_C_L")
		)
		(pad "3" smd rect
			(at 0.94996 1.225042 90)
			(size 0.4572 1.3208)
			(layers "F.Cu" "F.Mask" "F.Paste")
			(net "GND")
		)
		(pad "4" smd rect
			(at 0.94996 -1.225042 90)
			(size 0.4572 1.3208)
			(layers "F.Cu" "F.Mask" "F.Paste")
			(net "FM_CPLD_NODE1_PWR_BTN_L")
		)
		(pad "5" smd rect
			(at -0.94996 -1.225042 90)
			(size 0.4572 1.3208)
			(layers "F.Cu" "F.Mask" "F.Paste")
			(net "P3V3_STB_NODE1")
		)
	)
	(footprint ""
		(layer "F.Cu")
		(at 113.368836 -138.0109 180)
		(property "Reference" "PJ15"
			(at -3.553968 3.597656 90)
			(unlocked yes)
			(layer "F.SilkS")
			(effects
				(font
					(size 0.635 0.4064)
					(thickness 0.1524)
				)
				(justify left)
			)
		)
		(property "Value" ""
			(at 0 0 180)
			(layer "F.Fab")
			(effects
				(font
					(size 1.27 1.27)
				)
			)
		)
		(duplicate_pad_numbers_are_jumpers no)
		(fp_poly
			(pts
				(xy 0.2794 0.907796) (xy 0.254 0.907796) (xy 0.254 1.0414) (xy -0.254 1.0414) (xy -0.254 1.034796)
				(xy -0.254 0.933196) (xy -0.2794 0.933196) (xy -0.2794 -0.133604) (xy -0.254 -0.133604) (xy -0.254 -0.235204)
				(xy 0.254 -0.235204) (xy 0.254 -0.133604) (xy 0.2794 -0.133604)
			)
			(stroke
				(width 0)
				(type default)
			)
			(fill no)
			(layer "F.CrtYd")
		)
		(pad "1" smd custom
			(at 0 -0.000254 180)
			(size 0.127 0.127)
			(layers "F.Cu" "F.Mask" "F.Paste")
			(net "VR_PVCCP_NODE1_RGND")
			(options
				(clearance outline)
				(anchor circle)
			)
			(primitives
				(gr_poly
					(pts
						(xy -0.127 0.508) (xy -0.127 -0.0508) (xy -0.254 -0.0508) (xy -0.254 -0.508) (xy 0.254 -0.508)
						(xy 0.254 -0.0508) (xy 0.127 -0.0508) (xy 0.127 0.508)
					)
					(width 0)
					(fill yes)
				)
			)
		)
		(pad "2" smd rect
			(at 0 0.799846 270)
			(size 0.4572 0.508)
			(layers "F.Cu" "F.Mask" "F.Paste")
			(net "VSENSE_VSS_CPU_NODE1")
		)
		(zone
			(layer "F.Cu")
			(hatch none 0.5)
			(connect_pads
				(clearance 0)
			)
			(min_thickness 0.25)
			(keepout
				(tracks allowed)
				(vias not_allowed)
				(pads allowed)
				(copperpour not_allowed)
				(footprints allowed)
			)
			(placement
				(enabled no)
				(sheetname "")
			)
			(fill
				(thermal_gap 0.5)
				(thermal_bridge_width 0.5)
				(island_removal_mode 0)
			)
			(polygon
				(pts
					(xy 113.673636 -139.096496) (xy 113.064036 -139.096496) (xy 113.064036 -137.724896) (xy 113.673636 -137.724896)
				)
			)
		)
	)
	(footprint ""
		(layer "F.Cu")
		(at 66.356992 -7.424166)
		(property "Reference" "PR21"
			(at -1.31572 -4.28625 0)
			(unlocked yes)
			(layer "F.SilkS")
			(effects
				(font
					(size 0.7874 0.5842)
					(thickness 0.1524)
				)
				(justify left)
			)
		)
		(property "Value" ""
			(at 0 0 0)
			(layer "F.Fab")
			(effects
				(font
					(size 1.27 1.27)
				)
			)
		)
		(duplicate_pad_numbers_are_jumpers no)
		(fp_line
			(start -0.7874 -0.4064)
			(end 0.7874 -0.4064)
			(stroke
				(width 0.1524)
				(type default)
			)
			(layer "F.SilkS")
		)
		(fp_line
			(start -0.7874 0.4064)
			(end -0.7874 -0.4064)
			(stroke
				(width 0.1524)
				(type default)
			)
			(layer "F.SilkS")
		)
		(fp_line
			(start 0.7874 -0.4064)
			(end 0.7874 0.4064)
			(stroke
				(width 0.1524)
				(type default)
			)
			(layer "F.SilkS")
		)
		(fp_line
			(start 0.7874 0.4064)
			(end -0.7874 0.4064)
			(stroke
				(width 0.1524)
				(type default)
			)
			(layer "F.SilkS")
		)
		(fp_poly
			(pts
				(xy -0.508 0.2794) (xy -0.508 0.2286) (xy -0.635 0.2286) (xy -0.635 -0.254) (xy -0.5334 -0.254)
				(xy -0.5334 -0.2794) (xy 0.5334 -0.2794) (xy 0.5334 -0.254) (xy 0.635 -0.254) (xy 0.635 0.254) (xy 0.5334 0.254)
				(xy 0.5334 0.2794)
			)
			(stroke
				(width 0)
				(type default)
			)
			(fill no)
			(layer "F.CrtYd")
		)
		(pad "1" smd rect
			(at 0.40005 0)
			(size 0.4572 0.508)
			(layers "F.Cu" "F.Mask" "F.Paste")
			(net "P3V3_NODE1_FB")
		)
		(pad "2" smd rect
			(at -0.40005 0)
			(size 0.4572 0.508)
			(layers "F.Cu" "F.Mask" "F.Paste")
			(net "GND")
		)
	)
	(footprint ""
		(layer "F.Cu")
		(at 44.207176 -178.301904 180)
		(property "Reference" "C772"
			(at 0.98552 -132.632196 0)
			(unlocked yes)
			(layer "F.SilkS")
			(effects
				(font
					(size 0.7874 0.5842)
					(thickness 0.1524)
				)
				(justify left)
			)
		)
		(property "Value" ""
			(at 0 0 180)
			(layer "F.Fab")
			(effects
				(font
					(size 1.27 1.27)
				)
			)
		)
		(duplicate_pad_numbers_are_jumpers no)
		(fp_line
			(start 0.7874 0.4064)
			(end -0.7874 0.4064)
			(stroke
				(width 0.1524)
				(type default)
			)
			(layer "F.SilkS")
		)
		(fp_line
			(start 0.7874 -0.4064)
			(end 0.7874 0.4064)
			(stroke
				(width 0.1524)
				(type default)
			)
			(layer "F.SilkS")
		)
		(fp_line
			(start 0 0.381)
			(end 0 -0.381)
			(stroke
				(width 0.1524)
				(type default)
			)
			(layer "F.SilkS")
		)
		(fp_line
			(start -0.7874 0.4064)
			(end -0.7874 -0.4064)
			(stroke
				(width 0.1524)
				(type default)
			)
			(layer "F.SilkS")
		)
		(fp_line
			(start -0.7874 -0.4064)
			(end 0.7874 -0.4064)
			(stroke
				(width 0.1524)
				(type default)
			)
			(layer "F.SilkS")
		)
		(fp_poly
			(pts
				(xy -0.5334 0.254) (xy -0.635 0.254) (xy -0.635 0.2286) (xy -0.635 -0.254) (xy -0.5334 -0.254) (xy -0.5334 -0.2794)
				(xy 0.5334 -0.2794) (xy 0.5334 -0.254) (xy 0.635 -0.254) (xy 0.635 0.254) (xy 0.5334 0.254) (xy 0.5334 0.2794)
				(xy -0.508 0.2794) (xy -0.5334 0.2794)
			)
			(stroke
				(width 0)
				(type default)
			)
			(fill no)
			(layer "F.CrtYd")
		)
		(pad "1" smd rect
			(at 0.40005 0 180)
			(size 0.4572 0.508)
			(layers "F.Cu" "F.Mask" "F.Paste")
			(net "P12V_AUX")
		)
		(pad "2" smd rect
			(at -0.40005 0 180)
			(size 0.4572 0.508)
			(layers "F.Cu" "F.Mask" "F.Paste")
			(net "GND")
		)
	)
	(footprint ""
		(layer "F.Cu")
		(at 134.807452 -154.81935 -90)
		(property "Reference" "R234"
			(at 110.801912 60.44946 90)
			(unlocked yes)
			(layer "F.SilkS")
			(effects
				(font
					(size 0.7874 0.5842)
					(thickness 0.1524)
				)
				(justify left)
			)
		)
		(property "Value" ""
			(at 0 0 270)
			(layer "F.Fab")
			(effects
				(font
					(size 1.27 1.27)
				)
			)
		)
		(duplicate_pad_numbers_are_jumpers no)
		(fp_line
			(start -0.7874 0.4064)
			(end -0.7874 -0.4064)
			(stroke
				(width 0.1524)
				(type default)
			)
			(layer "F.SilkS")
		)
		(fp_line
			(start 0.7874 0.4064)
			(end -0.7874 0.4064)
			(stroke
				(width 0.1524)
				(type default)
			)
			(layer "F.SilkS")
		)
		(fp_line
			(start -0.7874 -0.4064)
			(end 0.7874 -0.4064)
			(stroke
				(width 0.1524)
				(type default)
			)
			(layer "F.SilkS")
		)
		(fp_line
			(start 0.7874 -0.4064)
			(end 0.7874 0.4064)
			(stroke
				(width 0.1524)
				(type default)
			)
			(layer "F.SilkS")
		)
		(fp_poly
			(pts
				(xy -0.508 0.2794) (xy -0.508 0.2286) (xy -0.635 0.2286) (xy -0.635 -0.254) (xy -0.5334 -0.254)
				(xy -0.5334 -0.2794) (xy 0.5334 -0.2794) (xy 0.5334 -0.254) (xy 0.635 -0.254) (xy 0.635 0.254) (xy 0.5334 0.254)
				(xy 0.5334 0.2794)
			)
			(stroke
				(width 0)
				(type default)
			)
			(fill no)
			(layer "F.CrtYd")
		)
		(pad "1" smd rect
			(at 0.40005 0 270)
			(size 0.4572 0.508)
			(layers "F.Cu" "F.Mask" "F.Paste")
			(net "PCIE_SW_P0_ERR_R")
		)
		(pad "2" smd rect
			(at -0.40005 0 270)
			(size 0.4572 0.508)
			(layers "F.Cu" "F.Mask" "F.Paste")
			(net "PCIE_SW_P0_ERR")
		)
	)
	(footprint ""
		(layer "F.Cu")
		(at 138.991086 -156.743908 180)
		(property "Reference" "R1226"
			(at 63.166244 -109.010196 0)
			(unlocked yes)
			(layer "F.SilkS")
			(effects
				(font
					(size 0.7874 0.5842)
					(thickness 0.1524)
				)
				(justify left)
			)
		)
		(property "Value" ""
			(at 0 0 180)
			(layer "F.Fab")
			(effects
				(font
					(size 1.27 1.27)
				)
			)
		)
		(duplicate_pad_numbers_are_jumpers no)
		(fp_line
			(start 0.7874 0.4064)
			(end -0.7874 0.4064)
			(stroke
				(width 0.1524)
				(type default)
			)
			(layer "F.SilkS")
		)
		(fp_line
			(start 0.7874 -0.4064)
			(end 0.7874 0.4064)
			(stroke
				(width 0.1524)
				(type default)
			)
			(layer "F.SilkS")
		)
		(fp_line
			(start -0.7874 0.4064)
			(end -0.7874 -0.4064)
			(stroke
				(width 0.1524)
				(type default)
			)
			(layer "F.SilkS")
		)
		(fp_line
			(start -0.7874 -0.4064)
			(end 0.7874 -0.4064)
			(stroke
				(width 0.1524)
				(type default)
			)
			(layer "F.SilkS")
		)
		(fp_poly
			(pts
				(xy -0.508 0.2794) (xy -0.508 0.2286) (xy -0.635 0.2286) (xy -0.635 -0.254) (xy -0.5334 -0.254)
				(xy -0.5334 -0.2794) (xy 0.5334 -0.2794) (xy 0.5334 -0.254) (xy 0.635 -0.254) (xy 0.635 0.254) (xy 0.5334 0.254)
				(xy 0.5334 0.2794)
			)
			(stroke
				(width 0)
				(type default)
			)
			(fill no)
			(layer "F.CrtYd")
		)
		(pad "1" smd rect
			(at 0.40005 0 180)
			(size 0.4572 0.508)
			(layers "F.Cu" "F.Mask" "F.Paste")
			(net "GND")
		)
		(pad "2" smd rect
			(at -0.40005 0 180)
			(size 0.4572 0.508)
			(layers "F.Cu" "F.Mask" "F.Paste")
			(net "N49382752")
		)
	)
	(footprint ""
		(layer "F.Cu")
		(at 103.329994 -116.985796 180)
		(property "Reference" "PC126"
			(at 5.918454 -0.749808 0)
			(unlocked yes)
			(layer "F.SilkS")
			(effects
				(font
					(size 0.7874 0.5842)
					(thickness 0.1524)
				)
				(justify left)
			)
		)
		(property "Value" ""
			(at 0 0 180)
			(layer "F.Fab")
			(effects
				(font
					(size 1.27 1.27)
				)
			)
		)
		(duplicate_pad_numbers_are_jumpers no)
		(fp_line
			(start 1.905 0.8636)
			(end -1.905 0.8636)
			(stroke
				(width 0.1524)
				(type default)
			)
			(layer "F.SilkS")
		)
		(fp_line
			(start 1.905 -0.8636)
			(end 1.905 0.8636)
			(stroke
				(width 0.1524)
				(type default)
			)
			(layer "F.SilkS")
		)
		(fp_line
			(start 0 0.8382)
			(end 0 -0.8382)
			(stroke
				(width 0.1524)
				(type default)
			)
			(layer "F.SilkS")
		)
		(fp_line
			(start -1.905 0.8636)
			(end -1.905 -0.8636)
			(stroke
				(width 0.1524)
				(type default)
			)
			(layer "F.SilkS")
		)
		(fp_line
			(start -1.905 -0.8636)
			(end 1.905 -0.8636)
			(stroke
				(width 0.1524)
				(type default)
			)
			(layer "F.SilkS")
		)
		(fp_rect
			(start -1.524 0.7366)
			(end 1.524 -0.7366)
			(stroke
				(width 0)
				(type default)
			)
			(fill no)
			(layer "F.CrtYd")
		)
		(pad "1" smd rect
			(at 0.94996 0 180)
			(size 1.1176 1.3716)
			(layers "F.Cu" "F.Mask" "F.Paste")
			(net "GND")
		)
		(pad "2" smd rect
			(at -0.94996 0 180)
			(size 1.1176 1.3716)
			(layers "F.Cu" "F.Mask" "F.Paste")
			(net "PV_VCCP_NODE1")
		)
	)
	(footprint ""
		(layer "F.Cu")
		(at 12.26058 -154.13736 90)
		(property "Reference" "C549"
			(at -5.109464 8.025892 90)
			(unlocked yes)
			(layer "F.SilkS")
			(effects
				(font
					(size 0.7874 0.5842)
					(thickness 0.1524)
				)
				(justify left)
			)
		)
		(property "Value" ""
			(at 0 0 90)
			(layer "F.Fab")
			(effects
				(font
					(size 1.27 1.27)
				)
			)
		)
		(duplicate_pad_numbers_are_jumpers no)
		(fp_line
			(start 0.7874 -0.4064)
			(end 0.7874 0.4064)
			(stroke
				(width 0.1524)
				(type default)
			)
			(layer "F.SilkS")
		)
		(fp_line
			(start -0.7874 -0.4064)
			(end 0.7874 -0.4064)
			(stroke
				(width 0.1524)
				(type default)
			)
			(layer "F.SilkS")
		)
		(fp_line
			(start 0 0.381)
			(end 0 -0.381)
			(stroke
				(width 0.1524)
				(type default)
			)
			(layer "F.SilkS")
		)
		(fp_line
			(start 0.7874 0.4064)
			(end -0.7874 0.4064)
			(stroke
				(width 0.1524)
				(type default)
			)
			(layer "F.SilkS")
		)
		(fp_line
			(start -0.7874 0.4064)
			(end -0.7874 -0.4064)
			(stroke
				(width 0.1524)
				(type default)
			)
			(layer "F.SilkS")
		)
		(fp_poly
			(pts
				(xy -0.5334 0.254) (xy -0.635 0.254) (xy -0.635 0.2286) (xy -0.635 -0.254) (xy -0.5334 -0.254) (xy -0.5334 -0.2794)
				(xy 0.5334 -0.2794) (xy 0.5334 -0.254) (xy 0.635 -0.254) (xy 0.635 0.254) (xy 0.5334 0.254) (xy 0.5334 0.2794)
				(xy -0.508 0.2794) (xy -0.5334 0.2794)
			)
			(stroke
				(width 0)
				(type default)
			)
			(fill no)
			(layer "F.CrtYd")
		)
		(pad "1" smd rect
			(at 0.40005 0 90)
			(size 0.4572 0.508)
			(layers "F.Cu" "F.Mask" "F.Paste")
			(net "N54258513")
		)
		(pad "2" smd rect
			(at -0.40005 0 90)
			(size 0.4572 0.508)
			(layers "F.Cu" "F.Mask" "F.Paste")
			(net "N54258515")
		)
	)
	(footprint ""
		(layer "F.Cu")
		(at 167.630602 -8.585962 180)
		(property "Reference" "J27"
			(at 6.645402 -3.939032 0)
			(unlocked yes)
			(layer "F.SilkS")
			(effects
				(font
					(size 0.7874 0.5842)
					(thickness 0.1524)
				)
				(justify left)
			)
		)
		(property "Value" ""
			(at 0 0 180)
			(layer "F.Fab")
			(effects
				(font
					(size 1.27 1.27)
				)
			)
		)
		(duplicate_pad_numbers_are_jumpers no)
		(fp_line
			(start 6.599936 2.640076)
			(end -6.599936 2.640076)
			(stroke
				(width 0.1524)
				(type default)
			)
			(layer "F.SilkS")
		)
		(fp_line
			(start 6.599936 -2.640076)
			(end 6.599936 2.640076)
			(stroke
				(width 0.1524)
				(type default)
			)
			(layer "F.SilkS")
		)
		(fp_line
			(start -6.599936 2.640076)
			(end -6.599936 -2.640076)
			(stroke
				(width 0.1524)
				(type default)
			)
			(layer "F.SilkS")
		)
		(fp_line
			(start -6.599936 -2.640076)
			(end 6.599936 -2.640076)
			(stroke
				(width 0.1524)
				(type default)
			)
			(layer "F.SilkS")
		)
		(fp_poly
			(pts
				(xy -4.48818 4.713224) (xy -5.25018 6.618224) (xy -3.72618 6.618224)
			)
			(stroke
				(width 0)
				(type default)
			)
			(fill yes)
			(layer "F.SilkS")
		)
		(fp_poly
			(pts
				(xy -5.969 -2.159) (xy 5.969 -2.159) (xy 5.969 2.159) (xy -5.969 2.159)
			)
			(stroke
				(width 0)
				(type default)
			)
			(fill no)
			(layer "B.CrtYd")
		)
		(fp_poly
			(pts
				(xy -6.599936 2.640076) (xy 6.599936 2.640076) (xy 6.599936 -2.640076) (xy -6.599936 -2.640076)
			)
			(stroke
				(width 0)
				(type default)
			)
			(fill no)
			(layer "F.CrtYd")
		)
		(fp_line
			(start 6.599936 2.640076)
			(end -6.599936 2.640076)
			(stroke
				(width 0.1)
				(type default)
			)
			(layer "F.Fab")
		)
		(fp_line
			(start 6.599936 -2.640076)
			(end 6.599936 2.640076)
			(stroke
				(width 0.1)
				(type default)
			)
			(layer "F.Fab")
		)
		(fp_line
			(start -6.599936 2.640076)
			(end -6.599936 -2.640076)
			(stroke
				(width 0.1)
				(type default)
			)
			(layer "F.Fab")
		)
		(fp_line
			(start -6.599936 -2.640076)
			(end 6.599936 -2.640076)
			(stroke
				(width 0.1)
				(type default)
			)
			(layer "F.Fab")
		)
		(fp_poly
			(pts
				(xy -7.4295 1.27) (xy -9.3345 0.508) (xy -9.3345 2.032)
			)
			(stroke
				(width 0)
				(type default)
			)
			(fill yes)
			(layer "F.Fab")
		)
		(fp_text user "10"
			(at 8.129016 -1.710436 0)
			(unlocked yes)
			(layer "F.SilkS")
			(effects
				(font
					(size 0.7874 0.5842)
					(thickness 0.1524)
				)
				(justify left)
			)
		)
		(fp_text user "9"
			(at 7.730236 2.328164 0)
			(unlocked yes)
			(layer "F.SilkS")
			(effects
				(font
					(size 0.7874 0.5842)
					(thickness 0.1524)
				)
				(justify left)
			)
		)
		(fp_text user "1"
			(at -6.76402 2.261362 0)
			(unlocked yes)
			(layer "F.SilkS")
			(effects
				(font
					(size 0.7874 0.5842)
					(thickness 0.1524)
				)
				(justify left)
			)
		)
		(fp_text user "2"
			(at -6.872732 -1.448562 0)
			(unlocked yes)
			(layer "F.SilkS")
			(effects
				(font
					(size 0.7874 0.5842)
					(thickness 0.1524)
				)
				(justify left)
			)
		)
		(fp_text user "9"
			(at 6.256274 1.067308 0)
			(unlocked yes)
			(layer "B.SilkS")
			(effects
				(font
					(size 0.7874 0.5842)
					(thickness 0.1524)
				)
				(justify left mirror)
			)
		)
		(fp_text user "10"
			(at 6.126734 -1.340866 0)
			(unlocked yes)
			(layer "B.SilkS")
			(effects
				(font
					(size 0.7874 0.5842)
					(thickness 0.1524)
				)
				(justify left mirror)
			)
		)
		(fp_text user "1"
			(at -6.794246 1.360424 0)
			(unlocked yes)
			(layer "B.SilkS")
			(effects
				(font
					(size 0.7874 0.5842)
					(thickness 0.1524)
				)
				(justify left mirror)
			)
		)
		(fp_text user "2"
			(at -6.923786 -0.917956 0)
			(unlocked yes)
			(layer "B.SilkS")
			(effects
				(font
					(size 0.7874 0.5842)
					(thickness 0.1524)
				)
				(justify left mirror)
			)
		)
		(fp_text user "10"
			(at 7.5438 -1.361948 180)
			(unlocked yes)
			(layer "B.Fab")
			(effects
				(font
					(size 0.7874 0.5842)
					(thickness 0.000001)
				)
				(justify left mirror)
			)
		)
		(fp_text user "9"
			(at 7.1501 1.178052 180)
			(unlocked yes)
			(layer "B.Fab")
			(effects
				(font
					(size 0.7874 0.5842)
					(thickness 0.000001)
				)
				(justify left mirror)
			)
		)
		(fp_text user "1"
			(at -6.1849 1.178052 180)
			(unlocked yes)
			(layer "B.Fab")
			(effects
				(font
					(size 0.7874 0.5842)
					(thickness 0.000001)
				)
				(justify left mirror)
			)
		)
		(fp_text user "2"
			(at -6.1849 -1.361948 180)
			(unlocked yes)
			(layer "B.Fab")
			(effects
				(font
					(size 0.7874 0.5842)
					(thickness 0.000001)
				)
				(justify left mirror)
			)
		)
		(fp_text user "9"
			(at 6.9469 1.178052 180)
			(unlocked yes)
			(layer "F.Fab")
			(effects
				(font
					(size 0.7874 0.5842)
					(thickness 0.000001)
				)
				(justify left)
			)
		)
		(fp_text user "10"
			(at 6.5532 -1.361948 180)
			(unlocked yes)
			(layer "F.Fab")
			(effects
				(font
					(size 0.7874 0.5842)
					(thickness 0.000001)
				)
				(justify left)
			)
		)
		(fp_text user "1"
			(at -7.5311 1.178052 180)
			(unlocked yes)
			(layer "F.Fab")
			(effects
				(font
					(size 0.7874 0.5842)
					(thickness 0.000001)
				)
				(justify left)
			)
		)
		(fp_text user "2"
			(at -7.5311 -1.361948 180)
			(unlocked yes)
			(layer "F.Fab")
			(effects
				(font
					(size 0.7874 0.5842)
					(thickness 0.000001)
				)
				(justify left)
			)
		)
		(pad "1" thru_hole rect
			(at -5.08 1.27 270)
			(size 1.6764 1.6764)
			(drill 1.1684)
			(layers "*.Cu" "*.Mask")
			(remove_unused_layers no)
			(net "JTAG_CPLD3_TCK")
			(clearance 0)
			(padstack
				(mode front_inner_back)
				(layer "Inner"
					(shape circle)
					(size 1.6764 1.6764)
					(clearance 0)
				)
				(layer "B.Cu"
					(shape rect)
					(size 1.6764 1.6764)
					(clearance 0)
				)
			)
		)
		(pad "2" thru_hole circle
			(at -5.08 -1.27 270)
			(size 1.6764 1.6764)
			(drill 1.1684)
			(layers "*.Cu" "*.Mask")
			(remove_unused_layers no)
			(net "GND")
			(clearance 0)
		)
		(pad "3" thru_hole circle
			(at -2.54 1.27 270)
			(size 1.6764 1.6764)
			(drill 1.1684)
			(layers "*.Cu" "*.Mask")
			(remove_unused_layers no)
			(net "JTAG_CPLD3_TDO")
			(clearance 0)
		)
		(pad "4" thru_hole circle
			(at -2.54 -1.27 270)
			(size 1.6764 1.6764)
			(drill 1.1684)
			(layers "*.Cu" "*.Mask")
			(remove_unused_layers no)
			(net "P3V3_NODE1")
			(clearance 0)
		)
		(pad "5" thru_hole circle
			(at 0 1.27 270)
			(size 1.6764 1.6764)
			(drill 1.1684)
			(layers "*.Cu" "*.Mask")
			(remove_unused_layers no)
			(net "JTAG_CPLD3_TMS")
			(clearance 0)
		)
		(pad "6" thru_hole circle
			(at 0 -1.27 270)
			(size 1.6764 1.6764)
			(drill 1.1684)
			(layers "*.Cu" "*.Mask")
			(remove_unused_layers no)
			(net "Net_2275")
			(clearance 0)
		)
		(pad "7" thru_hole circle
			(at 2.54 1.27 270)
			(size 1.6764 1.6764)
			(drill 1.1684)
			(layers "*.Cu" "*.Mask")
			(remove_unused_layers no)
			(net "Net_2274")
			(clearance 0)
		)
		(pad "8" thru_hole circle
			(at 2.54 -1.27 270)
			(size 1.6764 1.6764)
			(drill 1.1684)
			(layers "*.Cu" "*.Mask")
			(remove_unused_layers no)
			(net "Net_2273")
			(clearance 0)
		)
		(pad "9" thru_hole circle
			(at 5.08 1.27 270)
			(size 1.6764 1.6764)
			(drill 1.1684)
			(layers "*.Cu" "*.Mask")
			(remove_unused_layers no)
			(net "JTAG_CPLD3_TDI")
			(clearance 0)
		)
		(pad "10" thru_hole circle
			(at 5.08 -1.27 270)
			(size 1.6764 1.6764)
			(drill 1.1684)
			(layers "*.Cu" "*.Mask")
			(remove_unused_layers no)
			(net "GND")
			(clearance 0)
		)
	)
	(footprint ""
		(layer "F.Cu")
		(at 65.464182 -173.527466 180)
		(property "Reference" "U84"
			(at 13.037058 -133.039612 90)
			(unlocked yes)
			(layer "F.SilkS")
			(effects
				(font
					(size 0.7874 0.5842)
					(thickness 0.1524)
				)
				(justify left)
			)
		)
		(property "Value" ""
			(at 0 0 180)
			(layer "F.Fab")
			(effects
				(font
					(size 1.27 1.27)
				)
			)
		)
		(duplicate_pad_numbers_are_jumpers no)
		(fp_line
			(start 1.549908 2.032)
			(end -1.549908 2.032)
			(stroke
				(width 0.1524)
				(type default)
			)
			(layer "F.SilkS")
		)
		(fp_line
			(start 1.549908 -2.032)
			(end 1.549908 2.032)
			(stroke
				(width 0.1524)
				(type default)
			)
			(layer "F.SilkS")
		)
		(fp_line
			(start -1.549908 2.032)
			(end -1.549908 -2.032)
			(stroke
				(width 0.1524)
				(type default)
			)
			(layer "F.SilkS")
		)
		(fp_line
			(start -1.549908 -2.032)
			(end 1.549908 -2.032)
			(stroke
				(width 0.1524)
				(type default)
			)
			(layer "F.SilkS")
		)
		(fp_poly
			(pts
				(xy -2.9464 1.016) (xy -2.9464 1.524) (xy -2.1844 1.27)
			)
			(stroke
				(width 0)
				(type default)
			)
			(fill yes)
			(layer "F.SilkS")
		)
		(fp_poly
			(pts
				(xy -1.549908 0.849884) (xy -1.2319 0.849884) (xy -1.2319 1.9431) (xy -1.1811 1.9431) (xy 1.1811 1.9431)
				(xy 1.2319 1.9431) (xy 1.2319 0.849884) (xy 1.549908 0.849884) (xy 1.549908 -0.849884) (xy 1.2319 -0.849884)
				(xy 1.2319 -1.9431) (xy 1.1811 -1.9431) (xy -1.1811 -1.9431) (xy -1.2319 -1.9431) (xy -1.2319 -0.849884)
				(xy -1.549908 -0.849884)
			)
			(stroke
				(width 0)
				(type default)
			)
			(fill no)
			(layer "F.CrtYd")
		)
		(fp_line
			(start 1.549908 0.849884)
			(end 1.549908 -0.849884)
			(stroke
				(width 0.1)
				(type default)
			)
			(layer "F.Fab")
		)
		(fp_line
			(start 1.549908 -0.849884)
			(end -1.549908 -0.849884)
			(stroke
				(width 0.1)
				(type default)
			)
			(layer "F.Fab")
		)
		(fp_line
			(start -1.549908 0.849884)
			(end 1.549908 0.849884)
			(stroke
				(width 0.1)
				(type default)
			)
			(layer "F.Fab")
		)
		(fp_line
			(start -1.549908 -0.849884)
			(end -1.549908 0.849884)
			(stroke
				(width 0.1)
				(type default)
			)
			(layer "F.Fab")
		)
		(fp_text user "3"
			(at 1.54686 2.678938 0)
			(unlocked yes)
			(layer "F.SilkS")
			(effects
				(font
					(size 0.635 0.4064)
					(thickness 0.1524)
				)
				(justify left)
			)
		)
		(fp_text user "4"
			(at 0.921258 -2.544826 0)
			(unlocked yes)
			(layer "F.SilkS")
			(effects
				(font
					(size 0.635 0.4064)
					(thickness 0.1524)
				)
				(justify left)
			)
		)
		(fp_text user "5"
			(at 0.363982 -2.565908 0)
			(unlocked yes)
			(layer "F.SilkS")
			(effects
				(font
					(size 0.635 0.4064)
					(thickness 0.1524)
				)
				(justify left)
			)
		)
		(fp_text user "1"
			(at -1.401572 2.503932 0)
			(unlocked yes)
			(layer "F.SilkS")
			(effects
				(font
					(size 0.635 0.4064)
					(thickness 0.1524)
				)
				(justify left)
			)
		)
		(pad "1" smd rect
			(at -0.94996 1.225042 180)
			(size 0.4572 1.3208)
			(layers "F.Cu" "F.Mask" "F.Paste")
			(net "Net_1705")
		)
		(pad "2" smd rect
			(at 0 1.225042 180)
			(size 0.4572 1.3208)
			(layers "F.Cu" "F.Mask" "F.Paste")
			(net "PSU1_DC_OK_R_BUF")
		)
		(pad "3" smd rect
			(at 0.94996 1.225042 180)
			(size 0.4572 1.3208)
			(layers "F.Cu" "F.Mask" "F.Paste")
			(net "GND")
		)
		(pad "4" smd rect
			(at 0.94996 -1.225042 180)
			(size 0.4572 1.3208)
			(layers "F.Cu" "F.Mask" "F.Paste")
			(net "PSU1_DC_OK")
		)
		(pad "5" smd rect
			(at -0.94996 -1.225042 180)
			(size 0.4572 1.3208)
			(layers "F.Cu" "F.Mask" "F.Paste")
			(net "P3V3_NODE1")
		)
	)
	(footprint ""
		(layer "F.Cu")
		(at 128.902206 -71.510652 -90)
		(property "Reference" "BT1"
			(at -22.363938 -6.686296 0)
			(unlocked yes)
			(layer "F.SilkS")
			(effects
				(font
					(size 0.7874 0.5842)
					(thickness 0.1524)
				)
				(justify left)
			)
		)
		(property "Value" ""
			(at 0 0 270)
			(layer "F.Fab")
			(effects
				(font
					(size 1.27 1.27)
				)
			)
		)
		(duplicate_pad_numbers_are_jumpers no)
		(fp_line
			(start -1.75006 3.899916)
			(end 1.130046 3.899916)
			(stroke
				(width 0.1524)
				(type default)
			)
			(layer "F.SilkS")
		)
		(fp_line
			(start 1.130046 3.899916)
			(end 1.130046 -3.899916)
			(stroke
				(width 0.1524)
				(type default)
			)
			(layer "F.SilkS")
		)
		(fp_line
			(start 1.130046 -3.899916)
			(end -1.75006 -3.899916)
			(stroke
				(width 0.1524)
				(type default)
			)
			(layer "F.SilkS")
		)
		(fp_circle
			(center -17.629886 8.720074)
			(end -17.629886 7.819898)
			(stroke
				(width 0.1524)
				(type default)
			)
			(fill no)
			(layer "F.SilkS")
		)
		(fp_circle
			(center -12.290044 0)
			(end -12.290044 -11.250168)
			(stroke
				(width 0.1524)
				(type default)
			)
			(fill no)
			(layer "F.SilkS")
		)
		(fp_circle
			(center -4.430014 0)
			(end -4.430014 -0.899922)
			(stroke
				(width 0.1524)
				(type default)
			)
			(fill no)
			(layer "F.SilkS")
		)
		(fp_circle
			(center -17.629886 -8.720074)
			(end -17.629886 -9.619996)
			(stroke
				(width 0.1524)
				(type default)
			)
			(fill no)
			(layer "F.SilkS")
		)
		(fp_poly
			(pts
				(xy 0.8128 0.8128) (xy 0.8128 -0.8128) (xy -0.8128 -0.8128) (xy -0.8128 0.8128)
			)
			(stroke
				(width 0)
				(type default)
			)
			(fill no)
			(layer "B.CrtYd")
		)
		(fp_poly
			(pts
				(arc
					(start -19.99996 -0.762)
					(mid -19.99996 0.762)
					(end -19.99996 -0.762)
				)
			)
			(stroke
				(width 0)
				(type default)
			)
			(fill no)
			(layer "B.CrtYd")
		)
		(fp_poly
			(pts
				(arc
					(start -1.737614 3.899916)
					(mid -23.540072 0)
					(end -1.737614 -3.899916)
				)
				(xy 1.130046 -3.899916) (xy 1.130046 3.899916)
			)
			(stroke
				(width 0)
				(type default)
			)
			(fill no)
			(layer "F.CrtYd")
		)
		(fp_text user "+"
			(at -0.187452 -4.61391 270)
			(unlocked yes)
			(layer "F.SilkS")
			(effects
				(font
					(size 1.6002 1.1938)
					(thickness 0.1524)
				)
				(justify left)
			)
		)
		(pad "1" thru_hole rect
			(at 0 0 270)
			(size 1.6256 1.6256)
			(drill 1.1176)
			(layers "*.Cu" "*.Mask")
			(remove_unused_layers no)
			(net "P3V_COIN_CELL")
			(clearance 0)
			(padstack
				(mode front_inner_back)
				(layer "Inner"
					(shape circle)
					(size 1.6256 1.6256)
					(clearance 0)
				)
				(layer "B.Cu"
					(shape rect)
					(size 1.6256 1.6256)
					(clearance 0)
				)
			)
		)
		(pad "2" thru_hole circle
			(at -19.99996 0 270)
			(size 1.524 1.524)
			(drill 1.016)
			(layers "*.Cu" "*.Mask")
			(remove_unused_layers no)
			(net "GND")
			(clearance 0)
		)
	)
	(footprint ""
		(layer "F.Cu")
		(at 82.02676 -182.411624 -90)
		(property "Reference" "C586"
			(at 1.068324 -1.173226 90)
			(unlocked yes)
			(layer "F.SilkS")
			(effects
				(font
					(size 0.7874 0.5842)
					(thickness 0.1524)
				)
				(justify left)
			)
		)
		(property "Value" ""
			(at 0 0 270)
			(layer "F.Fab")
			(effects
				(font
					(size 1.27 1.27)
				)
			)
		)
		(duplicate_pad_numbers_are_jumpers no)
		(fp_line
			(start -0.7874 0.4064)
			(end -0.7874 -0.4064)
			(stroke
				(width 0.1524)
				(type default)
			)
			(layer "F.SilkS")
		)
		(fp_line
			(start 0.7874 0.4064)
			(end -0.7874 0.4064)
			(stroke
				(width 0.1524)
				(type default)
			)
			(layer "F.SilkS")
		)
		(fp_line
			(start 0 0.381)
			(end 0 -0.381)
			(stroke
				(width 0.1524)
				(type default)
			)
			(layer "F.SilkS")
		)
		(fp_line
			(start -0.7874 -0.4064)
			(end 0.7874 -0.4064)
			(stroke
				(width 0.1524)
				(type default)
			)
			(layer "F.SilkS")
		)
		(fp_line
			(start 0.7874 -0.4064)
			(end 0.7874 0.4064)
			(stroke
				(width 0.1524)
				(type default)
			)
			(layer "F.SilkS")
		)
		(fp_poly
			(pts
				(xy -0.5334 0.254) (xy -0.635 0.254) (xy -0.635 0.2286) (xy -0.635 -0.254) (xy -0.5334 -0.254) (xy -0.5334 -0.2794)
				(xy 0.5334 -0.2794) (xy 0.5334 -0.254) (xy 0.635 -0.254) (xy 0.635 0.254) (xy 0.5334 0.254) (xy 0.5334 0.2794)
				(xy -0.508 0.2794) (xy -0.5334 0.2794)
			)
			(stroke
				(width 0)
				(type default)
			)
			(fill no)
			(layer "F.CrtYd")
		)
		(pad "1" smd rect
			(at 0.40005 0 270)
			(size 0.4572 0.508)
			(layers "F.Cu" "F.Mask" "F.Paste")
			(net "P3V3_NODE1")
		)
		(pad "2" smd rect
			(at -0.40005 0 270)
			(size 0.4572 0.508)
			(layers "F.Cu" "F.Mask" "F.Paste")
			(net "GND")
		)
	)
	(footprint ""
		(layer "F.Cu")
		(at 165.811454 -165.118288)
		(property "Reference" "R575"
			(at 1.22936 0.3937 0)
			(unlocked yes)
			(layer "F.SilkS")
			(effects
				(font
					(size 0.7874 0.5842)
					(thickness 0.1524)
				)
				(justify left)
			)
		)
		(property "Value" ""
			(at 0 0 0)
			(layer "F.Fab")
			(effects
				(font
					(size 1.27 1.27)
				)
			)
		)
		(duplicate_pad_numbers_are_jumpers no)
		(fp_line
			(start -0.7874 -0.4064)
			(end 0.7874 -0.4064)
			(stroke
				(width 0.1524)
				(type default)
			)
			(layer "F.SilkS")
		)
		(fp_line
			(start -0.7874 0.4064)
			(end -0.7874 -0.4064)
			(stroke
				(width 0.1524)
				(type default)
			)
			(layer "F.SilkS")
		)
		(fp_line
			(start 0.7874 -0.4064)
			(end 0.7874 0.4064)
			(stroke
				(width 0.1524)
				(type default)
			)
			(layer "F.SilkS")
		)
		(fp_line
			(start 0.7874 0.4064)
			(end -0.7874 0.4064)
			(stroke
				(width 0.1524)
				(type default)
			)
			(layer "F.SilkS")
		)
		(fp_poly
			(pts
				(xy -0.508 0.2794) (xy -0.508 0.2286) (xy -0.635 0.2286) (xy -0.635 -0.254) (xy -0.5334 -0.254)
				(xy -0.5334 -0.2794) (xy 0.5334 -0.2794) (xy 0.5334 -0.254) (xy 0.635 -0.254) (xy 0.635 0.254) (xy 0.5334 0.254)
				(xy 0.5334 0.2794)
			)
			(stroke
				(width 0)
				(type default)
			)
			(fill no)
			(layer "F.CrtYd")
		)
		(pad "1" smd rect
			(at 0.40005 0)
			(size 0.4572 0.508)
			(layers "F.Cu" "F.Mask" "F.Paste")
			(net "SPI_LAN2_NVM_SK")
		)
		(pad "2" smd rect
			(at -0.40005 0)
			(size 0.4572 0.508)
			(layers "F.Cu" "F.Mask" "F.Paste")
			(net "LAN2_NVM_SK_R")
		)
	)
	(footprint ""
		(layer "F.Cu")
		(at 188.849 -127.254)
		(property "Reference" "R1268"
			(at 6.477 18.82267 0)
			(unlocked yes)
			(layer "F.SilkS")
			(effects
				(font
					(size 0.7874 0.5842)
					(thickness 0.1524)
				)
				(justify left)
			)
		)
		(property "Value" ""
			(at 0 0 0)
			(layer "F.Fab")
			(effects
				(font
					(size 1.27 1.27)
				)
			)
		)
		(duplicate_pad_numbers_are_jumpers no)
		(fp_line
			(start -0.7874 -0.4064)
			(end 0.7874 -0.4064)
			(stroke
				(width 0.1524)
				(type default)
			)
			(layer "F.SilkS")
		)
		(fp_line
			(start -0.7874 0.4064)
			(end -0.7874 -0.4064)
			(stroke
				(width 0.1524)
				(type default)
			)
			(layer "F.SilkS")
		)
		(fp_line
			(start 0.7874 -0.4064)
			(end 0.7874 0.4064)
			(stroke
				(width 0.1524)
				(type default)
			)
			(layer "F.SilkS")
		)
		(fp_line
			(start 0.7874 0.4064)
			(end -0.7874 0.4064)
			(stroke
				(width 0.1524)
				(type default)
			)
			(layer "F.SilkS")
		)
		(fp_poly
			(pts
				(xy -0.508 0.2794) (xy -0.508 0.2286) (xy -0.635 0.2286) (xy -0.635 -0.254) (xy -0.5334 -0.254)
				(xy -0.5334 -0.2794) (xy 0.5334 -0.2794) (xy 0.5334 -0.254) (xy 0.635 -0.254) (xy 0.635 0.254) (xy 0.5334 0.254)
				(xy 0.5334 0.2794)
			)
			(stroke
				(width 0)
				(type default)
			)
			(fill no)
			(layer "F.CrtYd")
		)
		(pad "1" smd rect
			(at 0.40005 0)
			(size 0.4572 0.508)
			(layers "F.Cu" "F.Mask" "F.Paste")
			(net "SIO_JTAG_CPLD1_TMS_R")
		)
		(pad "2" smd rect
			(at -0.40005 0)
			(size 0.4572 0.508)
			(layers "F.Cu" "F.Mask" "F.Paste")
			(net "SIO_JTAG_CPLD1_TMS")
		)
	)
	(footprint ""
		(layer "F.Cu")
		(at 113.361216 -18.649442 90)
		(property "Reference" "C860"
			(at -1.7018 5.742432 90)
			(unlocked yes)
			(layer "F.SilkS")
			(effects
				(font
					(size 0.7874 0.5842)
					(thickness 0.1524)
				)
				(justify left)
			)
		)
		(property "Value" ""
			(at 0 0 90)
			(layer "F.Fab")
			(effects
				(font
					(size 1.27 1.27)
				)
			)
		)
		(duplicate_pad_numbers_are_jumpers no)
		(fp_line
			(start 0.7874 -0.4064)
			(end 0.7874 0.4064)
			(stroke
				(width 0.1524)
				(type default)
			)
			(layer "F.SilkS")
		)
		(fp_line
			(start -0.7874 -0.4064)
			(end 0.7874 -0.4064)
			(stroke
				(width 0.1524)
				(type default)
			)
			(layer "F.SilkS")
		)
		(fp_line
			(start 0 0.381)
			(end 0 -0.381)
			(stroke
				(width 0.1524)
				(type default)
			)
			(layer "F.SilkS")
		)
		(fp_line
			(start 0.7874 0.4064)
			(end -0.7874 0.4064)
			(stroke
				(width 0.1524)
				(type default)
			)
			(layer "F.SilkS")
		)
		(fp_line
			(start -0.7874 0.4064)
			(end -0.7874 -0.4064)
			(stroke
				(width 0.1524)
				(type default)
			)
			(layer "F.SilkS")
		)
		(fp_poly
			(pts
				(xy -0.5334 0.254) (xy -0.635 0.254) (xy -0.635 0.2286) (xy -0.635 -0.254) (xy -0.5334 -0.254) (xy -0.5334 -0.2794)
				(xy 0.5334 -0.2794) (xy 0.5334 -0.254) (xy 0.635 -0.254) (xy 0.635 0.254) (xy 0.5334 0.254) (xy 0.5334 0.2794)
				(xy -0.508 0.2794) (xy -0.5334 0.2794)
			)
			(stroke
				(width 0)
				(type default)
			)
			(fill no)
			(layer "F.CrtYd")
		)
		(pad "1" smd rect
			(at 0.40005 0 90)
			(size 0.4572 0.508)
			(layers "F.Cu" "F.Mask" "F.Paste")
			(net "PV_VTT_DDR_NODE1_REFOUT")
		)
		(pad "2" smd rect
			(at -0.40005 0 90)
			(size 0.4572 0.508)
			(layers "F.Cu" "F.Mask" "F.Paste")
			(net "GND")
		)
	)
	(footprint ""
		(layer "F.Cu")
		(at 33.344104 -117.535452)
		(property "Reference" "C850"
			(at -6.139688 1.072642 0)
			(unlocked yes)
			(layer "F.SilkS")
			(effects
				(font
					(size 0.7874 0.5842)
					(thickness 0.1524)
				)
				(justify left)
			)
		)
		(property "Value" ""
			(at 0 0 0)
			(layer "F.Fab")
			(effects
				(font
					(size 1.27 1.27)
				)
			)
		)
		(duplicate_pad_numbers_are_jumpers no)
		(fp_line
			(start -0.7874 -0.4064)
			(end 0.7874 -0.4064)
			(stroke
				(width 0.1524)
				(type default)
			)
			(layer "F.SilkS")
		)
		(fp_line
			(start -0.7874 0.4064)
			(end -0.7874 -0.4064)
			(stroke
				(width 0.1524)
				(type default)
			)
			(layer "F.SilkS")
		)
		(fp_line
			(start 0 0.381)
			(end 0 -0.381)
			(stroke
				(width 0.1524)
				(type default)
			)
			(layer "F.SilkS")
		)
		(fp_line
			(start 0.7874 -0.4064)
			(end 0.7874 0.4064)
			(stroke
				(width 0.1524)
				(type default)
			)
			(layer "F.SilkS")
		)
		(fp_line
			(start 0.7874 0.4064)
			(end -0.7874 0.4064)
			(stroke
				(width 0.1524)
				(type default)
			)
			(layer "F.SilkS")
		)
		(fp_poly
			(pts
				(xy -0.5334 0.254) (xy -0.635 0.254) (xy -0.635 0.2286) (xy -0.635 -0.254) (xy -0.5334 -0.254) (xy -0.5334 -0.2794)
				(xy 0.5334 -0.2794) (xy 0.5334 -0.254) (xy 0.635 -0.254) (xy 0.635 0.254) (xy 0.5334 0.254) (xy 0.5334 0.2794)
				(xy -0.508 0.2794) (xy -0.5334 0.2794)
			)
			(stroke
				(width 0)
				(type default)
			)
			(fill no)
			(layer "F.CrtYd")
		)
		(pad "1" smd rect
			(at 0.40005 0)
			(size 0.4572 0.508)
			(layers "F.Cu" "F.Mask" "F.Paste")
			(net "FM_CPLD_NODE1_P1V5_EN")
		)
		(pad "2" smd rect
			(at -0.40005 0)
			(size 0.4572 0.508)
			(layers "F.Cu" "F.Mask" "F.Paste")
			(net "GND")
		)
	)
	(footprint ""
		(layer "F.Cu")
		(at 47.10176 -185.205624 90)
		(property "Reference" "R846"
			(at 4.006088 0.055372 90)
			(unlocked yes)
			(layer "F.SilkS")
			(effects
				(font
					(size 0.7874 0.5842)
					(thickness 0.1524)
				)
				(justify left)
			)
		)
		(property "Value" ""
			(at 0 0 90)
			(layer "F.Fab")
			(effects
				(font
					(size 1.27 1.27)
				)
			)
		)
		(duplicate_pad_numbers_are_jumpers no)
		(fp_line
			(start 0.7874 -0.4064)
			(end 0.7874 0.4064)
			(stroke
				(width 0.1524)
				(type default)
			)
			(layer "F.SilkS")
		)
		(fp_line
			(start -0.7874 -0.4064)
			(end 0.7874 -0.4064)
			(stroke
				(width 0.1524)
				(type default)
			)
			(layer "F.SilkS")
		)
		(fp_line
			(start 0.7874 0.4064)
			(end -0.7874 0.4064)
			(stroke
				(width 0.1524)
				(type default)
			)
			(layer "F.SilkS")
		)
		(fp_line
			(start -0.7874 0.4064)
			(end -0.7874 -0.4064)
			(stroke
				(width 0.1524)
				(type default)
			)
			(layer "F.SilkS")
		)
		(fp_poly
			(pts
				(xy -0.508 0.2794) (xy -0.508 0.2286) (xy -0.635 0.2286) (xy -0.635 -0.254) (xy -0.5334 -0.254)
				(xy -0.5334 -0.2794) (xy 0.5334 -0.2794) (xy 0.5334 -0.254) (xy 0.635 -0.254) (xy 0.635 0.254) (xy 0.5334 0.254)
				(xy 0.5334 0.2794)
			)
			(stroke
				(width 0)
				(type default)
			)
			(fill no)
			(layer "F.CrtYd")
		)
		(pad "1" smd rect
			(at 0.40005 0 90)
			(size 0.4572 0.508)
			(layers "F.Cu" "F.Mask" "F.Paste")
			(net "PSU6_AC_OK_R")
		)
		(pad "2" smd rect
			(at -0.40005 0 90)
			(size 0.4572 0.508)
			(layers "F.Cu" "F.Mask" "F.Paste")
			(net "PSU6_AC_OK")
		)
	)
	(footprint ""
		(layer "F.Cu")
		(at 30.55747 -131.833874 180)
		(property "Reference" "R1095"
			(at 1.270254 3.13055 0)
			(unlocked yes)
			(layer "F.SilkS")
			(effects
				(font
					(size 0.7874 0.5842)
					(thickness 0.1524)
				)
				(justify left)
			)
		)
		(property "Value" ""
			(at 0 0 180)
			(layer "F.Fab")
			(effects
				(font
					(size 1.27 1.27)
				)
			)
		)
		(duplicate_pad_numbers_are_jumpers no)
		(fp_line
			(start 0.7874 0.4064)
			(end -0.7874 0.4064)
			(stroke
				(width 0.1524)
				(type default)
			)
			(layer "F.SilkS")
		)
		(fp_line
			(start 0.7874 -0.4064)
			(end 0.7874 0.4064)
			(stroke
				(width 0.1524)
				(type default)
			)
			(layer "F.SilkS")
		)
		(fp_line
			(start -0.7874 0.4064)
			(end -0.7874 -0.4064)
			(stroke
				(width 0.1524)
				(type default)
			)
			(layer "F.SilkS")
		)
		(fp_line
			(start -0.7874 -0.4064)
			(end 0.7874 -0.4064)
			(stroke
				(width 0.1524)
				(type default)
			)
			(layer "F.SilkS")
		)
		(fp_poly
			(pts
				(xy -0.508 0.2794) (xy -0.508 0.2286) (xy -0.635 0.2286) (xy -0.635 -0.254) (xy -0.5334 -0.254)
				(xy -0.5334 -0.2794) (xy 0.5334 -0.2794) (xy 0.5334 -0.254) (xy 0.635 -0.254) (xy 0.635 0.254) (xy 0.5334 0.254)
				(xy 0.5334 0.2794)
			)
			(stroke
				(width 0)
				(type default)
			)
			(fill no)
			(layer "F.CrtYd")
		)
		(pad "1" smd rect
			(at 0.40005 0 180)
			(size 0.4572 0.508)
			(layers "F.Cu" "F.Mask" "F.Paste")
			(net "P1V538_BMC_NODE1_ADJ")
		)
		(pad "2" smd rect
			(at -0.40005 0 180)
			(size 0.4572 0.508)
			(layers "F.Cu" "F.Mask" "F.Paste")
			(net "P1V538_STB_NODE1_ADJ_S")
		)
	)
	(footprint ""
		(layer "F.Cu")
		(at 23.230332 -128.936242 -90)
		(property "Reference" "R1239"
			(at 2.981706 -4.05257 90)
			(unlocked yes)
			(layer "F.SilkS")
			(effects
				(font
					(size 0.7874 0.5842)
					(thickness 0.1524)
				)
				(justify left)
			)
		)
		(property "Value" ""
			(at 0 0 270)
			(layer "F.Fab")
			(effects
				(font
					(size 1.27 1.27)
				)
			)
		)
		(duplicate_pad_numbers_are_jumpers no)
		(fp_line
			(start -0.7874 0.4064)
			(end -0.7874 -0.4064)
			(stroke
				(width 0.1524)
				(type default)
			)
			(layer "F.SilkS")
		)
		(fp_line
			(start 0.7874 0.4064)
			(end -0.7874 0.4064)
			(stroke
				(width 0.1524)
				(type default)
			)
			(layer "F.SilkS")
		)
		(fp_line
			(start -0.7874 -0.4064)
			(end 0.7874 -0.4064)
			(stroke
				(width 0.1524)
				(type default)
			)
			(layer "F.SilkS")
		)
		(fp_line
			(start 0.7874 -0.4064)
			(end 0.7874 0.4064)
			(stroke
				(width 0.1524)
				(type default)
			)
			(layer "F.SilkS")
		)
		(fp_poly
			(pts
				(xy -0.508 0.2794) (xy -0.508 0.2286) (xy -0.635 0.2286) (xy -0.635 -0.254) (xy -0.5334 -0.254)
				(xy -0.5334 -0.2794) (xy 0.5334 -0.2794) (xy 0.5334 -0.254) (xy 0.635 -0.254) (xy 0.635 0.254) (xy 0.5334 0.254)
				(xy 0.5334 0.2794)
			)
			(stroke
				(width 0)
				(type default)
			)
			(fill no)
			(layer "F.CrtYd")
		)
		(pad "1" smd rect
			(at 0.40005 0 270)
			(size 0.4572 0.508)
			(layers "F.Cu" "F.Mask" "F.Paste")
			(net "FM_CPLD_NODE1_P1V05_EN")
		)
		(pad "2" smd rect
			(at -0.40005 0 270)
			(size 0.4572 0.508)
			(layers "F.Cu" "F.Mask" "F.Paste")
			(net "GND")
		)
	)
	(footprint ""
		(layer "F.Cu")
		(at 78.350364 -17.679416 90)
		(property "Reference" "C166"
			(at -4.546854 5.52323 90)
			(unlocked yes)
			(layer "F.SilkS")
			(effects
				(font
					(size 0.7874 0.5842)
					(thickness 0.1524)
				)
				(justify left)
			)
		)
		(property "Value" ""
			(at 0 0 90)
			(layer "F.Fab")
			(effects
				(font
					(size 1.27 1.27)
				)
			)
		)
		(duplicate_pad_numbers_are_jumpers no)
		(fp_line
			(start 0.7874 -0.4064)
			(end 0.7874 0.4064)
			(stroke
				(width 0.1524)
				(type default)
			)
			(layer "F.SilkS")
		)
		(fp_line
			(start -0.7874 -0.4064)
			(end 0.7874 -0.4064)
			(stroke
				(width 0.1524)
				(type default)
			)
			(layer "F.SilkS")
		)
		(fp_line
			(start 0 0.381)
			(end 0 -0.381)
			(stroke
				(width 0.1524)
				(type default)
			)
			(layer "F.SilkS")
		)
		(fp_line
			(start 0.7874 0.4064)
			(end -0.7874 0.4064)
			(stroke
				(width 0.1524)
				(type default)
			)
			(layer "F.SilkS")
		)
		(fp_line
			(start -0.7874 0.4064)
			(end -0.7874 -0.4064)
			(stroke
				(width 0.1524)
				(type default)
			)
			(layer "F.SilkS")
		)
		(fp_poly
			(pts
				(xy -0.5334 0.254) (xy -0.635 0.254) (xy -0.635 0.2286) (xy -0.635 -0.254) (xy -0.5334 -0.254) (xy -0.5334 -0.2794)
				(xy 0.5334 -0.2794) (xy 0.5334 -0.254) (xy 0.635 -0.254) (xy 0.635 0.254) (xy 0.5334 0.254) (xy 0.5334 0.2794)
				(xy -0.508 0.2794) (xy -0.5334 0.2794)
			)
			(stroke
				(width 0)
				(type default)
			)
			(fill no)
			(layer "F.CrtYd")
		)
		(pad "1" smd rect
			(at 0.40005 0 90)
			(size 0.4572 0.508)
			(layers "F.Cu" "F.Mask" "F.Paste")
			(net "PV_VDDR_NODE1")
		)
		(pad "2" smd rect
			(at -0.40005 0 90)
			(size 0.4572 0.508)
			(layers "F.Cu" "F.Mask" "F.Paste")
			(net "GND")
		)
	)
	(footprint ""
		(layer "F.Cu")
		(at 145.780252 -26.193242)
		(property "Reference" "L37"
			(at -1.04394 -1.092454 0)
			(unlocked yes)
			(layer "F.SilkS")
			(effects
				(font
					(size 0.7874 0.5842)
					(thickness 0.1524)
				)
				(justify left)
			)
		)
		(property "Value" ""
			(at 0 0 0)
			(layer "F.Fab")
			(effects
				(font
					(size 1.27 1.27)
				)
			)
		)
		(duplicate_pad_numbers_are_jumpers no)
		(fp_line
			(start -0.7874 -0.4064)
			(end 0.7874 -0.4064)
			(stroke
				(width 0.1524)
				(type default)
			)
			(layer "F.SilkS")
		)
		(fp_line
			(start -0.7874 0.4064)
			(end -0.7874 -0.4064)
			(stroke
				(width 0.1524)
				(type default)
			)
			(layer "F.SilkS")
		)
		(fp_line
			(start -0.0889 0.4064)
			(end -0.0889 -0.4064)
			(stroke
				(width 0.1524)
				(type default)
			)
			(layer "F.SilkS")
		)
		(fp_line
			(start 0.0889 0.4064)
			(end 0.0889 -0.4064)
			(stroke
				(width 0.1524)
				(type default)
			)
			(layer "F.SilkS")
		)
		(fp_line
			(start 0.7874 -0.4064)
			(end 0.7874 0.4064)
			(stroke
				(width 0.1524)
				(type default)
			)
			(layer "F.SilkS")
		)
		(fp_line
			(start 0.7874 0.4064)
			(end -0.7874 0.4064)
			(stroke
				(width 0.1524)
				(type default)
			)
			(layer "F.SilkS")
		)
		(fp_poly
			(pts
				(xy -0.5334 0.254) (xy -0.635 0.254) (xy -0.635 0.2286) (xy -0.635 -0.254) (xy -0.5334 -0.254) (xy -0.5334 -0.2794)
				(xy 0.5334 -0.2794) (xy 0.5334 -0.254) (xy 0.635 -0.254) (xy 0.635 0.254) (xy 0.5334 0.254) (xy 0.5334 0.2794)
				(xy -0.508 0.2794) (xy -0.5334 0.2794)
			)
			(stroke
				(width 0)
				(type default)
			)
			(fill no)
			(layer "F.CrtYd")
		)
		(pad "1" smd rect
			(at 0.40005 0)
			(size 0.4572 0.508)
			(layers "F.Cu" "F.Mask" "F.Paste")
			(net "GND")
		)
		(pad "2" smd rect
			(at -0.40005 0)
			(size 0.4572 0.508)
			(layers "F.Cu" "F.Mask" "F.Paste")
			(net "GNDA")
		)
	)
	(footprint ""
		(layer "F.Cu")
		(at 155.477972 -26.601928)
		(property "Reference" "C534"
			(at 4.576826 0.855218 90)
			(unlocked yes)
			(layer "F.SilkS")
			(effects
				(font
					(size 0.7874 0.5842)
					(thickness 0.1524)
				)
				(justify left)
			)
		)
		(property "Value" ""
			(at 0 0 0)
			(layer "F.Fab")
			(effects
				(font
					(size 1.27 1.27)
				)
			)
		)
		(duplicate_pad_numbers_are_jumpers no)
		(fp_line
			(start -0.7874 -0.4064)
			(end 0.7874 -0.4064)
			(stroke
				(width 0.1524)
				(type default)
			)
			(layer "F.SilkS")
		)
		(fp_line
			(start -0.7874 0.4064)
			(end -0.7874 -0.4064)
			(stroke
				(width 0.1524)
				(type default)
			)
			(layer "F.SilkS")
		)
		(fp_line
			(start 0 0.381)
			(end 0 -0.381)
			(stroke
				(width 0.1524)
				(type default)
			)
			(layer "F.SilkS")
		)
		(fp_line
			(start 0.7874 -0.4064)
			(end 0.7874 0.4064)
			(stroke
				(width 0.1524)
				(type default)
			)
			(layer "F.SilkS")
		)
		(fp_line
			(start 0.7874 0.4064)
			(end -0.7874 0.4064)
			(stroke
				(width 0.1524)
				(type default)
			)
			(layer "F.SilkS")
		)
		(fp_poly
			(pts
				(xy -0.5334 0.254) (xy -0.635 0.254) (xy -0.635 0.2286) (xy -0.635 -0.254) (xy -0.5334 -0.254) (xy -0.5334 -0.2794)
				(xy 0.5334 -0.2794) (xy 0.5334 -0.254) (xy 0.635 -0.254) (xy 0.635 0.254) (xy 0.5334 0.254) (xy 0.5334 0.2794)
				(xy -0.508 0.2794) (xy -0.5334 0.2794)
			)
			(stroke
				(width 0)
				(type default)
			)
			(fill no)
			(layer "F.CrtYd")
		)
		(pad "1" smd rect
			(at 0.40005 0)
			(size 0.4572 0.508)
			(layers "F.Cu" "F.Mask" "F.Paste")
			(net "N21624861")
		)
		(pad "2" smd rect
			(at -0.40005 0)
			(size 0.4572 0.508)
			(layers "F.Cu" "F.Mask" "F.Paste")
			(net "N21624866")
		)
	)
	(footprint ""
		(layer "F.Cu")
		(at 64.899286 -121.044462 -90)
		(property "Reference" "R331"
			(at 6.142736 -8.217916 90)
			(unlocked yes)
			(layer "F.SilkS")
			(effects
				(font
					(size 0.7874 0.5842)
					(thickness 0.1524)
				)
				(justify left)
			)
		)
		(property "Value" ""
			(at 0 0 270)
			(layer "F.Fab")
			(effects
				(font
					(size 1.27 1.27)
				)
			)
		)
		(duplicate_pad_numbers_are_jumpers no)
		(fp_line
			(start -0.7874 0.4064)
			(end -0.7874 -0.4064)
			(stroke
				(width 0.1524)
				(type default)
			)
			(layer "F.SilkS")
		)
		(fp_line
			(start 0.7874 0.4064)
			(end -0.7874 0.4064)
			(stroke
				(width 0.1524)
				(type default)
			)
			(layer "F.SilkS")
		)
		(fp_line
			(start -0.7874 -0.4064)
			(end 0.7874 -0.4064)
			(stroke
				(width 0.1524)
				(type default)
			)
			(layer "F.SilkS")
		)
		(fp_line
			(start 0.7874 -0.4064)
			(end 0.7874 0.4064)
			(stroke
				(width 0.1524)
				(type default)
			)
			(layer "F.SilkS")
		)
		(fp_poly
			(pts
				(xy -0.508 0.2794) (xy -0.508 0.2286) (xy -0.635 0.2286) (xy -0.635 -0.254) (xy -0.5334 -0.254)
				(xy -0.5334 -0.2794) (xy 0.5334 -0.2794) (xy 0.5334 -0.254) (xy 0.635 -0.254) (xy 0.635 0.254) (xy 0.5334 0.254)
				(xy 0.5334 0.2794)
			)
			(stroke
				(width 0)
				(type default)
			)
			(fill no)
			(layer "F.CrtYd")
		)
		(pad "1" smd rect
			(at 0.40005 0 270)
			(size 0.4572 0.508)
			(layers "F.Cu" "F.Mask" "F.Paste")
			(net "P3V3_NODE1")
		)
		(pad "2" smd rect
			(at -0.40005 0 270)
			(size 0.4572 0.508)
			(layers "F.Cu" "F.Mask" "F.Paste")
			(net "BMC_ROMA15")
		)
	)
	(footprint ""
		(layer "F.Cu")
		(at 163.449 -188.087 -90)
		(property "Reference" "R1334"
			(at -1.1684 -1.55067 90)
			(unlocked yes)
			(layer "F.SilkS")
			(effects
				(font
					(size 0.7874 0.5842)
					(thickness 0.1524)
				)
				(justify left)
			)
		)
		(property "Value" ""
			(at 0 0 270)
			(layer "F.Fab")
			(effects
				(font
					(size 1.27 1.27)
				)
			)
		)
		(duplicate_pad_numbers_are_jumpers no)
		(fp_line
			(start -0.7874 0.4064)
			(end -0.7874 -0.4064)
			(stroke
				(width 0.1524)
				(type default)
			)
			(layer "F.SilkS")
		)
		(fp_line
			(start 0.7874 0.4064)
			(end -0.7874 0.4064)
			(stroke
				(width 0.1524)
				(type default)
			)
			(layer "F.SilkS")
		)
		(fp_line
			(start -0.7874 -0.4064)
			(end 0.7874 -0.4064)
			(stroke
				(width 0.1524)
				(type default)
			)
			(layer "F.SilkS")
		)
		(fp_line
			(start 0.7874 -0.4064)
			(end 0.7874 0.4064)
			(stroke
				(width 0.1524)
				(type default)
			)
			(layer "F.SilkS")
		)
		(fp_poly
			(pts
				(xy -0.508 0.2794) (xy -0.508 0.2286) (xy -0.635 0.2286) (xy -0.635 -0.254) (xy -0.5334 -0.254)
				(xy -0.5334 -0.2794) (xy 0.5334 -0.2794) (xy 0.5334 -0.254) (xy 0.635 -0.254) (xy 0.635 0.254) (xy 0.5334 0.254)
				(xy 0.5334 0.2794)
			)
			(stroke
				(width 0)
				(type default)
			)
			(fill no)
			(layer "F.CrtYd")
		)
		(pad "1" smd rect
			(at 0.40005 0 270)
			(size 0.4572 0.508)
			(layers "F.Cu" "F.Mask" "F.Paste")
			(net "UART_RI_RP5_L_N")
		)
		(pad "2" smd rect
			(at -0.40005 0 270)
			(size 0.4572 0.508)
			(layers "F.Cu" "F.Mask" "F.Paste")
			(net "UART_RI_RP5_L_N_R")
		)
	)
	(footprint ""
		(layer "F.Cu")
		(at 145.515584 -205.199488 180)
		(property "Reference" "J18"
			(at 41.139364 -7.366762 0)
			(unlocked yes)
			(layer "F.SilkS")
			(effects
				(font
					(size 0.7874 0.5842)
					(thickness 0.1524)
				)
				(justify left)
			)
		)
		(property "Value" ""
			(at 0 0 180)
			(layer "F.Fab")
			(effects
				(font
					(size 1.27 1.27)
				)
			)
		)
		(duplicate_pad_numbers_are_jumpers no)
		(fp_line
			(start 42.15003 2.86512)
			(end 42.15003 -4.899914)
			(stroke
				(width 0.1524)
				(type default)
			)
			(layer "F.SilkS")
		)
		(fp_line
			(start 41.51503 3.50012)
			(end 42.15003 2.86512)
			(stroke
				(width 0.1524)
				(type default)
			)
			(layer "F.SilkS")
		)
		(fp_line
			(start -28.385008 3.50012)
			(end 41.51503 3.50012)
			(stroke
				(width 0.1524)
				(type default)
			)
			(layer "F.SilkS")
		)
		(fp_line
			(start -29.020008 2.86512)
			(end -28.385008 3.50012)
			(stroke
				(width 0.1524)
				(type default)
			)
			(layer "F.SilkS")
		)
		(fp_line
			(start -29.020008 -3.919982)
			(end -29.020008 2.86512)
			(stroke
				(width 0.1524)
				(type default)
			)
			(layer "F.SilkS")
		)
		(fp_line
			(start -30.979872 2.86512)
			(end -31.614872 3.50012)
			(stroke
				(width 0.1524)
				(type default)
			)
			(layer "F.SilkS")
		)
		(fp_line
			(start -30.979872 -3.919982)
			(end -30.979872 2.86512)
			(stroke
				(width 0.1524)
				(type default)
			)
			(layer "F.SilkS")
		)
		(fp_line
			(start -31.614872 3.50012)
			(end -41.51503 3.50012)
			(stroke
				(width 0.1524)
				(type default)
			)
			(layer "F.SilkS")
		)
		(fp_line
			(start -41.51503 3.50012)
			(end -42.15003 2.86512)
			(stroke
				(width 0.1524)
				(type default)
			)
			(layer "F.SilkS")
		)
		(fp_line
			(start -42.15003 2.86512)
			(end -42.15003 -4.899914)
			(stroke
				(width 0.1524)
				(type default)
			)
			(layer "F.SilkS")
		)
		(fp_line
			(start -42.15003 -6.500114)
			(end 42.15003 -6.500114)
			(stroke
				(width 0.1524)
				(type default)
			)
			(layer "F.SilkS")
		)
		(fp_arc
			(start -30.979872 -3.919982)
			(mid -29.99994 -4.899914)
			(end -29.020008 -3.919982)
			(stroke
				(width 0.1524)
				(type default)
			)
			(layer "F.SilkS")
		)
		(fp_line
			(start 18.312384 -6.500114)
			(end 42.15003 -6.500114)
			(stroke
				(width 0.1524)
				(type default)
			)
			(layer "B.SilkS")
		)
		(fp_line
			(start 11.936984 -6.500114)
			(end 17.296384 -6.500114)
			(stroke
				(width 0.1524)
				(type default)
			)
			(layer "B.SilkS")
		)
		(fp_line
			(start 8.914384 -6.500114)
			(end 10.895584 -6.500114)
			(stroke
				(width 0.1524)
				(type default)
			)
			(layer "B.SilkS")
		)
		(fp_line
			(start -9.653016 -6.500114)
			(end 6.475984 -6.500114)
			(stroke
				(width 0.1524)
				(type default)
			)
			(layer "B.SilkS")
		)
		(fp_line
			(start -14.377416 -6.500114)
			(end -10.491216 -6.500114)
			(stroke
				(width 0.1524)
				(type default)
			)
			(layer "B.SilkS")
		)
		(fp_line
			(start -19.559016 -6.500114)
			(end -15.368016 -6.500114)
			(stroke
				(width 0.1524)
				(type default)
			)
			(layer "B.SilkS")
		)
		(fp_line
			(start -27.128216 -6.500114)
			(end -22.073616 -6.500114)
			(stroke
				(width 0.1524)
				(type default)
			)
			(layer "B.SilkS")
		)
		(fp_line
			(start -42.15003 -6.500114)
			(end -27.864816 -6.500114)
			(stroke
				(width 0.1524)
				(type default)
			)
			(layer "B.SilkS")
		)
		(fp_rect
			(start -29.0322 3.5052)
			(end 42.164 -2.1082)
			(stroke
				(width 0)
				(type default)
			)
			(fill no)
			(layer "F.CrtYd")
		)
		(fp_rect
			(start -42.164 3.5052)
			(end -30.9626 -2.1082)
			(stroke
				(width 0)
				(type default)
			)
			(fill no)
			(layer "F.CrtYd")
		)
		(fp_text user "B82"
			(at 41.307004 -5.907278 0)
			(unlocked yes)
			(layer "F.SilkS")
			(effects
				(font
					(size 0.635 0.4064)
					(thickness 0.1524)
				)
				(justify left)
			)
		)
		(fp_text user "B12"
			(at -27.42057 -5.796788 0)
			(unlocked yes)
			(layer "F.SilkS")
			(effects
				(font
					(size 0.635 0.4064)
					(thickness 0.1524)
				)
				(justify left)
			)
		)
		(fp_text user "B11"
			(at -30.420564 -5.796788 0)
			(unlocked yes)
			(layer "F.SilkS")
			(effects
				(font
					(size 0.635 0.4064)
					(thickness 0.1524)
				)
				(justify left)
			)
		)
		(fp_text user "B1"
			(at -40.445436 -5.935726 0)
			(unlocked yes)
			(layer "F.SilkS")
			(effects
				(font
					(size 0.635 0.4064)
					(thickness 0.1524)
				)
				(justify left)
			)
		)
		(fp_text user "A82"
			(at 39.773352 -3.352292 0)
			(unlocked yes)
			(layer "B.SilkS")
			(effects
				(font
					(size 0.7874 0.5842)
					(thickness 0.1524)
				)
				(justify left mirror)
			)
		)
		(fp_text user "A12"
			(at -28.595828 -2.989326 0)
			(unlocked yes)
			(layer "B.SilkS")
			(effects
				(font
					(size 0.7874 0.5842)
					(thickness 0.1524)
				)
				(justify left mirror)
			)
		)
		(fp_text user "A11"
			(at -33.350708 -3.187192 0)
			(unlocked yes)
			(layer "B.SilkS")
			(effects
				(font
					(size 0.7874 0.5842)
					(thickness 0.1524)
				)
				(justify left mirror)
			)
		)
		(fp_text user "A1"
			(at -41.702228 -2.956306 0)
			(unlocked yes)
			(layer "B.SilkS")
			(effects
				(font
					(size 0.7874 0.5842)
					(thickness 0.1524)
				)
				(justify left mirror)
			)
		)
		(pad "A1" smd rect
			(at -41.500044 -0.499872 180)
			(size 0.762 3.2004)
			(layers "F.Cu" "F.Mask" "F.Paste")
			(net "GND")
		)
		(pad "A2" smd rect
			(at -40.500046 0 180)
			(size 0.762 4.2164)
			(layers "F.Cu" "F.Mask" "F.Paste")
			(net "GND")
		)
		(pad "A3" smd rect
			(at -39.500048 0 180)
			(size 0.762 4.2164)
			(layers "F.Cu" "F.Mask" "F.Paste")
			(net "LAN2_P3_P")
		)
		(pad "A4" smd rect
			(at -38.50005 0 180)
			(size 0.762 4.2164)
			(layers "F.Cu" "F.Mask" "F.Paste")
			(net "LAN2_P3_N")
		)
		(pad "A5" smd rect
			(at -37.500052 0 180)
			(size 0.762 4.2164)
			(layers "F.Cu" "F.Mask" "F.Paste")
			(net "GND")
		)
		(pad "A6" smd rect
			(at -36.500054 0 180)
			(size 0.762 4.2164)
			(layers "F.Cu" "F.Mask" "F.Paste")
			(net "LAN2_P4_P")
		)
		(pad "A7" smd rect
			(at -35.500056 0 180)
			(size 0.762 4.2164)
			(layers "F.Cu" "F.Mask" "F.Paste")
			(net "LAN2_P4_N")
		)
		(pad "A8" smd rect
			(at -34.500058 0 180)
			(size 0.762 4.2164)
			(layers "F.Cu" "F.Mask" "F.Paste")
			(net "GND")
		)
		(pad "A9" smd rect
			(at -33.50006 0 180)
			(size 0.762 4.2164)
			(layers "F.Cu" "F.Mask" "F.Paste")
			(net "POWER_SW3_PWR_CTR_12V_R")
		)
		(pad "A10" smd rect
			(at -32.500062 0 180)
			(size 0.762 4.2164)
			(layers "F.Cu" "F.Mask" "F.Paste")
			(net "POWER_SW2_PWR_CTR_12V_R")
		)
		(pad "A11" smd rect
			(at -31.500064 0 180)
			(size 0.762 4.2164)
			(layers "F.Cu" "F.Mask" "F.Paste")
			(net "POWER_SW1_PWR_CTR_12V_R")
		)
		(pad "A12" smd rect
			(at -28.50007 0 180)
			(size 0.762 4.2164)
			(layers "F.Cu" "F.Mask" "F.Paste")
			(net "GND2")
		)
		(pad "A13" smd rect
			(at -27.500072 0 180)
			(size 0.762 4.2164)
			(layers "F.Cu" "F.Mask" "F.Paste")
			(net "Net_225")
		)
		(pad "A14" smd rect
			(at -26.500074 0 180)
			(size 0.762 4.2164)
			(layers "F.Cu" "F.Mask" "F.Paste")
			(net "Net_226")
		)
		(pad "A15" smd rect
			(at -25.500076 0 180)
			(size 0.762 4.2164)
			(layers "F.Cu" "F.Mask" "F.Paste")
			(net "GND3")
		)
		(pad "A16" smd rect
			(at -24.500078 0 180)
			(size 0.762 4.2164)
			(layers "F.Cu" "F.Mask" "F.Paste")
			(net "Net_221")
		)
		(pad "A17" smd rect
			(at -23.50008 0 180)
			(size 0.762 4.2164)
			(layers "F.Cu" "F.Mask" "F.Paste")
			(net "GND")
		)
		(pad "A18" smd rect
			(at -22.500082 0 180)
			(size 0.762 4.2164)
			(layers "F.Cu" "F.Mask" "F.Paste")
			(net "UART_RTS_RP6_L_N")
		)
		(pad "A19" smd rect
			(at -21.500084 0 180)
			(size 0.762 4.2164)
			(layers "F.Cu" "F.Mask" "F.Paste")
			(net "UART_DSR_RP6_L_N")
		)
		(pad "A20" smd rect
			(at -20.500086 0 180)
			(size 0.762 4.2164)
			(layers "F.Cu" "F.Mask" "F.Paste")
			(net "UART_RX_RP6_L")
		)
		(pad "A21" smd rect
			(at -19.500088 0 180)
			(size 0.762 4.2164)
			(layers "F.Cu" "F.Mask" "F.Paste")
			(net "UART_TX_RP6_L")
		)
		(pad "A22" smd rect
			(at -18.50009 0 180)
			(size 0.762 4.2164)
			(layers "F.Cu" "F.Mask" "F.Paste")
			(net "UART_DTR_RP6_L_N")
		)
		(pad "A23" smd rect
			(at -17.500092 0 180)
			(size 0.762 4.2164)
			(layers "F.Cu" "F.Mask" "F.Paste")
			(net "UART_CTS_RP6_L")
		)
		(pad "A24" smd rect
			(at -16.500094 0 180)
			(size 0.762 4.2164)
			(layers "F.Cu" "F.Mask" "F.Paste")
			(net "UART_RI_RP6_L_N_R")
		)
		(pad "A25" smd rect
			(at -15.500096 0 180)
			(size 0.762 4.2164)
			(layers "F.Cu" "F.Mask" "F.Paste")
			(net "GND")
		)
		(pad "A26" smd rect
			(at -14.500098 0 180)
			(size 0.762 4.2164)
			(layers "F.Cu" "F.Mask" "F.Paste")
			(net "FAN4_TACH_R")
		)
		(pad "A27" smd rect
			(at -13.5001 0 180)
			(size 0.762 4.2164)
			(layers "F.Cu" "F.Mask" "F.Paste")
			(net "FAN5_TACH_R")
		)
		(pad "A28" smd rect
			(at -12.500102 0 180)
			(size 0.762 4.2164)
			(layers "F.Cu" "F.Mask" "F.Paste")
			(net "FAN6_TACH_R")
		)
		(pad "A29" smd rect
			(at -11.500104 0 180)
			(size 0.762 4.2164)
			(layers "F.Cu" "F.Mask" "F.Paste")
			(net "GND")
		)
		(pad "A30" smd rect
			(at -10.500106 0 180)
			(size 0.762 4.2164)
			(layers "F.Cu" "F.Mask" "F.Paste")
			(net "FAN_PWM_R")
		)
		(pad "A31" smd rect
			(at -9.500108 0 180)
			(size 0.762 4.2164)
			(layers "F.Cu" "F.Mask" "F.Paste")
			(net "GND")
		)
		(pad "A32" smd rect
			(at -8.50011 0 180)
			(size 0.762 4.2164)
			(layers "F.Cu" "F.Mask" "F.Paste")
			(net "I2C_PSU3_R_SCL")
		)
		(pad "A33" smd rect
			(at -7.500112 0 180)
			(size 0.762 4.2164)
			(layers "F.Cu" "F.Mask" "F.Paste")
			(net "I2C_PSU3_R_SDA")
		)
		(pad "A34" smd rect
			(at -6.500114 0 180)
			(size 0.762 4.2164)
			(layers "F.Cu" "F.Mask" "F.Paste")
			(net "GND")
		)
		(pad "A35" smd rect
			(at -5.500116 0 180)
			(size 0.762 4.2164)
			(layers "F.Cu" "F.Mask" "F.Paste")
			(net "T11_NODE1_EN_R")
		)
		(pad "A36" smd rect
			(at -4.500118 0 180)
			(size 0.762 4.2164)
			(layers "F.Cu" "F.Mask" "F.Paste")
			(net "T11_NODE2_EN_R")
		)
		(pad "A37" smd rect
			(at -3.50012 0 180)
			(size 0.762 4.2164)
			(layers "F.Cu" "F.Mask" "F.Paste")
			(net "T11_NODE3_EN_R")
		)
		(pad "A38" smd rect
			(at -2.500122 0 180)
			(size 0.762 4.2164)
			(layers "F.Cu" "F.Mask" "F.Paste")
			(net "T11_NODE4_EN_R")
		)
		(pad "A39" smd rect
			(at -1.500124 0 180)
			(size 0.762 4.2164)
			(layers "F.Cu" "F.Mask" "F.Paste")
			(net "GND")
		)
		(pad "A40" smd rect
			(at -0.499872 0 180)
			(size 0.762 4.2164)
			(layers "F.Cu" "F.Mask" "F.Paste")
			(net "UART_T11_NODE1_RXD_R")
		)
		(pad "A41" smd rect
			(at 0.499872 0 180)
			(size 0.762 4.2164)
			(layers "F.Cu" "F.Mask" "F.Paste")
			(net "UART_T11_NODE1_TXD_R")
		)
		(pad "A42" smd rect
			(at 1.500124 0 180)
			(size 0.762 4.2164)
			(layers "F.Cu" "F.Mask" "F.Paste")
			(net "UART_T11_NODE2_RXD_R")
		)
		(pad "A43" smd rect
			(at 2.500122 0 180)
			(size 0.762 4.2164)
			(layers "F.Cu" "F.Mask" "F.Paste")
			(net "UART_T11_NODE2_TXD_R")
		)
		(pad "A44" smd rect
			(at 3.50012 0 180)
			(size 0.762 4.2164)
			(layers "F.Cu" "F.Mask" "F.Paste")
			(net "GND")
		)
		(pad "A45" smd rect
			(at 4.500118 0 180)
			(size 0.762 4.2164)
			(layers "F.Cu" "F.Mask" "F.Paste")
			(net "UART_T11_NODE3_RXD_R")
		)
		(pad "A46" smd rect
			(at 5.500116 0 180)
			(size 0.762 4.2164)
			(layers "F.Cu" "F.Mask" "F.Paste")
			(net "UART_T11_NODE3_TXD_R")
		)
		(pad "A47" smd rect
			(at 6.500114 0 180)
			(size 0.762 4.2164)
			(layers "F.Cu" "F.Mask" "F.Paste")
			(net "UART_T11_NODE4_RXD_R")
		)
		(pad "A48" smd rect
			(at 7.500112 0 180)
			(size 0.762 4.2164)
			(layers "F.Cu" "F.Mask" "F.Paste")
			(net "UART_T11_NODE4_TXD_R")
		)
		(pad "A49" smd rect
			(at 8.50011 0 180)
			(size 0.762 4.2164)
			(layers "F.Cu" "F.Mask" "F.Paste")
			(net "GND")
		)
		(pad "A50" smd rect
			(at 9.500108 0 180)
			(size 0.762 4.2164)
			(layers "F.Cu" "F.Mask" "F.Paste")
			(net "T9_NODE1_EN_R")
		)
		(pad "A51" smd rect
			(at 10.500106 0 180)
			(size 0.762 4.2164)
			(layers "F.Cu" "F.Mask" "F.Paste")
			(net "T9_NODE2_EN_R")
		)
		(pad "A52" smd rect
			(at 11.500104 0 180)
			(size 0.762 4.2164)
			(layers "F.Cu" "F.Mask" "F.Paste")
			(net "T9_NODE3_EN_R")
		)
		(pad "A53" smd rect
			(at 12.500102 0 180)
			(size 0.762 4.2164)
			(layers "F.Cu" "F.Mask" "F.Paste")
			(net "T9_NODE4_EN_R")
		)
		(pad "A54" smd rect
			(at 13.5001 0 180)
			(size 0.762 4.2164)
			(layers "F.Cu" "F.Mask" "F.Paste")
			(net "GND")
		)
		(pad "A55" smd rect
			(at 14.500098 0 180)
			(size 0.762 4.2164)
			(layers "F.Cu" "F.Mask" "F.Paste")
			(net "UART_T9_NODE1_RXD_R")
		)
		(pad "A56" smd rect
			(at 15.500096 0 180)
			(size 0.762 4.2164)
			(layers "F.Cu" "F.Mask" "F.Paste")
			(net "UART_T9_NODE1_TXD_R")
		)
		(pad "A57" smd rect
			(at 16.500094 0 180)
			(size 0.762 4.2164)
			(layers "F.Cu" "F.Mask" "F.Paste")
			(net "UART_T9_NODE2_RXD_R")
		)
		(pad "A58" smd rect
			(at 17.500092 0 180)
			(size 0.762 4.2164)
			(layers "F.Cu" "F.Mask" "F.Paste")
			(net "UART_T9_NODE2_TXD_R")
		)
		(pad "A59" smd rect
			(at 18.50009 0 180)
			(size 0.762 4.2164)
			(layers "F.Cu" "F.Mask" "F.Paste")
			(net "GND")
		)
		(pad "A60" smd rect
			(at 19.500088 0 180)
			(size 0.762 4.2164)
			(layers "F.Cu" "F.Mask" "F.Paste")
			(net "UART_T9_NODE3_RXD_R")
		)
		(pad "A61" smd rect
			(at 20.500086 0 180)
			(size 0.762 4.2164)
			(layers "F.Cu" "F.Mask" "F.Paste")
			(net "UART_T9_NODE3_TXD_R")
		)
		(pad "A62" smd rect
			(at 21.500084 0 180)
			(size 0.762 4.2164)
			(layers "F.Cu" "F.Mask" "F.Paste")
			(net "UART_T9_NODE4_RXD_R")
		)
		(pad "A63" smd rect
			(at 22.500082 0 180)
			(size 0.762 4.2164)
			(layers "F.Cu" "F.Mask" "F.Paste")
			(net "UART_T9_NODE4_TXD_R")
		)
		(pad "A64" smd rect
			(at 23.50008 0 180)
			(size 0.762 4.2164)
			(layers "F.Cu" "F.Mask" "F.Paste")
			(net "GND")
		)
		(pad "A65" smd rect
			(at 24.500078 0 180)
			(size 0.762 4.2164)
			(layers "F.Cu" "F.Mask" "F.Paste")
			(net "T7_NODE1_EN_R")
		)
		(pad "A66" smd rect
			(at 25.500076 0 180)
			(size 0.762 4.2164)
			(layers "F.Cu" "F.Mask" "F.Paste")
			(net "T7_NODE2_EN_R")
		)
		(pad "A67" smd rect
			(at 26.500074 0 180)
			(size 0.762 4.2164)
			(layers "F.Cu" "F.Mask" "F.Paste")
			(net "T7_NODE3_EN_R")
		)
		(pad "A68" smd rect
			(at 27.500072 0 180)
			(size 0.762 4.2164)
			(layers "F.Cu" "F.Mask" "F.Paste")
			(net "T7_NODE4_EN_R")
		)
		(pad "A69" smd rect
			(at 28.50007 0 180)
			(size 0.762 4.2164)
			(layers "F.Cu" "F.Mask" "F.Paste")
			(net "GND")
		)
		(pad "A70" smd rect
			(at 29.500068 0 180)
			(size 0.762 4.2164)
			(layers "F.Cu" "F.Mask" "F.Paste")
			(net "UART_T7_NODE1_RXD_R")
		)
		(pad "A71" smd rect
			(at 30.500066 0 180)
			(size 0.762 4.2164)
			(layers "F.Cu" "F.Mask" "F.Paste")
			(net "UART_T7_NODE1_TXD_R")
		)
		(pad "A72" smd rect
			(at 31.500064 0 180)
			(size 0.762 4.2164)
			(layers "F.Cu" "F.Mask" "F.Paste")
			(net "UART_T7_NODE2_RXD_R")
		)
		(pad "A73" smd rect
			(at 32.500062 0 180)
			(size 0.762 4.2164)
			(layers "F.Cu" "F.Mask" "F.Paste")
			(net "UART_T7_NODE2_TXD_R")
		)
		(pad "A74" smd rect
			(at 33.50006 0 180)
			(size 0.762 4.2164)
			(layers "F.Cu" "F.Mask" "F.Paste")
			(net "GND")
		)
		(pad "A75" smd rect
			(at 34.500058 0 180)
			(size 0.762 4.2164)
			(layers "F.Cu" "F.Mask" "F.Paste")
			(net "UART_T7_NODE3_RXD_R")
		)
		(pad "A76" smd rect
			(at 35.500056 0 180)
			(size 0.762 4.2164)
			(layers "F.Cu" "F.Mask" "F.Paste")
			(net "UART_T7_NODE3_TXD_R")
		)
		(pad "A77" smd rect
			(at 36.500054 0 180)
			(size 0.762 4.2164)
			(layers "F.Cu" "F.Mask" "F.Paste")
			(net "UART_T7_NODE4_RXD_R")
		)
		(pad "A78" smd rect
			(at 37.500052 0 180)
			(size 0.762 4.2164)
			(layers "F.Cu" "F.Mask" "F.Paste")
			(net "UART_T7_NODE4_TXD_R")
		)
		(pad "A79" smd rect
			(at 38.50005 0 180)
			(size 0.762 4.2164)
			(layers "F.Cu" "F.Mask" "F.Paste")
			(net "GND")
		)
		(pad "A80" smd rect
			(at 39.500048 0 180)
			(size 0.762 4.2164)
			(layers "F.Cu" "F.Mask" "F.Paste")
			(net "PSU_ALERT_R_N")
		)
		(pad "A81" smd rect
			(at 40.500046 0 180)
			(size 0.762 4.2164)
			(layers "F.Cu" "F.Mask" "F.Paste")
			(net "T5_NODE1_EN_R")
		)
		(pad "A82" smd rect
			(at 41.500044 0 180)
			(size 0.762 4.2164)
			(layers "F.Cu" "F.Mask" "F.Paste")
			(net "T5_NODE2_EN_R")
		)
		(pad "B1" smd rect
			(at -41.500044 0 180)
			(size 0.762 4.2164)
			(layers "F.Cu" "F.Mask" "F.Paste")
			(net "GND")
		)
		(pad "B2" smd rect
			(at -40.500046 0 180)
			(size 0.762 4.2164)
			(layers "F.Cu" "F.Mask" "F.Paste")
			(net "LAN2_P1_P")
		)
		(pad "B3" smd rect
			(at -39.500048 0 180)
			(size 0.762 4.2164)
			(layers "F.Cu" "F.Mask" "F.Paste")
			(net "LAN2_P1_N")
		)
		(pad "B4" smd rect
			(at -38.50005 0 180)
			(size 0.762 4.2164)
			(layers "F.Cu" "F.Mask" "F.Paste")
			(net "GND")
		)
		(pad "B5" smd rect
			(at -37.500052 0 180)
			(size 0.762 4.2164)
			(layers "F.Cu" "F.Mask" "F.Paste")
			(net "LAN2_P2_P")
		)
		(pad "B6" smd rect
			(at -36.500054 0 180)
			(size 0.762 4.2164)
			(layers "F.Cu" "F.Mask" "F.Paste")
			(net "LAN2_P2_N")
		)
		(pad "B7" smd rect
			(at -35.500056 0 180)
			(size 0.762 4.2164)
			(layers "F.Cu" "F.Mask" "F.Paste")
			(net "GND")
		)
		(pad "B8" smd rect
			(at -34.500058 0 180)
			(size 0.762 4.2164)
			(layers "F.Cu" "F.Mask" "F.Paste")
			(net "GND")
		)
		(pad "B9" smd rect
			(at -33.50006 0 180)
			(size 0.762 4.2164)
			(layers "F.Cu" "F.Mask" "F.Paste")
			(net "GND")
		)
		(pad "B10" smd rect
			(at -32.500062 0 180)
			(size 0.762 4.2164)
			(layers "F.Cu" "F.Mask" "F.Paste")
			(net "I2C_PDB_R_SCL")
		)
		(pad "B11" smd rect
			(at -31.500064 0 180)
			(size 0.762 4.2164)
			(layers "F.Cu" "F.Mask" "F.Paste")
			(net "I2C_PDB_R_SDA")
		)
		(pad "B12" smd rect
			(at -28.50007 0 180)
			(size 0.762 4.2164)
			(layers "F.Cu" "F.Mask" "F.Paste")
			(net "P3V3_NODE1")
		)
		(pad "B13" smd rect
			(at -27.500072 0 180)
			(size 0.762 4.2164)
			(layers "F.Cu" "F.Mask" "F.Paste")
			(net "GND36")
		)
		(pad "B14" smd rect
			(at -26.500074 0 180)
			(size 0.762 4.2164)
			(layers "F.Cu" "F.Mask" "F.Paste")
			(net "Net_222")
		)
		(pad "B15" smd rect
			(at -25.500076 0 180)
			(size 0.762 4.2164)
			(layers "F.Cu" "F.Mask" "F.Paste")
			(net "Net_223")
		)
		(pad "B16" smd rect
			(at -24.500078 0 180)
			(size 0.762 4.2164)
			(layers "F.Cu" "F.Mask" "F.Paste")
			(net "GND37")
		)
		(pad "B17" smd rect
			(at -23.50008 -0.499872 180)
			(size 0.762 3.2004)
			(layers "F.Cu" "F.Mask" "F.Paste")
			(net "Net_224")
		)
		(pad "B18" smd rect
			(at -22.500082 0 180)
			(size 0.762 4.2164)
			(layers "F.Cu" "F.Mask" "F.Paste")
			(net "GND")
		)
		(pad "B19" smd rect
			(at -21.500084 0 180)
			(size 0.762 4.2164)
			(layers "F.Cu" "F.Mask" "F.Paste")
			(net "UART_RTS_RP5_L_N")
		)
		(pad "B20" smd rect
			(at -20.500086 0 180)
			(size 0.762 4.2164)
			(layers "F.Cu" "F.Mask" "F.Paste")
			(net "UART_DSR_RP5_L")
		)
		(pad "B21" smd rect
			(at -19.500088 0 180)
			(size 0.762 4.2164)
			(layers "F.Cu" "F.Mask" "F.Paste")
			(net "UART_RX_RP5_L")
		)
		(pad "B22" smd rect
			(at -18.50009 0 180)
			(size 0.762 4.2164)
			(layers "F.Cu" "F.Mask" "F.Paste")
			(net "UART_TX_RP5_L")
		)
		(pad "B23" smd rect
			(at -17.500092 0 180)
			(size 0.762 4.2164)
			(layers "F.Cu" "F.Mask" "F.Paste")
			(net "UART_DTR_RP5_L_N")
		)
		(pad "B24" smd rect
			(at -16.500094 0 180)
			(size 0.762 4.2164)
			(layers "F.Cu" "F.Mask" "F.Paste")
			(net "UART_CTS_RP5_L_N")
		)
		(pad "B25" smd rect
			(at -15.500096 0 180)
			(size 0.762 4.2164)
			(layers "F.Cu" "F.Mask" "F.Paste")
			(net "UART_RI_RP5_L_N_R")
		)
		(pad "B26" smd rect
			(at -14.500098 0 180)
			(size 0.762 4.2164)
			(layers "F.Cu" "F.Mask" "F.Paste")
			(net "GND")
		)
		(pad "B27" smd rect
			(at -13.5001 0 180)
			(size 0.762 4.2164)
			(layers "F.Cu" "F.Mask" "F.Paste")
			(net "FAN1_TACH_R")
		)
		(pad "B28" smd rect
			(at -12.500102 0 180)
			(size 0.762 4.2164)
			(layers "F.Cu" "F.Mask" "F.Paste")
			(net "FAN2_TACH_R")
		)
		(pad "B29" smd rect
			(at -11.500104 0 180)
			(size 0.762 4.2164)
			(layers "F.Cu" "F.Mask" "F.Paste")
			(net "FAN3_TACH_R")
		)
		(pad "B30" smd rect
			(at -10.500106 0 180)
			(size 0.762 4.2164)
			(layers "F.Cu" "F.Mask" "F.Paste")
			(net "GND")
		)
		(pad "B31" smd rect
			(at -9.500108 -0.499872 180)
			(size 0.762 3.2004)
			(layers "F.Cu" "F.Mask" "F.Paste")
			(net "T12_NODE1_EN_R")
		)
		(pad "B32" smd rect
			(at -8.50011 0 180)
			(size 0.762 4.2164)
			(layers "F.Cu" "F.Mask" "F.Paste")
			(net "T12_NODE2_EN_R")
		)
		(pad "B33" smd rect
			(at -7.500112 0 180)
			(size 0.762 4.2164)
			(layers "F.Cu" "F.Mask" "F.Paste")
			(net "T12_NODE3_EN_R")
		)
		(pad "B34" smd rect
			(at -6.500114 0 180)
			(size 0.762 4.2164)
			(layers "F.Cu" "F.Mask" "F.Paste")
			(net "T12_NODE4_EN_R")
		)
		(pad "B35" smd rect
			(at -5.500116 0 180)
			(size 0.762 4.2164)
			(layers "F.Cu" "F.Mask" "F.Paste")
			(net "GND")
		)
		(pad "B36" smd rect
			(at -4.500118 0 180)
			(size 0.762 4.2164)
			(layers "F.Cu" "F.Mask" "F.Paste")
			(net "UART_T12_NODE1_RXD_R")
		)
		(pad "B37" smd rect
			(at -3.50012 0 180)
			(size 0.762 4.2164)
			(layers "F.Cu" "F.Mask" "F.Paste")
			(net "UART_T12_NODE1_TXD_R")
		)
		(pad "B38" smd rect
			(at -2.500122 0 180)
			(size 0.762 4.2164)
			(layers "F.Cu" "F.Mask" "F.Paste")
			(net "UART_T12_NODE2_RXD_R")
		)
		(pad "B39" smd rect
			(at -1.500124 0 180)
			(size 0.762 4.2164)
			(layers "F.Cu" "F.Mask" "F.Paste")
			(net "UART_T12_NODE2_TXD_R")
		)
		(pad "B40" smd rect
			(at -0.499872 0 180)
			(size 0.762 4.2164)
			(layers "F.Cu" "F.Mask" "F.Paste")
			(net "GND")
		)
		(pad "B41" smd rect
			(at 0.499872 0 180)
			(size 0.762 4.2164)
			(layers "F.Cu" "F.Mask" "F.Paste")
			(net "UART_T12_NODE3_RXD_R")
		)
		(pad "B42" smd rect
			(at 1.500124 0 180)
			(size 0.762 4.2164)
			(layers "F.Cu" "F.Mask" "F.Paste")
			(net "UART_T12_NODE3_TXD_R")
		)
		(pad "B43" smd rect
			(at 2.500122 0 180)
			(size 0.762 4.2164)
			(layers "F.Cu" "F.Mask" "F.Paste")
			(net "UART_T12_NODE4_RXD_R")
		)
		(pad "B44" smd rect
			(at 3.50012 0 180)
			(size 0.762 4.2164)
			(layers "F.Cu" "F.Mask" "F.Paste")
			(net "UART_T12_NODE4_TXD_R")
		)
		(pad "B45" smd rect
			(at 4.500118 0 180)
			(size 0.762 4.2164)
			(layers "F.Cu" "F.Mask" "F.Paste")
			(net "GND")
		)
		(pad "B46" smd rect
			(at 5.500116 0 180)
			(size 0.762 4.2164)
			(layers "F.Cu" "F.Mask" "F.Paste")
			(net "T10_NODE1_EN_R")
		)
		(pad "B47" smd rect
			(at 6.500114 0 180)
			(size 0.762 4.2164)
			(layers "F.Cu" "F.Mask" "F.Paste")
			(net "T10_NODE2_EN_R")
		)
		(pad "B48" smd rect
			(at 7.500112 -0.499872 180)
			(size 0.762 3.2004)
			(layers "F.Cu" "F.Mask" "F.Paste")
			(net "T10_NODE3_EN_R")
		)
		(pad "B49" smd rect
			(at 8.50011 0 180)
			(size 0.762 4.2164)
			(layers "F.Cu" "F.Mask" "F.Paste")
			(net "T10_NODE4_EN_R")
		)
		(pad "B50" smd rect
			(at 9.500108 0 180)
			(size 0.762 4.2164)
			(layers "F.Cu" "F.Mask" "F.Paste")
			(net "GND")
		)
		(pad "B51" smd rect
			(at 10.500106 0 180)
			(size 0.762 4.2164)
			(layers "F.Cu" "F.Mask" "F.Paste")
			(net "UART_T10_NODE1_RXD_R")
		)
		(pad "B52" smd rect
			(at 11.500104 0 180)
			(size 0.762 4.2164)
			(layers "F.Cu" "F.Mask" "F.Paste")
			(net "UART_T10_NODE1_TXD_R")
		)
		(pad "B53" smd rect
			(at 12.500102 0 180)
			(size 0.762 4.2164)
			(layers "F.Cu" "F.Mask" "F.Paste")
			(net "UART_T10_NODE2_RXD_R")
		)
		(pad "B54" smd rect
			(at 13.5001 0 180)
			(size 0.762 4.2164)
			(layers "F.Cu" "F.Mask" "F.Paste")
			(net "UART_T10_NODE2_TXD_R")
		)
		(pad "B55" smd rect
			(at 14.500098 0 180)
			(size 0.762 4.2164)
			(layers "F.Cu" "F.Mask" "F.Paste")
			(net "GND")
		)
		(pad "B56" smd rect
			(at 15.500096 0 180)
			(size 0.762 4.2164)
			(layers "F.Cu" "F.Mask" "F.Paste")
			(net "UART_T10_NODE3_RXD_R")
		)
		(pad "B57" smd rect
			(at 16.500094 0 180)
			(size 0.762 4.2164)
			(layers "F.Cu" "F.Mask" "F.Paste")
			(net "UART_T10_NODE3_TXD_R")
		)
		(pad "B58" smd rect
			(at 17.500092 0 180)
			(size 0.762 4.2164)
			(layers "F.Cu" "F.Mask" "F.Paste")
			(net "UART_T10_NODE4_RXD_R")
		)
		(pad "B59" smd rect
			(at 18.50009 0 180)
			(size 0.762 4.2164)
			(layers "F.Cu" "F.Mask" "F.Paste")
			(net "UART_T10_NODE4_TXD_R")
		)
		(pad "B60" smd rect
			(at 19.500088 0 180)
			(size 0.762 4.2164)
			(layers "F.Cu" "F.Mask" "F.Paste")
			(net "GND")
		)
		(pad "B61" smd rect
			(at 20.500086 0 180)
			(size 0.762 4.2164)
			(layers "F.Cu" "F.Mask" "F.Paste")
			(net "T8_NODE1_EN_R")
		)
		(pad "B62" smd rect
			(at 21.500084 0 180)
			(size 0.762 4.2164)
			(layers "F.Cu" "F.Mask" "F.Paste")
			(net "T8_NODE2_EN_R")
		)
		(pad "B63" smd rect
			(at 22.500082 0 180)
			(size 0.762 4.2164)
			(layers "F.Cu" "F.Mask" "F.Paste")
			(net "T8_NODE3_EN_R")
		)
		(pad "B64" smd rect
			(at 23.50008 0 180)
			(size 0.762 4.2164)
			(layers "F.Cu" "F.Mask" "F.Paste")
			(net "T8_NODE4_EN_R")
		)
		(pad "B65" smd rect
			(at 24.500078 0 180)
			(size 0.762 4.2164)
			(layers "F.Cu" "F.Mask" "F.Paste")
			(net "GND")
		)
		(pad "B66" smd rect
			(at 25.500076 0 180)
			(size 0.762 4.2164)
			(layers "F.Cu" "F.Mask" "F.Paste")
			(net "UART_T8_NODE1_RXD_R")
		)
		(pad "B67" smd rect
			(at 26.500074 0 180)
			(size 0.762 4.2164)
			(layers "F.Cu" "F.Mask" "F.Paste")
			(net "UART_T8_NODE1_TXD_R")
		)
		(pad "B68" smd rect
			(at 27.500072 0 180)
			(size 0.762 4.2164)
			(layers "F.Cu" "F.Mask" "F.Paste")
			(net "UART_T8_NODE2_RXD_R")
		)
		(pad "B69" smd rect
			(at 28.50007 0 180)
			(size 0.762 4.2164)
			(layers "F.Cu" "F.Mask" "F.Paste")
			(net "UART_T8_NODE2_TXD_R")
		)
		(pad "B70" smd rect
			(at 29.500068 0 180)
			(size 0.762 4.2164)
			(layers "F.Cu" "F.Mask" "F.Paste")
			(net "GND")
		)
		(pad "B71" smd rect
			(at 30.500066 0 180)
			(size 0.762 4.2164)
			(layers "F.Cu" "F.Mask" "F.Paste")
			(net "UART_T8_NODE3_RXD_R")
		)
		(pad "B72" smd rect
			(at 31.500064 0 180)
			(size 0.762 4.2164)
			(layers "F.Cu" "F.Mask" "F.Paste")
			(net "UART_T8_NODE3_TXD_R")
		)
		(pad "B73" smd rect
			(at 32.500062 0 180)
			(size 0.762 4.2164)
			(layers "F.Cu" "F.Mask" "F.Paste")
			(net "UART_T8_NODE4_RXD_R")
		)
		(pad "B74" smd rect
			(at 33.50006 0 180)
			(size 0.762 4.2164)
			(layers "F.Cu" "F.Mask" "F.Paste")
			(net "UART_T8_NODE4_TXD_R")
		)
		(pad "B75" smd rect
			(at 34.500058 0 180)
			(size 0.762 4.2164)
			(layers "F.Cu" "F.Mask" "F.Paste")
			(net "GND")
		)
		(pad "B76" smd rect
			(at 35.500056 0 180)
			(size 0.762 4.2164)
			(layers "F.Cu" "F.Mask" "F.Paste")
			(net "T6_NODE1_EN_R")
		)
		(pad "B77" smd rect
			(at 36.500054 0 180)
			(size 0.762 4.2164)
			(layers "F.Cu" "F.Mask" "F.Paste")
			(net "T6_NODE2_EN_R")
		)
		(pad "B78" smd rect
			(at 37.500052 0 180)
			(size 0.762 4.2164)
			(layers "F.Cu" "F.Mask" "F.Paste")
			(net "T6_NODE3_EN_R")
		)
		(pad "B79" smd rect
			(at 38.50005 0 180)
			(size 0.762 4.2164)
			(layers "F.Cu" "F.Mask" "F.Paste")
			(net "T6_NODE4_EN_R")
		)
		(pad "B80" smd rect
			(at 39.500048 0 180)
			(size 0.762 4.2164)
			(layers "F.Cu" "F.Mask" "F.Paste")
			(net "GND")
		)
		(pad "B81" smd rect
			(at 40.500046 -0.499872 180)
			(size 0.762 3.2004)
			(layers "F.Cu" "F.Mask" "F.Paste")
			(net "UART_T6_NODE1_RXD_R")
		)
		(pad "B82" smd rect
			(at 41.500044 0 180)
			(size 0.762 4.2164)
			(layers "F.Cu" "F.Mask" "F.Paste")
			(net "UART_T6_NODE1_TXD_R")
		)
		(zone
			(layers "F.Cu" "B.Cu" "In1.Cu" "In2.Cu" "In3.Cu" "In4.Cu" "In5.Cu" "In6.Cu"
				"In7.Cu" "In8.Cu"
			)
			(hatch none 0.5)
			(connect_pads
				(clearance 0)
			)
			(min_thickness 0.25)
			(keepout
				(tracks allowed)
				(vias not_allowed)
				(pads allowed)
				(copperpour not_allowed)
				(footprints allowed)
			)
			(placement
				(enabled no)
				(sheetname "")
			)
			(fill
				(thermal_gap 0.5)
				(thermal_bridge_width 0.5)
				(island_removal_mode 0)
			)
			(polygon
				(pts
					(xy 174.471584 -207.358488) (xy 103.580184 -207.358488) (xy 103.580184 -201.770488) (xy 174.471584 -201.770488)
				)
			)
		)
		(zone
			(layers "F.Cu" "B.Cu" "In1.Cu" "In2.Cu" "In3.Cu" "In4.Cu" "In5.Cu" "In6.Cu"
				"In7.Cu" "In8.Cu"
			)
			(hatch none 0.5)
			(connect_pads
				(clearance 0)
			)
			(min_thickness 0.25)
			(keepout
				(tracks allowed)
				(vias not_allowed)
				(pads allowed)
				(copperpour not_allowed)
				(footprints allowed)
			)
			(placement
				(enabled no)
				(sheetname "")
			)
			(fill
				(thermal_gap 0.5)
				(thermal_bridge_width 0.5)
				(island_removal_mode 0)
			)
			(polygon
				(pts
					(xy 176.579784 -201.770488) (xy 187.450984 -201.770488) (xy 187.450984 -207.358488) (xy 176.579784 -207.358488)
				)
			)
		)
	)
	(footprint ""
		(layer "F.Cu")
		(at 80.907128 -141.347952)
		(property "Reference" "C840"
			(at -2.42062 3.949192 0)
			(unlocked yes)
			(layer "F.SilkS")
			(effects
				(font
					(size 0.635 0.4064)
					(thickness 0.1524)
				)
				(justify left)
			)
		)
		(property "Value" ""
			(at 0 0 0)
			(layer "F.Fab")
			(effects
				(font
					(size 1.27 1.27)
				)
			)
		)
		(duplicate_pad_numbers_are_jumpers no)
		(fp_line
			(start -0.7874 -0.4064)
			(end 0.7874 -0.4064)
			(stroke
				(width 0.1524)
				(type default)
			)
			(layer "F.SilkS")
		)
		(fp_line
			(start -0.7874 0.4064)
			(end -0.7874 -0.4064)
			(stroke
				(width 0.1524)
				(type default)
			)
			(layer "F.SilkS")
		)
		(fp_line
			(start 0 0.381)
			(end 0 -0.381)
			(stroke
				(width 0.1524)
				(type default)
			)
			(layer "F.SilkS")
		)
		(fp_line
			(start 0.7874 -0.4064)
			(end 0.7874 0.4064)
			(stroke
				(width 0.1524)
				(type default)
			)
			(layer "F.SilkS")
		)
		(fp_line
			(start 0.7874 0.4064)
			(end -0.7874 0.4064)
			(stroke
				(width 0.1524)
				(type default)
			)
			(layer "F.SilkS")
		)
		(fp_poly
			(pts
				(xy -0.5334 0.254) (xy -0.635 0.254) (xy -0.635 0.2286) (xy -0.635 -0.254) (xy -0.5334 -0.254) (xy -0.5334 -0.2794)
				(xy 0.5334 -0.2794) (xy 0.5334 -0.254) (xy 0.635 -0.254) (xy 0.635 0.254) (xy 0.5334 0.254) (xy 0.5334 0.2794)
				(xy -0.508 0.2794) (xy -0.5334 0.2794)
			)
			(stroke
				(width 0)
				(type default)
			)
			(fill no)
			(layer "F.CrtYd")
		)
		(pad "1" smd rect
			(at 0.40005 0)
			(size 0.4572 0.508)
			(layers "F.Cu" "F.Mask" "F.Paste")
			(net "P1V26_BMC_NODE1")
		)
		(pad "2" smd rect
			(at -0.40005 0)
			(size 0.4572 0.508)
			(layers "F.Cu" "F.Mask" "F.Paste")
			(net "GND")
		)
	)
	(footprint ""
		(layer "F.Cu")
		(at 8.67156 -138.620246 -90)
		(property "Reference" "R1302"
			(at 4.242054 4.105402 90)
			(unlocked yes)
			(layer "F.SilkS")
			(effects
				(font
					(size 0.7874 0.5842)
					(thickness 0.1524)
				)
				(justify left)
			)
		)
		(property "Value" ""
			(at 0 0 270)
			(layer "F.Fab")
			(effects
				(font
					(size 1.27 1.27)
				)
			)
		)
		(duplicate_pad_numbers_are_jumpers no)
		(fp_line
			(start -0.7874 0.4064)
			(end -0.7874 -0.4064)
			(stroke
				(width 0.1524)
				(type default)
			)
			(layer "F.SilkS")
		)
		(fp_line
			(start 0.7874 0.4064)
			(end -0.7874 0.4064)
			(stroke
				(width 0.1524)
				(type default)
			)
			(layer "F.SilkS")
		)
		(fp_line
			(start -0.7874 -0.4064)
			(end 0.7874 -0.4064)
			(stroke
				(width 0.1524)
				(type default)
			)
			(layer "F.SilkS")
		)
		(fp_line
			(start 0.7874 -0.4064)
			(end 0.7874 0.4064)
			(stroke
				(width 0.1524)
				(type default)
			)
			(layer "F.SilkS")
		)
		(fp_poly
			(pts
				(xy -0.508 0.2794) (xy -0.508 0.2286) (xy -0.635 0.2286) (xy -0.635 -0.254) (xy -0.5334 -0.254)
				(xy -0.5334 -0.2794) (xy 0.5334 -0.2794) (xy 0.5334 -0.254) (xy 0.635 -0.254) (xy 0.635 0.254) (xy 0.5334 0.254)
				(xy 0.5334 0.2794)
			)
			(stroke
				(width 0)
				(type default)
			)
			(fill no)
			(layer "F.CrtYd")
		)
		(pad "1" smd rect
			(at 0.40005 0 270)
			(size 0.4572 0.508)
			(layers "F.Cu" "F.Mask" "F.Paste")
			(net "P3V3_NODE1")
		)
		(pad "2" smd rect
			(at -0.40005 0 270)
			(size 0.4572 0.508)
			(layers "F.Cu" "F.Mask" "F.Paste")
			(net "N54310543")
		)
	)
	(footprint ""
		(layer "F.Cu")
		(at 169.792396 -60.66663)
		(property "Reference" "R271"
			(at -0.427736 -2.219452 0)
			(unlocked yes)
			(layer "F.SilkS")
			(effects
				(font
					(size 0.7874 0.5842)
					(thickness 0.1524)
				)
				(justify left)
			)
		)
		(property "Value" ""
			(at 0 0 0)
			(layer "F.Fab")
			(effects
				(font
					(size 1.27 1.27)
				)
			)
		)
		(duplicate_pad_numbers_are_jumpers no)
		(fp_line
			(start -0.7874 -0.4064)
			(end 0.7874 -0.4064)
			(stroke
				(width 0.1524)
				(type default)
			)
			(layer "F.SilkS")
		)
		(fp_line
			(start -0.7874 0.4064)
			(end -0.7874 -0.4064)
			(stroke
				(width 0.1524)
				(type default)
			)
			(layer "F.SilkS")
		)
		(fp_line
			(start 0.7874 -0.4064)
			(end 0.7874 0.4064)
			(stroke
				(width 0.1524)
				(type default)
			)
			(layer "F.SilkS")
		)
		(fp_line
			(start 0.7874 0.4064)
			(end -0.7874 0.4064)
			(stroke
				(width 0.1524)
				(type default)
			)
			(layer "F.SilkS")
		)
		(fp_poly
			(pts
				(xy -0.508 0.2794) (xy -0.508 0.2286) (xy -0.635 0.2286) (xy -0.635 -0.254) (xy -0.5334 -0.254)
				(xy -0.5334 -0.2794) (xy 0.5334 -0.2794) (xy 0.5334 -0.254) (xy 0.635 -0.254) (xy 0.635 0.254) (xy 0.5334 0.254)
				(xy 0.5334 0.2794)
			)
			(stroke
				(width 0)
				(type default)
			)
			(fill no)
			(layer "F.CrtYd")
		)
		(pad "1" smd rect
			(at 0.40005 0)
			(size 0.4572 0.508)
			(layers "F.Cu" "F.Mask" "F.Paste")
			(net "USB3_L_DN")
		)
		(pad "2" smd rect
			(at -0.40005 0)
			(size 0.4572 0.508)
			(layers "F.Cu" "F.Mask" "F.Paste")
			(net "USB3_DN")
		)
	)
	(footprint ""
		(layer "F.Cu")
		(at 144.789652 -150.19655)
		(property "Reference" "R278"
			(at -0.319786 17.243044 0)
			(unlocked yes)
			(layer "F.SilkS")
			(effects
				(font
					(size 0.7874 0.5842)
					(thickness 0.1524)
				)
				(justify left)
			)
		)
		(property "Value" ""
			(at 0 0 0)
			(layer "F.Fab")
			(effects
				(font
					(size 1.27 1.27)
				)
			)
		)
		(duplicate_pad_numbers_are_jumpers no)
		(fp_line
			(start -0.7874 -0.4064)
			(end 0.7874 -0.4064)
			(stroke
				(width 0.1524)
				(type default)
			)
			(layer "F.SilkS")
		)
		(fp_line
			(start -0.7874 0.4064)
			(end -0.7874 -0.4064)
			(stroke
				(width 0.1524)
				(type default)
			)
			(layer "F.SilkS")
		)
		(fp_line
			(start 0.7874 -0.4064)
			(end 0.7874 0.4064)
			(stroke
				(width 0.1524)
				(type default)
			)
			(layer "F.SilkS")
		)
		(fp_line
			(start 0.7874 0.4064)
			(end -0.7874 0.4064)
			(stroke
				(width 0.1524)
				(type default)
			)
			(layer "F.SilkS")
		)
		(fp_poly
			(pts
				(xy -0.508 0.2794) (xy -0.508 0.2286) (xy -0.635 0.2286) (xy -0.635 -0.254) (xy -0.5334 -0.254)
				(xy -0.5334 -0.2794) (xy 0.5334 -0.2794) (xy 0.5334 -0.254) (xy 0.635 -0.254) (xy 0.635 0.254) (xy 0.5334 0.254)
				(xy 0.5334 0.2794)
			)
			(stroke
				(width 0)
				(type default)
			)
			(fill no)
			(layer "F.CrtYd")
		)
		(pad "1" smd rect
			(at 0.40005 0)
			(size 0.4572 0.508)
			(layers "F.Cu" "F.Mask" "F.Paste")
			(net "GND")
		)
		(pad "2" smd rect
			(at -0.40005 0)
			(size 0.4572 0.508)
			(layers "F.Cu" "F.Mask" "F.Paste")
			(net "PCIE_SW_P1_CTCDIS")
		)
	)
	(footprint ""
		(layer "F.Cu")
		(at 137.593578 -62.736222 180)
		(property "Reference" "R510"
			(at 1.277874 -4.45643 0)
			(unlocked yes)
			(layer "F.SilkS")
			(effects
				(font
					(size 0.7874 0.5842)
					(thickness 0.1524)
				)
				(justify left)
			)
		)
		(property "Value" ""
			(at 0 0 180)
			(layer "F.Fab")
			(effects
				(font
					(size 1.27 1.27)
				)
			)
		)
		(duplicate_pad_numbers_are_jumpers no)
		(fp_line
			(start 0.7874 0.4064)
			(end -0.7874 0.4064)
			(stroke
				(width 0.1524)
				(type default)
			)
			(layer "F.SilkS")
		)
		(fp_line
			(start 0.7874 -0.4064)
			(end 0.7874 0.4064)
			(stroke
				(width 0.1524)
				(type default)
			)
			(layer "F.SilkS")
		)
		(fp_line
			(start -0.7874 0.4064)
			(end -0.7874 -0.4064)
			(stroke
				(width 0.1524)
				(type default)
			)
			(layer "F.SilkS")
		)
		(fp_line
			(start -0.7874 -0.4064)
			(end 0.7874 -0.4064)
			(stroke
				(width 0.1524)
				(type default)
			)
			(layer "F.SilkS")
		)
		(fp_poly
			(pts
				(xy -0.508 0.2794) (xy -0.508 0.2286) (xy -0.635 0.2286) (xy -0.635 -0.254) (xy -0.5334 -0.254)
				(xy -0.5334 -0.2794) (xy 0.5334 -0.2794) (xy 0.5334 -0.254) (xy 0.635 -0.254) (xy 0.635 0.254) (xy 0.5334 0.254)
				(xy 0.5334 0.2794)
			)
			(stroke
				(width 0)
				(type default)
			)
			(fill no)
			(layer "F.CrtYd")
		)
		(pad "1" smd rect
			(at 0.40005 0 180)
			(size 0.4572 0.508)
			(layers "F.Cu" "F.Mask" "F.Paste")
			(net "GND")
		)
		(pad "2" smd rect
			(at -0.40005 0 180)
			(size 0.4572 0.508)
			(layers "F.Cu" "F.Mask" "F.Paste")
			(net "SATA_NODE1_GPIO1")
		)
	)
	(footprint ""
		(layer "F.Cu")
		(at 36.093908 -19.453352 180)
		(property "Reference" "C143"
			(at 1.836928 -1.289558 0)
			(unlocked yes)
			(layer "F.SilkS")
			(effects
				(font
					(size 0.7874 0.5842)
					(thickness 0.1524)
				)
				(justify left)
			)
		)
		(property "Value" ""
			(at 0 0 180)
			(layer "F.Fab")
			(effects
				(font
					(size 1.27 1.27)
				)
			)
		)
		(duplicate_pad_numbers_are_jumpers no)
		(fp_line
			(start 0.7874 0.4064)
			(end -0.7874 0.4064)
			(stroke
				(width 0.1524)
				(type default)
			)
			(layer "F.SilkS")
		)
		(fp_line
			(start 0.7874 -0.4064)
			(end 0.7874 0.4064)
			(stroke
				(width 0.1524)
				(type default)
			)
			(layer "F.SilkS")
		)
		(fp_line
			(start 0 0.381)
			(end 0 -0.381)
			(stroke
				(width 0.1524)
				(type default)
			)
			(layer "F.SilkS")
		)
		(fp_line
			(start -0.7874 0.4064)
			(end -0.7874 -0.4064)
			(stroke
				(width 0.1524)
				(type default)
			)
			(layer "F.SilkS")
		)
		(fp_line
			(start -0.7874 -0.4064)
			(end 0.7874 -0.4064)
			(stroke
				(width 0.1524)
				(type default)
			)
			(layer "F.SilkS")
		)
		(fp_poly
			(pts
				(xy -0.5334 0.254) (xy -0.635 0.254) (xy -0.635 0.2286) (xy -0.635 -0.254) (xy -0.5334 -0.254) (xy -0.5334 -0.2794)
				(xy 0.5334 -0.2794) (xy 0.5334 -0.254) (xy 0.635 -0.254) (xy 0.635 0.254) (xy 0.5334 0.254) (xy 0.5334 0.2794)
				(xy -0.508 0.2794) (xy -0.5334 0.2794)
			)
			(stroke
				(width 0)
				(type default)
			)
			(fill no)
			(layer "F.CrtYd")
		)
		(pad "1" smd rect
			(at 0.40005 0 180)
			(size 0.4572 0.508)
			(layers "F.Cu" "F.Mask" "F.Paste")
			(net "P1V5_NODE1_DDR3_VREF0_D")
		)
		(pad "2" smd rect
			(at -0.40005 0 180)
			(size 0.4572 0.508)
			(layers "F.Cu" "F.Mask" "F.Paste")
			(net "GND")
		)
	)
	(footprint ""
		(layer "F.Cu")
		(at 19.684746 -119.127524)
		(property "Reference" "PL6"
			(at -4.056634 3.772154 90)
			(unlocked yes)
			(layer "F.SilkS")
			(effects
				(font
					(size 0.7874 0.5842)
					(thickness 0.1524)
				)
				(justify left)
			)
		)
		(property "Value" ""
			(at 0 0 0)
			(layer "F.Fab")
			(effects
				(font
					(size 1.27 1.27)
				)
			)
		)
		(duplicate_pad_numbers_are_jumpers no)
		(fp_line
			(start -3.350006 -4.1656)
			(end 3.350006 -4.1656)
			(stroke
				(width 0.1524)
				(type default)
			)
			(layer "F.SilkS")
		)
		(fp_line
			(start -3.350006 4.1656)
			(end -3.350006 -4.1656)
			(stroke
				(width 0.1524)
				(type default)
			)
			(layer "F.SilkS")
		)
		(fp_line
			(start 3.350006 -4.1656)
			(end 3.350006 4.1656)
			(stroke
				(width 0.1524)
				(type default)
			)
			(layer "F.SilkS")
		)
		(fp_line
			(start 3.350006 4.1656)
			(end -3.350006 4.1656)
			(stroke
				(width 0.1524)
				(type default)
			)
			(layer "F.SilkS")
		)
		(fp_poly
			(pts
				(xy -3.350006 -3.64998) (xy -1.7018 -3.64998) (xy -1.7018 -4.05257) (xy 1.7018 -4.05257) (xy 1.7018 -3.64998)
				(xy 3.350006 -3.64998) (xy 3.350006 3.64998) (xy 1.7018 3.64998) (xy 1.7018 4.05257) (xy -1.7018 4.05257)
				(xy -1.7018 3.64998) (xy -3.350006 3.64998)
			)
			(stroke
				(width 0)
				(type default)
			)
			(fill no)
			(layer "F.CrtYd")
		)
		(fp_line
			(start -3.350006 -3.64998)
			(end 3.350006 -3.64998)
			(stroke
				(width 0.1)
				(type default)
			)
			(layer "F.Fab")
		)
		(fp_line
			(start -3.350006 3.64998)
			(end -3.350006 -3.64998)
			(stroke
				(width 0.1)
				(type default)
			)
			(layer "F.Fab")
		)
		(fp_line
			(start 3.350006 -3.64998)
			(end 3.350006 3.64998)
			(stroke
				(width 0.1)
				(type default)
			)
			(layer "F.Fab")
		)
		(fp_line
			(start 3.350006 3.64998)
			(end -3.350006 3.64998)
			(stroke
				(width 0.1)
				(type default)
			)
			(layer "F.Fab")
		)
		(pad "1" smd rect
			(at 0 -2.92481 270)
			(size 2.15392 3.302)
			(layers "F.Cu" "F.Mask" "F.Paste")
			(net "SW_P1V05_NODE1_PH")
		)
		(pad "2" smd rect
			(at 0 2.92481 270)
			(size 2.15392 3.302)
			(layers "F.Cu" "F.Mask" "F.Paste")
			(net "P1V05_NODE1")
		)
	)
	(footprint ""
		(layer "F.Cu")
		(at 35.85464 -14.23797 -90)
		(property "Reference" "PR35"
			(at 0.977392 3.54711 90)
			(unlocked yes)
			(layer "F.SilkS")
			(effects
				(font
					(size 0.7874 0.5842)
					(thickness 0.1524)
				)
				(justify left)
			)
		)
		(property "Value" ""
			(at 0 0 270)
			(layer "F.Fab")
			(effects
				(font
					(size 1.27 1.27)
				)
			)
		)
		(duplicate_pad_numbers_are_jumpers no)
		(fp_line
			(start -0.7874 0.4064)
			(end -0.7874 -0.4064)
			(stroke
				(width 0.1524)
				(type default)
			)
			(layer "F.SilkS")
		)
		(fp_line
			(start 0.7874 0.4064)
			(end -0.7874 0.4064)
			(stroke
				(width 0.1524)
				(type default)
			)
			(layer "F.SilkS")
		)
		(fp_line
			(start -0.7874 -0.4064)
			(end 0.7874 -0.4064)
			(stroke
				(width 0.1524)
				(type default)
			)
			(layer "F.SilkS")
		)
		(fp_line
			(start 0.7874 -0.4064)
			(end 0.7874 0.4064)
			(stroke
				(width 0.1524)
				(type default)
			)
			(layer "F.SilkS")
		)
		(fp_poly
			(pts
				(xy -0.508 0.2794) (xy -0.508 0.2286) (xy -0.635 0.2286) (xy -0.635 -0.254) (xy -0.5334 -0.254)
				(xy -0.5334 -0.2794) (xy 0.5334 -0.2794) (xy 0.5334 -0.254) (xy 0.635 -0.254) (xy 0.635 0.254) (xy 0.5334 0.254)
				(xy 0.5334 0.2794)
			)
			(stroke
				(width 0)
				(type default)
			)
			(fill no)
			(layer "F.CrtYd")
		)
		(pad "1" smd rect
			(at 0.40005 0 270)
			(size 0.4572 0.508)
			(layers "F.Cu" "F.Mask" "F.Paste")
			(net "VSENSE_PV_VDDR_NODE1_P")
		)
		(pad "2" smd rect
			(at -0.40005 0 270)
			(size 0.4572 0.508)
			(layers "F.Cu" "F.Mask" "F.Paste")
			(net "PV_VDDR_NODE1")
		)
	)
	(footprint ""
		(layer "F.Cu")
		(at 25.999948 -62.799976)
		(property "Reference" "H3"
			(at 2.062734 -2.494788 0)
			(unlocked yes)
			(layer "F.SilkS")
			(effects
				(font
					(size 0.7874 0.5842)
					(thickness 0.1524)
				)
				(justify left)
			)
		)
		(property "Value" ""
			(at 0 0 0)
			(layer "F.Fab")
			(effects
				(font
					(size 1.27 1.27)
				)
			)
		)
		(duplicate_pad_numbers_are_jumpers no)
		(fp_circle
			(center 0 0)
			(end 2.3114 0)
			(stroke
				(width 0.1524)
				(type default)
			)
			(fill no)
			(layer "F.SilkS")
		)
		(fp_circle
			(center 0 0)
			(end 2.3114 0)
			(stroke
				(width 0.1524)
				(type default)
			)
			(fill no)
			(layer "B.SilkS")
		)
		(fp_poly
			(pts
				(arc
					(start 0 1.4986)
					(mid 0 -1.4986)
					(end 0 1.4986)
				)
			)
			(stroke
				(width 0)
				(type default)
			)
			(fill no)
			(layer "F.CrtYd")
		)
		(pad "" np_thru_hole circle
			(at 0 0)
			(size 2.9972 2.9972)
			(drill 2.9972)
			(layers "*.Cu" "*.Mask")
			(clearance 0.381)
			(thermal_gap 0.381)
		)
		(zone
			(layers "F.Cu" "B.Cu" "In1.Cu" "In2.Cu" "In3.Cu" "In4.Cu" "In5.Cu" "In6.Cu"
				"In7.Cu" "In8.Cu"
			)
			(hatch none 0.5)
			(connect_pads
				(clearance 0)
			)
			(min_thickness 0.25)
			(keepout
				(tracks not_allowed)
				(vias allowed)
				(pads allowed)
				(copperpour not_allowed)
				(footprints allowed)
			)
			(placement
				(enabled no)
				(sheetname "")
			)
			(fill
				(thermal_gap 0.5)
				(thermal_bridge_width 0.5)
				(island_removal_mode 0)
			)
			(polygon
				(pts
					(arc
						(start 25.999948 -60.793376)
						(mid 25.999948 -64.806576)
						(end 25.999948 -60.793376)
					)
				)
			)
		)
	)
	(footprint ""
		(layer "F.Cu")
		(at 14.052804 -163.557712 180)
		(property "Reference" "R1275"
			(at 1.786128 2.286 0)
			(unlocked yes)
			(layer "F.SilkS")
			(effects
				(font
					(size 0.7874 0.5842)
					(thickness 0.1524)
				)
				(justify left)
			)
		)
		(property "Value" ""
			(at 0 0 180)
			(layer "F.Fab")
			(effects
				(font
					(size 1.27 1.27)
				)
			)
		)
		(duplicate_pad_numbers_are_jumpers no)
		(fp_line
			(start 0.7874 0.4064)
			(end -0.7874 0.4064)
			(stroke
				(width 0.1524)
				(type default)
			)
			(layer "F.SilkS")
		)
		(fp_line
			(start 0.7874 -0.4064)
			(end 0.7874 0.4064)
			(stroke
				(width 0.1524)
				(type default)
			)
			(layer "F.SilkS")
		)
		(fp_line
			(start -0.7874 0.4064)
			(end -0.7874 -0.4064)
			(stroke
				(width 0.1524)
				(type default)
			)
			(layer "F.SilkS")
		)
		(fp_line
			(start -0.7874 -0.4064)
			(end 0.7874 -0.4064)
			(stroke
				(width 0.1524)
				(type default)
			)
			(layer "F.SilkS")
		)
		(fp_poly
			(pts
				(xy -0.508 0.2794) (xy -0.508 0.2286) (xy -0.635 0.2286) (xy -0.635 -0.254) (xy -0.5334 -0.254)
				(xy -0.5334 -0.2794) (xy 0.5334 -0.2794) (xy 0.5334 -0.254) (xy 0.635 -0.254) (xy 0.635 0.254) (xy 0.5334 0.254)
				(xy 0.5334 0.2794)
			)
			(stroke
				(width 0)
				(type default)
			)
			(fill no)
			(layer "F.CrtYd")
		)
		(pad "1" smd rect
			(at 0.40005 0 180)
			(size 0.4572 0.508)
			(layers "F.Cu" "F.Mask" "F.Paste")
			(net "N54065132")
		)
		(pad "2" smd rect
			(at -0.40005 0 180)
			(size 0.4572 0.508)
			(layers "F.Cu" "F.Mask" "F.Paste")
			(net "LAN1_P3_R")
		)
	)
	(footprint ""
		(layer "F.Cu")
		(at 33.344104 -118.551452)
		(property "Reference" "R1116"
			(at -6.116828 0.981456 0)
			(unlocked yes)
			(layer "F.SilkS")
			(effects
				(font
					(size 0.7874 0.5842)
					(thickness 0.1524)
				)
				(justify left)
			)
		)
		(property "Value" ""
			(at 0 0 0)
			(layer "F.Fab")
			(effects
				(font
					(size 1.27 1.27)
				)
			)
		)
		(duplicate_pad_numbers_are_jumpers no)
		(fp_line
			(start -0.7874 -0.4064)
			(end 0.7874 -0.4064)
			(stroke
				(width 0.1524)
				(type default)
			)
			(layer "F.SilkS")
		)
		(fp_line
			(start -0.7874 0.4064)
			(end -0.7874 -0.4064)
			(stroke
				(width 0.1524)
				(type default)
			)
			(layer "F.SilkS")
		)
		(fp_line
			(start 0.7874 -0.4064)
			(end 0.7874 0.4064)
			(stroke
				(width 0.1524)
				(type default)
			)
			(layer "F.SilkS")
		)
		(fp_line
			(start 0.7874 0.4064)
			(end -0.7874 0.4064)
			(stroke
				(width 0.1524)
				(type default)
			)
			(layer "F.SilkS")
		)
		(fp_poly
			(pts
				(xy -0.508 0.2794) (xy -0.508 0.2286) (xy -0.635 0.2286) (xy -0.635 -0.254) (xy -0.5334 -0.254)
				(xy -0.5334 -0.2794) (xy 0.5334 -0.2794) (xy 0.5334 -0.254) (xy 0.635 -0.254) (xy 0.635 0.254) (xy 0.5334 0.254)
				(xy 0.5334 0.2794)
			)
			(stroke
				(width 0)
				(type default)
			)
			(fill no)
			(layer "F.CrtYd")
		)
		(pad "1" smd rect
			(at 0.40005 0)
			(size 0.4572 0.508)
			(layers "F.Cu" "F.Mask" "F.Paste")
			(net "FM_CPLD_NODE1_P1V5_EN")
		)
		(pad "2" smd rect
			(at -0.40005 0)
			(size 0.4572 0.508)
			(layers "F.Cu" "F.Mask" "F.Paste")
			(net "P3V3_STB_NODE1")
		)
	)
	(footprint ""
		(layer "F.Cu")
		(at 60.469526 -161.888932 -90)
		(property "Reference" "Q36"
			(at 0.21463 -10.954258 90)
			(unlocked yes)
			(layer "F.SilkS")
			(effects
				(font
					(size 0.7874 0.5842)
					(thickness 0.1524)
				)
			)
		)
		(property "Value" ""
			(at 0 0 270)
			(layer "F.Fab")
			(effects
				(font
					(size 1.27 1.27)
				)
			)
		)
		(duplicate_pad_numbers_are_jumpers no)
		(fp_line
			(start -1.603248 1.500124)
			(end -1.603248 -1.500124)
			(stroke
				(width 0.1524)
				(type default)
			)
			(layer "F.SilkS")
		)
		(fp_line
			(start 1.603248 1.500124)
			(end -1.603248 1.500124)
			(stroke
				(width 0.1524)
				(type default)
			)
			(layer "F.SilkS")
		)
		(fp_line
			(start -1.603248 -1.500124)
			(end 1.603248 -1.500124)
			(stroke
				(width 0.1524)
				(type default)
			)
			(layer "F.SilkS")
		)
		(fp_line
			(start 1.603248 -1.500124)
			(end 1.603248 1.500124)
			(stroke
				(width 0.1524)
				(type default)
			)
			(layer "F.SilkS")
		)
		(fp_poly
			(pts
				(xy -0.700024 -1.500124) (xy -0.700024 -1.40716) (xy -1.507998 -1.40716) (xy -1.507998 -0.49276)
				(xy -0.700024 -0.49276) (xy -0.700024 0.47244) (xy -1.507998 0.47244) (xy -1.507998 1.41224) (xy -0.700024 1.41224)
				(xy -0.700024 1.500124) (xy 0.700024 1.500124) (xy 0.700024 0.47244) (xy 1.514602 0.47244) (xy 1.514602 -0.46736)
				(xy 0.700024 -0.46736) (xy 0.700024 -1.500124)
			)
			(stroke
				(width 0)
				(type default)
			)
			(fill no)
			(layer "F.CrtYd")
		)
		(fp_line
			(start -0.700024 1.500124)
			(end -0.700024 -1.500124)
			(stroke
				(width 0.1)
				(type default)
			)
			(layer "F.Fab")
		)
		(fp_line
			(start 0.700024 1.500124)
			(end -0.700024 1.500124)
			(stroke
				(width 0.1)
				(type default)
			)
			(layer "F.Fab")
		)
		(fp_line
			(start -0.700024 -1.500124)
			(end 0.700024 -1.500124)
			(stroke
				(width 0.1)
				(type default)
			)
			(layer "F.Fab")
		)
		(fp_line
			(start 0.700024 -1.500124)
			(end 0.700024 1.500124)
			(stroke
				(width 0.1)
				(type default)
			)
			(layer "F.Fab")
		)
		(fp_text user "S"
			(at 1.451864 1.890268 0)
			(unlocked yes)
			(layer "F.SilkS")
			(effects
				(font
					(size 0.635 0.4064)
					(thickness 0.1524)
				)
			)
		)
		(fp_text user "D"
			(at 2.252218 -0.858774 0)
			(unlocked yes)
			(layer "F.SilkS")
			(effects
				(font
					(size 0.635 0.4064)
					(thickness 0.1524)
				)
			)
		)
		(fp_text user "G"
			(at -0.907796 -2.31775 0)
			(unlocked yes)
			(layer "F.SilkS")
			(effects
				(font
					(size 0.635 0.4064)
					(thickness 0.1524)
				)
			)
		)
		(fp_text user "S"
			(at -1.025906 2.0066 180)
			(unlocked yes)
			(layer "F.Fab")
			(effects
				(font
					(size 0.7874 0.5842)
					(thickness 0.000001)
				)
			)
		)
		(fp_text user "D"
			(at 2.098294 0.1016 180)
			(unlocked yes)
			(layer "F.Fab")
			(effects
				(font
					(size 0.7874 0.5842)
					(thickness 0.000001)
				)
			)
		)
		(fp_text user "G"
			(at -1.051306 -2.032 180)
			(unlocked yes)
			(layer "F.Fab")
			(effects
				(font
					(size 0.7874 0.5842)
					(thickness 0.000001)
				)
			)
		)
		(pad "D" smd rect
			(at 0.999998 0 180)
			(size 0.8128 0.9144)
			(layers "F.Cu" "F.Mask" "F.Paste")
			(net "FM_CPLD_NODE1_P5V_EN_LV")
		)
		(pad "G" smd rect
			(at -0.999998 -0.94996 180)
			(size 0.8128 0.9144)
			(layers "F.Cu" "F.Mask" "F.Paste")
			(net "FM_CPLD_NODE1_P5V_NODE1_EN_G")
		)
		(pad "S" smd rect
			(at -0.999998 0.94996 180)
			(size 0.8128 0.9144)
			(layers "F.Cu" "F.Mask" "F.Paste")
			(net "FM_CPLD_NODE1_P5V_EN")
		)
	)
	(footprint ""
		(layer "F.Cu")
		(at 109.30001 -156.330142 180)
		(property "Reference" "U108"
			(at -4.302252 3.040126 90)
			(unlocked yes)
			(layer "F.SilkS")
			(effects
				(font
					(size 0.635 0.4064)
					(thickness 0.1524)
				)
			)
		)
		(property "Value" ""
			(at 0 0 180)
			(layer "F.Fab")
			(effects
				(font
					(size 1.27 1.27)
				)
			)
		)
		(duplicate_pad_numbers_are_jumpers no)
		(fp_line
			(start 1.651 1.905)
			(end -1.651 1.905)
			(stroke
				(width 0.1524)
				(type default)
			)
			(layer "F.SilkS")
		)
		(fp_line
			(start 1.651 -1.905)
			(end 1.651 1.905)
			(stroke
				(width 0.1524)
				(type default)
			)
			(layer "F.SilkS")
		)
		(fp_line
			(start -1.651 1.905)
			(end -1.651 -1.905)
			(stroke
				(width 0.1524)
				(type default)
			)
			(layer "F.SilkS")
		)
		(fp_line
			(start -1.651 -1.905)
			(end 1.651 -1.905)
			(stroke
				(width 0.1524)
				(type default)
			)
			(layer "F.SilkS")
		)
		(fp_poly
			(pts
				(xy -1.524 0.7112) (xy -1.524 1.7526) (xy -0.508 1.7526) (xy -0.508 0.6985) (xy 0.508 0.6985) (xy 0.508 1.7526)
				(xy 1.524 1.7526) (xy 1.524 0.6985) (xy 1.524 -0.6985) (xy 0.508 -0.6985) (xy 0.508 -1.7526) (xy -0.508 -1.7526)
				(xy -0.508 -0.6985) (xy -1.524 -0.6985) (xy -1.524 0.6985)
			)
			(stroke
				(width 0)
				(type default)
			)
			(fill no)
			(layer "F.CrtYd")
		)
		(fp_text user "D"
			(at 0.947928 -1.425448 0)
			(unlocked yes)
			(layer "F.SilkS")
			(effects
				(font
					(size 0.635 0.4064)
					(thickness 0.1524)
				)
			)
		)
		(fp_text user "G"
			(at 0.09779 1.149604 0)
			(unlocked yes)
			(layer "F.SilkS")
			(effects
				(font
					(size 0.635 0.4064)
					(thickness 0.1524)
				)
			)
		)
		(fp_text user "S"
			(at -1.046988 -1.28397 0)
			(unlocked yes)
			(layer "F.SilkS")
			(effects
				(font
					(size 0.635 0.4064)
					(thickness 0.1524)
				)
			)
		)
		(pad "D" smd rect
			(at 0 -1.1176 180)
			(size 1.016 1.27)
			(layers "F.Cu" "F.Mask" "F.Paste")
			(net "N52411212")
		)
		(pad "G" smd rect
			(at -1.016 1.1176 180)
			(size 1.016 1.27)
			(layers "F.Cu" "F.Mask" "F.Paste")
			(net "N52410978")
		)
		(pad "S" smd rect
			(at 1.016 1.1176 180)
			(size 1.016 1.27)
			(layers "F.Cu" "F.Mask" "F.Paste")
			(net "GND")
		)
	)
	(footprint ""
		(layer "F.Cu")
		(at 88.232488 -157.737302)
		(property "Reference" "PC130"
			(at -1.467104 6.650482 0)
			(unlocked yes)
			(layer "F.SilkS")
			(effects
				(font
					(size 0.7874 0.5842)
					(thickness 0.1524)
				)
				(justify left)
			)
		)
		(property "Value" ""
			(at 0 0 0)
			(layer "F.Fab")
			(effects
				(font
					(size 1.27 1.27)
				)
			)
		)
		(duplicate_pad_numbers_are_jumpers no)
		(fp_line
			(start -1.905 -0.8636)
			(end 1.905 -0.8636)
			(stroke
				(width 0.1524)
				(type default)
			)
			(layer "F.SilkS")
		)
		(fp_line
			(start -1.905 0.8636)
			(end -1.905 -0.8636)
			(stroke
				(width 0.1524)
				(type default)
			)
			(layer "F.SilkS")
		)
		(fp_line
			(start 0 0.8382)
			(end 0 -0.8382)
			(stroke
				(width 0.1524)
				(type default)
			)
			(layer "F.SilkS")
		)
		(fp_line
			(start 1.905 -0.8636)
			(end 1.905 0.8636)
			(stroke
				(width 0.1524)
				(type default)
			)
			(layer "F.SilkS")
		)
		(fp_line
			(start 1.905 0.8636)
			(end -1.905 0.8636)
			(stroke
				(width 0.1524)
				(type default)
			)
			(layer "F.SilkS")
		)
		(fp_rect
			(start -1.524 0.7366)
			(end 1.524 -0.7366)
			(stroke
				(width 0)
				(type default)
			)
			(fill no)
			(layer "F.CrtYd")
		)
		(pad "1" smd rect
			(at 0.94996 0)
			(size 1.1176 1.3716)
			(layers "F.Cu" "F.Mask" "F.Paste")
			(net "P1V8_STB_NODE1")
		)
		(pad "2" smd rect
			(at -0.94996 0)
			(size 1.1176 1.3716)
			(layers "F.Cu" "F.Mask" "F.Paste")
			(net "GND")
		)
	)
	(footprint ""
		(layer "F.Cu")
		(at 84.18322 -8.212074 180)
		(property "Reference" "PC50"
			(at -2.287524 -4.117848 0)
			(unlocked yes)
			(layer "F.SilkS")
			(effects
				(font
					(size 0.7874 0.5842)
					(thickness 0.1524)
				)
				(justify left)
			)
		)
		(property "Value" ""
			(at 0 0 180)
			(layer "F.Fab")
			(effects
				(font
					(size 1.27 1.27)
				)
			)
		)
		(duplicate_pad_numbers_are_jumpers no)
		(fp_line
			(start 0.7874 0.4064)
			(end -0.7874 0.4064)
			(stroke
				(width 0.1524)
				(type default)
			)
			(layer "F.SilkS")
		)
		(fp_line
			(start 0.7874 -0.4064)
			(end 0.7874 0.4064)
			(stroke
				(width 0.1524)
				(type default)
			)
			(layer "F.SilkS")
		)
		(fp_line
			(start 0 0.381)
			(end 0 -0.381)
			(stroke
				(width 0.1524)
				(type default)
			)
			(layer "F.SilkS")
		)
		(fp_line
			(start -0.7874 0.4064)
			(end -0.7874 -0.4064)
			(stroke
				(width 0.1524)
				(type default)
			)
			(layer "F.SilkS")
		)
		(fp_line
			(start -0.7874 -0.4064)
			(end 0.7874 -0.4064)
			(stroke
				(width 0.1524)
				(type default)
			)
			(layer "F.SilkS")
		)
		(fp_poly
			(pts
				(xy -0.5334 0.254) (xy -0.635 0.254) (xy -0.635 0.2286) (xy -0.635 -0.254) (xy -0.5334 -0.254) (xy -0.5334 -0.2794)
				(xy 0.5334 -0.2794) (xy 0.5334 -0.254) (xy 0.635 -0.254) (xy 0.635 0.254) (xy 0.5334 0.254) (xy 0.5334 0.2794)
				(xy -0.508 0.2794) (xy -0.5334 0.2794)
			)
			(stroke
				(width 0)
				(type default)
			)
			(fill no)
			(layer "F.CrtYd")
		)
		(pad "1" smd rect
			(at 0.40005 0 180)
			(size 0.4572 0.508)
			(layers "F.Cu" "F.Mask" "F.Paste")
			(net "P3V3_NODE1")
		)
		(pad "2" smd rect
			(at -0.40005 0 180)
			(size 0.4572 0.508)
			(layers "F.Cu" "F.Mask" "F.Paste")
			(net "GND")
		)
	)
	(footprint ""
		(layer "F.Cu")
		(at 184.3786 -182.8292)
		(property "Reference" "R1317"
			(at 9.4234 17.04467 0)
			(unlocked yes)
			(layer "F.SilkS")
			(effects
				(font
					(size 0.7874 0.5842)
					(thickness 0.1524)
				)
				(justify left)
			)
		)
		(property "Value" ""
			(at 0 0 0)
			(layer "F.Fab")
			(effects
				(font
					(size 1.27 1.27)
				)
			)
		)
		(duplicate_pad_numbers_are_jumpers no)
		(fp_line
			(start -0.7874 -0.4064)
			(end 0.7874 -0.4064)
			(stroke
				(width 0.1524)
				(type default)
			)
			(layer "F.SilkS")
		)
		(fp_line
			(start -0.7874 0.4064)
			(end -0.7874 -0.4064)
			(stroke
				(width 0.1524)
				(type default)
			)
			(layer "F.SilkS")
		)
		(fp_line
			(start 0.7874 -0.4064)
			(end 0.7874 0.4064)
			(stroke
				(width 0.1524)
				(type default)
			)
			(layer "F.SilkS")
		)
		(fp_line
			(start 0.7874 0.4064)
			(end -0.7874 0.4064)
			(stroke
				(width 0.1524)
				(type default)
			)
			(layer "F.SilkS")
		)
		(fp_poly
			(pts
				(xy -0.508 0.2794) (xy -0.508 0.2286) (xy -0.635 0.2286) (xy -0.635 -0.254) (xy -0.5334 -0.254)
				(xy -0.5334 -0.2794) (xy 0.5334 -0.2794) (xy 0.5334 -0.254) (xy 0.635 -0.254) (xy 0.635 0.254) (xy 0.5334 0.254)
				(xy 0.5334 0.2794)
			)
			(stroke
				(width 0)
				(type default)
			)
			(fill no)
			(layer "F.CrtYd")
		)
		(pad "1" smd rect
			(at 0.40005 0)
			(size 0.4572 0.508)
			(layers "F.Cu" "F.Mask" "F.Paste")
			(net "POWER_SW3_PWR_CTR_12V")
		)
		(pad "2" smd rect
			(at -0.40005 0)
			(size 0.4572 0.508)
			(layers "F.Cu" "F.Mask" "F.Paste")
			(net "POWER_SW3_PWR_CTR_12V_R")
		)
	)
	(footprint ""
		(layer "F.Cu")
		(at 137.593578 -59.688222 180)
		(property "Reference" "R512"
			(at 0.57785 -4.901184 0)
			(unlocked yes)
			(layer "F.SilkS")
			(effects
				(font
					(size 0.7874 0.5842)
					(thickness 0.1524)
				)
				(justify left)
			)
		)
		(property "Value" ""
			(at 0 0 180)
			(layer "F.Fab")
			(effects
				(font
					(size 1.27 1.27)
				)
			)
		)
		(duplicate_pad_numbers_are_jumpers no)
		(fp_line
			(start 0.7874 0.4064)
			(end -0.7874 0.4064)
			(stroke
				(width 0.1524)
				(type default)
			)
			(layer "F.SilkS")
		)
		(fp_line
			(start 0.7874 -0.4064)
			(end 0.7874 0.4064)
			(stroke
				(width 0.1524)
				(type default)
			)
			(layer "F.SilkS")
		)
		(fp_line
			(start -0.7874 0.4064)
			(end -0.7874 -0.4064)
			(stroke
				(width 0.1524)
				(type default)
			)
			(layer "F.SilkS")
		)
		(fp_line
			(start -0.7874 -0.4064)
			(end 0.7874 -0.4064)
			(stroke
				(width 0.1524)
				(type default)
			)
			(layer "F.SilkS")
		)
		(fp_poly
			(pts
				(xy -0.508 0.2794) (xy -0.508 0.2286) (xy -0.635 0.2286) (xy -0.635 -0.254) (xy -0.5334 -0.254)
				(xy -0.5334 -0.2794) (xy 0.5334 -0.2794) (xy 0.5334 -0.254) (xy 0.635 -0.254) (xy 0.635 0.254) (xy 0.5334 0.254)
				(xy 0.5334 0.2794)
			)
			(stroke
				(width 0)
				(type default)
			)
			(fill no)
			(layer "F.CrtYd")
		)
		(pad "1" smd rect
			(at 0.40005 0 180)
			(size 0.4572 0.508)
			(layers "F.Cu" "F.Mask" "F.Paste")
			(net "GND")
		)
		(pad "2" smd rect
			(at -0.40005 0 180)
			(size 0.4572 0.508)
			(layers "F.Cu" "F.Mask" "F.Paste")
			(net "SATA_NODE1_GPIO2")
		)
	)
	(footprint ""
		(layer "F.Cu")
		(at 112.067594 -164.305234)
		(property "Reference" "R681"
			(at -2.090674 -12.486894 0)
			(unlocked yes)
			(layer "F.SilkS")
			(effects
				(font
					(size 0.7874 0.5842)
					(thickness 0.1524)
				)
				(justify left)
			)
		)
		(property "Value" ""
			(at 0 0 0)
			(layer "F.Fab")
			(effects
				(font
					(size 1.27 1.27)
				)
			)
		)
		(duplicate_pad_numbers_are_jumpers no)
		(fp_line
			(start -0.7874 -0.4064)
			(end 0.7874 -0.4064)
			(stroke
				(width 0.1524)
				(type default)
			)
			(layer "F.SilkS")
		)
		(fp_line
			(start -0.7874 0.4064)
			(end -0.7874 -0.4064)
			(stroke
				(width 0.1524)
				(type default)
			)
			(layer "F.SilkS")
		)
		(fp_line
			(start 0.7874 -0.4064)
			(end 0.7874 0.4064)
			(stroke
				(width 0.1524)
				(type default)
			)
			(layer "F.SilkS")
		)
		(fp_line
			(start 0.7874 0.4064)
			(end -0.7874 0.4064)
			(stroke
				(width 0.1524)
				(type default)
			)
			(layer "F.SilkS")
		)
		(fp_poly
			(pts
				(xy -0.508 0.2794) (xy -0.508 0.2286) (xy -0.635 0.2286) (xy -0.635 -0.254) (xy -0.5334 -0.254)
				(xy -0.5334 -0.2794) (xy 0.5334 -0.2794) (xy 0.5334 -0.254) (xy 0.635 -0.254) (xy 0.635 0.254) (xy 0.5334 0.254)
				(xy 0.5334 0.2794)
			)
			(stroke
				(width 0)
				(type default)
			)
			(fill no)
			(layer "F.CrtYd")
		)
		(pad "1" smd rect
			(at 0.40005 0)
			(size 0.4572 0.508)
			(layers "F.Cu" "F.Mask" "F.Paste")
			(net "I2C_COM3_SDA")
		)
		(pad "2" smd rect
			(at -0.40005 0)
			(size 0.4572 0.508)
			(layers "F.Cu" "F.Mask" "F.Paste")
			(net "I2C_PDB_SDA")
		)
	)
	(footprint ""
		(layer "F.Cu")
		(at 104.605836 -138.90117 -90)
		(property "Reference" "PC115"
			(at -3.936238 3.473196 0)
			(unlocked yes)
			(layer "F.SilkS")
			(effects
				(font
					(size 0.635 0.4064)
					(thickness 0.1524)
				)
				(justify left)
			)
		)
		(property "Value" ""
			(at 0 0 270)
			(layer "F.Fab")
			(effects
				(font
					(size 1.27 1.27)
				)
			)
		)
		(duplicate_pad_numbers_are_jumpers no)
		(fp_line
			(start -0.7874 0.4064)
			(end -0.7874 -0.4064)
			(stroke
				(width 0.1524)
				(type default)
			)
			(layer "F.SilkS")
		)
		(fp_line
			(start 0.7874 0.4064)
			(end -0.7874 0.4064)
			(stroke
				(width 0.1524)
				(type default)
			)
			(layer "F.SilkS")
		)
		(fp_line
			(start 0 0.381)
			(end 0 -0.381)
			(stroke
				(width 0.1524)
				(type default)
			)
			(layer "F.SilkS")
		)
		(fp_line
			(start -0.7874 -0.4064)
			(end 0.7874 -0.4064)
			(stroke
				(width 0.1524)
				(type default)
			)
			(layer "F.SilkS")
		)
		(fp_line
			(start 0.7874 -0.4064)
			(end 0.7874 0.4064)
			(stroke
				(width 0.1524)
				(type default)
			)
			(layer "F.SilkS")
		)
		(fp_poly
			(pts
				(xy -0.5334 0.254) (xy -0.635 0.254) (xy -0.635 0.2286) (xy -0.635 -0.254) (xy -0.5334 -0.254) (xy -0.5334 -0.2794)
				(xy 0.5334 -0.2794) (xy 0.5334 -0.254) (xy 0.635 -0.254) (xy 0.635 0.254) (xy 0.5334 0.254) (xy 0.5334 0.2794)
				(xy -0.508 0.2794) (xy -0.5334 0.2794)
			)
			(stroke
				(width 0)
				(type default)
			)
			(fill no)
			(layer "F.CrtYd")
		)
		(pad "1" smd rect
			(at 0.40005 0 270)
			(size 0.4572 0.508)
			(layers "F.Cu" "F.Mask" "F.Paste")
			(net "VR_PVCCP_NODE1_IBIAS")
		)
		(pad "2" smd rect
			(at -0.40005 0 270)
			(size 0.4572 0.508)
			(layers "F.Cu" "F.Mask" "F.Paste")
			(net "AGND_PVCCP_NODE1")
		)
	)
	(footprint ""
		(layer "F.Cu")
		(at 68.480686 -148.476462 90)
		(property "Reference" "R302"
			(at 1.233932 -0.013462 90)
			(unlocked yes)
			(layer "F.SilkS")
			(effects
				(font
					(size 0.7874 0.5842)
					(thickness 0.1524)
				)
				(justify left)
			)
		)
		(property "Value" ""
			(at 0 0 90)
			(layer "F.Fab")
			(effects
				(font
					(size 1.27 1.27)
				)
			)
		)
		(duplicate_pad_numbers_are_jumpers no)
		(fp_line
			(start 0.7874 -0.4064)
			(end 0.7874 0.4064)
			(stroke
				(width 0.1524)
				(type default)
			)
			(layer "F.SilkS")
		)
		(fp_line
			(start -0.7874 -0.4064)
			(end 0.7874 -0.4064)
			(stroke
				(width 0.1524)
				(type default)
			)
			(layer "F.SilkS")
		)
		(fp_line
			(start 0.7874 0.4064)
			(end -0.7874 0.4064)
			(stroke
				(width 0.1524)
				(type default)
			)
			(layer "F.SilkS")
		)
		(fp_line
			(start -0.7874 0.4064)
			(end -0.7874 -0.4064)
			(stroke
				(width 0.1524)
				(type default)
			)
			(layer "F.SilkS")
		)
		(fp_poly
			(pts
				(xy -0.508 0.2794) (xy -0.508 0.2286) (xy -0.635 0.2286) (xy -0.635 -0.254) (xy -0.5334 -0.254)
				(xy -0.5334 -0.2794) (xy 0.5334 -0.2794) (xy 0.5334 -0.254) (xy 0.635 -0.254) (xy 0.635 0.254) (xy 0.5334 0.254)
				(xy 0.5334 0.2794)
			)
			(stroke
				(width 0)
				(type default)
			)
			(fill no)
			(layer "F.CrtYd")
		)
		(pad "1" smd rect
			(at 0.40005 0 90)
			(size 0.4572 0.508)
			(layers "F.Cu" "F.Mask" "F.Paste")
			(net "P3V3_NODE1")
		)
		(pad "2" smd rect
			(at -0.40005 0 90)
			(size 0.4572 0.508)
			(layers "F.Cu" "F.Mask" "F.Paste")
			(net "BMC_NODE1_JTAG_TMS")
		)
	)
	(footprint ""
		(layer "F.Cu")
		(at 148.040852 -142.09903 180)
		(property "Reference" "R310"
			(at -1.563116 -1.17221 0)
			(unlocked yes)
			(layer "F.SilkS")
			(effects
				(font
					(size 0.635 0.4064)
					(thickness 0.1524)
				)
				(justify left)
			)
		)
		(property "Value" ""
			(at 0 0 180)
			(layer "F.Fab")
			(effects
				(font
					(size 1.27 1.27)
				)
			)
		)
		(duplicate_pad_numbers_are_jumpers no)
		(fp_line
			(start 0.7874 0.4064)
			(end -0.7874 0.4064)
			(stroke
				(width 0.1524)
				(type default)
			)
			(layer "F.SilkS")
		)
		(fp_line
			(start 0.7874 -0.4064)
			(end 0.7874 0.4064)
			(stroke
				(width 0.1524)
				(type default)
			)
			(layer "F.SilkS")
		)
		(fp_line
			(start -0.7874 0.4064)
			(end -0.7874 -0.4064)
			(stroke
				(width 0.1524)
				(type default)
			)
			(layer "F.SilkS")
		)
		(fp_line
			(start -0.7874 -0.4064)
			(end 0.7874 -0.4064)
			(stroke
				(width 0.1524)
				(type default)
			)
			(layer "F.SilkS")
		)
		(fp_poly
			(pts
				(xy -0.508 0.2794) (xy -0.508 0.2286) (xy -0.635 0.2286) (xy -0.635 -0.254) (xy -0.5334 -0.254)
				(xy -0.5334 -0.2794) (xy 0.5334 -0.2794) (xy 0.5334 -0.254) (xy 0.635 -0.254) (xy 0.635 0.254) (xy 0.5334 0.254)
				(xy 0.5334 0.2794)
			)
			(stroke
				(width 0)
				(type default)
			)
			(fill no)
			(layer "F.CrtYd")
		)
		(pad "1" smd rect
			(at 0.40005 0 180)
			(size 0.4572 0.508)
			(layers "F.Cu" "F.Mask" "F.Paste")
			(net "PCIE_SW_I2C_SDA")
		)
		(pad "2" smd rect
			(at -0.40005 0 180)
			(size 0.4572 0.508)
			(layers "F.Cu" "F.Mask" "F.Paste")
			(net "P3V3_NODE1")
		)
	)
	(footprint ""
		(layer "F.Cu")
		(at 152.67051 -148.057362)
		(property "Reference" "C527"
			(at -1.33858 -3.798824 0)
			(unlocked yes)
			(layer "F.SilkS")
			(effects
				(font
					(size 0.635 0.4064)
					(thickness 0.1524)
				)
				(justify left)
			)
		)
		(property "Value" ""
			(at 0 0 0)
			(layer "F.Fab")
			(effects
				(font
					(size 1.27 1.27)
				)
			)
		)
		(duplicate_pad_numbers_are_jumpers no)
		(fp_line
			(start -0.7874 -0.4064)
			(end 0.7874 -0.4064)
			(stroke
				(width 0.1524)
				(type default)
			)
			(layer "F.SilkS")
		)
		(fp_line
			(start -0.7874 0.4064)
			(end -0.7874 -0.4064)
			(stroke
				(width 0.1524)
				(type default)
			)
			(layer "F.SilkS")
		)
		(fp_line
			(start 0 0.381)
			(end 0 -0.381)
			(stroke
				(width 0.1524)
				(type default)
			)
			(layer "F.SilkS")
		)
		(fp_line
			(start 0.7874 -0.4064)
			(end 0.7874 0.4064)
			(stroke
				(width 0.1524)
				(type default)
			)
			(layer "F.SilkS")
		)
		(fp_line
			(start 0.7874 0.4064)
			(end -0.7874 0.4064)
			(stroke
				(width 0.1524)
				(type default)
			)
			(layer "F.SilkS")
		)
		(fp_poly
			(pts
				(xy -0.5334 0.254) (xy -0.635 0.254) (xy -0.635 0.2286) (xy -0.635 -0.254) (xy -0.5334 -0.254) (xy -0.5334 -0.2794)
				(xy 0.5334 -0.2794) (xy 0.5334 -0.254) (xy 0.635 -0.254) (xy 0.635 0.254) (xy 0.5334 0.254) (xy 0.5334 0.2794)
				(xy -0.508 0.2794) (xy -0.5334 0.2794)
			)
			(stroke
				(width 0)
				(type default)
			)
			(fill no)
			(layer "F.CrtYd")
		)
		(pad "1" smd rect
			(at 0.40005 0)
			(size 0.4572 0.508)
			(layers "F.Cu" "F.Mask" "F.Paste")
			(net "LAN2_LED_ACT_N")
		)
		(pad "2" smd rect
			(at -0.40005 0)
			(size 0.4572 0.508)
			(layers "F.Cu" "F.Mask" "F.Paste")
			(net "GND")
		)
	)
	(footprint ""
		(layer "F.Cu")
		(at 53.621686 -120.942862 180)
		(property "Reference" "L13"
			(at 5.542026 0.271526 0)
			(unlocked yes)
			(layer "F.SilkS")
			(effects
				(font
					(size 0.7874 0.5842)
					(thickness 0.1524)
				)
			)
		)
		(property "Value" ""
			(at 0 0 180)
			(layer "F.Fab")
			(effects
				(font
					(size 1.27 1.27)
				)
			)
		)
		(duplicate_pad_numbers_are_jumpers no)
		(fp_line
			(start 1.2954 0.635)
			(end -1.2954 0.635)
			(stroke
				(width 0.1524)
				(type default)
			)
			(layer "F.SilkS")
		)
		(fp_line
			(start 1.2954 -0.635)
			(end 1.2954 0.635)
			(stroke
				(width 0.1524)
				(type default)
			)
			(layer "F.SilkS")
		)
		(fp_line
			(start 0.127 -0.5842)
			(end 0.127 0.5842)
			(stroke
				(width 0.1524)
				(type default)
			)
			(layer "F.SilkS")
		)
		(fp_line
			(start -0.127 -0.5842)
			(end -0.127 0.5842)
			(stroke
				(width 0.1524)
				(type default)
			)
			(layer "F.SilkS")
		)
		(fp_line
			(start -1.2954 -0.635)
			(end 1.2954 -0.635)
			(stroke
				(width 0.1524)
				(type default)
			)
			(layer "F.SilkS")
		)
		(fp_line
			(start -1.2954 -0.635)
			(end -1.2954 0.635)
			(stroke
				(width 0.1524)
				(type default)
			)
			(layer "F.SilkS")
		)
		(fp_poly
			(pts
				(xy -0.9144 0.508) (xy -0.9144 0.3556) (xy -1.143 0.3556) (xy -1.143 -0.3556) (xy -0.9144 -0.3556)
				(xy -0.9144 -0.508) (xy 0.9144 -0.508) (xy 0.9144 -0.3556) (xy 1.143 -0.3556) (xy 1.143 0.3556)
				(xy 0.9144 0.3556) (xy 0.9144 0.508)
			)
			(stroke
				(width 0)
				(type default)
			)
			(fill no)
			(layer "F.CrtYd")
		)
		(pad "1" smd rect
			(at 0.7366 0 270)
			(size 0.7112 0.8128)
			(layers "F.Cu" "F.Mask" "F.Paste")
			(net "BMC_NODE1_OSC1_VDD")
		)
		(pad "2" smd rect
			(at -0.7366 0 270)
			(size 0.7112 0.8128)
			(layers "F.Cu" "F.Mask" "F.Paste")
			(net "P3V3_NODE1")
		)
	)
	(footprint ""
		(layer "F.Cu")
		(at 98.06305 -181.722268)
		(property "Reference" "R146"
			(at 84.126324 75.315826 0)
			(unlocked yes)
			(layer "F.SilkS")
			(effects
				(font
					(size 0.7874 0.5842)
					(thickness 0.1524)
				)
				(justify left)
			)
		)
		(property "Value" ""
			(at 0 0 0)
			(layer "F.Fab")
			(effects
				(font
					(size 1.27 1.27)
				)
			)
		)
		(duplicate_pad_numbers_are_jumpers no)
		(fp_line
			(start -0.7874 -0.4064)
			(end 0.7874 -0.4064)
			(stroke
				(width 0.1524)
				(type default)
			)
			(layer "F.SilkS")
		)
		(fp_line
			(start -0.7874 0.4064)
			(end -0.7874 -0.4064)
			(stroke
				(width 0.1524)
				(type default)
			)
			(layer "F.SilkS")
		)
		(fp_line
			(start 0.7874 -0.4064)
			(end 0.7874 0.4064)
			(stroke
				(width 0.1524)
				(type default)
			)
			(layer "F.SilkS")
		)
		(fp_line
			(start 0.7874 0.4064)
			(end -0.7874 0.4064)
			(stroke
				(width 0.1524)
				(type default)
			)
			(layer "F.SilkS")
		)
		(fp_poly
			(pts
				(xy -0.508 0.2794) (xy -0.508 0.2286) (xy -0.635 0.2286) (xy -0.635 -0.254) (xy -0.5334 -0.254)
				(xy -0.5334 -0.2794) (xy 0.5334 -0.2794) (xy 0.5334 -0.254) (xy 0.635 -0.254) (xy 0.635 0.254) (xy 0.5334 0.254)
				(xy 0.5334 0.2794)
			)
			(stroke
				(width 0)
				(type default)
			)
			(fill no)
			(layer "F.CrtYd")
		)
		(pad "1" smd rect
			(at 0.40005 0)
			(size 0.4572 0.508)
			(layers "F.Cu" "F.Mask" "F.Paste")
			(net "ATTENTION_LED_N")
		)
		(pad "2" smd rect
			(at -0.40005 0)
			(size 0.4572 0.508)
			(layers "F.Cu" "F.Mask" "F.Paste")
			(net "P3V3_NODE1")
		)
	)
	(footprint ""
		(layer "F.Cu")
		(at 130.902456 -161.150046 180)
		(property "Reference" "R775"
			(at 61.040772 -108.866686 0)
			(unlocked yes)
			(layer "F.SilkS")
			(effects
				(font
					(size 0.7874 0.5842)
					(thickness 0.1524)
				)
				(justify left)
			)
		)
		(property "Value" ""
			(at 0 0 180)
			(layer "F.Fab")
			(effects
				(font
					(size 1.27 1.27)
				)
			)
		)
		(duplicate_pad_numbers_are_jumpers no)
		(fp_line
			(start 0.7874 0.4064)
			(end -0.7874 0.4064)
			(stroke
				(width 0.1524)
				(type default)
			)
			(layer "F.SilkS")
		)
		(fp_line
			(start 0.7874 -0.4064)
			(end 0.7874 0.4064)
			(stroke
				(width 0.1524)
				(type default)
			)
			(layer "F.SilkS")
		)
		(fp_line
			(start -0.7874 0.4064)
			(end -0.7874 -0.4064)
			(stroke
				(width 0.1524)
				(type default)
			)
			(layer "F.SilkS")
		)
		(fp_line
			(start -0.7874 -0.4064)
			(end 0.7874 -0.4064)
			(stroke
				(width 0.1524)
				(type default)
			)
			(layer "F.SilkS")
		)
		(fp_poly
			(pts
				(xy -0.508 0.2794) (xy -0.508 0.2286) (xy -0.635 0.2286) (xy -0.635 -0.254) (xy -0.5334 -0.254)
				(xy -0.5334 -0.2794) (xy 0.5334 -0.2794) (xy 0.5334 -0.254) (xy 0.635 -0.254) (xy 0.635 0.254) (xy 0.5334 0.254)
				(xy 0.5334 0.2794)
			)
			(stroke
				(width 0)
				(type default)
			)
			(fill no)
			(layer "F.CrtYd")
		)
		(pad "1" smd rect
			(at 0.40005 0 180)
			(size 0.4572 0.508)
			(layers "F.Cu" "F.Mask" "F.Paste")
			(net "CPLD123_RSV3")
		)
		(pad "2" smd rect
			(at -0.40005 0 180)
			(size 0.4572 0.508)
			(layers "F.Cu" "F.Mask" "F.Paste")
			(net "CPLD3_RSV3")
		)
	)
	(footprint ""
		(layer "F.Cu")
		(at 53.561996 -160.014158 180)
		(property "Reference" "C517"
			(at 0.575564 5.472176 0)
			(unlocked yes)
			(layer "F.SilkS")
			(effects
				(font
					(size 0.7874 0.5842)
					(thickness 0.1524)
				)
				(justify left)
			)
		)
		(property "Value" ""
			(at 0 0 180)
			(layer "F.Fab")
			(effects
				(font
					(size 1.27 1.27)
				)
			)
		)
		(duplicate_pad_numbers_are_jumpers no)
		(fp_line
			(start 0.7874 0.4064)
			(end -0.7874 0.4064)
			(stroke
				(width 0.1524)
				(type default)
			)
			(layer "F.SilkS")
		)
		(fp_line
			(start 0.7874 -0.4064)
			(end 0.7874 0.4064)
			(stroke
				(width 0.1524)
				(type default)
			)
			(layer "F.SilkS")
		)
		(fp_line
			(start 0 0.381)
			(end 0 -0.381)
			(stroke
				(width 0.1524)
				(type default)
			)
			(layer "F.SilkS")
		)
		(fp_line
			(start -0.7874 0.4064)
			(end -0.7874 -0.4064)
			(stroke
				(width 0.1524)
				(type default)
			)
			(layer "F.SilkS")
		)
		(fp_line
			(start -0.7874 -0.4064)
			(end 0.7874 -0.4064)
			(stroke
				(width 0.1524)
				(type default)
			)
			(layer "F.SilkS")
		)
		(fp_poly
			(pts
				(xy -0.5334 0.254) (xy -0.635 0.254) (xy -0.635 0.2286) (xy -0.635 -0.254) (xy -0.5334 -0.254) (xy -0.5334 -0.2794)
				(xy 0.5334 -0.2794) (xy 0.5334 -0.254) (xy 0.635 -0.254) (xy 0.635 0.254) (xy 0.5334 0.254) (xy 0.5334 0.2794)
				(xy -0.508 0.2794) (xy -0.5334 0.2794)
			)
			(stroke
				(width 0)
				(type default)
			)
			(fill no)
			(layer "F.CrtYd")
		)
		(pad "1" smd rect
			(at 0.40005 0 180)
			(size 0.4572 0.508)
			(layers "F.Cu" "F.Mask" "F.Paste")
			(net "LAN1_LED_ACT_N")
		)
		(pad "2" smd rect
			(at -0.40005 0 180)
			(size 0.4572 0.508)
			(layers "F.Cu" "F.Mask" "F.Paste")
			(net "GND")
		)
	)
	(footprint ""
		(layer "F.Cu")
		(at 53.561996 -158.998158)
		(property "Reference" "R558"
			(at -0.575564 -5.39115 0)
			(unlocked yes)
			(layer "F.SilkS")
			(effects
				(font
					(size 0.7874 0.5842)
					(thickness 0.1524)
				)
				(justify left)
			)
		)
		(property "Value" ""
			(at 0 0 0)
			(layer "F.Fab")
			(effects
				(font
					(size 1.27 1.27)
				)
			)
		)
		(duplicate_pad_numbers_are_jumpers no)
		(fp_line
			(start -0.7874 -0.4064)
			(end 0.7874 -0.4064)
			(stroke
				(width 0.1524)
				(type default)
			)
			(layer "F.SilkS")
		)
		(fp_line
			(start -0.7874 0.4064)
			(end -0.7874 -0.4064)
			(stroke
				(width 0.1524)
				(type default)
			)
			(layer "F.SilkS")
		)
		(fp_line
			(start 0.7874 -0.4064)
			(end 0.7874 0.4064)
			(stroke
				(width 0.1524)
				(type default)
			)
			(layer "F.SilkS")
		)
		(fp_line
			(start 0.7874 0.4064)
			(end -0.7874 0.4064)
			(stroke
				(width 0.1524)
				(type default)
			)
			(layer "F.SilkS")
		)
		(fp_poly
			(pts
				(xy -0.508 0.2794) (xy -0.508 0.2286) (xy -0.635 0.2286) (xy -0.635 -0.254) (xy -0.5334 -0.254)
				(xy -0.5334 -0.2794) (xy 0.5334 -0.2794) (xy 0.5334 -0.254) (xy 0.635 -0.254) (xy 0.635 0.254) (xy 0.5334 0.254)
				(xy 0.5334 0.2794)
			)
			(stroke
				(width 0)
				(type default)
			)
			(fill no)
			(layer "F.CrtYd")
		)
		(pad "1" smd rect
			(at 0.40005 0)
			(size 0.4572 0.508)
			(layers "F.Cu" "F.Mask" "F.Paste")
			(net "GND")
		)
		(pad "2" smd rect
			(at -0.40005 0)
			(size 0.4572 0.508)
			(layers "F.Cu" "F.Mask" "F.Paste")
			(net "LAN1_TEST_EN")
		)
	)
	(footprint ""
		(layer "F.Cu")
		(at 44.454826 -169.625264 -90)
		(property "Reference" "U114"
			(at 0.081788 3.65506 90)
			(unlocked yes)
			(layer "F.SilkS")
			(effects
				(font
					(size 0.7874 0.5842)
					(thickness 0.1524)
				)
			)
		)
		(property "Value" ""
			(at 0 0 270)
			(layer "F.Fab")
			(effects
				(font
					(size 1.27 1.27)
				)
			)
		)
		(duplicate_pad_numbers_are_jumpers no)
		(fp_line
			(start -1.651 1.905)
			(end -1.651 -1.905)
			(stroke
				(width 0.1524)
				(type default)
			)
			(layer "F.SilkS")
		)
		(fp_line
			(start 1.651 1.905)
			(end -1.651 1.905)
			(stroke
				(width 0.1524)
				(type default)
			)
			(layer "F.SilkS")
		)
		(fp_line
			(start -1.651 -1.905)
			(end 1.651 -1.905)
			(stroke
				(width 0.1524)
				(type default)
			)
			(layer "F.SilkS")
		)
		(fp_line
			(start 1.651 -1.905)
			(end 1.651 1.905)
			(stroke
				(width 0.1524)
				(type default)
			)
			(layer "F.SilkS")
		)
		(fp_poly
			(pts
				(xy -1.524 0.7112) (xy -1.524 1.7526) (xy -0.508 1.7526) (xy -0.508 0.6985) (xy 0.508 0.6985) (xy 0.508 1.7526)
				(xy 1.524 1.7526) (xy 1.524 0.6985) (xy 1.524 -0.6985) (xy 0.508 -0.6985) (xy 0.508 -1.7526) (xy -0.508 -1.7526)
				(xy -0.508 -0.6985) (xy -1.524 -0.6985) (xy -1.524 0.6985)
			)
			(stroke
				(width 0)
				(type default)
			)
			(fill no)
			(layer "F.CrtYd")
		)
		(fp_text user "G"
			(at -1.410208 2.63779 0)
			(unlocked yes)
			(layer "F.SilkS")
			(effects
				(font
					(size 0.635 0.4064)
					(thickness 0.1524)
				)
			)
		)
		(fp_text user "S"
			(at 1.344168 2.23647 0)
			(unlocked yes)
			(layer "F.SilkS")
			(effects
				(font
					(size 0.635 0.4064)
					(thickness 0.1524)
				)
			)
		)
		(fp_text user "D"
			(at -0.016764 -2.367534 0)
			(unlocked yes)
			(layer "F.SilkS")
			(effects
				(font
					(size 0.635 0.4064)
					(thickness 0.1524)
				)
			)
		)
		(pad "D" smd rect
			(at 0 -1.1176 270)
			(size 1.016 1.27)
			(layers "F.Cu" "F.Mask" "F.Paste")
			(net "PSU_DC_OK_N")
		)
		(pad "G" smd rect
			(at -1.016 1.1176 270)
			(size 1.016 1.27)
			(layers "F.Cu" "F.Mask" "F.Paste")
			(net "N53103066")
		)
		(pad "S" smd rect
			(at 1.016 1.1176 270)
			(size 1.016 1.27)
			(layers "F.Cu" "F.Mask" "F.Paste")
			(net "GND")
		)
	)
	(footprint ""
		(layer "F.Cu")
		(at 19.651472 -74.207878 90)
		(property "Reference" "L38"
			(at 3.237738 -0.04318 90)
			(unlocked yes)
			(layer "F.SilkS")
			(effects
				(font
					(size 0.7874 0.5842)
					(thickness 0.1524)
				)
			)
		)
		(property "Value" ""
			(at 0 0 90)
			(layer "F.Fab")
			(effects
				(font
					(size 1.27 1.27)
				)
			)
		)
		(duplicate_pad_numbers_are_jumpers no)
		(fp_line
			(start 1.2954 -0.635)
			(end 1.2954 0.635)
			(stroke
				(width 0.1524)
				(type default)
			)
			(layer "F.SilkS")
		)
		(fp_line
			(start -1.2954 -0.635)
			(end 1.2954 -0.635)
			(stroke
				(width 0.1524)
				(type default)
			)
			(layer "F.SilkS")
		)
		(fp_line
			(start -1.2954 -0.635)
			(end -1.2954 0.635)
			(stroke
				(width 0.1524)
				(type default)
			)
			(layer "F.SilkS")
		)
		(fp_line
			(start 0.127 -0.5842)
			(end 0.127 0.5842)
			(stroke
				(width 0.1524)
				(type default)
			)
			(layer "F.SilkS")
		)
		(fp_line
			(start -0.127 -0.5842)
			(end -0.127 0.5842)
			(stroke
				(width 0.1524)
				(type default)
			)
			(layer "F.SilkS")
		)
		(fp_line
			(start 1.2954 0.635)
			(end -1.2954 0.635)
			(stroke
				(width 0.1524)
				(type default)
			)
			(layer "F.SilkS")
		)
		(fp_poly
			(pts
				(xy -0.9144 0.508) (xy -0.9144 0.3556) (xy -1.143 0.3556) (xy -1.143 -0.3556) (xy -0.9144 -0.3556)
				(xy -0.9144 -0.508) (xy 0.9144 -0.508) (xy 0.9144 -0.3556) (xy 1.143 -0.3556) (xy 1.143 0.3556)
				(xy 0.9144 0.3556) (xy 0.9144 0.508)
			)
			(stroke
				(width 0)
				(type default)
			)
			(fill no)
			(layer "F.CrtYd")
		)
		(pad "1" smd rect
			(at 0.7366 0 180)
			(size 0.7112 0.8128)
			(layers "F.Cu" "F.Mask" "F.Paste")
			(net "VCC5_CRTXX")
		)
		(pad "2" smd rect
			(at -0.7366 0 180)
			(size 0.7112 0.8128)
			(layers "F.Cu" "F.Mask" "F.Paste")
			(net "P5V_NODE1")
		)
	)
	(footprint ""
		(layer "F.Cu")
		(at 169.792396 -61.68263)
		(property "Reference" "R270"
			(at -0.427736 -2.219452 0)
			(unlocked yes)
			(layer "F.SilkS")
			(effects
				(font
					(size 0.7874 0.5842)
					(thickness 0.1524)
				)
				(justify left)
			)
		)
		(property "Value" ""
			(at 0 0 0)
			(layer "F.Fab")
			(effects
				(font
					(size 1.27 1.27)
				)
			)
		)
		(duplicate_pad_numbers_are_jumpers no)
		(fp_line
			(start -0.7874 -0.4064)
			(end 0.7874 -0.4064)
			(stroke
				(width 0.1524)
				(type default)
			)
			(layer "F.SilkS")
		)
		(fp_line
			(start -0.7874 0.4064)
			(end -0.7874 -0.4064)
			(stroke
				(width 0.1524)
				(type default)
			)
			(layer "F.SilkS")
		)
		(fp_line
			(start 0.7874 -0.4064)
			(end 0.7874 0.4064)
			(stroke
				(width 0.1524)
				(type default)
			)
			(layer "F.SilkS")
		)
		(fp_line
			(start 0.7874 0.4064)
			(end -0.7874 0.4064)
			(stroke
				(width 0.1524)
				(type default)
			)
			(layer "F.SilkS")
		)
		(fp_poly
			(pts
				(xy -0.508 0.2794) (xy -0.508 0.2286) (xy -0.635 0.2286) (xy -0.635 -0.254) (xy -0.5334 -0.254)
				(xy -0.5334 -0.2794) (xy 0.5334 -0.2794) (xy 0.5334 -0.254) (xy 0.635 -0.254) (xy 0.635 0.254) (xy 0.5334 0.254)
				(xy 0.5334 0.2794)
			)
			(stroke
				(width 0)
				(type default)
			)
			(fill no)
			(layer "F.CrtYd")
		)
		(pad "1" smd rect
			(at 0.40005 0)
			(size 0.4572 0.508)
			(layers "F.Cu" "F.Mask" "F.Paste")
			(net "USB3_L_DP")
		)
		(pad "2" smd rect
			(at -0.40005 0)
			(size 0.4572 0.508)
			(layers "F.Cu" "F.Mask" "F.Paste")
			(net "USB3_DP")
		)
	)
	(footprint ""
		(layer "F.Cu")
		(at 160.154874 -165.753288 -90)
		(property "Reference" "U38"
			(at -3.253232 1.430528 0)
			(unlocked yes)
			(layer "F.SilkS")
			(effects
				(font
					(size 0.7874 0.5842)
					(thickness 0.1524)
				)
				(justify left)
			)
		)
		(property "Value" ""
			(at 0 0 270)
			(layer "F.Fab")
			(effects
				(font
					(size 1.27 1.27)
				)
			)
		)
		(duplicate_pad_numbers_are_jumpers no)
		(fp_line
			(start -2.5146 1.4224)
			(end -2.5146 0.4572)
			(stroke
				(width 0.1524)
				(type default)
			)
			(layer "F.SilkS")
		)
		(fp_line
			(start 2.5146 1.4224)
			(end -2.5146 1.4224)
			(stroke
				(width 0.1524)
				(type default)
			)
			(layer "F.SilkS")
		)
		(fp_line
			(start -2.5146 0.4572)
			(end -2.0574 0)
			(stroke
				(width 0.1524)
				(type default)
			)
			(layer "F.SilkS")
		)
		(fp_line
			(start -2.0574 0)
			(end -2.5146 -0.4572)
			(stroke
				(width 0.1524)
				(type default)
			)
			(layer "F.SilkS")
		)
		(fp_line
			(start -2.5146 -0.4572)
			(end -2.5146 -1.4224)
			(stroke
				(width 0.1524)
				(type default)
			)
			(layer "F.SilkS")
		)
		(fp_line
			(start -2.5146 -1.4224)
			(end 2.5146 -1.4224)
			(stroke
				(width 0.1524)
				(type default)
			)
			(layer "F.SilkS")
		)
		(fp_line
			(start 2.5146 -1.4224)
			(end 2.5146 1.4224)
			(stroke
				(width 0.1524)
				(type default)
			)
			(layer "F.SilkS")
		)
		(fp_circle
			(center -1.905 0.889)
			(end -1.905 0.635)
			(stroke
				(width 0.1524)
				(type default)
			)
			(fill no)
			(layer "F.SilkS")
		)
		(fp_poly
			(pts
				(xy -2.1844 3.5052) (xy -2.1844 2.0066) (xy -2.5146 2.0066) (xy -2.5146 -2.0066) (xy -2.1844 -2.0066)
				(xy -2.1844 -3.5052) (xy 2.1844 -3.5052) (xy 2.1844 -2.0066) (xy 2.5146 -2.0066) (xy 2.5146 2.0066)
				(xy 2.1844 2.0066) (xy 2.1844 3.5052)
			)
			(stroke
				(width 0)
				(type default)
			)
			(fill no)
			(layer "F.CrtYd")
		)
		(pad "1" smd rect
			(at -1.905 2.6416 270)
			(size 0.5588 1.7272)
			(layers "F.Cu" "F.Mask" "F.Paste")
			(net "LAN2_NVM_CS_N_R")
		)
		(pad "2" smd rect
			(at -0.635 2.6416 270)
			(size 0.5588 1.7272)
			(layers "F.Cu" "F.Mask" "F.Paste")
			(net "LAN2_NVM_SO_R")
		)
		(pad "3" smd rect
			(at 0.635 2.6416 270)
			(size 0.5588 1.7272)
			(layers "F.Cu" "F.Mask" "F.Paste")
			(net "LAN2_NVM_WP_N")
		)
		(pad "4" smd rect
			(at 1.905 2.6416 270)
			(size 0.5588 1.7272)
			(layers "F.Cu" "F.Mask" "F.Paste")
			(net "GND")
		)
		(pad "5" smd rect
			(at 1.905 -2.6416 270)
			(size 0.5588 1.7272)
			(layers "F.Cu" "F.Mask" "F.Paste")
			(net "LAN2_NVM_SI_R")
		)
		(pad "6" smd rect
			(at 0.635 -2.6416 270)
			(size 0.5588 1.7272)
			(layers "F.Cu" "F.Mask" "F.Paste")
			(net "LAN2_NVM_SK_R")
		)
		(pad "7" smd rect
			(at -0.635 -2.6416 270)
			(size 0.5588 1.7272)
			(layers "F.Cu" "F.Mask" "F.Paste")
			(net "LAN2_NVM_HOLD_N")
		)
		(pad "8" smd rect
			(at -1.905 -2.6416 270)
			(size 0.5588 1.7272)
			(layers "F.Cu" "F.Mask" "F.Paste")
			(net "P3V3_NODE1")
		)
	)
	(footprint ""
		(layer "F.Cu")
		(at 7.18058 -154.13736 -90)
		(property "Reference" "R1298"
			(at 5.109464 -8.825992 90)
			(unlocked yes)
			(layer "F.SilkS")
			(effects
				(font
					(size 0.7874 0.5842)
					(thickness 0.1524)
				)
				(justify left)
			)
		)
		(property "Value" ""
			(at 0 0 270)
			(layer "F.Fab")
			(effects
				(font
					(size 1.27 1.27)
				)
			)
		)
		(duplicate_pad_numbers_are_jumpers no)
		(fp_line
			(start -0.7874 0.4064)
			(end -0.7874 -0.4064)
			(stroke
				(width 0.1524)
				(type default)
			)
			(layer "F.SilkS")
		)
		(fp_line
			(start 0.7874 0.4064)
			(end -0.7874 0.4064)
			(stroke
				(width 0.1524)
				(type default)
			)
			(layer "F.SilkS")
		)
		(fp_line
			(start -0.7874 -0.4064)
			(end 0.7874 -0.4064)
			(stroke
				(width 0.1524)
				(type default)
			)
			(layer "F.SilkS")
		)
		(fp_line
			(start 0.7874 -0.4064)
			(end 0.7874 0.4064)
			(stroke
				(width 0.1524)
				(type default)
			)
			(layer "F.SilkS")
		)
		(fp_poly
			(pts
				(xy -0.508 0.2794) (xy -0.508 0.2286) (xy -0.635 0.2286) (xy -0.635 -0.254) (xy -0.5334 -0.254)
				(xy -0.5334 -0.2794) (xy 0.5334 -0.2794) (xy 0.5334 -0.254) (xy 0.635 -0.254) (xy 0.635 0.254) (xy 0.5334 0.254)
				(xy 0.5334 0.2794)
			)
			(stroke
				(width 0)
				(type default)
			)
			(fill no)
			(layer "F.CrtYd")
		)
		(pad "1" smd rect
			(at 0.40005 0 270)
			(size 0.4572 0.508)
			(layers "F.Cu" "F.Mask" "F.Paste")
			(net "P3V3_NODE1")
		)
		(pad "2" smd rect
			(at -0.40005 0 270)
			(size 0.4572 0.508)
			(layers "F.Cu" "F.Mask" "F.Paste")
			(net "N54258476")
		)
	)
	(footprint ""
		(layer "F.Cu")
		(at 106.170476 -173.004988 180)
		(property "Reference" "R760"
			(at -1.206754 -0.196342 0)
			(unlocked yes)
			(layer "F.SilkS")
			(effects
				(font
					(size 0.7874 0.5842)
					(thickness 0.1524)
				)
				(justify left)
			)
		)
		(property "Value" ""
			(at 0 0 180)
			(layer "F.Fab")
			(effects
				(font
					(size 1.27 1.27)
				)
			)
		)
		(duplicate_pad_numbers_are_jumpers no)
		(fp_line
			(start 0.7874 0.4064)
			(end -0.7874 0.4064)
			(stroke
				(width 0.1524)
				(type default)
			)
			(layer "F.SilkS")
		)
		(fp_line
			(start 0.7874 -0.4064)
			(end 0.7874 0.4064)
			(stroke
				(width 0.1524)
				(type default)
			)
			(layer "F.SilkS")
		)
		(fp_line
			(start -0.7874 0.4064)
			(end -0.7874 -0.4064)
			(stroke
				(width 0.1524)
				(type default)
			)
			(layer "F.SilkS")
		)
		(fp_line
			(start -0.7874 -0.4064)
			(end 0.7874 -0.4064)
			(stroke
				(width 0.1524)
				(type default)
			)
			(layer "F.SilkS")
		)
		(fp_poly
			(pts
				(xy -0.508 0.2794) (xy -0.508 0.2286) (xy -0.635 0.2286) (xy -0.635 -0.254) (xy -0.5334 -0.254)
				(xy -0.5334 -0.2794) (xy 0.5334 -0.2794) (xy 0.5334 -0.254) (xy 0.635 -0.254) (xy 0.635 0.254) (xy 0.5334 0.254)
				(xy 0.5334 0.2794)
			)
			(stroke
				(width 0)
				(type default)
			)
			(fill no)
			(layer "F.CrtYd")
		)
		(pad "1" smd rect
			(at 0.40005 0 180)
			(size 0.4572 0.508)
			(layers "F.Cu" "F.Mask" "F.Paste")
			(net "I2C_ALERT_FNACTRL1_N")
		)
		(pad "2" smd rect
			(at -0.40005 0 180)
			(size 0.4572 0.508)
			(layers "F.Cu" "F.Mask" "F.Paste")
			(net "P3V3_NODE1")
		)
	)
	(footprint ""
		(layer "F.Cu")
		(at 130.98145 -60.930282 90)
		(property "Reference" "R516"
			(at -1.037082 -2.22758 90)
			(unlocked yes)
			(layer "F.SilkS")
			(effects
				(font
					(size 0.7874 0.5842)
					(thickness 0.1524)
				)
				(justify left)
			)
		)
		(property "Value" ""
			(at 0 0 90)
			(layer "F.Fab")
			(effects
				(font
					(size 1.27 1.27)
				)
			)
		)
		(duplicate_pad_numbers_are_jumpers no)
		(fp_line
			(start 0.7874 -0.4064)
			(end 0.7874 0.4064)
			(stroke
				(width 0.1524)
				(type default)
			)
			(layer "F.SilkS")
		)
		(fp_line
			(start -0.7874 -0.4064)
			(end 0.7874 -0.4064)
			(stroke
				(width 0.1524)
				(type default)
			)
			(layer "F.SilkS")
		)
		(fp_line
			(start 0.7874 0.4064)
			(end -0.7874 0.4064)
			(stroke
				(width 0.1524)
				(type default)
			)
			(layer "F.SilkS")
		)
		(fp_line
			(start -0.7874 0.4064)
			(end -0.7874 -0.4064)
			(stroke
				(width 0.1524)
				(type default)
			)
			(layer "F.SilkS")
		)
		(fp_poly
			(pts
				(xy -0.508 0.2794) (xy -0.508 0.2286) (xy -0.635 0.2286) (xy -0.635 -0.254) (xy -0.5334 -0.254)
				(xy -0.5334 -0.2794) (xy 0.5334 -0.2794) (xy 0.5334 -0.254) (xy 0.635 -0.254) (xy 0.635 0.254) (xy 0.5334 0.254)
				(xy 0.5334 0.2794)
			)
			(stroke
				(width 0)
				(type default)
			)
			(fill no)
			(layer "F.CrtYd")
		)
		(pad "1" smd rect
			(at 0.40005 0 90)
			(size 0.4572 0.508)
			(layers "F.Cu" "F.Mask" "F.Paste")
			(net "SATA_SPI_DI_NODE1_R")
		)
		(pad "2" smd rect
			(at -0.40005 0 90)
			(size 0.4572 0.508)
			(layers "F.Cu" "F.Mask" "F.Paste")
			(net "P3V3_NODE1")
		)
	)
	(footprint ""
		(layer "F.Cu")
		(at 25.999948 -88.799924)
		(property "Reference" "H1"
			(at 2.265172 -2.582164 0)
			(unlocked yes)
			(layer "F.SilkS")
			(effects
				(font
					(size 0.7874 0.5842)
					(thickness 0.1524)
				)
				(justify left)
			)
		)
		(property "Value" ""
			(at 0 0 0)
			(layer "F.Fab")
			(effects
				(font
					(size 1.27 1.27)
				)
			)
		)
		(duplicate_pad_numbers_are_jumpers no)
		(fp_circle
			(center 0 0)
			(end 2.3114 0)
			(stroke
				(width 0.1524)
				(type default)
			)
			(fill no)
			(layer "F.SilkS")
		)
		(fp_circle
			(center 0 0)
			(end 2.3114 0)
			(stroke
				(width 0.1524)
				(type default)
			)
			(fill no)
			(layer "B.SilkS")
		)
		(fp_poly
			(pts
				(arc
					(start 0 1.4986)
					(mid 0 -1.4986)
					(end 0 1.4986)
				)
			)
			(stroke
				(width 0)
				(type default)
			)
			(fill no)
			(layer "F.CrtYd")
		)
		(pad "" np_thru_hole circle
			(at 0 0)
			(size 2.9972 2.9972)
			(drill 2.9972)
			(layers "*.Cu" "*.Mask")
			(clearance 0.381)
			(thermal_gap 0.381)
		)
		(zone
			(layers "F.Cu" "B.Cu" "In1.Cu" "In2.Cu" "In3.Cu" "In4.Cu" "In5.Cu" "In6.Cu"
				"In7.Cu" "In8.Cu"
			)
			(hatch none 0.5)
			(connect_pads
				(clearance 0)
			)
			(min_thickness 0.25)
			(keepout
				(tracks not_allowed)
				(vias allowed)
				(pads allowed)
				(copperpour not_allowed)
				(footprints allowed)
			)
			(placement
				(enabled no)
				(sheetname "")
			)
			(fill
				(thermal_gap 0.5)
				(thermal_bridge_width 0.5)
				(island_removal_mode 0)
			)
			(polygon
				(pts
					(arc
						(start 25.999948 -86.793324)
						(mid 25.999948 -90.806524)
						(end 25.999948 -86.793324)
					)
				)
			)
		)
	)
	(footprint ""
		(layer "F.Cu")
		(at 184.614566 -130.602228 -90)
		(property "Reference" "R1120"
			(at 1.003554 -13.856716 90)
			(unlocked yes)
			(layer "F.SilkS")
			(effects
				(font
					(size 0.7874 0.5842)
					(thickness 0.1524)
				)
				(justify left)
			)
		)
		(property "Value" ""
			(at 0 0 270)
			(layer "F.Fab")
			(effects
				(font
					(size 1.27 1.27)
				)
			)
		)
		(duplicate_pad_numbers_are_jumpers no)
		(fp_line
			(start -0.7874 0.4064)
			(end -0.7874 -0.4064)
			(stroke
				(width 0.1524)
				(type default)
			)
			(layer "F.SilkS")
		)
		(fp_line
			(start 0.7874 0.4064)
			(end -0.7874 0.4064)
			(stroke
				(width 0.1524)
				(type default)
			)
			(layer "F.SilkS")
		)
		(fp_line
			(start -0.7874 -0.4064)
			(end 0.7874 -0.4064)
			(stroke
				(width 0.1524)
				(type default)
			)
			(layer "F.SilkS")
		)
		(fp_line
			(start 0.7874 -0.4064)
			(end 0.7874 0.4064)
			(stroke
				(width 0.1524)
				(type default)
			)
			(layer "F.SilkS")
		)
		(fp_poly
			(pts
				(xy -0.508 0.2794) (xy -0.508 0.2286) (xy -0.635 0.2286) (xy -0.635 -0.254) (xy -0.5334 -0.254)
				(xy -0.5334 -0.2794) (xy 0.5334 -0.2794) (xy 0.5334 -0.254) (xy 0.635 -0.254) (xy 0.635 0.254) (xy 0.5334 0.254)
				(xy 0.5334 0.2794)
			)
			(stroke
				(width 0)
				(type default)
			)
			(fill no)
			(layer "F.CrtYd")
		)
		(pad "1" smd rect
			(at 0.40005 0 270)
			(size 0.4572 0.508)
			(layers "F.Cu" "F.Mask" "F.Paste")
			(net "SYS_AUTO_POWER_ON_N")
		)
		(pad "2" smd rect
			(at -0.40005 0 270)
			(size 0.4572 0.508)
			(layers "F.Cu" "F.Mask" "F.Paste")
			(net "GND")
		)
	)
	(footprint ""
		(layer "F.Cu")
		(at 162.549078 -12.4714 90)
		(property "Reference" "R1198"
			(at -0.888238 -2.062988 90)
			(unlocked yes)
			(layer "F.SilkS")
			(effects
				(font
					(size 0.7874 0.5842)
					(thickness 0.1524)
				)
				(justify left)
			)
		)
		(property "Value" ""
			(at 0 0 90)
			(layer "F.Fab")
			(effects
				(font
					(size 1.27 1.27)
				)
			)
		)
		(duplicate_pad_numbers_are_jumpers no)
		(fp_line
			(start 0.7874 -0.4064)
			(end 0.7874 0.4064)
			(stroke
				(width 0.1524)
				(type default)
			)
			(layer "F.SilkS")
		)
		(fp_line
			(start -0.7874 -0.4064)
			(end 0.7874 -0.4064)
			(stroke
				(width 0.1524)
				(type default)
			)
			(layer "F.SilkS")
		)
		(fp_line
			(start 0.7874 0.4064)
			(end -0.7874 0.4064)
			(stroke
				(width 0.1524)
				(type default)
			)
			(layer "F.SilkS")
		)
		(fp_line
			(start -0.7874 0.4064)
			(end -0.7874 -0.4064)
			(stroke
				(width 0.1524)
				(type default)
			)
			(layer "F.SilkS")
		)
		(fp_poly
			(pts
				(xy -0.508 0.2794) (xy -0.508 0.2286) (xy -0.635 0.2286) (xy -0.635 -0.254) (xy -0.5334 -0.254)
				(xy -0.5334 -0.2794) (xy 0.5334 -0.2794) (xy 0.5334 -0.254) (xy 0.635 -0.254) (xy 0.635 0.254) (xy 0.5334 0.254)
				(xy 0.5334 0.2794)
			)
			(stroke
				(width 0)
				(type default)
			)
			(fill no)
			(layer "F.CrtYd")
		)
		(pad "1" smd rect
			(at 0.40005 0 90)
			(size 0.4572 0.508)
			(layers "F.Cu" "F.Mask" "F.Paste")
			(net "SIO_JTAG_CPLD3_TDI")
		)
		(pad "2" smd rect
			(at -0.40005 0 90)
			(size 0.4572 0.508)
			(layers "F.Cu" "F.Mask" "F.Paste")
			(net "JTAG_CPLD3_TDI")
		)
	)
	(footprint ""
		(layer "F.Cu")
		(at 114.79276 -175.426624 90)
		(property "Reference" "R1058"
			(at -57.01538 33.114488 90)
			(unlocked yes)
			(layer "F.SilkS")
			(effects
				(font
					(size 0.7874 0.5842)
					(thickness 0.1524)
				)
				(justify left)
			)
		)
		(property "Value" ""
			(at 0 0 90)
			(layer "F.Fab")
			(effects
				(font
					(size 1.27 1.27)
				)
			)
		)
		(duplicate_pad_numbers_are_jumpers no)
		(fp_line
			(start 0.7874 -0.4064)
			(end 0.7874 0.4064)
			(stroke
				(width 0.1524)
				(type default)
			)
			(layer "F.SilkS")
		)
		(fp_line
			(start -0.7874 -0.4064)
			(end 0.7874 -0.4064)
			(stroke
				(width 0.1524)
				(type default)
			)
			(layer "F.SilkS")
		)
		(fp_line
			(start 0.7874 0.4064)
			(end -0.7874 0.4064)
			(stroke
				(width 0.1524)
				(type default)
			)
			(layer "F.SilkS")
		)
		(fp_line
			(start -0.7874 0.4064)
			(end -0.7874 -0.4064)
			(stroke
				(width 0.1524)
				(type default)
			)
			(layer "F.SilkS")
		)
		(fp_poly
			(pts
				(xy -0.508 0.2794) (xy -0.508 0.2286) (xy -0.635 0.2286) (xy -0.635 -0.254) (xy -0.5334 -0.254)
				(xy -0.5334 -0.2794) (xy 0.5334 -0.2794) (xy 0.5334 -0.254) (xy 0.635 -0.254) (xy 0.635 0.254) (xy 0.5334 0.254)
				(xy 0.5334 0.2794)
			)
			(stroke
				(width 0)
				(type default)
			)
			(fill no)
			(layer "F.CrtYd")
		)
		(pad "1" smd rect
			(at 0.40005 0 90)
			(size 0.4572 0.508)
			(layers "F.Cu" "F.Mask" "F.Paste")
			(net "N31348569")
		)
		(pad "2" smd rect
			(at -0.40005 0 90)
			(size 0.4572 0.508)
			(layers "F.Cu" "F.Mask" "F.Paste")
			(net "GND")
		)
	)
	(footprint ""
		(layer "F.Cu")
		(at 154.170888 -175.356266 90)
		(property "Reference" "R1305"
			(at 0.549148 -1.260348 90)
			(unlocked yes)
			(layer "F.SilkS")
			(effects
				(font
					(size 0.7874 0.5842)
					(thickness 0.1524)
				)
				(justify left)
			)
		)
		(property "Value" ""
			(at 0 0 90)
			(layer "F.Fab")
			(effects
				(font
					(size 1.27 1.27)
				)
			)
		)
		(duplicate_pad_numbers_are_jumpers no)
		(fp_line
			(start 0.7874 -0.4064)
			(end 0.7874 0.4064)
			(stroke
				(width 0.1524)
				(type default)
			)
			(layer "F.SilkS")
		)
		(fp_line
			(start -0.7874 -0.4064)
			(end 0.7874 -0.4064)
			(stroke
				(width 0.1524)
				(type default)
			)
			(layer "F.SilkS")
		)
		(fp_line
			(start 0.7874 0.4064)
			(end -0.7874 0.4064)
			(stroke
				(width 0.1524)
				(type default)
			)
			(layer "F.SilkS")
		)
		(fp_line
			(start -0.7874 0.4064)
			(end -0.7874 -0.4064)
			(stroke
				(width 0.1524)
				(type default)
			)
			(layer "F.SilkS")
		)
		(fp_poly
			(pts
				(xy -0.508 0.2794) (xy -0.508 0.2286) (xy -0.635 0.2286) (xy -0.635 -0.254) (xy -0.5334 -0.254)
				(xy -0.5334 -0.2794) (xy 0.5334 -0.2794) (xy 0.5334 -0.254) (xy 0.635 -0.254) (xy 0.635 0.254) (xy 0.5334 0.254)
				(xy 0.5334 0.2794)
			)
			(stroke
				(width 0)
				(type default)
			)
			(fill no)
			(layer "F.CrtYd")
		)
		(pad "1" smd rect
			(at 0.40005 0 90)
			(size 0.4572 0.508)
			(layers "F.Cu" "F.Mask" "F.Paste")
			(net "P3V3_NODE1")
		)
		(pad "2" smd rect
			(at -0.40005 0 90)
			(size 0.4572 0.508)
			(layers "F.Cu" "F.Mask" "F.Paste")
			(net "N54365554")
		)
	)
	(footprint ""
		(layer "F.Cu")
		(at 47.418244 -106.40695 180)
		(property "Reference" "PC26"
			(at 0.202692 -2.089658 0)
			(unlocked yes)
			(layer "F.SilkS")
			(effects
				(font
					(size 0.7874 0.5842)
					(thickness 0.1524)
				)
				(justify left)
			)
		)
		(property "Value" ""
			(at 0 0 180)
			(layer "F.Fab")
			(effects
				(font
					(size 1.27 1.27)
				)
			)
		)
		(duplicate_pad_numbers_are_jumpers no)
		(fp_line
			(start 0.7874 0.4064)
			(end -0.7874 0.4064)
			(stroke
				(width 0.1524)
				(type default)
			)
			(layer "F.SilkS")
		)
		(fp_line
			(start 0.7874 -0.4064)
			(end 0.7874 0.4064)
			(stroke
				(width 0.1524)
				(type default)
			)
			(layer "F.SilkS")
		)
		(fp_line
			(start 0 0.381)
			(end 0 -0.381)
			(stroke
				(width 0.1524)
				(type default)
			)
			(layer "F.SilkS")
		)
		(fp_line
			(start -0.7874 0.4064)
			(end -0.7874 -0.4064)
			(stroke
				(width 0.1524)
				(type default)
			)
			(layer "F.SilkS")
		)
		(fp_line
			(start -0.7874 -0.4064)
			(end 0.7874 -0.4064)
			(stroke
				(width 0.1524)
				(type default)
			)
			(layer "F.SilkS")
		)
		(fp_poly
			(pts
				(xy -0.5334 0.254) (xy -0.635 0.254) (xy -0.635 0.2286) (xy -0.635 -0.254) (xy -0.5334 -0.254) (xy -0.5334 -0.2794)
				(xy 0.5334 -0.2794) (xy 0.5334 -0.254) (xy 0.635 -0.254) (xy 0.635 0.254) (xy 0.5334 0.254) (xy 0.5334 0.2794)
				(xy -0.508 0.2794) (xy -0.5334 0.2794)
			)
			(stroke
				(width 0)
				(type default)
			)
			(fill no)
			(layer "F.CrtYd")
		)
		(pad "1" smd rect
			(at 0.40005 0 180)
			(size 0.4572 0.508)
			(layers "F.Cu" "F.Mask" "F.Paste")
			(net "PWRGD_NODE1_P5V_STB_PG")
		)
		(pad "2" smd rect
			(at -0.40005 0 180)
			(size 0.4572 0.508)
			(layers "F.Cu" "F.Mask" "F.Paste")
			(net "GND")
		)
	)
	(footprint ""
		(layer "F.Cu")
		(at 86.914228 -133.213094 -90)
		(property "Reference" "D35"
			(at -3.52552 -0.706374 90)
			(unlocked yes)
			(layer "F.SilkS")
			(effects
				(font
					(size 0.7874 0.5842)
					(thickness 0.1524)
				)
				(justify left)
			)
		)
		(property "Value" ""
			(at 0 0 270)
			(layer "F.Fab")
			(effects
				(font
					(size 1.27 1.27)
				)
			)
		)
		(duplicate_pad_numbers_are_jumpers no)
		(fp_line
			(start -1.3208 0.5588)
			(end -1.3208 -0.5588)
			(stroke
				(width 0.1524)
				(type default)
			)
			(layer "F.SilkS")
		)
		(fp_line
			(start 1.3208 0.5588)
			(end -1.3208 0.5588)
			(stroke
				(width 0.1524)
				(type default)
			)
			(layer "F.SilkS")
		)
		(fp_line
			(start 1.6256 0.5588)
			(end 1.6256 -0.5588)
			(stroke
				(width 0.1524)
				(type default)
			)
			(layer "F.SilkS")
		)
		(fp_line
			(start 1.778 0.5588)
			(end 1.3208 0.5588)
			(stroke
				(width 0.1524)
				(type default)
			)
			(layer "F.SilkS")
		)
		(fp_line
			(start -1.3208 -0.5588)
			(end 1.3208 -0.5588)
			(stroke
				(width 0.1524)
				(type default)
			)
			(layer "F.SilkS")
		)
		(fp_line
			(start 1.3208 -0.5588)
			(end 1.3208 0.5588)
			(stroke
				(width 0.1524)
				(type default)
			)
			(layer "F.SilkS")
		)
		(fp_line
			(start 1.4732 -0.5588)
			(end 1.4732 0.5588)
			(stroke
				(width 0.1524)
				(type default)
			)
			(layer "F.SilkS")
		)
		(fp_line
			(start 1.778 -0.5588)
			(end 1.778 0.5588)
			(stroke
				(width 0.1524)
				(type default)
			)
			(layer "F.SilkS")
		)
		(fp_line
			(start 1.778 -0.5588)
			(end 1.3208 -0.5588)
			(stroke
				(width 0.1524)
				(type default)
			)
			(layer "F.SilkS")
		)
		(fp_circle
			(center 2.4384 0)
			(end 2.4384 -0.413512)
			(stroke
				(width 0.1524)
				(type default)
			)
			(fill no)
			(layer "F.SilkS")
		)
		(fp_rect
			(start -1.1684 0.508)
			(end 1.1684 -0.508)
			(stroke
				(width 0)
				(type default)
			)
			(fill no)
			(layer "F.CrtYd")
		)
		(fp_text user "-"
			(at 2.350008 0.57912 270)
			(unlocked yes)
			(layer "F.SilkS")
			(effects
				(font
					(size 0.7874 0.5842)
					(thickness 0.1524)
				)
				(justify left)
			)
		)
		(pad "A" smd rect
			(at -0.750062 0 270)
			(size 0.8128 0.8128)
			(layers "F.Cu" "F.Mask" "F.Paste")
			(net "P3V3_NODE1")
		)
		(pad "C" smd rect
			(at 0.750062 0 270)
			(size 0.8128 0.8128)
			(layers "F.Cu" "F.Mask" "F.Paste")
			(net "N53313513")
		)
	)
	(footprint ""
		(layer "F.Cu")
		(at 74.394822 -17.664176 90)
		(property "Reference" "C177"
			(at -3.058414 6.144514 90)
			(unlocked yes)
			(layer "F.SilkS")
			(effects
				(font
					(size 0.7874 0.5842)
					(thickness 0.1524)
				)
			)
		)
		(property "Value" ""
			(at 0 0 90)
			(layer "F.Fab")
			(effects
				(font
					(size 1.27 1.27)
				)
			)
		)
		(duplicate_pad_numbers_are_jumpers no)
		(fp_line
			(start 1.2954 -0.5842)
			(end 1.2954 0.5842)
			(stroke
				(width 0.1524)
				(type default)
			)
			(layer "F.SilkS")
		)
		(fp_line
			(start 0 -0.5842)
			(end 0 0.5842)
			(stroke
				(width 0.1524)
				(type default)
			)
			(layer "F.SilkS")
		)
		(fp_line
			(start -1.2954 -0.5842)
			(end 1.2954 -0.5842)
			(stroke
				(width 0.1524)
				(type default)
			)
			(layer "F.SilkS")
		)
		(fp_line
			(start 1.2954 0.5842)
			(end -1.2954 0.5842)
			(stroke
				(width 0.1524)
				(type default)
			)
			(layer "F.SilkS")
		)
		(fp_line
			(start -1.2954 0.5842)
			(end -1.2954 -0.5842)
			(stroke
				(width 0.1524)
				(type default)
			)
			(layer "F.SilkS")
		)
		(fp_poly
			(pts
				(xy 0.8636 -0.4572) (xy 0.8636 -0.3556) (xy 1.143 -0.3556) (xy 1.143 0.3556) (xy 0.8636 0.3556)
				(xy 0.8636 0.4572) (xy -0.8636 0.4572) (xy -0.8636 0.3556) (xy -1.143 0.3556) (xy -1.143 -0.3556)
				(xy -0.8636 -0.3556) (xy -0.8636 -0.4572)
			)
			(stroke
				(width 0)
				(type default)
			)
			(fill no)
			(layer "F.CrtYd")
		)
		(fp_line
			(start 0.884936 -0.504952)
			(end 0.884936 0.504952)
			(stroke
				(width 0.1)
				(type default)
			)
			(layer "F.Fab")
		)
		(fp_line
			(start -0.884936 -0.504952)
			(end 0.884936 -0.504952)
			(stroke
				(width 0.1)
				(type default)
			)
			(layer "F.Fab")
		)
		(fp_line
			(start 0.884936 0.504952)
			(end -0.884936 0.504952)
			(stroke
				(width 0.1)
				(type default)
			)
			(layer "F.Fab")
		)
		(fp_line
			(start -0.884936 0.504952)
			(end -0.884936 -0.504952)
			(stroke
				(width 0.1)
				(type default)
			)
			(layer "F.Fab")
		)
		(pad "1" smd rect
			(at 0.7366 0 180)
			(size 0.7112 0.8128)
			(layers "F.Cu" "F.Mask" "F.Paste")
			(net "PV_VDDR_NODE1")
		)
		(pad "2" smd rect
			(at -0.7366 0 180)
			(size 0.7112 0.8128)
			(layers "F.Cu" "F.Mask" "F.Paste")
			(net "GND")
		)
	)
	(footprint ""
		(layer "F.Cu")
		(at 186.131708 -128.029716)
		(property "Reference" "R1286"
			(at 4.114292 19.725386 0)
			(unlocked yes)
			(layer "F.SilkS")
			(effects
				(font
					(size 0.7874 0.5842)
					(thickness 0.1524)
				)
				(justify left)
			)
		)
		(property "Value" ""
			(at 0 0 0)
			(layer "F.Fab")
			(effects
				(font
					(size 1.27 1.27)
				)
			)
		)
		(duplicate_pad_numbers_are_jumpers no)
		(fp_line
			(start -0.7874 -0.4064)
			(end 0.7874 -0.4064)
			(stroke
				(width 0.1524)
				(type default)
			)
			(layer "F.SilkS")
		)
		(fp_line
			(start -0.7874 0.4064)
			(end -0.7874 -0.4064)
			(stroke
				(width 0.1524)
				(type default)
			)
			(layer "F.SilkS")
		)
		(fp_line
			(start 0.7874 -0.4064)
			(end 0.7874 0.4064)
			(stroke
				(width 0.1524)
				(type default)
			)
			(layer "F.SilkS")
		)
		(fp_line
			(start 0.7874 0.4064)
			(end -0.7874 0.4064)
			(stroke
				(width 0.1524)
				(type default)
			)
			(layer "F.SilkS")
		)
		(fp_poly
			(pts
				(xy -0.508 0.2794) (xy -0.508 0.2286) (xy -0.635 0.2286) (xy -0.635 -0.254) (xy -0.5334 -0.254)
				(xy -0.5334 -0.2794) (xy 0.5334 -0.2794) (xy 0.5334 -0.254) (xy 0.635 -0.254) (xy 0.635 0.254) (xy 0.5334 0.254)
				(xy 0.5334 0.2794)
			)
			(stroke
				(width 0)
				(type default)
			)
			(fill no)
			(layer "F.CrtYd")
		)
		(pad "1" smd rect
			(at 0.40005 0)
			(size 0.4572 0.508)
			(layers "F.Cu" "F.Mask" "F.Paste")
			(net "SIO_JTAG_CPLD1_TDO")
		)
		(pad "2" smd rect
			(at -0.40005 0)
			(size 0.4572 0.508)
			(layers "F.Cu" "F.Mask" "F.Paste")
			(net "JTAG_CPLD1_TDO")
		)
	)
	(footprint ""
		(layer "F.Cu")
		(at 35.669728 -82.179922)
		(property "Reference" "R44"
			(at -4.58851 0.037338 0)
			(unlocked yes)
			(layer "F.SilkS")
			(effects
				(font
					(size 0.7874 0.5842)
					(thickness 0.1524)
				)
				(justify left)
			)
		)
		(property "Value" ""
			(at 0 0 0)
			(layer "F.Fab")
			(effects
				(font
					(size 1.27 1.27)
				)
			)
		)
		(duplicate_pad_numbers_are_jumpers no)
		(fp_line
			(start -0.7874 -0.4064)
			(end 0.7874 -0.4064)
			(stroke
				(width 0.1524)
				(type default)
			)
			(layer "F.SilkS")
		)
		(fp_line
			(start -0.7874 0.4064)
			(end -0.7874 -0.4064)
			(stroke
				(width 0.1524)
				(type default)
			)
			(layer "F.SilkS")
		)
		(fp_line
			(start 0.7874 -0.4064)
			(end 0.7874 0.4064)
			(stroke
				(width 0.1524)
				(type default)
			)
			(layer "F.SilkS")
		)
		(fp_line
			(start 0.7874 0.4064)
			(end -0.7874 0.4064)
			(stroke
				(width 0.1524)
				(type default)
			)
			(layer "F.SilkS")
		)
		(fp_poly
			(pts
				(xy -0.508 0.2794) (xy -0.508 0.2286) (xy -0.635 0.2286) (xy -0.635 -0.254) (xy -0.5334 -0.254)
				(xy -0.5334 -0.2794) (xy 0.5334 -0.2794) (xy 0.5334 -0.254) (xy 0.635 -0.254) (xy 0.635 0.254) (xy 0.5334 0.254)
				(xy 0.5334 0.2794)
			)
			(stroke
				(width 0)
				(type default)
			)
			(fill no)
			(layer "F.CrtYd")
		)
		(pad "1" smd rect
			(at 0.40005 0)
			(size 0.4572 0.508)
			(layers "F.Cu" "F.Mask" "F.Paste")
			(net "PD_CPU_NODE1_RP2_PERN")
		)
		(pad "2" smd rect
			(at -0.40005 0)
			(size 0.4572 0.508)
			(layers "F.Cu" "F.Mask" "F.Paste")
			(net "GND")
		)
	)
	(footprint ""
		(layer "F.Cu")
		(at 113.47831 -133.735572)
		(property "Reference" "PC101"
			(at 5.35051 -2.894076 0)
			(unlocked yes)
			(layer "F.SilkS")
			(effects
				(font
					(size 0.635 0.4064)
					(thickness 0.1524)
				)
				(justify left)
			)
		)
		(property "Value" ""
			(at 0 0 0)
			(layer "F.Fab")
			(effects
				(font
					(size 1.27 1.27)
				)
			)
		)
		(duplicate_pad_numbers_are_jumpers no)
		(fp_line
			(start -0.7874 -0.4064)
			(end 0.7874 -0.4064)
			(stroke
				(width 0.1524)
				(type default)
			)
			(layer "F.SilkS")
		)
		(fp_line
			(start -0.7874 0.4064)
			(end -0.7874 -0.4064)
			(stroke
				(width 0.1524)
				(type default)
			)
			(layer "F.SilkS")
		)
		(fp_line
			(start 0 0.381)
			(end 0 -0.381)
			(stroke
				(width 0.1524)
				(type default)
			)
			(layer "F.SilkS")
		)
		(fp_line
			(start 0.7874 -0.4064)
			(end 0.7874 0.4064)
			(stroke
				(width 0.1524)
				(type default)
			)
			(layer "F.SilkS")
		)
		(fp_line
			(start 0.7874 0.4064)
			(end -0.7874 0.4064)
			(stroke
				(width 0.1524)
				(type default)
			)
			(layer "F.SilkS")
		)
		(fp_poly
			(pts
				(xy -0.5334 0.254) (xy -0.635 0.254) (xy -0.635 0.2286) (xy -0.635 -0.254) (xy -0.5334 -0.254) (xy -0.5334 -0.2794)
				(xy 0.5334 -0.2794) (xy 0.5334 -0.254) (xy 0.635 -0.254) (xy 0.635 0.254) (xy 0.5334 0.254) (xy 0.5334 0.2794)
				(xy -0.508 0.2794) (xy -0.5334 0.2794)
			)
			(stroke
				(width 0)
				(type default)
			)
			(fill no)
			(layer "F.CrtYd")
		)
		(pad "1" smd rect
			(at 0.40005 0)
			(size 0.4572 0.508)
			(layers "F.Cu" "F.Mask" "F.Paste")
			(net "AGND_PVCCP_NODE1")
		)
		(pad "2" smd rect
			(at -0.40005 0)
			(size 0.4572 0.508)
			(layers "F.Cu" "F.Mask" "F.Paste")
			(net "ISENSE_PVCCP_NODE1_ISEN1N")
		)
	)
	(footprint ""
		(layer "F.Cu")
		(at 111.87176 -170.593512 180)
		(property "Reference" "R666"
			(at 2.02438 10.473436 0)
			(unlocked yes)
			(layer "F.SilkS")
			(effects
				(font
					(size 0.7874 0.5842)
					(thickness 0.1524)
				)
				(justify left)
			)
		)
		(property "Value" ""
			(at 0 0 180)
			(layer "F.Fab")
			(effects
				(font
					(size 1.27 1.27)
				)
			)
		)
		(duplicate_pad_numbers_are_jumpers no)
		(fp_line
			(start 0.7874 0.4064)
			(end -0.7874 0.4064)
			(stroke
				(width 0.1524)
				(type default)
			)
			(layer "F.SilkS")
		)
		(fp_line
			(start 0.7874 -0.4064)
			(end 0.7874 0.4064)
			(stroke
				(width 0.1524)
				(type default)
			)
			(layer "F.SilkS")
		)
		(fp_line
			(start -0.7874 0.4064)
			(end -0.7874 -0.4064)
			(stroke
				(width 0.1524)
				(type default)
			)
			(layer "F.SilkS")
		)
		(fp_line
			(start -0.7874 -0.4064)
			(end 0.7874 -0.4064)
			(stroke
				(width 0.1524)
				(type default)
			)
			(layer "F.SilkS")
		)
		(fp_poly
			(pts
				(xy -0.508 0.2794) (xy -0.508 0.2286) (xy -0.635 0.2286) (xy -0.635 -0.254) (xy -0.5334 -0.254)
				(xy -0.5334 -0.2794) (xy 0.5334 -0.2794) (xy 0.5334 -0.254) (xy 0.635 -0.254) (xy 0.635 0.254) (xy 0.5334 0.254)
				(xy 0.5334 0.2794)
			)
			(stroke
				(width 0)
				(type default)
			)
			(fill no)
			(layer "F.CrtYd")
		)
		(pad "1" smd rect
			(at 0.40005 0 180)
			(size 0.4572 0.508)
			(layers "F.Cu" "F.Mask" "F.Paste")
			(net "P3V3_NODE1")
		)
		(pad "2" smd rect
			(at -0.40005 0 180)
			(size 0.4572 0.508)
			(layers "F.Cu" "F.Mask" "F.Paste")
			(net "I2C_PSU1_SDA_MOS")
		)
	)
	(footprint ""
		(layer "F.Cu")
		(at 59.586368 -170.604688)
		(property "Reference" "C616"
			(at -9.464294 131.044696 0)
			(unlocked yes)
			(layer "F.SilkS")
			(effects
				(font
					(size 0.7874 0.5842)
					(thickness 0.1524)
				)
				(justify left)
			)
		)
		(property "Value" ""
			(at 0 0 0)
			(layer "F.Fab")
			(effects
				(font
					(size 1.27 1.27)
				)
			)
		)
		(duplicate_pad_numbers_are_jumpers no)
		(fp_line
			(start -0.7874 -0.4064)
			(end 0.7874 -0.4064)
			(stroke
				(width 0.1524)
				(type default)
			)
			(layer "F.SilkS")
		)
		(fp_line
			(start -0.7874 0.4064)
			(end -0.7874 -0.4064)
			(stroke
				(width 0.1524)
				(type default)
			)
			(layer "F.SilkS")
		)
		(fp_line
			(start 0 0.381)
			(end 0 -0.381)
			(stroke
				(width 0.1524)
				(type default)
			)
			(layer "F.SilkS")
		)
		(fp_line
			(start 0.7874 -0.4064)
			(end 0.7874 0.4064)
			(stroke
				(width 0.1524)
				(type default)
			)
			(layer "F.SilkS")
		)
		(fp_line
			(start 0.7874 0.4064)
			(end -0.7874 0.4064)
			(stroke
				(width 0.1524)
				(type default)
			)
			(layer "F.SilkS")
		)
		(fp_poly
			(pts
				(xy -0.5334 0.254) (xy -0.635 0.254) (xy -0.635 0.2286) (xy -0.635 -0.254) (xy -0.5334 -0.254) (xy -0.5334 -0.2794)
				(xy 0.5334 -0.2794) (xy 0.5334 -0.254) (xy 0.635 -0.254) (xy 0.635 0.254) (xy 0.5334 0.254) (xy 0.5334 0.2794)
				(xy -0.508 0.2794) (xy -0.5334 0.2794)
			)
			(stroke
				(width 0)
				(type default)
			)
			(fill no)
			(layer "F.CrtYd")
		)
		(pad "1" smd rect
			(at 0.40005 0)
			(size 0.4572 0.508)
			(layers "F.Cu" "F.Mask" "F.Paste")
			(net "P3V3_NODE1")
		)
		(pad "2" smd rect
			(at -0.40005 0)
			(size 0.4572 0.508)
			(layers "F.Cu" "F.Mask" "F.Paste")
			(net "GND")
		)
	)
	(footprint ""
		(layer "F.Cu")
		(at 90.81262 -167.41902 180)
		(property "Reference" "C581"
			(at -85.97392 -72.653652 0)
			(unlocked yes)
			(layer "F.SilkS")
			(effects
				(font
					(size 0.7874 0.5842)
					(thickness 0.1524)
				)
				(justify left)
			)
		)
		(property "Value" ""
			(at 0 0 180)
			(layer "F.Fab")
			(effects
				(font
					(size 1.27 1.27)
				)
			)
		)
		(duplicate_pad_numbers_are_jumpers no)
		(fp_line
			(start 0.7874 0.4064)
			(end -0.7874 0.4064)
			(stroke
				(width 0.1524)
				(type default)
			)
			(layer "F.SilkS")
		)
		(fp_line
			(start 0.7874 -0.4064)
			(end 0.7874 0.4064)
			(stroke
				(width 0.1524)
				(type default)
			)
			(layer "F.SilkS")
		)
		(fp_line
			(start 0 0.381)
			(end 0 -0.381)
			(stroke
				(width 0.1524)
				(type default)
			)
			(layer "F.SilkS")
		)
		(fp_line
			(start -0.7874 0.4064)
			(end -0.7874 -0.4064)
			(stroke
				(width 0.1524)
				(type default)
			)
			(layer "F.SilkS")
		)
		(fp_line
			(start -0.7874 -0.4064)
			(end 0.7874 -0.4064)
			(stroke
				(width 0.1524)
				(type default)
			)
			(layer "F.SilkS")
		)
		(fp_poly
			(pts
				(xy -0.5334 0.254) (xy -0.635 0.254) (xy -0.635 0.2286) (xy -0.635 -0.254) (xy -0.5334 -0.254) (xy -0.5334 -0.2794)
				(xy 0.5334 -0.2794) (xy 0.5334 -0.254) (xy 0.635 -0.254) (xy 0.635 0.254) (xy 0.5334 0.254) (xy 0.5334 0.2794)
				(xy -0.508 0.2794) (xy -0.5334 0.2794)
			)
			(stroke
				(width 0)
				(type default)
			)
			(fill no)
			(layer "F.CrtYd")
		)
		(pad "1" smd rect
			(at 0.40005 0 180)
			(size 0.4572 0.508)
			(layers "F.Cu" "F.Mask" "F.Paste")
			(net "P3V3_NODE1")
		)
		(pad "2" smd rect
			(at -0.40005 0 180)
			(size 0.4572 0.508)
			(layers "F.Cu" "F.Mask" "F.Paste")
			(net "GND")
		)
	)
	(footprint ""
		(layer "F.Cu")
		(at 105.191814 -106.89082 180)
		(property "Reference" "PC119"
			(at 5.923534 0.317754 0)
			(unlocked yes)
			(layer "F.SilkS")
			(effects
				(font
					(size 0.7874 0.5842)
					(thickness 0.1524)
				)
				(justify left)
			)
		)
		(property "Value" ""
			(at 0 0 180)
			(layer "F.Fab")
			(effects
				(font
					(size 1.27 1.27)
				)
			)
		)
		(duplicate_pad_numbers_are_jumpers no)
		(fp_line
			(start 1.905 0.8636)
			(end -1.905 0.8636)
			(stroke
				(width 0.1524)
				(type default)
			)
			(layer "F.SilkS")
		)
		(fp_line
			(start 1.905 -0.8636)
			(end 1.905 0.8636)
			(stroke
				(width 0.1524)
				(type default)
			)
			(layer "F.SilkS")
		)
		(fp_line
			(start 0 0.8382)
			(end 0 -0.8382)
			(stroke
				(width 0.1524)
				(type default)
			)
			(layer "F.SilkS")
		)
		(fp_line
			(start -1.905 0.8636)
			(end -1.905 -0.8636)
			(stroke
				(width 0.1524)
				(type default)
			)
			(layer "F.SilkS")
		)
		(fp_line
			(start -1.905 -0.8636)
			(end 1.905 -0.8636)
			(stroke
				(width 0.1524)
				(type default)
			)
			(layer "F.SilkS")
		)
		(fp_rect
			(start -1.524 0.7366)
			(end 1.524 -0.7366)
			(stroke
				(width 0)
				(type default)
			)
			(fill no)
			(layer "F.CrtYd")
		)
		(pad "1" smd rect
			(at 0.94996 0 180)
			(size 1.1176 1.3716)
			(layers "F.Cu" "F.Mask" "F.Paste")
			(net "GND")
		)
		(pad "2" smd rect
			(at -0.94996 0 180)
			(size 1.1176 1.3716)
			(layers "F.Cu" "F.Mask" "F.Paste")
			(net "PV_VCCP_NODE1")
		)
	)
	(footprint ""
		(layer "F.Cu")
		(at 51.67376 -188.126624 90)
		(property "Reference" "R848"
			(at 4.548886 0.205232 90)
			(unlocked yes)
			(layer "F.SilkS")
			(effects
				(font
					(size 0.7874 0.5842)
					(thickness 0.1524)
				)
				(justify left)
			)
		)
		(property "Value" ""
			(at 0 0 90)
			(layer "F.Fab")
			(effects
				(font
					(size 1.27 1.27)
				)
			)
		)
		(duplicate_pad_numbers_are_jumpers no)
		(fp_line
			(start 0.7874 -0.4064)
			(end 0.7874 0.4064)
			(stroke
				(width 0.1524)
				(type default)
			)
			(layer "F.SilkS")
		)
		(fp_line
			(start -0.7874 -0.4064)
			(end 0.7874 -0.4064)
			(stroke
				(width 0.1524)
				(type default)
			)
			(layer "F.SilkS")
		)
		(fp_line
			(start 0.7874 0.4064)
			(end -0.7874 0.4064)
			(stroke
				(width 0.1524)
				(type default)
			)
			(layer "F.SilkS")
		)
		(fp_line
			(start -0.7874 0.4064)
			(end -0.7874 -0.4064)
			(stroke
				(width 0.1524)
				(type default)
			)
			(layer "F.SilkS")
		)
		(fp_poly
			(pts
				(xy -0.508 0.2794) (xy -0.508 0.2286) (xy -0.635 0.2286) (xy -0.635 -0.254) (xy -0.5334 -0.254)
				(xy -0.5334 -0.2794) (xy 0.5334 -0.2794) (xy 0.5334 -0.254) (xy 0.635 -0.254) (xy 0.635 0.254) (xy 0.5334 0.254)
				(xy 0.5334 0.2794)
			)
			(stroke
				(width 0)
				(type default)
			)
			(fill no)
			(layer "F.CrtYd")
		)
		(pad "1" smd rect
			(at 0.40005 0 90)
			(size 0.4572 0.508)
			(layers "F.Cu" "F.Mask" "F.Paste")
			(net "PSU2_AC_OK_R")
		)
		(pad "2" smd rect
			(at -0.40005 0 90)
			(size 0.4572 0.508)
			(layers "F.Cu" "F.Mask" "F.Paste")
			(net "GND")
		)
	)
	(footprint ""
		(layer "F.Cu")
		(at 20.47494 -41.548558 90)
		(property "Reference" "U46"
			(at -2.331974 0.548386 0)
			(unlocked yes)
			(layer "F.SilkS")
			(effects
				(font
					(size 0.7874 0.5842)
					(thickness 0.1524)
				)
			)
		)
		(property "Value" ""
			(at 0 0 90)
			(layer "F.Fab")
			(effects
				(font
					(size 1.27 1.27)
				)
			)
		)
		(duplicate_pad_numbers_are_jumpers no)
		(fp_line
			(start 1.651 -1.905)
			(end 1.651 1.905)
			(stroke
				(width 0.1524)
				(type default)
			)
			(layer "F.SilkS")
		)
		(fp_line
			(start -1.651 -1.905)
			(end 1.651 -1.905)
			(stroke
				(width 0.1524)
				(type default)
			)
			(layer "F.SilkS")
		)
		(fp_line
			(start 1.651 1.905)
			(end -1.651 1.905)
			(stroke
				(width 0.1524)
				(type default)
			)
			(layer "F.SilkS")
		)
		(fp_line
			(start -1.651 1.905)
			(end -1.651 -1.905)
			(stroke
				(width 0.1524)
				(type default)
			)
			(layer "F.SilkS")
		)
		(fp_poly
			(pts
				(xy -1.524 0.7112) (xy -1.524 1.7526) (xy -0.508 1.7526) (xy -0.508 0.6985) (xy 0.508 0.6985) (xy 0.508 1.7526)
				(xy 1.524 1.7526) (xy 1.524 0.6985) (xy 1.524 -0.6985) (xy 0.508 -0.6985) (xy 0.508 -1.7526) (xy -0.508 -1.7526)
				(xy -0.508 -0.6985) (xy -1.524 -0.6985) (xy -1.524 0.6985)
			)
			(stroke
				(width 0)
				(type default)
			)
			(fill no)
			(layer "F.CrtYd")
		)
		(fp_text user "3"
			(at -2.892044 -1.7399 0)
			(unlocked yes)
			(layer "F.SilkS")
			(effects
				(font
					(size 0.635 0.4064)
					(thickness 0.1524)
				)
			)
		)
		(fp_text user "2"
			(at 2.230374 0.85344 0)
			(unlocked yes)
			(layer "F.SilkS")
			(effects
				(font
					(size 0.635 0.4064)
					(thickness 0.1524)
				)
			)
		)
		(fp_text user "1"
			(at -2.13106 2.29616 0)
			(unlocked yes)
			(layer "F.SilkS")
			(effects
				(font
					(size 0.635 0.4064)
					(thickness 0.1524)
				)
			)
		)
		(pad "1" smd rect
			(at -1.016 1.1176 90)
			(size 1.016 1.27)
			(layers "F.Cu" "F.Mask" "F.Paste")
			(net "GND")
		)
		(pad "2" smd rect
			(at 1.016 1.1176 90)
			(size 1.016 1.27)
			(layers "F.Cu" "F.Mask" "F.Paste")
			(net "P5V_CRT")
		)
		(pad "3" smd rect
			(at 0 -1.1176 90)
			(size 1.016 1.27)
			(layers "F.Cu" "F.Mask" "F.Paste")
			(net "CRT_R")
		)
	)
	(footprint ""
		(layer "F.Cu")
		(at 188.214 -125.095)
		(property "Reference" "R1287"
			(at 6.35 18.94967 0)
			(unlocked yes)
			(layer "F.SilkS")
			(effects
				(font
					(size 0.7874 0.5842)
					(thickness 0.1524)
				)
				(justify left)
			)
		)
		(property "Value" ""
			(at 0 0 0)
			(layer "F.Fab")
			(effects
				(font
					(size 1.27 1.27)
				)
			)
		)
		(duplicate_pad_numbers_are_jumpers no)
		(fp_line
			(start -0.7874 -0.4064)
			(end 0.7874 -0.4064)
			(stroke
				(width 0.1524)
				(type default)
			)
			(layer "F.SilkS")
		)
		(fp_line
			(start -0.7874 0.4064)
			(end -0.7874 -0.4064)
			(stroke
				(width 0.1524)
				(type default)
			)
			(layer "F.SilkS")
		)
		(fp_line
			(start 0.7874 -0.4064)
			(end 0.7874 0.4064)
			(stroke
				(width 0.1524)
				(type default)
			)
			(layer "F.SilkS")
		)
		(fp_line
			(start 0.7874 0.4064)
			(end -0.7874 0.4064)
			(stroke
				(width 0.1524)
				(type default)
			)
			(layer "F.SilkS")
		)
		(fp_poly
			(pts
				(xy -0.508 0.2794) (xy -0.508 0.2286) (xy -0.635 0.2286) (xy -0.635 -0.254) (xy -0.5334 -0.254)
				(xy -0.5334 -0.2794) (xy 0.5334 -0.2794) (xy 0.5334 -0.254) (xy 0.635 -0.254) (xy 0.635 0.254) (xy 0.5334 0.254)
				(xy 0.5334 0.2794)
			)
			(stroke
				(width 0)
				(type default)
			)
			(fill no)
			(layer "F.CrtYd")
		)
		(pad "1" smd rect
			(at 0.40005 0)
			(size 0.4572 0.508)
			(layers "F.Cu" "F.Mask" "F.Paste")
			(net "SIO_JTAG_CPLD1_TCK")
		)
		(pad "2" smd rect
			(at -0.40005 0)
			(size 0.4572 0.508)
			(layers "F.Cu" "F.Mask" "F.Paste")
			(net "JTAG_CPLD1_TCK")
		)
	)
	(footprint ""
		(layer "F.Cu")
		(at 112.529112 -138.354308 90)
		(property "Reference" "PC122"
			(at 3.235452 3.561334 90)
			(unlocked yes)
			(layer "F.SilkS")
			(effects
				(font
					(size 0.635 0.4064)
					(thickness 0.1524)
				)
				(justify left)
			)
		)
		(property "Value" ""
			(at 0 0 90)
			(layer "F.Fab")
			(effects
				(font
					(size 1.27 1.27)
				)
			)
		)
		(duplicate_pad_numbers_are_jumpers no)
		(fp_line
			(start 0.7874 -0.4064)
			(end 0.7874 0.4064)
			(stroke
				(width 0.1524)
				(type default)
			)
			(layer "F.SilkS")
		)
		(fp_line
			(start -0.7874 -0.4064)
			(end 0.7874 -0.4064)
			(stroke
				(width 0.1524)
				(type default)
			)
			(layer "F.SilkS")
		)
		(fp_line
			(start 0 0.381)
			(end 0 -0.381)
			(stroke
				(width 0.1524)
				(type default)
			)
			(layer "F.SilkS")
		)
		(fp_line
			(start 0.7874 0.4064)
			(end -0.7874 0.4064)
			(stroke
				(width 0.1524)
				(type default)
			)
			(layer "F.SilkS")
		)
		(fp_line
			(start -0.7874 0.4064)
			(end -0.7874 -0.4064)
			(stroke
				(width 0.1524)
				(type default)
			)
			(layer "F.SilkS")
		)
		(fp_poly
			(pts
				(xy -0.5334 0.254) (xy -0.635 0.254) (xy -0.635 0.2286) (xy -0.635 -0.254) (xy -0.5334 -0.254) (xy -0.5334 -0.2794)
				(xy 0.5334 -0.2794) (xy 0.5334 -0.254) (xy 0.635 -0.254) (xy 0.635 0.254) (xy 0.5334 0.254) (xy 0.5334 0.2794)
				(xy -0.508 0.2794) (xy -0.5334 0.2794)
			)
			(stroke
				(width 0)
				(type default)
			)
			(fill no)
			(layer "F.CrtYd")
		)
		(pad "1" smd rect
			(at 0.40005 0 90)
			(size 0.4572 0.508)
			(layers "F.Cu" "F.Mask" "F.Paste")
			(net "VR_PVCCP_NODE1_EN")
		)
		(pad "2" smd rect
			(at -0.40005 0 90)
			(size 0.4572 0.508)
			(layers "F.Cu" "F.Mask" "F.Paste")
			(net "AGND_PVCCP_NODE1")
		)
	)
	(footprint ""
		(layer "F.Cu")
		(at 94.654878 -155.28163 -90)
		(property "Reference" "PL4"
			(at 4.078224 2.123948 0)
			(unlocked yes)
			(layer "F.SilkS")
			(effects
				(font
					(size 0.7874 0.5842)
					(thickness 0.1524)
				)
				(justify left)
			)
		)
		(property "Value" ""
			(at 0 0 270)
			(layer "F.Fab")
			(effects
				(font
					(size 1.27 1.27)
				)
			)
		)
		(duplicate_pad_numbers_are_jumpers no)
		(fp_line
			(start -3.350006 4.1656)
			(end -3.350006 -4.1656)
			(stroke
				(width 0.1524)
				(type default)
			)
			(layer "F.SilkS")
		)
		(fp_line
			(start 3.350006 4.1656)
			(end -3.350006 4.1656)
			(stroke
				(width 0.1524)
				(type default)
			)
			(layer "F.SilkS")
		)
		(fp_line
			(start -3.350006 -4.1656)
			(end 3.350006 -4.1656)
			(stroke
				(width 0.1524)
				(type default)
			)
			(layer "F.SilkS")
		)
		(fp_line
			(start 3.350006 -4.1656)
			(end 3.350006 4.1656)
			(stroke
				(width 0.1524)
				(type default)
			)
			(layer "F.SilkS")
		)
		(fp_poly
			(pts
				(xy -3.350006 -3.64998) (xy -1.7018 -3.64998) (xy -1.7018 -4.05257) (xy 1.7018 -4.05257) (xy 1.7018 -3.64998)
				(xy 3.350006 -3.64998) (xy 3.350006 3.64998) (xy 1.7018 3.64998) (xy 1.7018 4.05257) (xy -1.7018 4.05257)
				(xy -1.7018 3.64998) (xy -3.350006 3.64998)
			)
			(stroke
				(width 0)
				(type default)
			)
			(fill no)
			(layer "F.CrtYd")
		)
		(fp_line
			(start -3.350006 3.64998)
			(end -3.350006 -3.64998)
			(stroke
				(width 0.1)
				(type default)
			)
			(layer "F.Fab")
		)
		(fp_line
			(start 3.350006 3.64998)
			(end -3.350006 3.64998)
			(stroke
				(width 0.1)
				(type default)
			)
			(layer "F.Fab")
		)
		(fp_line
			(start -3.350006 -3.64998)
			(end 3.350006 -3.64998)
			(stroke
				(width 0.1)
				(type default)
			)
			(layer "F.Fab")
		)
		(fp_line
			(start 3.350006 -3.64998)
			(end 3.350006 3.64998)
			(stroke
				(width 0.1)
				(type default)
			)
			(layer "F.Fab")
		)
		(pad "1" smd rect
			(at 0 -2.92481 180)
			(size 2.15392 3.302)
			(layers "F.Cu" "F.Mask" "F.Paste")
			(net "SW_P1V8_STB_NODE1_PH")
		)
		(pad "2" smd rect
			(at 0 2.92481 180)
			(size 2.15392 3.302)
			(layers "F.Cu" "F.Mask" "F.Paste")
			(net "P1V8_STB_NODE1")
		)
	)
	(footprint ""
		(layer "F.Cu")
		(at 169.622724 -57.47258 90)
		(property "Reference" "L44"
			(at -0.940562 -7.028434 90)
			(unlocked yes)
			(layer "F.SilkS")
			(effects
				(font
					(size 0.7874 0.5842)
					(thickness 0.1524)
				)
				(justify left)
			)
		)
		(property "Value" ""
			(at 0 0 90)
			(layer "F.Fab")
			(effects
				(font
					(size 1.27 1.27)
				)
			)
		)
		(duplicate_pad_numbers_are_jumpers no)
		(fp_line
			(start 0.989838 -2.0066)
			(end 0.989838 2.0066)
			(stroke
				(width 0.1524)
				(type default)
			)
			(layer "F.SilkS")
		)
		(fp_line
			(start -1.015238 -2.0066)
			(end 0.989838 -2.0066)
			(stroke
				(width 0.1524)
				(type default)
			)
			(layer "F.SilkS")
		)
		(fp_line
			(start 0.989838 2.0066)
			(end -1.015238 2.0066)
			(stroke
				(width 0.1524)
				(type default)
			)
			(layer "F.SilkS")
		)
		(fp_line
			(start -1.015238 2.0066)
			(end -1.015238 -2.0066)
			(stroke
				(width 0.1524)
				(type default)
			)
			(layer "F.SilkS")
		)
		(fp_poly
			(pts
				(xy -0.899922 -1.700022) (xy -0.899922 1.700022) (xy -0.8636 1.700022) (xy -0.8636 1.9304) (xy -0.127 1.9304)
				(xy -0.127 1.700022) (xy 0.127 1.700022) (xy 0.127 1.9304) (xy 0.8636 1.9304) (xy 0.8636 1.700022)
				(xy 0.899922 1.700022) (xy 0.899922 -1.700022) (xy 0.8636 -1.700022) (xy 0.8636 -1.9304) (xy 0.127 -1.9304)
				(xy 0.127 -1.700022) (xy -0.127 -1.700022) (xy -0.127 -1.9304) (xy -0.8636 -1.9304) (xy -0.8636 -1.700022)
			)
			(stroke
				(width 0)
				(type default)
			)
			(fill no)
			(layer "F.CrtYd")
		)
		(fp_line
			(start 0.899922 -1.700022)
			(end 0.899922 1.700022)
			(stroke
				(width 0.1)
				(type default)
			)
			(layer "F.Fab")
		)
		(fp_line
			(start -0.899922 -1.700022)
			(end 0.899922 -1.700022)
			(stroke
				(width 0.1)
				(type default)
			)
			(layer "F.Fab")
		)
		(fp_line
			(start 0.899922 1.700022)
			(end -0.899922 1.700022)
			(stroke
				(width 0.1)
				(type default)
			)
			(layer "F.Fab")
		)
		(fp_line
			(start -0.899922 1.700022)
			(end -0.899922 -1.700022)
			(stroke
				(width 0.1)
				(type default)
			)
			(layer "F.Fab")
		)
		(pad "1" smd rect
			(at -0.499872 -1.400048 90)
			(size 0.6096 0.9144)
			(layers "F.Cu" "F.Mask" "F.Paste")
			(net "USB2_DN")
		)
		(pad "2" smd rect
			(at -0.499872 1.400048 90)
			(size 0.6096 0.9144)
			(layers "F.Cu" "F.Mask" "F.Paste")
			(net "USB2_L_DN")
		)
		(pad "3" smd rect
			(at 0.499872 1.400048 90)
			(size 0.6096 0.9144)
			(layers "F.Cu" "F.Mask" "F.Paste")
			(net "USB2_L_DP")
		)
		(pad "4" smd rect
			(at 0.499872 -1.400048 90)
			(size 0.6096 0.9144)
			(layers "F.Cu" "F.Mask" "F.Paste")
			(net "USB2_DP")
		)
	)
	(footprint ""
		(layer "F.Cu")
		(at 103.725726 -118.600982 90)
		(property "Reference" "PR56"
			(at 0.012192 -3.62077 0)
			(unlocked yes)
			(layer "F.SilkS")
			(effects
				(font
					(size 0.7874 0.5842)
					(thickness 0.1524)
				)
				(justify left)
			)
		)
		(property "Value" ""
			(at 0 0 90)
			(layer "F.Fab")
			(effects
				(font
					(size 1.27 1.27)
				)
			)
		)
		(duplicate_pad_numbers_are_jumpers no)
		(fp_line
			(start 0.4572 -0.44069)
			(end 0.4572 1.54051)
			(stroke
				(width 0.1524)
				(type default)
			)
			(layer "F.SilkS")
		)
		(fp_line
			(start -0.4572 -0.44069)
			(end 0.4572 -0.44069)
			(stroke
				(width 0.1524)
				(type default)
			)
			(layer "F.SilkS")
		)
		(fp_line
			(start -0.4572 1.51511)
			(end -0.4572 -0.44069)
			(stroke
				(width 0.1524)
				(type default)
			)
			(layer "F.SilkS")
		)
		(fp_line
			(start 0.4572 1.54051)
			(end -0.4572 1.54051)
			(stroke
				(width 0.1524)
				(type default)
			)
			(layer "F.SilkS")
		)
		(fp_line
			(start -0.4572 1.54051)
			(end -0.4572 1.51511)
			(stroke
				(width 0.1524)
				(type default)
			)
			(layer "F.SilkS")
		)
		(fp_poly
			(pts
				(xy 0.3556 0.37211) (xy 0.3556 -0.36449) (xy -0.3556 -0.36449) (xy -0.3556 1.46431) (xy 0.3556 1.46431)
				(xy 0.3556 0.72771)
			)
			(stroke
				(width 0)
				(type default)
			)
			(fill no)
			(layer "F.CrtYd")
		)
		(fp_line
			(start 0.299974 -0.025146)
			(end 0.299974 1.124966)
			(stroke
				(width 0.1)
				(type default)
			)
			(layer "F.Fab")
		)
		(fp_line
			(start -0.299974 -0.025146)
			(end 0.299974 -0.025146)
			(stroke
				(width 0.1)
				(type default)
			)
			(layer "F.Fab")
		)
		(fp_line
			(start 0.299974 1.124966)
			(end -0.299974 1.124966)
			(stroke
				(width 0.1)
				(type default)
			)
			(layer "F.Fab")
		)
		(fp_line
			(start -0.299974 1.124966)
			(end -0.299974 -0.025146)
			(stroke
				(width 0.1)
				(type default)
			)
			(layer "F.Fab")
		)
		(pad "1" smd rect
			(at 0 0 180)
			(size 0.6096 0.6096)
			(layers "F.Cu" "F.Mask" "F.Paste")
			(net "VR_PVCCP_NODE1_ISEN1P_RR")
		)
		(pad "2" smd rect
			(at 0 1.09982 180)
			(size 0.6096 0.6096)
			(layers "F.Cu" "F.Mask" "F.Paste")
			(net "ISENSE_PVCCP_NODE1_ISEN1N")
		)
	)
	(footprint ""
		(layer "F.Cu")
		(at 135.01878 -181.55158 -90)
		(property "Reference" "R1160"
			(at 1.183386 1.493266 90)
			(unlocked yes)
			(layer "F.SilkS")
			(effects
				(font
					(size 0.7874 0.5842)
					(thickness 0.1524)
				)
				(justify left)
			)
		)
		(property "Value" ""
			(at 0 0 270)
			(layer "F.Fab")
			(effects
				(font
					(size 1.27 1.27)
				)
			)
		)
		(duplicate_pad_numbers_are_jumpers no)
		(fp_line
			(start -0.7874 0.4064)
			(end -0.7874 -0.4064)
			(stroke
				(width 0.1524)
				(type default)
			)
			(layer "F.SilkS")
		)
		(fp_line
			(start 0.7874 0.4064)
			(end -0.7874 0.4064)
			(stroke
				(width 0.1524)
				(type default)
			)
			(layer "F.SilkS")
		)
		(fp_line
			(start -0.7874 -0.4064)
			(end 0.7874 -0.4064)
			(stroke
				(width 0.1524)
				(type default)
			)
			(layer "F.SilkS")
		)
		(fp_line
			(start 0.7874 -0.4064)
			(end 0.7874 0.4064)
			(stroke
				(width 0.1524)
				(type default)
			)
			(layer "F.SilkS")
		)
		(fp_poly
			(pts
				(xy -0.508 0.2794) (xy -0.508 0.2286) (xy -0.635 0.2286) (xy -0.635 -0.254) (xy -0.5334 -0.254)
				(xy -0.5334 -0.2794) (xy 0.5334 -0.2794) (xy 0.5334 -0.254) (xy 0.635 -0.254) (xy 0.635 0.254) (xy 0.5334 0.254)
				(xy 0.5334 0.2794)
			)
			(stroke
				(width 0)
				(type default)
			)
			(fill no)
			(layer "F.CrtYd")
		)
		(pad "1" smd rect
			(at 0.40005 0 270)
			(size 0.4572 0.508)
			(layers "F.Cu" "F.Mask" "F.Paste")
			(net "UART_TX_P3")
		)
		(pad "2" smd rect
			(at -0.40005 0 270)
			(size 0.4572 0.508)
			(layers "F.Cu" "F.Mask" "F.Paste")
			(net "GND")
		)
	)
	(footprint ""
		(layer "F.Cu")
		(at 144.764252 -148.21535)
		(property "Reference" "R307"
			(at -0.294386 17.484344 0)
			(unlocked yes)
			(layer "F.SilkS")
			(effects
				(font
					(size 0.7874 0.5842)
					(thickness 0.1524)
				)
				(justify left)
			)
		)
		(property "Value" ""
			(at 0 0 0)
			(layer "F.Fab")
			(effects
				(font
					(size 1.27 1.27)
				)
			)
		)
		(duplicate_pad_numbers_are_jumpers no)
		(fp_line
			(start -0.7874 -0.4064)
			(end 0.7874 -0.4064)
			(stroke
				(width 0.1524)
				(type default)
			)
			(layer "F.SilkS")
		)
		(fp_line
			(start -0.7874 0.4064)
			(end -0.7874 -0.4064)
			(stroke
				(width 0.1524)
				(type default)
			)
			(layer "F.SilkS")
		)
		(fp_line
			(start 0.7874 -0.4064)
			(end 0.7874 0.4064)
			(stroke
				(width 0.1524)
				(type default)
			)
			(layer "F.SilkS")
		)
		(fp_line
			(start 0.7874 0.4064)
			(end -0.7874 0.4064)
			(stroke
				(width 0.1524)
				(type default)
			)
			(layer "F.SilkS")
		)
		(fp_poly
			(pts
				(xy -0.508 0.2794) (xy -0.508 0.2286) (xy -0.635 0.2286) (xy -0.635 -0.254) (xy -0.5334 -0.254)
				(xy -0.5334 -0.2794) (xy 0.5334 -0.2794) (xy 0.5334 -0.254) (xy 0.635 -0.254) (xy 0.635 0.254) (xy 0.5334 0.254)
				(xy 0.5334 0.2794)
			)
			(stroke
				(width 0)
				(type default)
			)
			(fill no)
			(layer "F.CrtYd")
		)
		(pad "1" smd rect
			(at 0.40005 0)
			(size 0.4572 0.508)
			(layers "F.Cu" "F.Mask" "F.Paste")
			(net "GND")
		)
		(pad "2" smd rect
			(at -0.40005 0)
			(size 0.4572 0.508)
			(layers "F.Cu" "F.Mask" "F.Paste")
			(net "PCIE_SW_GPIO7")
		)
	)
	(footprint ""
		(layer "F.Cu")
		(at 48.24476 -182.246524 90)
		(property "Reference" "C611"
			(at -133.313932 -3.637788 90)
			(unlocked yes)
			(layer "F.SilkS")
			(effects
				(font
					(size 0.7874 0.5842)
					(thickness 0.1524)
				)
				(justify left)
			)
		)
		(property "Value" ""
			(at 0 0 90)
			(layer "F.Fab")
			(effects
				(font
					(size 1.27 1.27)
				)
			)
		)
		(duplicate_pad_numbers_are_jumpers no)
		(fp_line
			(start 0.7874 -0.4064)
			(end 0.7874 0.4064)
			(stroke
				(width 0.1524)
				(type default)
			)
			(layer "F.SilkS")
		)
		(fp_line
			(start -0.7874 -0.4064)
			(end 0.7874 -0.4064)
			(stroke
				(width 0.1524)
				(type default)
			)
			(layer "F.SilkS")
		)
		(fp_line
			(start 0 0.381)
			(end 0 -0.381)
			(stroke
				(width 0.1524)
				(type default)
			)
			(layer "F.SilkS")
		)
		(fp_line
			(start 0.7874 0.4064)
			(end -0.7874 0.4064)
			(stroke
				(width 0.1524)
				(type default)
			)
			(layer "F.SilkS")
		)
		(fp_line
			(start -0.7874 0.4064)
			(end -0.7874 -0.4064)
			(stroke
				(width 0.1524)
				(type default)
			)
			(layer "F.SilkS")
		)
		(fp_poly
			(pts
				(xy -0.5334 0.254) (xy -0.635 0.254) (xy -0.635 0.2286) (xy -0.635 -0.254) (xy -0.5334 -0.254) (xy -0.5334 -0.2794)
				(xy 0.5334 -0.2794) (xy 0.5334 -0.254) (xy 0.635 -0.254) (xy 0.635 0.254) (xy 0.5334 0.254) (xy 0.5334 0.2794)
				(xy -0.508 0.2794) (xy -0.5334 0.2794)
			)
			(stroke
				(width 0)
				(type default)
			)
			(fill no)
			(layer "F.CrtYd")
		)
		(pad "1" smd rect
			(at 0.40005 0 90)
			(size 0.4572 0.508)
			(layers "F.Cu" "F.Mask" "F.Paste")
			(net "PSU5_AC_OK")
		)
		(pad "2" smd rect
			(at -0.40005 0 90)
			(size 0.4572 0.508)
			(layers "F.Cu" "F.Mask" "F.Paste")
			(net "GND")
		)
	)
	(footprint ""
		(layer "F.Cu")
		(at 102.006654 -133.119114 180)
		(property "Reference" "PR44"
			(at 4.38404 8.411972 0)
			(unlocked yes)
			(layer "F.SilkS")
			(effects
				(font
					(size 0.7874 0.5842)
					(thickness 0.1524)
				)
				(justify left)
			)
		)
		(property "Value" ""
			(at 0 0 180)
			(layer "F.Fab")
			(effects
				(font
					(size 1.27 1.27)
				)
			)
		)
		(duplicate_pad_numbers_are_jumpers no)
		(fp_line
			(start 0.7874 0.4064)
			(end -0.7874 0.4064)
			(stroke
				(width 0.1524)
				(type default)
			)
			(layer "F.SilkS")
		)
		(fp_line
			(start 0.7874 -0.4064)
			(end 0.7874 0.4064)
			(stroke
				(width 0.1524)
				(type default)
			)
			(layer "F.SilkS")
		)
		(fp_line
			(start -0.7874 0.4064)
			(end -0.7874 -0.4064)
			(stroke
				(width 0.1524)
				(type default)
			)
			(layer "F.SilkS")
		)
		(fp_line
			(start -0.7874 -0.4064)
			(end 0.7874 -0.4064)
			(stroke
				(width 0.1524)
				(type default)
			)
			(layer "F.SilkS")
		)
		(fp_poly
			(pts
				(xy -0.508 0.2794) (xy -0.508 0.2286) (xy -0.635 0.2286) (xy -0.635 -0.254) (xy -0.5334 -0.254)
				(xy -0.5334 -0.2794) (xy 0.5334 -0.2794) (xy 0.5334 -0.254) (xy 0.635 -0.254) (xy 0.635 0.254) (xy 0.5334 0.254)
				(xy 0.5334 0.2794)
			)
			(stroke
				(width 0)
				(type default)
			)
			(fill no)
			(layer "F.CrtYd")
		)
		(pad "1" smd rect
			(at 0.40005 0 180)
			(size 0.4572 0.508)
			(layers "F.Cu" "F.Mask" "F.Paste")
			(net "SVID_CPU_NODE1_PVCCP_CLK")
		)
		(pad "2" smd rect
			(at -0.40005 0 180)
			(size 0.4572 0.508)
			(layers "F.Cu" "F.Mask" "F.Paste")
			(net "SVID_CPU_NODE1_CLK_R")
		)
	)
	(footprint ""
		(layer "F.Cu")
		(at 164.12337 -136.064498 180)
		(property "Reference" "S1"
			(at -0.46101 3.601466 0)
			(unlocked yes)
			(layer "F.SilkS")
			(effects
				(font
					(size 0.7874 0.5842)
					(thickness 0.1524)
				)
				(justify left)
			)
		)
		(property "Value" ""
			(at 0 0 180)
			(layer "F.Fab")
			(effects
				(font
					(size 1.27 1.27)
				)
			)
		)
		(duplicate_pad_numbers_are_jumpers no)
		(fp_line
			(start 3.0988 3.0988)
			(end 3.0988 2.667)
			(stroke
				(width 0.1524)
				(type default)
			)
			(layer "F.SilkS")
		)
		(fp_line
			(start 3.0988 1.3208)
			(end 3.0988 -1.3208)
			(stroke
				(width 0.1524)
				(type default)
			)
			(layer "F.SilkS")
		)
		(fp_line
			(start 3.0988 -3.0988)
			(end 3.0988 -2.667)
			(stroke
				(width 0.1524)
				(type default)
			)
			(layer "F.SilkS")
		)
		(fp_line
			(start -3.0988 3.0988)
			(end 3.0988 3.0988)
			(stroke
				(width 0.1524)
				(type default)
			)
			(layer "F.SilkS")
		)
		(fp_line
			(start -3.0988 2.6416)
			(end -3.0988 3.0988)
			(stroke
				(width 0.1524)
				(type default)
			)
			(layer "F.SilkS")
		)
		(fp_line
			(start -3.0988 -1.3462)
			(end -3.0988 1.3208)
			(stroke
				(width 0.1524)
				(type default)
			)
			(layer "F.SilkS")
		)
		(fp_line
			(start -3.0988 -2.667)
			(end -3.0988 -3.0988)
			(stroke
				(width 0.1524)
				(type default)
			)
			(layer "F.SilkS")
		)
		(fp_line
			(start -3.0988 -3.0988)
			(end 3.0988 -3.0988)
			(stroke
				(width 0.1524)
				(type default)
			)
			(layer "F.SilkS")
		)
		(fp_poly
			(pts
				(xy -3.987038 -2.765044) (xy -6.019038 -2.180844) (xy -6.019038 -3.476244)
			)
			(stroke
				(width 0)
				(type default)
			)
			(fill yes)
			(layer "F.SilkS")
		)
		(fp_poly
			(pts
				(xy -3.0988 3.0988) (xy -3.0988 2.5146) (xy -5.0038 2.5146) (xy -5.0038 1.4732) (xy -3.0988 1.4732)
				(xy -3.0988 -1.4986) (xy -5.0038 -1.4986) (xy -5.0038 -2.5146) (xy -3.0988 -2.5146) (xy -3.0988 -3.0988)
				(xy 3.0988 -3.0988) (xy 3.0988 -2.5146) (xy 5.0038 -2.5146) (xy 5.0038 -1.4732) (xy 3.0988 -1.4732)
				(xy 3.0988 1.4732) (xy 5.0038 1.4732) (xy 5.0038 2.5146) (xy 3.0988 2.5146) (xy 3.0988 3.0988)
			)
			(stroke
				(width 0)
				(type default)
			)
			(fill no)
			(layer "F.CrtYd")
		)
		(fp_text user "2"
			(at 5.571236 -2.078228 0)
			(unlocked yes)
			(layer "F.SilkS")
			(effects
				(font
					(size 0.635 0.4064)
					(thickness 0.1524)
				)
				(justify left)
			)
		)
		(fp_text user "4"
			(at 5.023866 0.972566 0)
			(unlocked yes)
			(layer "F.SilkS")
			(effects
				(font
					(size 0.635 0.4064)
					(thickness 0.1524)
				)
				(justify left)
			)
		)
		(fp_text user "3"
			(at -5.189474 2.14122 0)
			(unlocked yes)
			(layer "F.SilkS")
			(effects
				(font
					(size 0.635 0.4064)
					(thickness 0.1524)
				)
				(justify left)
			)
		)
		(fp_text user "1"
			(at -5.226304 -1.949196 0)
			(unlocked yes)
			(layer "F.SilkS")
			(effects
				(font
					(size 0.635 0.4064)
					(thickness 0.1524)
				)
				(justify left)
			)
		)
		(pad "1" smd rect
			(at -3.400044 -1.999996 270)
			(size 1.016 3.2004)
			(layers "F.Cu" "F.Mask" "F.Paste")
			(net "PWR_BTN_NODE1_L")
		)
		(pad "2" smd rect
			(at 3.400044 -1.999996 270)
			(size 1.016 3.2004)
			(layers "F.Cu" "F.Mask" "F.Paste")
			(net "PWR_BTN_NODE1_L")
		)
		(pad "3" smd rect
			(at -3.400044 1.999996 270)
			(size 1.016 3.2004)
			(layers "F.Cu" "F.Mask" "F.Paste")
			(net "GND")
		)
		(pad "4" smd rect
			(at 3.400044 1.999996 270)
			(size 1.016 3.2004)
			(layers "F.Cu" "F.Mask" "F.Paste")
			(net "GND")
		)
	)
	(footprint ""
		(layer "F.Cu")
		(at 102.060248 -137.192258)
		(property "Reference" "PR54"
			(at -4.437634 -8.420608 0)
			(unlocked yes)
			(layer "F.SilkS")
			(effects
				(font
					(size 0.7874 0.5842)
					(thickness 0.1524)
				)
				(justify left)
			)
		)
		(property "Value" ""
			(at 0 0 0)
			(layer "F.Fab")
			(effects
				(font
					(size 1.27 1.27)
				)
			)
		)
		(duplicate_pad_numbers_are_jumpers no)
		(fp_line
			(start -0.7874 -0.4064)
			(end 0.7874 -0.4064)
			(stroke
				(width 0.1524)
				(type default)
			)
			(layer "F.SilkS")
		)
		(fp_line
			(start -0.7874 0.4064)
			(end -0.7874 -0.4064)
			(stroke
				(width 0.1524)
				(type default)
			)
			(layer "F.SilkS")
		)
		(fp_line
			(start 0.7874 -0.4064)
			(end 0.7874 0.4064)
			(stroke
				(width 0.1524)
				(type default)
			)
			(layer "F.SilkS")
		)
		(fp_line
			(start 0.7874 0.4064)
			(end -0.7874 0.4064)
			(stroke
				(width 0.1524)
				(type default)
			)
			(layer "F.SilkS")
		)
		(fp_poly
			(pts
				(xy -0.508 0.2794) (xy -0.508 0.2286) (xy -0.635 0.2286) (xy -0.635 -0.254) (xy -0.5334 -0.254)
				(xy -0.5334 -0.2794) (xy 0.5334 -0.2794) (xy 0.5334 -0.254) (xy 0.635 -0.254) (xy 0.635 0.254) (xy 0.5334 0.254)
				(xy 0.5334 0.2794)
			)
			(stroke
				(width 0)
				(type default)
			)
			(fill no)
			(layer "F.CrtYd")
		)
		(pad "1" smd rect
			(at 0.40005 0)
			(size 0.4572 0.508)
			(layers "F.Cu" "F.Mask" "F.Paste")
			(net "H_CPU_NODE1_VR_HOT_L")
		)
		(pad "2" smd rect
			(at -0.40005 0)
			(size 0.4572 0.508)
			(layers "F.Cu" "F.Mask" "F.Paste")
			(net "P3V3_NODE1")
		)
	)
	(footprint ""
		(layer "F.Cu")
		(at 56.721756 -14.910054 -90)
		(property "Reference" "PC83"
			(at 0.031242 5.737606 90)
			(unlocked yes)
			(layer "F.SilkS")
			(effects
				(font
					(size 0.7874 0.5842)
					(thickness 0.1524)
				)
				(justify left)
			)
		)
		(property "Value" ""
			(at 0 0 270)
			(layer "F.Fab")
			(effects
				(font
					(size 1.27 1.27)
				)
			)
		)
		(duplicate_pad_numbers_are_jumpers no)
		(fp_line
			(start -1.905 0.8636)
			(end -1.905 -0.8636)
			(stroke
				(width 0.1524)
				(type default)
			)
			(layer "F.SilkS")
		)
		(fp_line
			(start 1.905 0.8636)
			(end -1.905 0.8636)
			(stroke
				(width 0.1524)
				(type default)
			)
			(layer "F.SilkS")
		)
		(fp_line
			(start 0 0.8382)
			(end 0 -0.8382)
			(stroke
				(width 0.1524)
				(type default)
			)
			(layer "F.SilkS")
		)
		(fp_line
			(start -1.905 -0.8636)
			(end 1.905 -0.8636)
			(stroke
				(width 0.1524)
				(type default)
			)
			(layer "F.SilkS")
		)
		(fp_line
			(start 1.905 -0.8636)
			(end 1.905 0.8636)
			(stroke
				(width 0.1524)
				(type default)
			)
			(layer "F.SilkS")
		)
		(fp_rect
			(start -1.524 0.7366)
			(end 1.524 -0.7366)
			(stroke
				(width 0)
				(type default)
			)
			(fill no)
			(layer "F.CrtYd")
		)
		(pad "1" smd rect
			(at 0.94996 0 270)
			(size 1.1176 1.3716)
			(layers "F.Cu" "F.Mask" "F.Paste")
			(net "PV_VDDR_NODE1")
		)
		(pad "2" smd rect
			(at -0.94996 0 270)
			(size 1.1176 1.3716)
			(layers "F.Cu" "F.Mask" "F.Paste")
			(net "GND")
		)
	)
	(footprint ""
		(layer "F.Cu")
		(at 49.38776 -188.126624 90)
		(property "Reference" "R850"
			(at 4.548886 0.205232 90)
			(unlocked yes)
			(layer "F.SilkS")
			(effects
				(font
					(size 0.7874 0.5842)
					(thickness 0.1524)
				)
				(justify left)
			)
		)
		(property "Value" ""
			(at 0 0 90)
			(layer "F.Fab")
			(effects
				(font
					(size 1.27 1.27)
				)
			)
		)
		(duplicate_pad_numbers_are_jumpers no)
		(fp_line
			(start 0.7874 -0.4064)
			(end 0.7874 0.4064)
			(stroke
				(width 0.1524)
				(type default)
			)
			(layer "F.SilkS")
		)
		(fp_line
			(start -0.7874 -0.4064)
			(end 0.7874 -0.4064)
			(stroke
				(width 0.1524)
				(type default)
			)
			(layer "F.SilkS")
		)
		(fp_line
			(start 0.7874 0.4064)
			(end -0.7874 0.4064)
			(stroke
				(width 0.1524)
				(type default)
			)
			(layer "F.SilkS")
		)
		(fp_line
			(start -0.7874 0.4064)
			(end -0.7874 -0.4064)
			(stroke
				(width 0.1524)
				(type default)
			)
			(layer "F.SilkS")
		)
		(fp_poly
			(pts
				(xy -0.508 0.2794) (xy -0.508 0.2286) (xy -0.635 0.2286) (xy -0.635 -0.254) (xy -0.5334 -0.254)
				(xy -0.5334 -0.2794) (xy 0.5334 -0.2794) (xy 0.5334 -0.254) (xy 0.635 -0.254) (xy 0.635 0.254) (xy 0.5334 0.254)
				(xy 0.5334 0.2794)
			)
			(stroke
				(width 0)
				(type default)
			)
			(fill no)
			(layer "F.CrtYd")
		)
		(pad "1" smd rect
			(at 0.40005 0 90)
			(size 0.4572 0.508)
			(layers "F.Cu" "F.Mask" "F.Paste")
			(net "PSU4_AC_OK_R")
		)
		(pad "2" smd rect
			(at -0.40005 0 90)
			(size 0.4572 0.508)
			(layers "F.Cu" "F.Mask" "F.Paste")
			(net "GND")
		)
	)
	(footprint ""
		(layer "F.Cu")
		(at 33.33623 -102.214934 -90)
		(property "Reference" "U120"
			(at -3.62839 4.09194 0)
			(unlocked yes)
			(layer "F.SilkS")
			(effects
				(font
					(size 0.7874 0.5842)
					(thickness 0.1524)
				)
				(justify left)
			)
		)
		(property "Value" ""
			(at 0 0 270)
			(layer "F.Fab")
			(effects
				(font
					(size 1.27 1.27)
				)
			)
		)
		(duplicate_pad_numbers_are_jumpers no)
		(fp_line
			(start -2.525014 3.075178)
			(end -2.320798 3.075178)
			(stroke
				(width 0.1524)
				(type default)
			)
			(layer "F.SilkS")
		)
		(fp_line
			(start -2.525014 3.075178)
			(end -2.525014 0.025146)
			(stroke
				(width 0.1524)
				(type default)
			)
			(layer "F.SilkS")
		)
		(fp_line
			(start 0.320802 3.075178)
			(end 0.525018 3.075178)
			(stroke
				(width 0.1524)
				(type default)
			)
			(layer "F.SilkS")
		)
		(fp_line
			(start 0.525018 3.075178)
			(end 0.525018 2.489962)
			(stroke
				(width 0.1524)
				(type default)
			)
			(layer "F.SilkS")
		)
		(fp_line
			(start 0.525018 3.075178)
			(end 0.525018 0.025146)
			(stroke
				(width 0.1524)
				(type default)
			)
			(layer "F.SilkS")
		)
		(fp_line
			(start -2.525014 2.540762)
			(end -2.525014 3.075178)
			(stroke
				(width 0.1524)
				(type default)
			)
			(layer "F.SilkS")
		)
		(fp_line
			(start 0.525018 0.686562)
			(end 0.525018 0.025146)
			(stroke
				(width 0.1524)
				(type default)
			)
			(layer "F.SilkS")
		)
		(fp_line
			(start -2.525014 0.025146)
			(end -2.525014 0.661162)
			(stroke
				(width 0.1524)
				(type default)
			)
			(layer "F.SilkS")
		)
		(fp_line
			(start -2.320798 0.025146)
			(end -2.525014 0.025146)
			(stroke
				(width 0.1524)
				(type default)
			)
			(layer "F.SilkS")
		)
		(fp_line
			(start 0.525018 0.025146)
			(end 0.320802 0.025146)
			(stroke
				(width 0.1524)
				(type default)
			)
			(layer "F.SilkS")
		)
		(fp_poly
			(pts
				(xy 0.55245 -0.45593) (xy 1.452626 -0.155956) (xy 1.452626 -0.755904)
			)
			(stroke
				(width 0)
				(type default)
			)
			(fill yes)
			(layer "F.SilkS")
		)
		(fp_poly
			(pts
				(xy 0.525018 0.025146) (xy 0.244602 0.025146) (xy 0.244602 -0.532638) (xy -2.244598 -0.532638) (xy -2.244598 0.025146)
				(xy -2.525014 0.025146) (xy -2.525014 3.075178) (xy -2.244598 3.075178) (xy -2.244598 3.632962)
				(xy 0.244602 3.632962) (xy 0.244602 3.075178) (xy 0.525018 3.075178)
			)
			(stroke
				(width 0)
				(type default)
			)
			(fill no)
			(layer "F.CrtYd")
		)
		(fp_line
			(start -2.525014 3.075178)
			(end -2.525014 0.025146)
			(stroke
				(width 0.1)
				(type default)
			)
			(layer "F.Fab")
		)
		(fp_line
			(start 0.525018 3.075178)
			(end -2.525014 3.075178)
			(stroke
				(width 0.1)
				(type default)
			)
			(layer "F.Fab")
		)
		(fp_line
			(start -2.525014 0.025146)
			(end 0.525018 0.025146)
			(stroke
				(width 0.1)
				(type default)
			)
			(layer "F.Fab")
		)
		(fp_line
			(start 0.525018 0.025146)
			(end 0.525018 3.075178)
			(stroke
				(width 0.1)
				(type default)
			)
			(layer "F.Fab")
		)
		(fp_poly
			(pts
				(xy 0 -0.519938) (xy 0.302514 -1.427734) (xy -0.302514 -1.427734)
			)
			(stroke
				(width 0)
				(type default)
			)
			(fill yes)
			(layer "F.Fab")
		)
		(fp_text user "10"
			(at 1.107948 3.746246 0)
			(unlocked yes)
			(layer "F.SilkS")
			(effects
				(font
					(size 0.635 0.4064)
					(thickness 0.1524)
				)
				(justify left)
			)
		)
		(fp_text user "6"
			(at -2.678684 3.617468 0)
			(unlocked yes)
			(layer "F.SilkS")
			(effects
				(font
					(size 0.635 0.4064)
					(thickness 0.1524)
				)
				(justify left)
			)
		)
		(fp_text user "1"
			(at 1.2192 0.331724 0)
			(unlocked yes)
			(layer "F.SilkS")
			(effects
				(font
					(size 0.635 0.4064)
					(thickness 0.1524)
				)
				(justify left)
			)
		)
		(fp_text user "5"
			(at -2.660142 -0.187452 0)
			(unlocked yes)
			(layer "F.SilkS")
			(effects
				(font
					(size 0.635 0.4064)
					(thickness 0.1524)
				)
				(justify left)
			)
		)
		(fp_text user "6"
			(at -2.155698 3.725672 90)
			(unlocked yes)
			(layer "F.Fab")
			(effects
				(font
					(size 0.7874 0.5842)
					(thickness 0.000001)
				)
				(justify left)
			)
		)
		(fp_text user "10"
			(at 1.565402 3.700272 90)
			(unlocked yes)
			(layer "F.Fab")
			(effects
				(font
					(size 0.7874 0.5842)
					(thickness 0.000001)
				)
				(justify left)
			)
		)
		(fp_text user "5"
			(at -2.155698 -0.695706 90)
			(unlocked yes)
			(layer "F.Fab")
			(effects
				(font
					(size 0.7874 0.5842)
					(thickness 0.000001)
				)
				(justify left)
			)
		)
		(fp_text user "1"
			(at 0.790702 -0.695706 90)
			(unlocked yes)
			(layer "F.Fab")
			(effects
				(font
					(size 0.7874 0.5842)
					(thickness 0.000001)
				)
				(justify left)
			)
		)
		(pad "1" smd rect
			(at 0 0 90)
			(size 0.2794 0.9144)
			(layers "F.Cu" "F.Mask" "F.Paste")
			(net "P1V5_SUS_NODE1")
		)
		(pad "2" smd rect
			(at -0.499872 0 90)
			(size 0.2794 0.9144)
			(layers "F.Cu" "F.Mask" "F.Paste")
			(net "P1V5_SUS_NODE1")
		)
		(pad "3" smd rect
			(at -0.999998 0 90)
			(size 0.2794 0.9144)
			(layers "F.Cu" "F.Mask" "F.Paste")
			(net "P1V5_SUS_NODE1")
		)
		(pad "4" smd rect
			(at -1.500124 0 90)
			(size 0.2794 0.9144)
			(layers "F.Cu" "F.Mask" "F.Paste")
			(net "P1V5_SUS_NODE1_ADJ")
		)
		(pad "5" smd rect
			(at -1.999996 0 270)
			(size 0.2794 0.9144)
			(layers "F.Cu" "F.Mask" "F.Paste")
			(net "PWRGD_NODE1_P1V5_SUS_PG")
		)
		(pad "6" smd rect
			(at -1.999996 3.100324 270)
			(size 0.2794 0.9144)
			(layers "F.Cu" "F.Mask" "F.Paste")
			(net "FM_CPLD_NODE1_P1V5_SUS_EN")
		)
		(pad "7" smd rect
			(at -1.500124 3.100324 90)
			(size 0.2794 0.9144)
			(layers "F.Cu" "F.Mask" "F.Paste")
			(net "P1V8_STB_NODE1")
		)
		(pad "8" smd rect
			(at -0.999998 3.100324 90)
			(size 0.2794 0.9144)
			(layers "F.Cu" "F.Mask" "F.Paste")
			(net "P1V8_STB_NODE1")
		)
		(pad "9" smd rect
			(at -0.499872 3.100324 90)
			(size 0.2794 0.9144)
			(layers "F.Cu" "F.Mask" "F.Paste")
			(net "P1V8_STB_NODE1")
		)
		(pad "10" smd rect
			(at 0 3.100324 90)
			(size 0.2794 0.9144)
			(layers "F.Cu" "F.Mask" "F.Paste")
			(net "P5V_STB_NODE1")
		)
		(pad "TH" smd rect
			(at -0.999998 1.550162 180)
			(size 1.7526 2.667)
			(layers "F.Cu" "F.Mask" "F.Paste")
			(net "GND")
		)
		(zone
			(layer "F.Cu")
			(hatch none 0.5)
			(connect_pads
				(clearance 0)
			)
			(min_thickness 0.25)
			(keepout
				(tracks allowed)
				(vias not_allowed)
				(pads allowed)
				(copperpour not_allowed)
				(footprints allowed)
			)
			(placement
				(enabled no)
				(sheetname "")
			)
			(fill
				(thermal_gap 0.5)
				(thermal_bridge_width 0.5)
				(island_removal_mode 0)
			)
			(polygon
				(pts
					(xy 32.80283 -101.681534) (xy 32.80283 -104.729534) (xy 30.77083 -104.729534) (xy 30.77083 -101.681534)
					(xy 32.70123 -101.681534) (xy 32.70123 -101.808534) (xy 30.84703 -101.808534) (xy 30.84703 -104.627934)
					(xy 32.72663 -104.627934) (xy 32.72663 -101.681534)
				)
			)
		)
	)
	(footprint ""
		(layer "F.Cu")
		(at 138.66876 -108.370624 90)
		(property "Reference" "R22"
			(at -6.585204 0.466852 90)
			(unlocked yes)
			(layer "F.SilkS")
			(effects
				(font
					(size 0.7874 0.5842)
					(thickness 0.1524)
				)
				(justify left)
			)
		)
		(property "Value" ""
			(at 0 0 90)
			(layer "F.Fab")
			(effects
				(font
					(size 1.27 1.27)
				)
			)
		)
		(duplicate_pad_numbers_are_jumpers no)
		(fp_line
			(start 0.7874 -0.4064)
			(end 0.7874 0.4064)
			(stroke
				(width 0.1524)
				(type default)
			)
			(layer "F.SilkS")
		)
		(fp_line
			(start -0.7874 -0.4064)
			(end 0.7874 -0.4064)
			(stroke
				(width 0.1524)
				(type default)
			)
			(layer "F.SilkS")
		)
		(fp_line
			(start 0.7874 0.4064)
			(end -0.7874 0.4064)
			(stroke
				(width 0.1524)
				(type default)
			)
			(layer "F.SilkS")
		)
		(fp_line
			(start -0.7874 0.4064)
			(end -0.7874 -0.4064)
			(stroke
				(width 0.1524)
				(type default)
			)
			(layer "F.SilkS")
		)
		(fp_poly
			(pts
				(xy -0.508 0.2794) (xy -0.508 0.2286) (xy -0.635 0.2286) (xy -0.635 -0.254) (xy -0.5334 -0.254)
				(xy -0.5334 -0.2794) (xy 0.5334 -0.2794) (xy 0.5334 -0.254) (xy 0.635 -0.254) (xy 0.635 0.254) (xy 0.5334 0.254)
				(xy 0.5334 0.2794)
			)
			(stroke
				(width 0)
				(type default)
			)
			(fill no)
			(layer "F.CrtYd")
		)
		(pad "1" smd rect
			(at 0.40005 0 90)
			(size 0.4572 0.508)
			(layers "F.Cu" "F.Mask" "F.Paste")
			(net "CLK_14M_CPU_NODE1_R")
		)
		(pad "2" smd rect
			(at -0.40005 0 90)
			(size 0.4572 0.508)
			(layers "F.Cu" "F.Mask" "F.Paste")
			(net "P3V3_CLK_NODE1")
		)
	)
	(footprint ""
		(layer "F.Cu")
		(at 111.74476 -185.205624 -90)
		(property "Reference" "R884"
			(at -4.768088 -0.724408 90)
			(unlocked yes)
			(layer "F.SilkS")
			(effects
				(font
					(size 0.7874 0.5842)
					(thickness 0.1524)
				)
				(justify left)
			)
		)
		(property "Value" ""
			(at 0 0 270)
			(layer "F.Fab")
			(effects
				(font
					(size 1.27 1.27)
				)
			)
		)
		(duplicate_pad_numbers_are_jumpers no)
		(fp_line
			(start -0.7874 0.4064)
			(end -0.7874 -0.4064)
			(stroke
				(width 0.1524)
				(type default)
			)
			(layer "F.SilkS")
		)
		(fp_line
			(start 0.7874 0.4064)
			(end -0.7874 0.4064)
			(stroke
				(width 0.1524)
				(type default)
			)
			(layer "F.SilkS")
		)
		(fp_line
			(start -0.7874 -0.4064)
			(end 0.7874 -0.4064)
			(stroke
				(width 0.1524)
				(type default)
			)
			(layer "F.SilkS")
		)
		(fp_line
			(start 0.7874 -0.4064)
			(end 0.7874 0.4064)
			(stroke
				(width 0.1524)
				(type default)
			)
			(layer "F.SilkS")
		)
		(fp_poly
			(pts
				(xy -0.508 0.2794) (xy -0.508 0.2286) (xy -0.635 0.2286) (xy -0.635 -0.254) (xy -0.5334 -0.254)
				(xy -0.5334 -0.2794) (xy 0.5334 -0.2794) (xy 0.5334 -0.254) (xy 0.635 -0.254) (xy 0.635 0.254) (xy 0.5334 0.254)
				(xy 0.5334 0.2794)
			)
			(stroke
				(width 0)
				(type default)
			)
			(fill no)
			(layer "F.CrtYd")
		)
		(pad "1" smd rect
			(at 0.40005 0 270)
			(size 0.4572 0.508)
			(layers "F.Cu" "F.Mask" "F.Paste")
			(net "T6_NODE1_EN")
		)
		(pad "2" smd rect
			(at -0.40005 0 270)
			(size 0.4572 0.508)
			(layers "F.Cu" "F.Mask" "F.Paste")
			(net "T6_NODE1_EN_R")
		)
	)
	(footprint ""
		(layer "F.Cu")
		(at 52.81676 -182.246524 90)
		(property "Reference" "C600"
			(at -133.313932 -3.637788 90)
			(unlocked yes)
			(layer "F.SilkS")
			(effects
				(font
					(size 0.7874 0.5842)
					(thickness 0.1524)
				)
				(justify left)
			)
		)
		(property "Value" ""
			(at 0 0 90)
			(layer "F.Fab")
			(effects
				(font
					(size 1.27 1.27)
				)
			)
		)
		(duplicate_pad_numbers_are_jumpers no)
		(fp_line
			(start 0.7874 -0.4064)
			(end 0.7874 0.4064)
			(stroke
				(width 0.1524)
				(type default)
			)
			(layer "F.SilkS")
		)
		(fp_line
			(start -0.7874 -0.4064)
			(end 0.7874 -0.4064)
			(stroke
				(width 0.1524)
				(type default)
			)
			(layer "F.SilkS")
		)
		(fp_line
			(start 0 0.381)
			(end 0 -0.381)
			(stroke
				(width 0.1524)
				(type default)
			)
			(layer "F.SilkS")
		)
		(fp_line
			(start 0.7874 0.4064)
			(end -0.7874 0.4064)
			(stroke
				(width 0.1524)
				(type default)
			)
			(layer "F.SilkS")
		)
		(fp_line
			(start -0.7874 0.4064)
			(end -0.7874 -0.4064)
			(stroke
				(width 0.1524)
				(type default)
			)
			(layer "F.SilkS")
		)
		(fp_poly
			(pts
				(xy -0.5334 0.254) (xy -0.635 0.254) (xy -0.635 0.2286) (xy -0.635 -0.254) (xy -0.5334 -0.254) (xy -0.5334 -0.2794)
				(xy 0.5334 -0.2794) (xy 0.5334 -0.254) (xy 0.635 -0.254) (xy 0.635 0.254) (xy 0.5334 0.254) (xy 0.5334 0.2794)
				(xy -0.508 0.2794) (xy -0.5334 0.2794)
			)
			(stroke
				(width 0)
				(type default)
			)
			(fill no)
			(layer "F.CrtYd")
		)
		(pad "1" smd rect
			(at 0.40005 0 90)
			(size 0.4572 0.508)
			(layers "F.Cu" "F.Mask" "F.Paste")
			(net "PSU1_AC_OK")
		)
		(pad "2" smd rect
			(at -0.40005 0 90)
			(size 0.4572 0.508)
			(layers "F.Cu" "F.Mask" "F.Paste")
			(net "GND")
		)
	)
	(footprint ""
		(layer "F.Cu")
		(at 152.67051 -149.073362 180)
		(property "Reference" "R588"
			(at 1.33858 3.613912 0)
			(unlocked yes)
			(layer "F.SilkS")
			(effects
				(font
					(size 0.635 0.4064)
					(thickness 0.1524)
				)
				(justify left)
			)
		)
		(property "Value" ""
			(at 0 0 180)
			(layer "F.Fab")
			(effects
				(font
					(size 1.27 1.27)
				)
			)
		)
		(duplicate_pad_numbers_are_jumpers no)
		(fp_line
			(start 0.7874 0.4064)
			(end -0.7874 0.4064)
			(stroke
				(width 0.1524)
				(type default)
			)
			(layer "F.SilkS")
		)
		(fp_line
			(start 0.7874 -0.4064)
			(end 0.7874 0.4064)
			(stroke
				(width 0.1524)
				(type default)
			)
			(layer "F.SilkS")
		)
		(fp_line
			(start -0.7874 0.4064)
			(end -0.7874 -0.4064)
			(stroke
				(width 0.1524)
				(type default)
			)
			(layer "F.SilkS")
		)
		(fp_line
			(start -0.7874 -0.4064)
			(end 0.7874 -0.4064)
			(stroke
				(width 0.1524)
				(type default)
			)
			(layer "F.SilkS")
		)
		(fp_poly
			(pts
				(xy -0.508 0.2794) (xy -0.508 0.2286) (xy -0.635 0.2286) (xy -0.635 -0.254) (xy -0.5334 -0.254)
				(xy -0.5334 -0.2794) (xy 0.5334 -0.2794) (xy 0.5334 -0.254) (xy 0.635 -0.254) (xy 0.635 0.254) (xy 0.5334 0.254)
				(xy 0.5334 0.2794)
			)
			(stroke
				(width 0)
				(type default)
			)
			(fill no)
			(layer "F.CrtYd")
		)
		(pad "1" smd rect
			(at 0.40005 0 180)
			(size 0.4572 0.508)
			(layers "F.Cu" "F.Mask" "F.Paste")
			(net "GND")
		)
		(pad "2" smd rect
			(at -0.40005 0 180)
			(size 0.4572 0.508)
			(layers "F.Cu" "F.Mask" "F.Paste")
			(net "LAN2_TEST_EN")
		)
	)
	(footprint ""
		(layer "F.Cu")
		(at 119.690134 -49.875186 90)
		(property "Reference" "R181"
			(at 1.087628 -0.643128 90)
			(unlocked yes)
			(layer "F.SilkS")
			(effects
				(font
					(size 0.7874 0.5842)
					(thickness 0.1524)
				)
				(justify left)
			)
		)
		(property "Value" ""
			(at 0 0 90)
			(layer "F.Fab")
			(effects
				(font
					(size 1.27 1.27)
				)
			)
		)
		(duplicate_pad_numbers_are_jumpers no)
		(fp_line
			(start 0.7874 -0.4064)
			(end 0.7874 0.4064)
			(stroke
				(width 0.1524)
				(type default)
			)
			(layer "F.SilkS")
		)
		(fp_line
			(start -0.7874 -0.4064)
			(end 0.7874 -0.4064)
			(stroke
				(width 0.1524)
				(type default)
			)
			(layer "F.SilkS")
		)
		(fp_line
			(start 0.7874 0.4064)
			(end -0.7874 0.4064)
			(stroke
				(width 0.1524)
				(type default)
			)
			(layer "F.SilkS")
		)
		(fp_line
			(start -0.7874 0.4064)
			(end -0.7874 -0.4064)
			(stroke
				(width 0.1524)
				(type default)
			)
			(layer "F.SilkS")
		)
		(fp_poly
			(pts
				(xy -0.508 0.2794) (xy -0.508 0.2286) (xy -0.635 0.2286) (xy -0.635 -0.254) (xy -0.5334 -0.254)
				(xy -0.5334 -0.2794) (xy 0.5334 -0.2794) (xy 0.5334 -0.254) (xy 0.635 -0.254) (xy 0.635 0.254) (xy 0.5334 0.254)
				(xy 0.5334 0.2794)
			)
			(stroke
				(width 0)
				(type default)
			)
			(fill no)
			(layer "F.CrtYd")
		)
		(pad "1" smd rect
			(at 0.40005 0 90)
			(size 0.4572 0.508)
			(layers "F.Cu" "F.Mask" "F.Paste")
			(net "LPC_CPU_NODE1_FRAME_L")
		)
		(pad "2" smd rect
			(at -0.40005 0 90)
			(size 0.4572 0.508)
			(layers "F.Cu" "F.Mask" "F.Paste")
			(net "LPC_CPU_NODE1_FRAME_SIO_L")
		)
	)
	(footprint ""
		(layer "F.Cu")
		(at 116.914676 -47.55007 180)
		(property "Reference" "L20"
			(at -0.03556 1.307084 0)
			(unlocked yes)
			(layer "F.SilkS")
			(effects
				(font
					(size 0.7874 0.5842)
					(thickness 0.1524)
				)
			)
		)
		(property "Value" ""
			(at 0 0 180)
			(layer "F.Fab")
			(effects
				(font
					(size 1.27 1.27)
				)
			)
		)
		(duplicate_pad_numbers_are_jumpers no)
		(fp_line
			(start 1.2954 0.635)
			(end -1.2954 0.635)
			(stroke
				(width 0.1524)
				(type default)
			)
			(layer "F.SilkS")
		)
		(fp_line
			(start 1.2954 -0.635)
			(end 1.2954 0.635)
			(stroke
				(width 0.1524)
				(type default)
			)
			(layer "F.SilkS")
		)
		(fp_line
			(start 0.127 -0.5842)
			(end 0.127 0.5842)
			(stroke
				(width 0.1524)
				(type default)
			)
			(layer "F.SilkS")
		)
		(fp_line
			(start -0.127 -0.5842)
			(end -0.127 0.5842)
			(stroke
				(width 0.1524)
				(type default)
			)
			(layer "F.SilkS")
		)
		(fp_line
			(start -1.2954 -0.635)
			(end 1.2954 -0.635)
			(stroke
				(width 0.1524)
				(type default)
			)
			(layer "F.SilkS")
		)
		(fp_line
			(start -1.2954 -0.635)
			(end -1.2954 0.635)
			(stroke
				(width 0.1524)
				(type default)
			)
			(layer "F.SilkS")
		)
		(fp_poly
			(pts
				(xy -0.9144 0.508) (xy -0.9144 0.3556) (xy -1.143 0.3556) (xy -1.143 -0.3556) (xy -0.9144 -0.3556)
				(xy -0.9144 -0.508) (xy 0.9144 -0.508) (xy 0.9144 -0.3556) (xy 1.143 -0.3556) (xy 1.143 0.3556)
				(xy 0.9144 0.3556) (xy 0.9144 0.508)
			)
			(stroke
				(width 0)
				(type default)
			)
			(fill no)
			(layer "F.CrtYd")
		)
		(pad "1" smd rect
			(at 0.7366 0 270)
			(size 0.7112 0.8128)
			(layers "F.Cu" "F.Mask" "F.Paste")
			(net "P3V3_NODE1")
		)
		(pad "2" smd rect
			(at -0.7366 0 270)
			(size 0.7112 0.8128)
			(layers "F.Cu" "F.Mask" "F.Paste")
			(net "N46114787")
		)
	)
	(footprint ""
		(layer "F.Cu")
		(at 105.737152 -129.483358 90)
		(property "Reference" "PR48"
			(at -3.211322 -7.332472 90)
			(unlocked yes)
			(layer "F.SilkS")
			(effects
				(font
					(size 0.7874 0.5842)
					(thickness 0.1524)
				)
			)
		)
		(property "Value" ""
			(at 0 0 90)
			(layer "F.Fab")
			(effects
				(font
					(size 1.27 1.27)
				)
			)
		)
		(duplicate_pad_numbers_are_jumpers no)
		(fp_line
			(start 1.2954 -0.5842)
			(end 1.2954 0.5842)
			(stroke
				(width 0.1524)
				(type default)
			)
			(layer "F.SilkS")
		)
		(fp_line
			(start -1.2954 -0.5842)
			(end 1.2954 -0.5842)
			(stroke
				(width 0.1524)
				(type default)
			)
			(layer "F.SilkS")
		)
		(fp_line
			(start 1.2954 0.5842)
			(end -1.2954 0.5842)
			(stroke
				(width 0.1524)
				(type default)
			)
			(layer "F.SilkS")
		)
		(fp_line
			(start -1.2954 0.5842)
			(end -1.2954 -0.5842)
			(stroke
				(width 0.1524)
				(type default)
			)
			(layer "F.SilkS")
		)
		(fp_poly
			(pts
				(xy 1.143 -0.3556) (xy 1.143 0.3556) (xy 0.8636 0.3556) (xy 0.8636 0.4572) (xy -0.8636 0.4572) (xy -0.8636 0.4318)
				(xy -0.8636 0.3556) (xy -1.143 0.3556) (xy -1.143 -0.3556) (xy -0.8636 -0.3556) (xy -0.8636 -0.4572)
				(xy 0.8636 -0.4572) (xy 0.8636 -0.3556)
			)
			(stroke
				(width 0)
				(type default)
			)
			(fill no)
			(layer "F.CrtYd")
		)
		(pad "1" smd rect
			(at 0.7366 0 180)
			(size 0.7112 0.8128)
			(layers "F.Cu" "F.Mask" "F.Paste")
			(net "VR_PVCCP_NODE1_PVCC")
		)
		(pad "2" smd rect
			(at -0.7366 0 180)
			(size 0.7112 0.8128)
			(layers "F.Cu" "F.Mask" "F.Paste")
			(net "P5V_STB_NODE1")
		)
	)
	(footprint ""
		(layer "F.Cu")
		(at 114.697002 -25.82672 -90)
		(property "Reference" "J24"
			(at 0.06858 4.35864 0)
			(unlocked yes)
			(layer "F.SilkS")
			(effects
				(font
					(size 0.7874 0.5842)
					(thickness 0.1524)
				)
				(justify left)
			)
		)
		(property "Value" ""
			(at 0 0 270)
			(layer "F.Fab")
			(effects
				(font
					(size 1.27 1.27)
				)
			)
		)
		(duplicate_pad_numbers_are_jumpers no)
		(fp_poly
			(pts
				(xy -0.360426 0.359156) (xy -0.360426 -0.381) (xy 0.3556 -0.381) (xy 0.3556 1.905) (xy -0.360426 1.905)
			)
			(stroke
				(width 0)
				(type default)
			)
			(fill no)
			(layer "F.CrtYd")
		)
		(pad "1" smd custom
			(at 0 0 270)
			(size 0.1778 0.1778)
			(layers "F.Cu" "F.Mask" "F.Paste")
			(net "PV_VTT_DDR_NODE1")
			(options
				(clearance outline)
				(anchor circle)
			)
			(primitives
				(gr_poly
					(pts
						(xy -0.127 0.9398) (xy -0.127 -0.127) (xy -0.3556 -0.127) (xy -0.3556 -0.9398) (xy 0.3556 -0.9398)
						(xy 0.3556 -0.127) (xy 0.127 -0.127) (xy 0.127 0.9398)
					)
					(width 0)
					(fill yes)
				)
			)
		)
		(pad "2" smd rect
			(at 0 1.4986 90)
			(size 0.7112 0.8128)
			(layers "F.Cu" "F.Mask" "F.Paste")
			(net "PV_VTT_DDR_NODE1_VOSNS")
		)
		(zone
			(layer "F.Cu")
			(hatch none 0.5)
			(connect_pads
				(clearance 0)
			)
			(min_thickness 0.25)
			(keepout
				(tracks allowed)
				(vias not_allowed)
				(pads allowed)
				(copperpour not_allowed)
				(footprints allowed)
			)
			(placement
				(enabled no)
				(sheetname "")
			)
			(fill
				(thermal_gap 0.5)
				(thermal_bridge_width 0.5)
				(island_removal_mode 0)
			)
			(polygon
				(pts
					(xy 112.741202 -25.42032) (xy 115.128802 -25.42032) (xy 115.128802 -26.237946) (xy 112.741202 -26.237946)
				)
			)
		)
	)
	(footprint ""
		(layer "F.Cu")
		(at 123.70816 -171.603416)
		(property "Reference" "R682"
			(at 30.127448 47.916338 0)
			(unlocked yes)
			(layer "F.SilkS")
			(effects
				(font
					(size 0.7874 0.5842)
					(thickness 0.1524)
				)
				(justify left)
			)
		)
		(property "Value" ""
			(at 0 0 0)
			(layer "F.Fab")
			(effects
				(font
					(size 1.27 1.27)
				)
			)
		)
		(duplicate_pad_numbers_are_jumpers no)
		(fp_line
			(start -0.7874 -0.4064)
			(end 0.7874 -0.4064)
			(stroke
				(width 0.1524)
				(type default)
			)
			(layer "F.SilkS")
		)
		(fp_line
			(start -0.7874 0.4064)
			(end -0.7874 -0.4064)
			(stroke
				(width 0.1524)
				(type default)
			)
			(layer "F.SilkS")
		)
		(fp_line
			(start 0.7874 -0.4064)
			(end 0.7874 0.4064)
			(stroke
				(width 0.1524)
				(type default)
			)
			(layer "F.SilkS")
		)
		(fp_line
			(start 0.7874 0.4064)
			(end -0.7874 0.4064)
			(stroke
				(width 0.1524)
				(type default)
			)
			(layer "F.SilkS")
		)
		(fp_poly
			(pts
				(xy -0.508 0.2794) (xy -0.508 0.2286) (xy -0.635 0.2286) (xy -0.635 -0.254) (xy -0.5334 -0.254)
				(xy -0.5334 -0.2794) (xy 0.5334 -0.2794) (xy 0.5334 -0.254) (xy 0.635 -0.254) (xy 0.635 0.254) (xy 0.5334 0.254)
				(xy 0.5334 0.2794)
			)
			(stroke
				(width 0)
				(type default)
			)
			(fill no)
			(layer "F.CrtYd")
		)
		(pad "1" smd rect
			(at 0.40005 0)
			(size 0.4572 0.508)
			(layers "F.Cu" "F.Mask" "F.Paste")
			(net "GND")
		)
		(pad "2" smd rect
			(at -0.40005 0)
			(size 0.4572 0.508)
			(layers "F.Cu" "F.Mask" "F.Paste")
			(net "N21699069")
		)
	)
	(footprint ""
		(layer "F.Cu")
		(at 36.707572 -73.402698)
		(property "Reference" "R45"
			(at -3.279394 0.319278 0)
			(unlocked yes)
			(layer "F.SilkS")
			(effects
				(font
					(size 0.7874 0.5842)
					(thickness 0.1524)
				)
				(justify left)
			)
		)
		(property "Value" ""
			(at 0 0 0)
			(layer "F.Fab")
			(effects
				(font
					(size 1.27 1.27)
				)
			)
		)
		(duplicate_pad_numbers_are_jumpers no)
		(fp_line
			(start -0.7874 -0.4064)
			(end 0.7874 -0.4064)
			(stroke
				(width 0.1524)
				(type default)
			)
			(layer "F.SilkS")
		)
		(fp_line
			(start -0.7874 0.4064)
			(end -0.7874 -0.4064)
			(stroke
				(width 0.1524)
				(type default)
			)
			(layer "F.SilkS")
		)
		(fp_line
			(start 0.7874 -0.4064)
			(end 0.7874 0.4064)
			(stroke
				(width 0.1524)
				(type default)
			)
			(layer "F.SilkS")
		)
		(fp_line
			(start 0.7874 0.4064)
			(end -0.7874 0.4064)
			(stroke
				(width 0.1524)
				(type default)
			)
			(layer "F.SilkS")
		)
		(fp_poly
			(pts
				(xy -0.508 0.2794) (xy -0.508 0.2286) (xy -0.635 0.2286) (xy -0.635 -0.254) (xy -0.5334 -0.254)
				(xy -0.5334 -0.2794) (xy 0.5334 -0.2794) (xy 0.5334 -0.254) (xy 0.635 -0.254) (xy 0.635 0.254) (xy 0.5334 0.254)
				(xy 0.5334 0.2794)
			)
			(stroke
				(width 0)
				(type default)
			)
			(fill no)
			(layer "F.CrtYd")
		)
		(pad "1" smd rect
			(at 0.40005 0)
			(size 0.4572 0.508)
			(layers "F.Cu" "F.Mask" "F.Paste")
			(net "PD_CPU_NODE1_RP1_PERP")
		)
		(pad "2" smd rect
			(at -0.40005 0)
			(size 0.4572 0.508)
			(layers "F.Cu" "F.Mask" "F.Paste")
			(net "GND")
		)
	)
	(footprint ""
		(layer "F.Cu")
		(at 115.863878 -18.992596)
		(property "Reference" "R1126"
			(at 5.284978 2.044954 90)
			(unlocked yes)
			(layer "F.SilkS")
			(effects
				(font
					(size 0.7874 0.5842)
					(thickness 0.1524)
				)
				(justify left)
			)
		)
		(property "Value" ""
			(at 0 0 0)
			(layer "F.Fab")
			(effects
				(font
					(size 1.27 1.27)
				)
			)
		)
		(duplicate_pad_numbers_are_jumpers no)
		(fp_line
			(start -0.7874 -0.4064)
			(end 0.7874 -0.4064)
			(stroke
				(width 0.1524)
				(type default)
			)
			(layer "F.SilkS")
		)
		(fp_line
			(start -0.7874 0.4064)
			(end -0.7874 -0.4064)
			(stroke
				(width 0.1524)
				(type default)
			)
			(layer "F.SilkS")
		)
		(fp_line
			(start 0.7874 -0.4064)
			(end 0.7874 0.4064)
			(stroke
				(width 0.1524)
				(type default)
			)
			(layer "F.SilkS")
		)
		(fp_line
			(start 0.7874 0.4064)
			(end -0.7874 0.4064)
			(stroke
				(width 0.1524)
				(type default)
			)
			(layer "F.SilkS")
		)
		(fp_poly
			(pts
				(xy -0.508 0.2794) (xy -0.508 0.2286) (xy -0.635 0.2286) (xy -0.635 -0.254) (xy -0.5334 -0.254)
				(xy -0.5334 -0.2794) (xy 0.5334 -0.2794) (xy 0.5334 -0.254) (xy 0.635 -0.254) (xy 0.635 0.254) (xy 0.5334 0.254)
				(xy 0.5334 0.2794)
			)
			(stroke
				(width 0)
				(type default)
			)
			(fill no)
			(layer "F.CrtYd")
		)
		(pad "1" smd rect
			(at 0.40005 0)
			(size 0.4572 0.508)
			(layers "F.Cu" "F.Mask" "F.Paste")
			(net "P3V3_STB_NODE1")
		)
		(pad "2" smd rect
			(at -0.40005 0)
			(size 0.4572 0.508)
			(layers "F.Cu" "F.Mask" "F.Paste")
			(net "PWRGD_NODE1_PVTT_DDR_PG")
		)
	)
	(footprint ""
		(layer "F.Cu")
		(at 75.766422 -17.664176 90)
		(property "Reference" "C173"
			(at -3.058414 5.94106 90)
			(unlocked yes)
			(layer "F.SilkS")
			(effects
				(font
					(size 0.7874 0.5842)
					(thickness 0.1524)
				)
			)
		)
		(property "Value" ""
			(at 0 0 90)
			(layer "F.Fab")
			(effects
				(font
					(size 1.27 1.27)
				)
			)
		)
		(duplicate_pad_numbers_are_jumpers no)
		(fp_line
			(start 1.2954 -0.5842)
			(end 1.2954 0.5842)
			(stroke
				(width 0.1524)
				(type default)
			)
			(layer "F.SilkS")
		)
		(fp_line
			(start 0 -0.5842)
			(end 0 0.5842)
			(stroke
				(width 0.1524)
				(type default)
			)
			(layer "F.SilkS")
		)
		(fp_line
			(start -1.2954 -0.5842)
			(end 1.2954 -0.5842)
			(stroke
				(width 0.1524)
				(type default)
			)
			(layer "F.SilkS")
		)
		(fp_line
			(start 1.2954 0.5842)
			(end -1.2954 0.5842)
			(stroke
				(width 0.1524)
				(type default)
			)
			(layer "F.SilkS")
		)
		(fp_line
			(start -1.2954 0.5842)
			(end -1.2954 -0.5842)
			(stroke
				(width 0.1524)
				(type default)
			)
			(layer "F.SilkS")
		)
		(fp_poly
			(pts
				(xy 0.8636 -0.4572) (xy 0.8636 -0.3556) (xy 1.143 -0.3556) (xy 1.143 0.3556) (xy 0.8636 0.3556)
				(xy 0.8636 0.4572) (xy -0.8636 0.4572) (xy -0.8636 0.3556) (xy -1.143 0.3556) (xy -1.143 -0.3556)
				(xy -0.8636 -0.3556) (xy -0.8636 -0.4572)
			)
			(stroke
				(width 0)
				(type default)
			)
			(fill no)
			(layer "F.CrtYd")
		)
		(fp_line
			(start 0.884936 -0.504952)
			(end 0.884936 0.504952)
			(stroke
				(width 0.1)
				(type default)
			)
			(layer "F.Fab")
		)
		(fp_line
			(start -0.884936 -0.504952)
			(end 0.884936 -0.504952)
			(stroke
				(width 0.1)
				(type default)
			)
			(layer "F.Fab")
		)
		(fp_line
			(start 0.884936 0.504952)
			(end -0.884936 0.504952)
			(stroke
				(width 0.1)
				(type default)
			)
			(layer "F.Fab")
		)
		(fp_line
			(start -0.884936 0.504952)
			(end -0.884936 -0.504952)
			(stroke
				(width 0.1)
				(type default)
			)
			(layer "F.Fab")
		)
		(pad "1" smd rect
			(at 0.7366 0 180)
			(size 0.7112 0.8128)
			(layers "F.Cu" "F.Mask" "F.Paste")
			(net "PV_VDDR_NODE1")
		)
		(pad "2" smd rect
			(at -0.7366 0 180)
			(size 0.7112 0.8128)
			(layers "F.Cu" "F.Mask" "F.Paste")
			(net "GND")
		)
	)
	(footprint ""
		(layer "F.Cu")
		(at 56.24576 -185.205624 -90)
		(property "Reference" "R952"
			(at -4.006088 0.027178 90)
			(unlocked yes)
			(layer "F.SilkS")
			(effects
				(font
					(size 0.7874 0.5842)
					(thickness 0.1524)
				)
				(justify left)
			)
		)
		(property "Value" ""
			(at 0 0 270)
			(layer "F.Fab")
			(effects
				(font
					(size 1.27 1.27)
				)
			)
		)
		(duplicate_pad_numbers_are_jumpers no)
		(fp_line
			(start -0.7874 0.4064)
			(end -0.7874 -0.4064)
			(stroke
				(width 0.1524)
				(type default)
			)
			(layer "F.SilkS")
		)
		(fp_line
			(start 0.7874 0.4064)
			(end -0.7874 0.4064)
			(stroke
				(width 0.1524)
				(type default)
			)
			(layer "F.SilkS")
		)
		(fp_line
			(start -0.7874 -0.4064)
			(end 0.7874 -0.4064)
			(stroke
				(width 0.1524)
				(type default)
			)
			(layer "F.SilkS")
		)
		(fp_line
			(start 0.7874 -0.4064)
			(end 0.7874 0.4064)
			(stroke
				(width 0.1524)
				(type default)
			)
			(layer "F.SilkS")
		)
		(fp_poly
			(pts
				(xy -0.508 0.2794) (xy -0.508 0.2286) (xy -0.635 0.2286) (xy -0.635 -0.254) (xy -0.5334 -0.254)
				(xy -0.5334 -0.2794) (xy 0.5334 -0.2794) (xy 0.5334 -0.254) (xy 0.635 -0.254) (xy 0.635 0.254) (xy 0.5334 0.254)
				(xy 0.5334 0.2794)
			)
			(stroke
				(width 0)
				(type default)
			)
			(fill no)
			(layer "F.CrtYd")
		)
		(pad "1" smd rect
			(at 0.40005 0 270)
			(size 0.4572 0.508)
			(layers "F.Cu" "F.Mask" "F.Paste")
			(net "UART_T2_NODE4_TXD")
		)
		(pad "2" smd rect
			(at -0.40005 0 270)
			(size 0.4572 0.508)
			(layers "F.Cu" "F.Mask" "F.Paste")
			(net "UART_T2_NODE4_TXD_R")
		)
	)
	(footprint ""
		(layer "F.Cu")
		(at 125.018292 -161.189162)
		(property "Reference" "R665"
			(at 29.279088 46.827694 0)
			(unlocked yes)
			(layer "F.SilkS")
			(effects
				(font
					(size 0.7874 0.5842)
					(thickness 0.1524)
				)
				(justify left)
			)
		)
		(property "Value" ""
			(at 0 0 0)
			(layer "F.Fab")
			(effects
				(font
					(size 1.27 1.27)
				)
			)
		)
		(duplicate_pad_numbers_are_jumpers no)
		(fp_line
			(start -0.7874 -0.4064)
			(end 0.7874 -0.4064)
			(stroke
				(width 0.1524)
				(type default)
			)
			(layer "F.SilkS")
		)
		(fp_line
			(start -0.7874 0.4064)
			(end -0.7874 -0.4064)
			(stroke
				(width 0.1524)
				(type default)
			)
			(layer "F.SilkS")
		)
		(fp_line
			(start 0.7874 -0.4064)
			(end 0.7874 0.4064)
			(stroke
				(width 0.1524)
				(type default)
			)
			(layer "F.SilkS")
		)
		(fp_line
			(start 0.7874 0.4064)
			(end -0.7874 0.4064)
			(stroke
				(width 0.1524)
				(type default)
			)
			(layer "F.SilkS")
		)
		(fp_poly
			(pts
				(xy -0.508 0.2794) (xy -0.508 0.2286) (xy -0.635 0.2286) (xy -0.635 -0.254) (xy -0.5334 -0.254)
				(xy -0.5334 -0.2794) (xy 0.5334 -0.2794) (xy 0.5334 -0.254) (xy 0.635 -0.254) (xy 0.635 0.254) (xy 0.5334 0.254)
				(xy 0.5334 0.2794)
			)
			(stroke
				(width 0)
				(type default)
			)
			(fill no)
			(layer "F.CrtYd")
		)
		(pad "1" smd rect
			(at 0.40005 0)
			(size 0.4572 0.508)
			(layers "F.Cu" "F.Mask" "F.Paste")
			(net "P3V3_NODE1")
		)
		(pad "2" smd rect
			(at -0.40005 0)
			(size 0.4572 0.508)
			(layers "F.Cu" "F.Mask" "F.Paste")
			(net "I2C_PSU1_SCL_MOS")
		)
	)
	(footprint ""
		(layer "F.Cu")
		(at 95.195644 -130.052318 90)
		(property "Reference" "C810"
			(at -4.296918 -0.489458 90)
			(unlocked yes)
			(layer "F.SilkS")
			(effects
				(font
					(size 0.635 0.4064)
					(thickness 0.1524)
				)
				(justify left)
			)
		)
		(property "Value" ""
			(at 0 0 90)
			(layer "F.Fab")
			(effects
				(font
					(size 1.27 1.27)
				)
			)
		)
		(duplicate_pad_numbers_are_jumpers no)
		(fp_line
			(start 1.905 -0.8636)
			(end 1.905 0.8636)
			(stroke
				(width 0.1524)
				(type default)
			)
			(layer "F.SilkS")
		)
		(fp_line
			(start -1.905 -0.8636)
			(end 1.905 -0.8636)
			(stroke
				(width 0.1524)
				(type default)
			)
			(layer "F.SilkS")
		)
		(fp_line
			(start 0 0.8382)
			(end 0 -0.8382)
			(stroke
				(width 0.1524)
				(type default)
			)
			(layer "F.SilkS")
		)
		(fp_line
			(start 1.905 0.8636)
			(end -1.905 0.8636)
			(stroke
				(width 0.1524)
				(type default)
			)
			(layer "F.SilkS")
		)
		(fp_line
			(start -1.905 0.8636)
			(end -1.905 -0.8636)
			(stroke
				(width 0.1524)
				(type default)
			)
			(layer "F.SilkS")
		)
		(fp_rect
			(start -1.524 0.7366)
			(end 1.524 -0.7366)
			(stroke
				(width 0)
				(type default)
			)
			(fill no)
			(layer "F.CrtYd")
		)
		(pad "1" smd rect
			(at 0.94996 0 90)
			(size 1.1176 1.3716)
			(layers "F.Cu" "F.Mask" "F.Paste")
			(net "P1V8_STB_NODE1")
		)
		(pad "2" smd rect
			(at -0.94996 0 90)
			(size 1.1176 1.3716)
			(layers "F.Cu" "F.Mask" "F.Paste")
			(net "GND")
		)
	)
	(footprint ""
		(layer "F.Cu")
		(at 107.82554 -174.098458)
		(property "Reference" "C574"
			(at -1.15824 -1.26111 0)
			(unlocked yes)
			(layer "F.SilkS")
			(effects
				(font
					(size 0.7874 0.5842)
					(thickness 0.1524)
				)
				(justify left)
			)
		)
		(property "Value" ""
			(at 0 0 0)
			(layer "F.Fab")
			(effects
				(font
					(size 1.27 1.27)
				)
			)
		)
		(duplicate_pad_numbers_are_jumpers no)
		(fp_line
			(start -0.7874 -0.4064)
			(end 0.7874 -0.4064)
			(stroke
				(width 0.1524)
				(type default)
			)
			(layer "F.SilkS")
		)
		(fp_line
			(start -0.7874 0.4064)
			(end -0.7874 -0.4064)
			(stroke
				(width 0.1524)
				(type default)
			)
			(layer "F.SilkS")
		)
		(fp_line
			(start 0 0.381)
			(end 0 -0.381)
			(stroke
				(width 0.1524)
				(type default)
			)
			(layer "F.SilkS")
		)
		(fp_line
			(start 0.7874 -0.4064)
			(end 0.7874 0.4064)
			(stroke
				(width 0.1524)
				(type default)
			)
			(layer "F.SilkS")
		)
		(fp_line
			(start 0.7874 0.4064)
			(end -0.7874 0.4064)
			(stroke
				(width 0.1524)
				(type default)
			)
			(layer "F.SilkS")
		)
		(fp_poly
			(pts
				(xy -0.5334 0.254) (xy -0.635 0.254) (xy -0.635 0.2286) (xy -0.635 -0.254) (xy -0.5334 -0.254) (xy -0.5334 -0.2794)
				(xy 0.5334 -0.2794) (xy 0.5334 -0.254) (xy 0.635 -0.254) (xy 0.635 0.254) (xy 0.5334 0.254) (xy 0.5334 0.2794)
				(xy -0.508 0.2794) (xy -0.5334 0.2794)
			)
			(stroke
				(width 0)
				(type default)
			)
			(fill no)
			(layer "F.CrtYd")
		)
		(pad "1" smd rect
			(at 0.40005 0)
			(size 0.4572 0.508)
			(layers "F.Cu" "F.Mask" "F.Paste")
			(net "P3V3_NODE1")
		)
		(pad "2" smd rect
			(at -0.40005 0)
			(size 0.4572 0.508)
			(layers "F.Cu" "F.Mask" "F.Paste")
			(net "GND")
		)
	)
	(footprint ""
		(layer "F.Cu")
		(at 15.499588 -46.300898 90)
		(property "Reference" "C505"
			(at -8.563864 -0.833628 90)
			(unlocked yes)
			(layer "F.SilkS")
			(effects
				(font
					(size 0.7874 0.5842)
					(thickness 0.1524)
				)
				(justify left)
			)
		)
		(property "Value" ""
			(at 0 0 90)
			(layer "F.Fab")
			(effects
				(font
					(size 1.27 1.27)
				)
			)
		)
		(duplicate_pad_numbers_are_jumpers no)
		(fp_line
			(start 0.7874 -0.4064)
			(end 0.7874 0.4064)
			(stroke
				(width 0.1524)
				(type default)
			)
			(layer "F.SilkS")
		)
		(fp_line
			(start -0.7874 -0.4064)
			(end 0.7874 -0.4064)
			(stroke
				(width 0.1524)
				(type default)
			)
			(layer "F.SilkS")
		)
		(fp_line
			(start 0 0.381)
			(end 0 -0.381)
			(stroke
				(width 0.1524)
				(type default)
			)
			(layer "F.SilkS")
		)
		(fp_line
			(start 0.7874 0.4064)
			(end -0.7874 0.4064)
			(stroke
				(width 0.1524)
				(type default)
			)
			(layer "F.SilkS")
		)
		(fp_line
			(start -0.7874 0.4064)
			(end -0.7874 -0.4064)
			(stroke
				(width 0.1524)
				(type default)
			)
			(layer "F.SilkS")
		)
		(fp_poly
			(pts
				(xy -0.5334 0.254) (xy -0.635 0.254) (xy -0.635 0.2286) (xy -0.635 -0.254) (xy -0.5334 -0.254) (xy -0.5334 -0.2794)
				(xy 0.5334 -0.2794) (xy 0.5334 -0.254) (xy 0.635 -0.254) (xy 0.635 0.254) (xy 0.5334 0.254) (xy 0.5334 0.2794)
				(xy -0.508 0.2794) (xy -0.5334 0.2794)
			)
			(stroke
				(width 0)
				(type default)
			)
			(fill no)
			(layer "F.CrtYd")
		)
		(pad "1" smd rect
			(at 0.40005 0 90)
			(size 0.4572 0.508)
			(layers "F.Cu" "F.Mask" "F.Paste")
			(net "CRT_DDCDATA")
		)
		(pad "2" smd rect
			(at -0.40005 0 90)
			(size 0.4572 0.508)
			(layers "F.Cu" "F.Mask" "F.Paste")
			(net "GND")
		)
	)
	(footprint ""
		(layer "F.Cu")
		(at 55.049166 -96.709992 90)
		(property "Reference" "R80"
			(at -54.98719 28.429712 90)
			(unlocked yes)
			(layer "F.SilkS")
			(effects
				(font
					(size 0.7874 0.5842)
					(thickness 0.1524)
				)
				(justify left)
			)
		)
		(property "Value" ""
			(at 0 0 90)
			(layer "F.Fab")
			(effects
				(font
					(size 1.27 1.27)
				)
			)
		)
		(duplicate_pad_numbers_are_jumpers no)
		(fp_line
			(start 0.7874 -0.4064)
			(end 0.7874 0.4064)
			(stroke
				(width 0.1524)
				(type default)
			)
			(layer "F.SilkS")
		)
		(fp_line
			(start -0.7874 -0.4064)
			(end 0.7874 -0.4064)
			(stroke
				(width 0.1524)
				(type default)
			)
			(layer "F.SilkS")
		)
		(fp_line
			(start 0.7874 0.4064)
			(end -0.7874 0.4064)
			(stroke
				(width 0.1524)
				(type default)
			)
			(layer "F.SilkS")
		)
		(fp_line
			(start -0.7874 0.4064)
			(end -0.7874 -0.4064)
			(stroke
				(width 0.1524)
				(type default)
			)
			(layer "F.SilkS")
		)
		(fp_poly
			(pts
				(xy -0.508 0.2794) (xy -0.508 0.2286) (xy -0.635 0.2286) (xy -0.635 -0.254) (xy -0.5334 -0.254)
				(xy -0.5334 -0.2794) (xy 0.5334 -0.2794) (xy 0.5334 -0.254) (xy 0.635 -0.254) (xy 0.635 0.254) (xy 0.5334 0.254)
				(xy 0.5334 0.2794)
			)
			(stroke
				(width 0)
				(type default)
			)
			(fill no)
			(layer "F.CrtYd")
		)
		(pad "1" smd rect
			(at 0.40005 0 90)
			(size 0.4572 0.508)
			(layers "F.Cu" "F.Mask" "F.Paste")
			(net "GND")
		)
		(pad "2" smd rect
			(at -0.40005 0 90)
			(size 0.4572 0.508)
			(layers "F.Cu" "F.Mask" "F.Paste")
			(net "PD_CPU_NODE1_DFX_GPIO_GRP0_6")
		)
	)
	(footprint ""
		(layer "F.Cu")
		(at 138.880088 -69.662548 180)
		(property "Reference" "R501"
			(at 3.772916 0.378968 0)
			(unlocked yes)
			(layer "F.SilkS")
			(effects
				(font
					(size 0.7874 0.5842)
					(thickness 0.1524)
				)
				(justify left)
			)
		)
		(property "Value" ""
			(at 0 0 180)
			(layer "F.Fab")
			(effects
				(font
					(size 1.27 1.27)
				)
			)
		)
		(duplicate_pad_numbers_are_jumpers no)
		(fp_line
			(start 0.7874 0.4064)
			(end -0.7874 0.4064)
			(stroke
				(width 0.1524)
				(type default)
			)
			(layer "F.SilkS")
		)
		(fp_line
			(start 0.7874 -0.4064)
			(end 0.7874 0.4064)
			(stroke
				(width 0.1524)
				(type default)
			)
			(layer "F.SilkS")
		)
		(fp_line
			(start -0.7874 0.4064)
			(end -0.7874 -0.4064)
			(stroke
				(width 0.1524)
				(type default)
			)
			(layer "F.SilkS")
		)
		(fp_line
			(start -0.7874 -0.4064)
			(end 0.7874 -0.4064)
			(stroke
				(width 0.1524)
				(type default)
			)
			(layer "F.SilkS")
		)
		(fp_poly
			(pts
				(xy -0.508 0.2794) (xy -0.508 0.2286) (xy -0.635 0.2286) (xy -0.635 -0.254) (xy -0.5334 -0.254)
				(xy -0.5334 -0.2794) (xy 0.5334 -0.2794) (xy 0.5334 -0.254) (xy 0.635 -0.254) (xy 0.635 0.254) (xy 0.5334 0.254)
				(xy 0.5334 0.2794)
			)
			(stroke
				(width 0)
				(type default)
			)
			(fill no)
			(layer "F.CrtYd")
		)
		(pad "1" smd rect
			(at 0.40005 0 180)
			(size 0.4572 0.508)
			(layers "F.Cu" "F.Mask" "F.Paste")
			(net "LED_SATA_NODE1_R")
		)
		(pad "2" smd rect
			(at -0.40005 0 180)
			(size 0.4572 0.508)
			(layers "F.Cu" "F.Mask" "F.Paste")
			(net "P3V3_NODE1")
		)
	)
	(footprint ""
		(layer "F.Cu")
		(at 53.561996 -162.046158 180)
		(property "Reference" "C519"
			(at 0.575564 5.663692 0)
			(unlocked yes)
			(layer "F.SilkS")
			(effects
				(font
					(size 0.7874 0.5842)
					(thickness 0.1524)
				)
				(justify left)
			)
		)
		(property "Value" ""
			(at 0 0 180)
			(layer "F.Fab")
			(effects
				(font
					(size 1.27 1.27)
				)
			)
		)
		(duplicate_pad_numbers_are_jumpers no)
		(fp_line
			(start 0.7874 0.4064)
			(end -0.7874 0.4064)
			(stroke
				(width 0.1524)
				(type default)
			)
			(layer "F.SilkS")
		)
		(fp_line
			(start 0.7874 -0.4064)
			(end 0.7874 0.4064)
			(stroke
				(width 0.1524)
				(type default)
			)
			(layer "F.SilkS")
		)
		(fp_line
			(start 0 0.381)
			(end 0 -0.381)
			(stroke
				(width 0.1524)
				(type default)
			)
			(layer "F.SilkS")
		)
		(fp_line
			(start -0.7874 0.4064)
			(end -0.7874 -0.4064)
			(stroke
				(width 0.1524)
				(type default)
			)
			(layer "F.SilkS")
		)
		(fp_line
			(start -0.7874 -0.4064)
			(end 0.7874 -0.4064)
			(stroke
				(width 0.1524)
				(type default)
			)
			(layer "F.SilkS")
		)
		(fp_poly
			(pts
				(xy -0.5334 0.254) (xy -0.635 0.254) (xy -0.635 0.2286) (xy -0.635 -0.254) (xy -0.5334 -0.254) (xy -0.5334 -0.2794)
				(xy 0.5334 -0.2794) (xy 0.5334 -0.254) (xy 0.635 -0.254) (xy 0.635 0.254) (xy 0.5334 0.254) (xy 0.5334 0.2794)
				(xy -0.508 0.2794) (xy -0.5334 0.2794)
			)
			(stroke
				(width 0)
				(type default)
			)
			(fill no)
			(layer "F.CrtYd")
		)
		(pad "1" smd rect
			(at 0.40005 0 180)
			(size 0.4572 0.508)
			(layers "F.Cu" "F.Mask" "F.Paste")
			(net "LAN1_LED_LINK_1000_N")
		)
		(pad "2" smd rect
			(at -0.40005 0 180)
			(size 0.4572 0.508)
			(layers "F.Cu" "F.Mask" "F.Paste")
			(net "GND")
		)
	)
	(footprint ""
		(layer "F.Cu")
		(at 131.99745 -60.930282 90)
		(property "Reference" "R519"
			(at -1.062482 -2.10058 90)
			(unlocked yes)
			(layer "F.SilkS")
			(effects
				(font
					(size 0.7874 0.5842)
					(thickness 0.1524)
				)
				(justify left)
			)
		)
		(property "Value" ""
			(at 0 0 90)
			(layer "F.Fab")
			(effects
				(font
					(size 1.27 1.27)
				)
			)
		)
		(duplicate_pad_numbers_are_jumpers no)
		(fp_line
			(start 0.7874 -0.4064)
			(end 0.7874 0.4064)
			(stroke
				(width 0.1524)
				(type default)
			)
			(layer "F.SilkS")
		)
		(fp_line
			(start -0.7874 -0.4064)
			(end 0.7874 -0.4064)
			(stroke
				(width 0.1524)
				(type default)
			)
			(layer "F.SilkS")
		)
		(fp_line
			(start 0.7874 0.4064)
			(end -0.7874 0.4064)
			(stroke
				(width 0.1524)
				(type default)
			)
			(layer "F.SilkS")
		)
		(fp_line
			(start -0.7874 0.4064)
			(end -0.7874 -0.4064)
			(stroke
				(width 0.1524)
				(type default)
			)
			(layer "F.SilkS")
		)
		(fp_poly
			(pts
				(xy -0.508 0.2794) (xy -0.508 0.2286) (xy -0.635 0.2286) (xy -0.635 -0.254) (xy -0.5334 -0.254)
				(xy -0.5334 -0.2794) (xy 0.5334 -0.2794) (xy 0.5334 -0.254) (xy 0.635 -0.254) (xy 0.635 0.254) (xy 0.5334 0.254)
				(xy 0.5334 0.2794)
			)
			(stroke
				(width 0)
				(type default)
			)
			(fill no)
			(layer "F.CrtYd")
		)
		(pad "1" smd rect
			(at 0.40005 0 90)
			(size 0.4572 0.508)
			(layers "F.Cu" "F.Mask" "F.Paste")
			(net "SATA_SPI_DI_NODE1_R")
		)
		(pad "2" smd rect
			(at -0.40005 0 90)
			(size 0.4572 0.508)
			(layers "F.Cu" "F.Mask" "F.Paste")
			(net "SATA_SPI_DI_NODE1")
		)
	)
	(footprint ""
		(layer "F.Cu")
		(at 89.562178 -107.83824)
		(property "Reference" "R177"
			(at -1.189482 -1.14427 0)
			(unlocked yes)
			(layer "F.SilkS")
			(effects
				(font
					(size 0.7874 0.5842)
					(thickness 0.1524)
				)
				(justify left)
			)
		)
		(property "Value" ""
			(at 0 0 0)
			(layer "F.Fab")
			(effects
				(font
					(size 1.27 1.27)
				)
			)
		)
		(duplicate_pad_numbers_are_jumpers no)
		(fp_line
			(start -0.7874 -0.4064)
			(end 0.7874 -0.4064)
			(stroke
				(width 0.1524)
				(type default)
			)
			(layer "F.SilkS")
		)
		(fp_line
			(start -0.7874 0.4064)
			(end -0.7874 -0.4064)
			(stroke
				(width 0.1524)
				(type default)
			)
			(layer "F.SilkS")
		)
		(fp_line
			(start 0.7874 -0.4064)
			(end 0.7874 0.4064)
			(stroke
				(width 0.1524)
				(type default)
			)
			(layer "F.SilkS")
		)
		(fp_line
			(start 0.7874 0.4064)
			(end -0.7874 0.4064)
			(stroke
				(width 0.1524)
				(type default)
			)
			(layer "F.SilkS")
		)
		(fp_poly
			(pts
				(xy -0.508 0.2794) (xy -0.508 0.2286) (xy -0.635 0.2286) (xy -0.635 -0.254) (xy -0.5334 -0.254)
				(xy -0.5334 -0.2794) (xy 0.5334 -0.2794) (xy 0.5334 -0.254) (xy 0.635 -0.254) (xy 0.635 0.254) (xy 0.5334 0.254)
				(xy 0.5334 0.2794)
			)
			(stroke
				(width 0)
				(type default)
			)
			(fill no)
			(layer "F.CrtYd")
		)
		(pad "1" smd rect
			(at 0.40005 0)
			(size 0.4572 0.508)
			(layers "F.Cu" "F.Mask" "F.Paste")
			(net "P3V3_NODE1")
		)
		(pad "2" smd rect
			(at -0.40005 0)
			(size 0.4572 0.508)
			(layers "F.Cu" "F.Mask" "F.Paste")
			(net "SPI_CPU_NODE1_HOLD_L")
		)
	)
	(footprint ""
		(layer "F.Cu")
		(at 53.561996 -161.030158 180)
		(property "Reference" "C518"
			(at 0.575564 5.564632 0)
			(unlocked yes)
			(layer "F.SilkS")
			(effects
				(font
					(size 0.7874 0.5842)
					(thickness 0.1524)
				)
				(justify left)
			)
		)
		(property "Value" ""
			(at 0 0 180)
			(layer "F.Fab")
			(effects
				(font
					(size 1.27 1.27)
				)
			)
		)
		(duplicate_pad_numbers_are_jumpers no)
		(fp_line
			(start 0.7874 0.4064)
			(end -0.7874 0.4064)
			(stroke
				(width 0.1524)
				(type default)
			)
			(layer "F.SilkS")
		)
		(fp_line
			(start 0.7874 -0.4064)
			(end 0.7874 0.4064)
			(stroke
				(width 0.1524)
				(type default)
			)
			(layer "F.SilkS")
		)
		(fp_line
			(start 0 0.381)
			(end 0 -0.381)
			(stroke
				(width 0.1524)
				(type default)
			)
			(layer "F.SilkS")
		)
		(fp_line
			(start -0.7874 0.4064)
			(end -0.7874 -0.4064)
			(stroke
				(width 0.1524)
				(type default)
			)
			(layer "F.SilkS")
		)
		(fp_line
			(start -0.7874 -0.4064)
			(end 0.7874 -0.4064)
			(stroke
				(width 0.1524)
				(type default)
			)
			(layer "F.SilkS")
		)
		(fp_poly
			(pts
				(xy -0.5334 0.254) (xy -0.635 0.254) (xy -0.635 0.2286) (xy -0.635 -0.254) (xy -0.5334 -0.254) (xy -0.5334 -0.2794)
				(xy 0.5334 -0.2794) (xy 0.5334 -0.254) (xy 0.635 -0.254) (xy 0.635 0.254) (xy 0.5334 0.254) (xy 0.5334 0.2794)
				(xy -0.508 0.2794) (xy -0.5334 0.2794)
			)
			(stroke
				(width 0)
				(type default)
			)
			(fill no)
			(layer "F.CrtYd")
		)
		(pad "1" smd rect
			(at 0.40005 0 180)
			(size 0.4572 0.508)
			(layers "F.Cu" "F.Mask" "F.Paste")
			(net "LAN1_LED_LINK_100_N")
		)
		(pad "2" smd rect
			(at -0.40005 0 180)
			(size 0.4572 0.508)
			(layers "F.Cu" "F.Mask" "F.Paste")
			(net "GND")
		)
	)
	(footprint ""
		(layer "F.Cu")
		(at 130.08356 -188.126624 90)
		(property "Reference" "C758"
			(at 4.949444 -0.710438 90)
			(unlocked yes)
			(layer "F.SilkS")
			(effects
				(font
					(size 0.7874 0.5842)
					(thickness 0.1524)
				)
				(justify left)
			)
		)
		(property "Value" ""
			(at 0 0 90)
			(layer "F.Fab")
			(effects
				(font
					(size 1.27 1.27)
				)
			)
		)
		(duplicate_pad_numbers_are_jumpers no)
		(fp_line
			(start 0.7874 -0.4064)
			(end 0.7874 0.4064)
			(stroke
				(width 0.1524)
				(type default)
			)
			(layer "F.SilkS")
		)
		(fp_line
			(start -0.7874 -0.4064)
			(end 0.7874 -0.4064)
			(stroke
				(width 0.1524)
				(type default)
			)
			(layer "F.SilkS")
		)
		(fp_line
			(start 0 0.381)
			(end 0 -0.381)
			(stroke
				(width 0.1524)
				(type default)
			)
			(layer "F.SilkS")
		)
		(fp_line
			(start 0.7874 0.4064)
			(end -0.7874 0.4064)
			(stroke
				(width 0.1524)
				(type default)
			)
			(layer "F.SilkS")
		)
		(fp_line
			(start -0.7874 0.4064)
			(end -0.7874 -0.4064)
			(stroke
				(width 0.1524)
				(type default)
			)
			(layer "F.SilkS")
		)
		(fp_poly
			(pts
				(xy -0.5334 0.254) (xy -0.635 0.254) (xy -0.635 0.2286) (xy -0.635 -0.254) (xy -0.5334 -0.254) (xy -0.5334 -0.2794)
				(xy 0.5334 -0.2794) (xy 0.5334 -0.254) (xy 0.635 -0.254) (xy 0.635 0.254) (xy 0.5334 0.254) (xy 0.5334 0.2794)
				(xy -0.508 0.2794) (xy -0.5334 0.2794)
			)
			(stroke
				(width 0)
				(type default)
			)
			(fill no)
			(layer "F.CrtYd")
		)
		(pad "1" smd rect
			(at 0.40005 0 90)
			(size 0.4572 0.508)
			(layers "F.Cu" "F.Mask" "F.Paste")
			(net "UART_T10_NODE3_TXD_R")
		)
		(pad "2" smd rect
			(at -0.40005 0 90)
			(size 0.4572 0.508)
			(layers "F.Cu" "F.Mask" "F.Paste")
			(net "GND")
		)
	)
	(footprint ""
		(layer "F.Cu")
		(at 15.425166 -52.298854 90)
		(property "Reference" "C506"
			(at -4.414266 14.419072 90)
			(unlocked yes)
			(layer "F.SilkS")
			(effects
				(font
					(size 0.7874 0.5842)
					(thickness 0.1524)
				)
				(justify left)
			)
		)
		(property "Value" ""
			(at 0 0 90)
			(layer "F.Fab")
			(effects
				(font
					(size 1.27 1.27)
				)
			)
		)
		(duplicate_pad_numbers_are_jumpers no)
		(fp_line
			(start 0.7874 -0.4064)
			(end 0.7874 0.4064)
			(stroke
				(width 0.1524)
				(type default)
			)
			(layer "F.SilkS")
		)
		(fp_line
			(start -0.7874 -0.4064)
			(end 0.7874 -0.4064)
			(stroke
				(width 0.1524)
				(type default)
			)
			(layer "F.SilkS")
		)
		(fp_line
			(start 0 0.381)
			(end 0 -0.381)
			(stroke
				(width 0.1524)
				(type default)
			)
			(layer "F.SilkS")
		)
		(fp_line
			(start 0.7874 0.4064)
			(end -0.7874 0.4064)
			(stroke
				(width 0.1524)
				(type default)
			)
			(layer "F.SilkS")
		)
		(fp_line
			(start -0.7874 0.4064)
			(end -0.7874 -0.4064)
			(stroke
				(width 0.1524)
				(type default)
			)
			(layer "F.SilkS")
		)
		(fp_poly
			(pts
				(xy -0.5334 0.254) (xy -0.635 0.254) (xy -0.635 0.2286) (xy -0.635 -0.254) (xy -0.5334 -0.254) (xy -0.5334 -0.2794)
				(xy 0.5334 -0.2794) (xy 0.5334 -0.254) (xy 0.635 -0.254) (xy 0.635 0.254) (xy 0.5334 0.254) (xy 0.5334 0.2794)
				(xy -0.508 0.2794) (xy -0.5334 0.2794)
			)
			(stroke
				(width 0)
				(type default)
			)
			(fill no)
			(layer "F.CrtYd")
		)
		(pad "1" smd rect
			(at 0.40005 0 90)
			(size 0.4572 0.508)
			(layers "F.Cu" "F.Mask" "F.Paste")
			(net "CRT_HSYNC")
		)
		(pad "2" smd rect
			(at -0.40005 0 90)
			(size 0.4572 0.508)
			(layers "F.Cu" "F.Mask" "F.Paste")
			(net "GND")
		)
	)
	(footprint ""
		(layer "F.Cu")
		(at 108.388404 -153.54808)
		(property "Reference" "R657"
			(at -1.084326 5.395976 0)
			(unlocked yes)
			(layer "F.SilkS")
			(effects
				(font
					(size 0.635 0.4064)
					(thickness 0.1524)
				)
				(justify left)
			)
		)
		(property "Value" ""
			(at 0 0 0)
			(layer "F.Fab")
			(effects
				(font
					(size 1.27 1.27)
				)
			)
		)
		(duplicate_pad_numbers_are_jumpers no)
		(fp_line
			(start -0.7874 -0.4064)
			(end 0.7874 -0.4064)
			(stroke
				(width 0.1524)
				(type default)
			)
			(layer "F.SilkS")
		)
		(fp_line
			(start -0.7874 0.4064)
			(end -0.7874 -0.4064)
			(stroke
				(width 0.1524)
				(type default)
			)
			(layer "F.SilkS")
		)
		(fp_line
			(start 0.7874 -0.4064)
			(end 0.7874 0.4064)
			(stroke
				(width 0.1524)
				(type default)
			)
			(layer "F.SilkS")
		)
		(fp_line
			(start 0.7874 0.4064)
			(end -0.7874 0.4064)
			(stroke
				(width 0.1524)
				(type default)
			)
			(layer "F.SilkS")
		)
		(fp_poly
			(pts
				(xy -0.508 0.2794) (xy -0.508 0.2286) (xy -0.635 0.2286) (xy -0.635 -0.254) (xy -0.5334 -0.254)
				(xy -0.5334 -0.2794) (xy 0.5334 -0.2794) (xy 0.5334 -0.254) (xy 0.635 -0.254) (xy 0.635 0.254) (xy 0.5334 0.254)
				(xy 0.5334 0.2794)
			)
			(stroke
				(width 0)
				(type default)
			)
			(fill no)
			(layer "F.CrtYd")
		)
		(pad "1" smd rect
			(at 0.40005 0)
			(size 0.4572 0.508)
			(layers "F.Cu" "F.Mask" "F.Paste")
			(net "N52411212")
		)
		(pad "2" smd rect
			(at -0.40005 0)
			(size 0.4572 0.508)
			(layers "F.Cu" "F.Mask" "F.Paste")
			(net "P12V_AUX")
		)
	)
	(footprint ""
		(layer "F.Cu")
		(at 28.498546 -99.573842)
		(property "Reference" "R1152"
			(at 1.402334 0.434594 0)
			(unlocked yes)
			(layer "F.SilkS")
			(effects
				(font
					(size 0.7874 0.5842)
					(thickness 0.1524)
				)
				(justify left)
			)
		)
		(property "Value" ""
			(at 0 0 0)
			(layer "F.Fab")
			(effects
				(font
					(size 1.27 1.27)
				)
			)
		)
		(duplicate_pad_numbers_are_jumpers no)
		(fp_line
			(start -0.7874 -0.4064)
			(end 0.7874 -0.4064)
			(stroke
				(width 0.1524)
				(type default)
			)
			(layer "F.SilkS")
		)
		(fp_line
			(start -0.7874 0.4064)
			(end -0.7874 -0.4064)
			(stroke
				(width 0.1524)
				(type default)
			)
			(layer "F.SilkS")
		)
		(fp_line
			(start 0.7874 -0.4064)
			(end 0.7874 0.4064)
			(stroke
				(width 0.1524)
				(type default)
			)
			(layer "F.SilkS")
		)
		(fp_line
			(start 0.7874 0.4064)
			(end -0.7874 0.4064)
			(stroke
				(width 0.1524)
				(type default)
			)
			(layer "F.SilkS")
		)
		(fp_poly
			(pts
				(xy -0.508 0.2794) (xy -0.508 0.2286) (xy -0.635 0.2286) (xy -0.635 -0.254) (xy -0.5334 -0.254)
				(xy -0.5334 -0.2794) (xy 0.5334 -0.2794) (xy 0.5334 -0.254) (xy 0.635 -0.254) (xy 0.635 0.254) (xy 0.5334 0.254)
				(xy 0.5334 0.2794)
			)
			(stroke
				(width 0)
				(type default)
			)
			(fill no)
			(layer "F.CrtYd")
		)
		(pad "1" smd rect
			(at 0.40005 0)
			(size 0.4572 0.508)
			(layers "F.Cu" "F.Mask" "F.Paste")
			(net "GND")
		)
		(pad "2" smd rect
			(at -0.40005 0)
			(size 0.4572 0.508)
			(layers "F.Cu" "F.Mask" "F.Paste")
			(net "FRU_SYS_A0")
		)
	)
	(footprint ""
		(layer "F.Cu")
		(at -6.825488 -31.804102 90)
		(property "Reference" "J30"
			(at 1.18872 -6.71703 90)
			(unlocked yes)
			(layer "F.SilkS")
			(effects
				(font
					(size 0.7874 0.5842)
					(thickness 0.1524)
				)
				(justify left)
			)
		)
		(property "Value" ""
			(at 0 0 90)
			(layer "F.Fab")
			(effects
				(font
					(size 1.27 1.27)
				)
			)
		)
		(duplicate_pad_numbers_are_jumpers no)
		(fp_circle
			(center 4.064 -4.572)
			(end 4.064 -3.937)
			(stroke
				(width 0.05)
				(type default)
			)
			(fill no)
			(layer "Edge.Cuts")
		)
		(fp_circle
			(center 0 -4.572)
			(end 0 -3.937)
			(stroke
				(width 0.05)
				(type default)
			)
			(fill no)
			(layer "Edge.Cuts")
		)
		(fp_circle
			(center 4.064 0)
			(end 4.064 0.635)
			(stroke
				(width 0.05)
				(type default)
			)
			(fill no)
			(layer "Edge.Cuts")
		)
		(fp_circle
			(center 0 0)
			(end 0 0.635)
			(stroke
				(width 0.05)
				(type default)
			)
			(fill no)
			(layer "Edge.Cuts")
		)
		(fp_rect
			(start -1.27 1.27)
			(end 5.334 -5.842)
			(stroke
				(width 0)
				(type default)
			)
			(fill no)
			(layer "F.CrtYd")
		)
		(pad "" np_thru_hole circle
			(at 0 -4.572 90)
			(size 0.254 0.254)
			(drill 1.27)
			(layers "*.Cu" "*.Mask")
			(clearance 0.889)
			(thermal_gap 0.889)
		)
		(pad "" np_thru_hole circle
			(at 0 0 90)
			(size 0.254 0.254)
			(drill 1.27)
			(layers "*.Cu" "*.Mask")
			(clearance 0.889)
			(thermal_gap 0.889)
		)
		(pad "" np_thru_hole circle
			(at 4.064 -4.572 90)
			(size 0.254 0.254)
			(drill 1.27)
			(layers "*.Cu" "*.Mask")
			(clearance 0.889)
			(thermal_gap 0.889)
		)
		(pad "" np_thru_hole circle
			(at 4.064 0 90)
			(size 0.254 0.254)
			(drill 1.27)
			(layers "*.Cu" "*.Mask")
			(clearance 0.889)
			(thermal_gap 0.889)
		)
		(pad "1" thru_hole custom
			(at 1.397 -2.286 180)
			(size 0.266741 0.266741)
			(drill 0.254)
			(layers "*.Cu" "*.Mask")
			(remove_unused_layers no)
			(net "GND")
			(options
				(clearance outline)
				(anchor circle)
			)
			(primitives
				(gr_poly
					(pts
						(xy -0.979932 0.5334)
						(arc
							(start -0.979932 -0.078994)
							(mid -0.925932 -0.48038)
							(end -0.527812 -0.4064)
						)
						(arc
							(start -0.234188 -0.4064)
							(mid 0 -0.53341)
							(end 0.234188 -0.4064)
						)
						(arc
							(start 0.527812 -0.4064)
							(mid 0.925878 -0.480305)
							(end 0.979932 -0.078994)
						)
						(xy 0.979932 0.5334) (xy 0.548132 0.5334) (xy 0.548132 0.1016) (xy -0.548132 0.1016) (xy -0.548132 0.5334)
					)
					(width 0)
					(fill yes)
				)
			)
			(padstack
				(mode front_inner_back)
				(layer "Inner"
					(shape custom)
					(size 0.139735 0.139735)
					(options
						(anchor circle)
					)
					(primitives
						(gr_poly
							(pts
								(arc
									(start 0.26035 0.1016)
									(mid 0 0.279472)
									(end -0.26035 0.1016)
								)
								(arc
									(start -0.50165 0.1016)
									(mid -1.041472 0)
									(end -0.50165 -0.1016)
								)
								(arc
									(start -0.26035 -0.1016)
									(mid 0 -0.279472)
									(end 0.26035 -0.1016)
								)
								(arc
									(start 0.50165 -0.1016)
									(mid 1.041472 0)
									(end 0.50165 0.1016)
								)
							)
							(width 0)
							(fill yes)
						)
					)
				)
				(layer "B.Cu"
					(shape custom)
					(size 0.139735 0.139735)
					(options
						(anchor circle)
					)
					(primitives
						(gr_poly
							(pts
								(arc
									(start 0.26035 0.1016)
									(mid 0 0.279472)
									(end -0.26035 0.1016)
								)
								(arc
									(start -0.50165 0.1016)
									(mid -1.041472 0)
									(end -0.50165 -0.1016)
								)
								(arc
									(start -0.26035 -0.1016)
									(mid 0 -0.279472)
									(end 0.26035 -0.1016)
								)
								(arc
									(start 0.50165 -0.1016)
									(mid 1.041472 0)
									(end 0.50165 0.1016)
								)
							)
							(width 0)
							(fill yes)
						)
					)
				)
			)
		)
		(pad "2" smd rect
			(at 2.032 -2.060956 90)
			(size 0.3048 0.2032)
			(layers "F.Cu" "F.Mask" "F.Paste")
			(net "THRU_85_OHM")
		)
		(pad "3" smd rect
			(at 2.032 -2.511044 90)
			(size 0.3048 0.2032)
			(layers "F.Cu" "F.Mask" "F.Paste")
			(net "THRU_85_OHM")
		)
		(zone
			(layers "F.Cu" "B.Cu" "In1.Cu" "In2.Cu" "In3.Cu" "In4.Cu" "In5.Cu" "In6.Cu"
				"In7.Cu" "In8.Cu"
			)
			(hatch none 0.5)
			(connect_pads
				(clearance 0)
			)
			(min_thickness 0.25)
			(keepout
				(tracks not_allowed)
				(vias allowed)
				(pads allowed)
				(copperpour not_allowed)
				(footprints allowed)
			)
			(placement
				(enabled no)
				(sheetname "")
			)
			(fill
				(thermal_gap 0.5)
				(thermal_bridge_width 0.5)
				(island_removal_mode 0)
			)
			(polygon
				(pts
					(arc
						(start -11.397488 -36.757102)
						(mid -11.397488 -34.979102)
						(end -11.397488 -36.757102)
					)
				)
			)
		)
		(zone
			(layers "F.Cu" "B.Cu" "In1.Cu" "In2.Cu" "In3.Cu" "In4.Cu" "In5.Cu" "In6.Cu"
				"In7.Cu" "In8.Cu"
			)
			(hatch none 0.5)
			(connect_pads
				(clearance 0)
			)
			(min_thickness 0.25)
			(keepout
				(tracks not_allowed)
				(vias allowed)
				(pads allowed)
				(copperpour not_allowed)
				(footprints allowed)
			)
			(placement
				(enabled no)
				(sheetname "")
			)
			(fill
				(thermal_gap 0.5)
				(thermal_bridge_width 0.5)
				(island_removal_mode 0)
			)
			(polygon
				(pts
					(arc
						(start -11.397488 -32.693102)
						(mid -11.397488 -30.915102)
						(end -11.397488 -32.693102)
					)
				)
			)
		)
		(zone
			(layers "F.Cu" "B.Cu" "In1.Cu" "In2.Cu" "In3.Cu" "In4.Cu" "In5.Cu" "In6.Cu"
				"In7.Cu" "In8.Cu"
			)
			(hatch none 0.5)
			(connect_pads
				(clearance 0)
			)
			(min_thickness 0.25)
			(keepout
				(tracks not_allowed)
				(vias allowed)
				(pads allowed)
				(copperpour not_allowed)
				(footprints allowed)
			)
			(placement
				(enabled no)
				(sheetname "")
			)
			(fill
				(thermal_gap 0.5)
				(thermal_bridge_width 0.5)
				(island_removal_mode 0)
			)
			(polygon
				(pts
					(arc
						(start -6.825488 -36.757102)
						(mid -6.825488 -34.979102)
						(end -6.825488 -36.757102)
					)
				)
			)
		)
		(zone
			(layers "F.Cu" "B.Cu" "In1.Cu" "In2.Cu" "In3.Cu" "In4.Cu" "In5.Cu" "In6.Cu"
				"In7.Cu" "In8.Cu"
			)
			(hatch none 0.5)
			(connect_pads
				(clearance 0)
			)
			(min_thickness 0.25)
			(keepout
				(tracks not_allowed)
				(vias allowed)
				(pads allowed)
				(copperpour not_allowed)
				(footprints allowed)
			)
			(placement
				(enabled no)
				(sheetname "")
			)
			(fill
				(thermal_gap 0.5)
				(thermal_bridge_width 0.5)
				(island_removal_mode 0)
			)
			(polygon
				(pts
					(arc
						(start -6.825488 -32.693102)
						(mid -6.825488 -30.915102)
						(end -6.825488 -32.693102)
					)
				)
			)
		)
	)
	(footprint ""
		(layer "F.Cu")
		(at 120.620536 -153.898854 -90)
		(property "Reference" "R644"
			(at 111.266986 57.81802 90)
			(unlocked yes)
			(layer "F.SilkS")
			(effects
				(font
					(size 0.7874 0.5842)
					(thickness 0.1524)
				)
				(justify left)
			)
		)
		(property "Value" ""
			(at 0 0 270)
			(layer "F.Fab")
			(effects
				(font
					(size 1.27 1.27)
				)
			)
		)
		(duplicate_pad_numbers_are_jumpers no)
		(fp_line
			(start -0.7874 0.406146)
			(end -0.7874 -0.406146)
			(stroke
				(width 0.1524)
				(type default)
			)
			(layer "F.SilkS")
		)
		(fp_line
			(start 0.7874 0.406146)
			(end -0.7874 0.406146)
			(stroke
				(width 0.1524)
				(type default)
			)
			(layer "F.SilkS")
		)
		(fp_line
			(start -0.7874 -0.406146)
			(end 0.7874 -0.406146)
			(stroke
				(width 0.1524)
				(type default)
			)
			(layer "F.SilkS")
		)
		(fp_line
			(start 0.7874 -0.406146)
			(end 0.7874 0.406146)
			(stroke
				(width 0.1524)
				(type default)
			)
			(layer "F.SilkS")
		)
		(fp_poly
			(pts
				(xy -0.508 0.2794) (xy -0.508 0.2286) (xy -0.635 0.2286) (xy -0.635 -0.254) (xy -0.5334 -0.254)
				(xy -0.5334 -0.2794) (xy 0.5334 -0.2794) (xy 0.5334 -0.254) (xy 0.635 -0.254) (xy 0.635 0.254) (xy 0.5334 0.254)
				(xy 0.5334 0.2794)
			)
			(stroke
				(width 0)
				(type default)
			)
			(fill no)
			(layer "F.CrtYd")
		)
		(pad "1" smd rect
			(at 0.40005 0 270)
			(size 0.4572 0.508)
			(layers "F.Cu" "F.Mask" "F.Paste")
			(net "I2C_PSU1_SDA")
		)
		(pad "2" smd rect
			(at -0.40005 0 270)
			(size 0.4572 0.508)
			(layers "F.Cu" "F.Mask" "F.Paste")
			(net "I2C_PSU1_SDA_MOS")
		)
	)
	(footprint ""
		(layer "F.Cu")
		(at 137.39876 -108.370624 90)
		(property "Reference" "R19"
			(at -6.585204 0.466852 90)
			(unlocked yes)
			(layer "F.SilkS")
			(effects
				(font
					(size 0.7874 0.5842)
					(thickness 0.1524)
				)
				(justify left)
			)
		)
		(property "Value" ""
			(at 0 0 90)
			(layer "F.Fab")
			(effects
				(font
					(size 1.27 1.27)
				)
			)
		)
		(duplicate_pad_numbers_are_jumpers no)
		(fp_line
			(start 0.7874 -0.4064)
			(end 0.7874 0.4064)
			(stroke
				(width 0.1524)
				(type default)
			)
			(layer "F.SilkS")
		)
		(fp_line
			(start -0.7874 -0.4064)
			(end 0.7874 -0.4064)
			(stroke
				(width 0.1524)
				(type default)
			)
			(layer "F.SilkS")
		)
		(fp_line
			(start 0.7874 0.4064)
			(end -0.7874 0.4064)
			(stroke
				(width 0.1524)
				(type default)
			)
			(layer "F.SilkS")
		)
		(fp_line
			(start -0.7874 0.4064)
			(end -0.7874 -0.4064)
			(stroke
				(width 0.1524)
				(type default)
			)
			(layer "F.SilkS")
		)
		(fp_poly
			(pts
				(xy -0.508 0.2794) (xy -0.508 0.2286) (xy -0.635 0.2286) (xy -0.635 -0.254) (xy -0.5334 -0.254)
				(xy -0.5334 -0.2794) (xy 0.5334 -0.2794) (xy 0.5334 -0.254) (xy 0.635 -0.254) (xy 0.635 0.254) (xy 0.5334 0.254)
				(xy 0.5334 0.2794)
			)
			(stroke
				(width 0)
				(type default)
			)
			(fill no)
			(layer "F.CrtYd")
		)
		(pad "1" smd rect
			(at 0.40005 0 90)
			(size 0.4572 0.508)
			(layers "F.Cu" "F.Mask" "F.Paste")
			(net "CLKREQA_NODE1_N")
		)
		(pad "2" smd rect
			(at -0.40005 0 90)
			(size 0.4572 0.508)
			(layers "F.Cu" "F.Mask" "F.Paste")
			(net "P3V3_CLK_NODE1")
		)
	)
	(footprint ""
		(layer "F.Cu")
		(at 25.10536 -51.858418 90)
		(property "Reference" "U132"
			(at 0.0889 15.889986 90)
			(unlocked yes)
			(layer "F.SilkS")
			(effects
				(font
					(size 0.7874 0.5842)
					(thickness 0.1524)
				)
				(justify left)
			)
		)
		(property "Value" ""
			(at 0 0 90)
			(layer "F.Fab")
			(effects
				(font
					(size 1.27 1.27)
				)
			)
		)
		(duplicate_pad_numbers_are_jumpers no)
		(fp_line
			(start 3.400044 -0.575056)
			(end 3.400044 -0.446532)
			(stroke
				(width 0.1524)
				(type default)
			)
			(layer "F.SilkS")
		)
		(fp_line
			(start 0.299974 -0.575056)
			(end 1.499362 -0.57404)
			(stroke
				(width 0.1524)
				(type default)
			)
			(layer "F.SilkS")
		)
		(fp_line
			(start 2.16662 -0.57404)
			(end 3.400044 -0.575056)
			(stroke
				(width 0.1524)
				(type default)
			)
			(layer "F.SilkS")
		)
		(fp_line
			(start 1.499362 -0.57404)
			(end 1.84912 -0.067056)
			(stroke
				(width 0.1524)
				(type default)
			)
			(layer "F.SilkS")
		)
		(fp_line
			(start 0.299974 -0.421132)
			(end 0.299974 -0.575056)
			(stroke
				(width 0.1524)
				(type default)
			)
			(layer "F.SilkS")
		)
		(fp_line
			(start 1.84912 -0.067056)
			(end 2.16662 -0.57404)
			(stroke
				(width 0.1524)
				(type default)
			)
			(layer "F.SilkS")
		)
		(fp_line
			(start 3.400044 2.271268)
			(end 3.400044 2.525014)
			(stroke
				(width 0.1524)
				(type default)
			)
			(layer "F.SilkS")
		)
		(fp_line
			(start 3.400044 2.525014)
			(end 0.299974 2.525014)
			(stroke
				(width 0.1524)
				(type default)
			)
			(layer "F.SilkS")
		)
		(fp_line
			(start 0.299974 2.525014)
			(end 0.299974 2.271268)
			(stroke
				(width 0.1524)
				(type default)
			)
			(layer "F.SilkS")
		)
		(fp_circle
			(center 1.113282 -0.015494)
			(end 1.113282 0.211582)
			(stroke
				(width 0.1524)
				(type default)
			)
			(fill no)
			(layer "F.SilkS")
		)
		(fp_poly
			(pts
				(xy -1.030986 -1.434084) (xy -1.537208 -0.928116) (xy -0.516636 -0.439928)
			)
			(stroke
				(width 0)
				(type default)
			)
			(fill yes)
			(layer "F.SilkS")
		)
		(fp_poly
			(pts
				(xy 0.299974 2.525014) (xy 3.400044 2.525014) (xy 3.400044 2.219706) (xy 4.415282 2.219706) (xy 4.415282 -0.269494)
				(xy 3.400044 -0.269494) (xy 3.400044 -0.575056) (xy 0.299974 -0.575056) (xy 0.299974 -0.269494)
				(xy -0.715518 -0.269494) (xy -0.715518 2.219706) (xy 0.299974 2.219706)
			)
			(stroke
				(width 0)
				(type default)
			)
			(fill no)
			(layer "F.CrtYd")
		)
		(fp_line
			(start 3.400044 -0.575056)
			(end 3.400044 2.525014)
			(stroke
				(width 0.1)
				(type default)
			)
			(layer "F.Fab")
		)
		(fp_line
			(start 0.299974 -0.575056)
			(end 3.400044 -0.575056)
			(stroke
				(width 0.1)
				(type default)
			)
			(layer "F.Fab")
		)
		(fp_line
			(start 3.400044 2.525014)
			(end 0.299974 2.525014)
			(stroke
				(width 0.1)
				(type default)
			)
			(layer "F.Fab")
		)
		(fp_line
			(start 0.299974 2.525014)
			(end 0.299974 -0.575056)
			(stroke
				(width 0.1)
				(type default)
			)
			(layer "F.Fab")
		)
		(fp_poly
			(pts
				(xy -2.4892 -0.440944) (xy -2.4892 0.274828) (xy -1.4224 -0.1016)
			)
			(stroke
				(width 0)
				(type default)
			)
			(fill yes)
			(layer "F.Fab")
		)
		(fp_text user "8"
			(at 4.099306 -0.719328 0)
			(unlocked yes)
			(layer "F.SilkS")
			(effects
				(font
					(size 0.635 0.4064)
					(thickness 0.1524)
				)
				(justify left)
			)
		)
		(fp_text user "1"
			(at -1.166622 0.17526 0)
			(unlocked yes)
			(layer "F.SilkS")
			(effects
				(font
					(size 0.635 0.4064)
					(thickness 0.1524)
				)
				(justify left)
			)
		)
		(fp_text user "5"
			(at 3.778758 2.855722 0)
			(unlocked yes)
			(layer "F.SilkS")
			(effects
				(font
					(size 0.635 0.4064)
					(thickness 0.1524)
				)
				(justify left)
			)
		)
		(fp_text user "4"
			(at 0.01651 3.070098 0)
			(unlocked yes)
			(layer "F.SilkS")
			(effects
				(font
					(size 0.635 0.4064)
					(thickness 0.1524)
				)
				(justify left)
			)
		)
		(fp_text user "1"
			(at -1.397 -0.100101 90)
			(unlocked yes)
			(layer "F.Fab")
			(effects
				(font
					(size 0.786892 0.583946)
					(thickness 0.000001)
				)
				(justify left)
			)
		)
		(fp_text user "8"
			(at 4.572 -0.074701 90)
			(unlocked yes)
			(layer "F.Fab")
			(effects
				(font
					(size 0.786892 0.583946)
					(thickness 0.000001)
				)
				(justify left)
			)
		)
		(fp_text user "5"
			(at 4.5974 2.008099 90)
			(unlocked yes)
			(layer "F.Fab")
			(effects
				(font
					(size 0.786892 0.583946)
					(thickness 0.000001)
				)
				(justify left)
			)
		)
		(fp_text user "4"
			(at -1.4986 2.033499 90)
			(unlocked yes)
			(layer "F.Fab")
			(effects
				(font
					(size 0.786892 0.583946)
					(thickness 0.000001)
				)
				(justify left)
			)
		)
		(pad "1" smd rect
			(at 0 0)
			(size 0.4318 1.3208)
			(layers "F.Cu" "F.Mask" "F.Paste")
			(net "GFX_BUF_EN_N")
		)
		(pad "2" smd rect
			(at 0 0.649986)
			(size 0.4318 1.3208)
			(layers "F.Cu" "F.Mask" "F.Paste")
			(net "BMC_NODE1_GFX_VSYNC")
		)
		(pad "3" smd rect
			(at 0 1.299972)
			(size 0.4318 1.3208)
			(layers "F.Cu" "F.Mask" "F.Paste")
			(net "VGA_HSYNC")
		)
		(pad "4" smd rect
			(at 0 1.949958)
			(size 0.4318 1.3208)
			(layers "F.Cu" "F.Mask" "F.Paste")
			(net "GND")
		)
		(pad "5" smd rect
			(at 3.700018 1.949958)
			(size 0.4318 1.3208)
			(layers "F.Cu" "F.Mask" "F.Paste")
			(net "BMC_NODE1_GFX_HSYNC")
		)
		(pad "6" smd rect
			(at 3.700018 1.299972)
			(size 0.4318 1.3208)
			(layers "F.Cu" "F.Mask" "F.Paste")
			(net "VGA_VSYNC")
		)
		(pad "7" smd rect
			(at 3.700018 0.649986)
			(size 0.4318 1.3208)
			(layers "F.Cu" "F.Mask" "F.Paste")
			(net "GFX_BUF_EN_N")
		)
		(pad "8" smd rect
			(at 3.700018 0)
			(size 0.4318 1.3208)
			(layers "F.Cu" "F.Mask" "F.Paste")
			(net "P5V_NODE1")
		)
	)
	(footprint ""
		(layer "F.Cu")
		(at 148.122894 -167.093392 180)
		(property "Reference" "C907"
			(at 1.508252 0.927862 0)
			(unlocked yes)
			(layer "F.SilkS")
			(effects
				(font
					(size 0.7874 0.5842)
					(thickness 0.1524)
				)
				(justify left)
			)
		)
		(property "Value" ""
			(at 0 0 180)
			(layer "F.Fab")
			(effects
				(font
					(size 1.27 1.27)
				)
			)
		)
		(duplicate_pad_numbers_are_jumpers no)
		(fp_line
			(start 0.7874 0.4064)
			(end -0.7874 0.4064)
			(stroke
				(width 0.1524)
				(type default)
			)
			(layer "F.SilkS")
		)
		(fp_line
			(start 0.7874 -0.4064)
			(end 0.7874 0.4064)
			(stroke
				(width 0.1524)
				(type default)
			)
			(layer "F.SilkS")
		)
		(fp_line
			(start 0 0.381)
			(end 0 -0.381)
			(stroke
				(width 0.1524)
				(type default)
			)
			(layer "F.SilkS")
		)
		(fp_line
			(start -0.7874 0.4064)
			(end -0.7874 -0.4064)
			(stroke
				(width 0.1524)
				(type default)
			)
			(layer "F.SilkS")
		)
		(fp_line
			(start -0.7874 -0.4064)
			(end 0.7874 -0.4064)
			(stroke
				(width 0.1524)
				(type default)
			)
			(layer "F.SilkS")
		)
		(fp_poly
			(pts
				(xy -0.5334 0.254) (xy -0.635 0.254) (xy -0.635 0.2286) (xy -0.635 -0.254) (xy -0.5334 -0.254) (xy -0.5334 -0.2794)
				(xy 0.5334 -0.2794) (xy 0.5334 -0.254) (xy 0.635 -0.254) (xy 0.635 0.254) (xy 0.5334 0.254) (xy 0.5334 0.2794)
				(xy -0.508 0.2794) (xy -0.5334 0.2794)
			)
			(stroke
				(width 0)
				(type default)
			)
			(fill no)
			(layer "F.CrtYd")
		)
		(pad "1" smd rect
			(at 0.40005 0 180)
			(size 0.4572 0.508)
			(layers "F.Cu" "F.Mask" "F.Paste")
			(net "P3V3_NODE1")
		)
		(pad "2" smd rect
			(at -0.40005 0 180)
			(size 0.4572 0.508)
			(layers "F.Cu" "F.Mask" "F.Paste")
			(net "GND")
		)
	)
	(footprint ""
		(layer "F.Cu")
		(at 128.517904 -162.25012)
		(property "Reference" "R669"
			(at -61.67882 109.81436 0)
			(unlocked yes)
			(layer "F.SilkS")
			(effects
				(font
					(size 0.7874 0.5842)
					(thickness 0.1524)
				)
				(justify left)
			)
		)
		(property "Value" ""
			(at 0 0 0)
			(layer "F.Fab")
			(effects
				(font
					(size 1.27 1.27)
				)
			)
		)
		(duplicate_pad_numbers_are_jumpers no)
		(fp_line
			(start -0.7874 -0.4064)
			(end 0.7874 -0.4064)
			(stroke
				(width 0.1524)
				(type default)
			)
			(layer "F.SilkS")
		)
		(fp_line
			(start -0.7874 0.4064)
			(end -0.7874 -0.4064)
			(stroke
				(width 0.1524)
				(type default)
			)
			(layer "F.SilkS")
		)
		(fp_line
			(start 0.7874 -0.4064)
			(end 0.7874 0.4064)
			(stroke
				(width 0.1524)
				(type default)
			)
			(layer "F.SilkS")
		)
		(fp_line
			(start 0.7874 0.4064)
			(end -0.7874 0.4064)
			(stroke
				(width 0.1524)
				(type default)
			)
			(layer "F.SilkS")
		)
		(fp_poly
			(pts
				(xy -0.508 0.2794) (xy -0.508 0.2286) (xy -0.635 0.2286) (xy -0.635 -0.254) (xy -0.5334 -0.254)
				(xy -0.5334 -0.2794) (xy 0.5334 -0.2794) (xy 0.5334 -0.254) (xy 0.635 -0.254) (xy 0.635 0.254) (xy 0.5334 0.254)
				(xy 0.5334 0.2794)
			)
			(stroke
				(width 0)
				(type default)
			)
			(fill no)
			(layer "F.CrtYd")
		)
		(pad "1" smd rect
			(at 0.40005 0)
			(size 0.4572 0.508)
			(layers "F.Cu" "F.Mask" "F.Paste")
			(net "P3V3_NODE1")
		)
		(pad "2" smd rect
			(at -0.40005 0)
			(size 0.4572 0.508)
			(layers "F.Cu" "F.Mask" "F.Paste")
			(net "I2C_PSU3_SCL_MOS")
		)
	)
	(footprint ""
		(layer "F.Cu")
		(at 105.191814 -104.85882 180)
		(property "Reference" "PC123"
			(at 6.020054 0.747014 0)
			(unlocked yes)
			(layer "F.SilkS")
			(effects
				(font
					(size 0.7874 0.5842)
					(thickness 0.1524)
				)
				(justify left)
			)
		)
		(property "Value" ""
			(at 0 0 180)
			(layer "F.Fab")
			(effects
				(font
					(size 1.27 1.27)
				)
			)
		)
		(duplicate_pad_numbers_are_jumpers no)
		(fp_line
			(start 1.905 0.8636)
			(end -1.905 0.8636)
			(stroke
				(width 0.1524)
				(type default)
			)
			(layer "F.SilkS")
		)
		(fp_line
			(start 1.905 -0.8636)
			(end 1.905 0.8636)
			(stroke
				(width 0.1524)
				(type default)
			)
			(layer "F.SilkS")
		)
		(fp_line
			(start 0 0.8382)
			(end 0 -0.8382)
			(stroke
				(width 0.1524)
				(type default)
			)
			(layer "F.SilkS")
		)
		(fp_line
			(start -1.905 0.8636)
			(end -1.905 -0.8636)
			(stroke
				(width 0.1524)
				(type default)
			)
			(layer "F.SilkS")
		)
		(fp_line
			(start -1.905 -0.8636)
			(end 1.905 -0.8636)
			(stroke
				(width 0.1524)
				(type default)
			)
			(layer "F.SilkS")
		)
		(fp_rect
			(start -1.524 0.7366)
			(end 1.524 -0.7366)
			(stroke
				(width 0)
				(type default)
			)
			(fill no)
			(layer "F.CrtYd")
		)
		(pad "1" smd rect
			(at 0.94996 0 180)
			(size 1.1176 1.3716)
			(layers "F.Cu" "F.Mask" "F.Paste")
			(net "GND")
		)
		(pad "2" smd rect
			(at -0.94996 0 180)
			(size 1.1176 1.3716)
			(layers "F.Cu" "F.Mask" "F.Paste")
			(net "PV_VCCP_NODE1")
		)
	)
	(footprint ""
		(layer "F.Cu")
		(at 144.916652 -137.36955 180)
		(property "Reference" "R263"
			(at 0.990346 -17.103344 0)
			(unlocked yes)
			(layer "F.SilkS")
			(effects
				(font
					(size 0.7874 0.5842)
					(thickness 0.1524)
				)
				(justify left)
			)
		)
		(property "Value" ""
			(at 0 0 180)
			(layer "F.Fab")
			(effects
				(font
					(size 1.27 1.27)
				)
			)
		)
		(duplicate_pad_numbers_are_jumpers no)
		(fp_line
			(start 0.7874 0.4064)
			(end -0.7874 0.4064)
			(stroke
				(width 0.1524)
				(type default)
			)
			(layer "F.SilkS")
		)
		(fp_line
			(start 0.7874 -0.4064)
			(end 0.7874 0.4064)
			(stroke
				(width 0.1524)
				(type default)
			)
			(layer "F.SilkS")
		)
		(fp_line
			(start -0.7874 0.4064)
			(end -0.7874 -0.4064)
			(stroke
				(width 0.1524)
				(type default)
			)
			(layer "F.SilkS")
		)
		(fp_line
			(start -0.7874 -0.4064)
			(end 0.7874 -0.4064)
			(stroke
				(width 0.1524)
				(type default)
			)
			(layer "F.SilkS")
		)
		(fp_poly
			(pts
				(xy -0.508 0.2794) (xy -0.508 0.2286) (xy -0.635 0.2286) (xy -0.635 -0.254) (xy -0.5334 -0.254)
				(xy -0.5334 -0.2794) (xy 0.5334 -0.2794) (xy 0.5334 -0.254) (xy 0.635 -0.254) (xy 0.635 0.254) (xy 0.5334 0.254)
				(xy 0.5334 0.2794)
			)
			(stroke
				(width 0)
				(type default)
			)
			(fill no)
			(layer "F.CrtYd")
		)
		(pad "1" smd rect
			(at 0.40005 0 180)
			(size 0.4572 0.508)
			(layers "F.Cu" "F.Mask" "F.Paste")
			(net "PCIE_SW_WAKE_N")
		)
		(pad "2" smd rect
			(at -0.40005 0 180)
			(size 0.4572 0.508)
			(layers "F.Cu" "F.Mask" "F.Paste")
			(net "IRQ_LVC3_CPU_NODE1_WAKE_L")
		)
	)
	(footprint ""
		(layer "F.Cu")
		(at 52.81676 -188.126624 90)
		(property "Reference" "R845"
			(at 4.548886 0.205232 90)
			(unlocked yes)
			(layer "F.SilkS")
			(effects
				(font
					(size 0.7874 0.5842)
					(thickness 0.1524)
				)
				(justify left)
			)
		)
		(property "Value" ""
			(at 0 0 90)
			(layer "F.Fab")
			(effects
				(font
					(size 1.27 1.27)
				)
			)
		)
		(duplicate_pad_numbers_are_jumpers no)
		(fp_line
			(start 0.7874 -0.4064)
			(end 0.7874 0.4064)
			(stroke
				(width 0.1524)
				(type default)
			)
			(layer "F.SilkS")
		)
		(fp_line
			(start -0.7874 -0.4064)
			(end 0.7874 -0.4064)
			(stroke
				(width 0.1524)
				(type default)
			)
			(layer "F.SilkS")
		)
		(fp_line
			(start 0.7874 0.4064)
			(end -0.7874 0.4064)
			(stroke
				(width 0.1524)
				(type default)
			)
			(layer "F.SilkS")
		)
		(fp_line
			(start -0.7874 0.4064)
			(end -0.7874 -0.4064)
			(stroke
				(width 0.1524)
				(type default)
			)
			(layer "F.SilkS")
		)
		(fp_poly
			(pts
				(xy -0.508 0.2794) (xy -0.508 0.2286) (xy -0.635 0.2286) (xy -0.635 -0.254) (xy -0.5334 -0.254)
				(xy -0.5334 -0.2794) (xy 0.5334 -0.2794) (xy 0.5334 -0.254) (xy 0.635 -0.254) (xy 0.635 0.254) (xy 0.5334 0.254)
				(xy 0.5334 0.2794)
			)
			(stroke
				(width 0)
				(type default)
			)
			(fill no)
			(layer "F.CrtYd")
		)
		(pad "1" smd rect
			(at 0.40005 0 90)
			(size 0.4572 0.508)
			(layers "F.Cu" "F.Mask" "F.Paste")
			(net "PSU1_AC_OK_R")
		)
		(pad "2" smd rect
			(at -0.40005 0 90)
			(size 0.4572 0.508)
			(layers "F.Cu" "F.Mask" "F.Paste")
			(net "GND")
		)
	)
	(footprint ""
		(layer "F.Cu")
		(at 73.148698 -17.679416 90)
		(property "Reference" "C151"
			(at -4.60629 6.316472 90)
			(unlocked yes)
			(layer "F.SilkS")
			(effects
				(font
					(size 0.7874 0.5842)
					(thickness 0.1524)
				)
				(justify left)
			)
		)
		(property "Value" ""
			(at 0 0 90)
			(layer "F.Fab")
			(effects
				(font
					(size 1.27 1.27)
				)
			)
		)
		(duplicate_pad_numbers_are_jumpers no)
		(fp_line
			(start 0.7874 -0.4064)
			(end 0.7874 0.4064)
			(stroke
				(width 0.1524)
				(type default)
			)
			(layer "F.SilkS")
		)
		(fp_line
			(start -0.7874 -0.4064)
			(end 0.7874 -0.4064)
			(stroke
				(width 0.1524)
				(type default)
			)
			(layer "F.SilkS")
		)
		(fp_line
			(start 0 0.381)
			(end 0 -0.381)
			(stroke
				(width 0.1524)
				(type default)
			)
			(layer "F.SilkS")
		)
		(fp_line
			(start 0.7874 0.4064)
			(end -0.7874 0.4064)
			(stroke
				(width 0.1524)
				(type default)
			)
			(layer "F.SilkS")
		)
		(fp_line
			(start -0.7874 0.4064)
			(end -0.7874 -0.4064)
			(stroke
				(width 0.1524)
				(type default)
			)
			(layer "F.SilkS")
		)
		(fp_poly
			(pts
				(xy -0.5334 0.254) (xy -0.635 0.254) (xy -0.635 0.2286) (xy -0.635 -0.254) (xy -0.5334 -0.254) (xy -0.5334 -0.2794)
				(xy 0.5334 -0.2794) (xy 0.5334 -0.254) (xy 0.635 -0.254) (xy 0.635 0.254) (xy 0.5334 0.254) (xy 0.5334 0.2794)
				(xy -0.508 0.2794) (xy -0.5334 0.2794)
			)
			(stroke
				(width 0)
				(type default)
			)
			(fill no)
			(layer "F.CrtYd")
		)
		(pad "1" smd rect
			(at 0.40005 0 90)
			(size 0.4572 0.508)
			(layers "F.Cu" "F.Mask" "F.Paste")
			(net "PV_VDDR_NODE1")
		)
		(pad "2" smd rect
			(at -0.40005 0 90)
			(size 0.4572 0.508)
			(layers "F.Cu" "F.Mask" "F.Paste")
			(net "GND")
		)
	)
	(footprint ""
		(layer "F.Cu")
		(at 123.70816 -166.523416)
		(property "Reference" "R623"
			(at 30.075378 46.17339 0)
			(unlocked yes)
			(layer "F.SilkS")
			(effects
				(font
					(size 0.7874 0.5842)
					(thickness 0.1524)
				)
				(justify left)
			)
		)
		(property "Value" ""
			(at 0 0 0)
			(layer "F.Fab")
			(effects
				(font
					(size 1.27 1.27)
				)
			)
		)
		(duplicate_pad_numbers_are_jumpers no)
		(fp_line
			(start -0.7874 -0.4064)
			(end 0.7874 -0.4064)
			(stroke
				(width 0.1524)
				(type default)
			)
			(layer "F.SilkS")
		)
		(fp_line
			(start -0.7874 0.4064)
			(end -0.7874 -0.4064)
			(stroke
				(width 0.1524)
				(type default)
			)
			(layer "F.SilkS")
		)
		(fp_line
			(start 0.7874 -0.4064)
			(end 0.7874 0.4064)
			(stroke
				(width 0.1524)
				(type default)
			)
			(layer "F.SilkS")
		)
		(fp_line
			(start 0.7874 0.4064)
			(end -0.7874 0.4064)
			(stroke
				(width 0.1524)
				(type default)
			)
			(layer "F.SilkS")
		)
		(fp_poly
			(pts
				(xy -0.508 0.2794) (xy -0.508 0.2286) (xy -0.635 0.2286) (xy -0.635 -0.254) (xy -0.5334 -0.254)
				(xy -0.5334 -0.2794) (xy 0.5334 -0.2794) (xy 0.5334 -0.254) (xy 0.635 -0.254) (xy 0.635 0.254) (xy 0.5334 0.254)
				(xy 0.5334 0.2794)
			)
			(stroke
				(width 0)
				(type default)
			)
			(fill no)
			(layer "F.CrtYd")
		)
		(pad "1" smd rect
			(at 0.40005 0)
			(size 0.4572 0.508)
			(layers "F.Cu" "F.Mask" "F.Paste")
			(net "CPLD_WDT1")
		)
		(pad "2" smd rect
			(at -0.40005 0)
			(size 0.4572 0.508)
			(layers "F.Cu" "F.Mask" "F.Paste")
			(net "CPLD_WDT1_R")
		)
	)
	(footprint ""
		(layer "F.Cu")
		(at 57.973468 -118.960646 -90)
		(property "Reference" "R343"
			(at 5.19049 -1.117092 90)
			(unlocked yes)
			(layer "F.SilkS")
			(effects
				(font
					(size 0.7874 0.5842)
					(thickness 0.1524)
				)
				(justify left)
			)
		)
		(property "Value" ""
			(at 0 0 270)
			(layer "F.Fab")
			(effects
				(font
					(size 1.27 1.27)
				)
			)
		)
		(duplicate_pad_numbers_are_jumpers no)
		(fp_line
			(start -0.7874 0.4064)
			(end -0.7874 -0.4064)
			(stroke
				(width 0.1524)
				(type default)
			)
			(layer "F.SilkS")
		)
		(fp_line
			(start 0.7874 0.4064)
			(end -0.7874 0.4064)
			(stroke
				(width 0.1524)
				(type default)
			)
			(layer "F.SilkS")
		)
		(fp_line
			(start -0.7874 -0.4064)
			(end 0.7874 -0.4064)
			(stroke
				(width 0.1524)
				(type default)
			)
			(layer "F.SilkS")
		)
		(fp_line
			(start 0.7874 -0.4064)
			(end 0.7874 0.4064)
			(stroke
				(width 0.1524)
				(type default)
			)
			(layer "F.SilkS")
		)
		(fp_poly
			(pts
				(xy -0.508 0.2794) (xy -0.508 0.2286) (xy -0.635 0.2286) (xy -0.635 -0.254) (xy -0.5334 -0.254)
				(xy -0.5334 -0.2794) (xy 0.5334 -0.2794) (xy 0.5334 -0.254) (xy 0.635 -0.254) (xy 0.635 0.254) (xy 0.5334 0.254)
				(xy 0.5334 0.2794)
			)
			(stroke
				(width 0)
				(type default)
			)
			(fill no)
			(layer "F.CrtYd")
		)
		(pad "1" smd rect
			(at 0.40005 0 270)
			(size 0.4572 0.508)
			(layers "F.Cu" "F.Mask" "F.Paste")
			(net "P3V3_NODE1")
		)
		(pad "2" smd rect
			(at -0.40005 0 270)
			(size 0.4572 0.508)
			(layers "F.Cu" "F.Mask" "F.Paste")
			(net "BMC_ROMD3")
		)
	)
	(footprint ""
		(layer "F.Cu")
		(at 80.99552 -158.242508 90)
		(property "Reference" "PR1"
			(at -0.945388 4.343146 90)
			(unlocked yes)
			(layer "F.SilkS")
			(effects
				(font
					(size 0.7874 0.5842)
					(thickness 0.1524)
				)
				(justify left)
			)
		)
		(property "Value" ""
			(at 0 0 90)
			(layer "F.Fab")
			(effects
				(font
					(size 1.27 1.27)
				)
			)
		)
		(duplicate_pad_numbers_are_jumpers no)
		(fp_line
			(start 0.7874 -0.4064)
			(end 0.7874 0.4064)
			(stroke
				(width 0.1524)
				(type default)
			)
			(layer "F.SilkS")
		)
		(fp_line
			(start -0.7874 -0.4064)
			(end 0.7874 -0.4064)
			(stroke
				(width 0.1524)
				(type default)
			)
			(layer "F.SilkS")
		)
		(fp_line
			(start 0.7874 0.4064)
			(end -0.7874 0.4064)
			(stroke
				(width 0.1524)
				(type default)
			)
			(layer "F.SilkS")
		)
		(fp_line
			(start -0.7874 0.4064)
			(end -0.7874 -0.4064)
			(stroke
				(width 0.1524)
				(type default)
			)
			(layer "F.SilkS")
		)
		(fp_poly
			(pts
				(xy -0.508 0.2794) (xy -0.508 0.2286) (xy -0.635 0.2286) (xy -0.635 -0.254) (xy -0.5334 -0.254)
				(xy -0.5334 -0.2794) (xy 0.5334 -0.2794) (xy 0.5334 -0.254) (xy 0.635 -0.254) (xy 0.635 0.254) (xy 0.5334 0.254)
				(xy 0.5334 0.2794)
			)
			(stroke
				(width 0)
				(type default)
			)
			(fill no)
			(layer "F.CrtYd")
		)
		(pad "1" smd rect
			(at 0.40005 0 90)
			(size 0.4572 0.508)
			(layers "F.Cu" "F.Mask" "F.Paste")
			(net "P5V_STB_NODE1_VREG5")
		)
		(pad "2" smd rect
			(at -0.40005 0 90)
			(size 0.4572 0.508)
			(layers "F.Cu" "F.Mask" "F.Paste")
			(net "PWRGD_NODE1_P5V_STB_PG")
		)
	)
	(footprint ""
		(layer "F.Cu")
		(at 134.35457 -26.569416 -90)
		(property "Reference" "R1148"
			(at 5.325618 -0.241808 90)
			(unlocked yes)
			(layer "F.SilkS")
			(effects
				(font
					(size 0.7874 0.5842)
					(thickness 0.1524)
				)
				(justify left)
			)
		)
		(property "Value" ""
			(at 0 0 270)
			(layer "F.Fab")
			(effects
				(font
					(size 1.27 1.27)
				)
			)
		)
		(duplicate_pad_numbers_are_jumpers no)
		(fp_line
			(start -0.7874 0.4064)
			(end -0.7874 -0.4064)
			(stroke
				(width 0.1524)
				(type default)
			)
			(layer "F.SilkS")
		)
		(fp_line
			(start 0.7874 0.4064)
			(end -0.7874 0.4064)
			(stroke
				(width 0.1524)
				(type default)
			)
			(layer "F.SilkS")
		)
		(fp_line
			(start -0.7874 -0.4064)
			(end 0.7874 -0.4064)
			(stroke
				(width 0.1524)
				(type default)
			)
			(layer "F.SilkS")
		)
		(fp_line
			(start 0.7874 -0.4064)
			(end 0.7874 0.4064)
			(stroke
				(width 0.1524)
				(type default)
			)
			(layer "F.SilkS")
		)
		(fp_poly
			(pts
				(xy -0.508 0.2794) (xy -0.508 0.2286) (xy -0.635 0.2286) (xy -0.635 -0.254) (xy -0.5334 -0.254)
				(xy -0.5334 -0.2794) (xy 0.5334 -0.2794) (xy 0.5334 -0.254) (xy 0.635 -0.254) (xy 0.635 0.254) (xy 0.5334 0.254)
				(xy 0.5334 0.2794)
			)
			(stroke
				(width 0)
				(type default)
			)
			(fill no)
			(layer "F.CrtYd")
		)
		(pad "1" smd rect
			(at 0.40005 0 270)
			(size 0.4572 0.508)
			(layers "F.Cu" "F.Mask" "F.Paste")
			(net "P3V3_STB_NODE1")
		)
		(pad "2" smd rect
			(at -0.40005 0 270)
			(size 0.4572 0.508)
			(layers "F.Cu" "F.Mask" "F.Paste")
			(net "SIO_PIN83")
		)
	)
	(footprint ""
		(layer "F.Cu")
		(at 118.376954 -24.064722 180)
		(property "Reference" "R1125"
			(at 0.435864 -2.038858 0)
			(unlocked yes)
			(layer "F.SilkS")
			(effects
				(font
					(size 0.7874 0.5842)
					(thickness 0.1524)
				)
				(justify left)
			)
		)
		(property "Value" ""
			(at 0 0 180)
			(layer "F.Fab")
			(effects
				(font
					(size 1.27 1.27)
				)
			)
		)
		(duplicate_pad_numbers_are_jumpers no)
		(fp_line
			(start 0.7874 0.4064)
			(end -0.7874 0.4064)
			(stroke
				(width 0.1524)
				(type default)
			)
			(layer "F.SilkS")
		)
		(fp_line
			(start 0.7874 -0.4064)
			(end 0.7874 0.4064)
			(stroke
				(width 0.1524)
				(type default)
			)
			(layer "F.SilkS")
		)
		(fp_line
			(start -0.7874 0.4064)
			(end -0.7874 -0.4064)
			(stroke
				(width 0.1524)
				(type default)
			)
			(layer "F.SilkS")
		)
		(fp_line
			(start -0.7874 -0.4064)
			(end 0.7874 -0.4064)
			(stroke
				(width 0.1524)
				(type default)
			)
			(layer "F.SilkS")
		)
		(fp_poly
			(pts
				(xy -0.508 0.2794) (xy -0.508 0.2286) (xy -0.635 0.2286) (xy -0.635 -0.254) (xy -0.5334 -0.254)
				(xy -0.5334 -0.2794) (xy 0.5334 -0.2794) (xy 0.5334 -0.254) (xy 0.635 -0.254) (xy 0.635 0.254) (xy 0.5334 0.254)
				(xy 0.5334 0.2794)
			)
			(stroke
				(width 0)
				(type default)
			)
			(fill no)
			(layer "F.CrtYd")
		)
		(pad "1" smd rect
			(at 0.40005 0 180)
			(size 0.4572 0.508)
			(layers "F.Cu" "F.Mask" "F.Paste")
			(net "PV_VTT_DDR_NODE1_REFIN")
		)
		(pad "2" smd rect
			(at -0.40005 0 180)
			(size 0.4572 0.508)
			(layers "F.Cu" "F.Mask" "F.Paste")
			(net "GND")
		)
	)
	(footprint ""
		(layer "F.Cu")
		(at 107.471464 -134.897876 180)
		(property "Reference" "PU8"
			(at -0.989076 3.710432 0)
			(unlocked yes)
			(layer "F.SilkS")
			(effects
				(font
					(size 0.7874 0.5842)
					(thickness 0.1524)
				)
				(justify left)
			)
		)
		(property "Value" ""
			(at 0 0 180)
			(layer "F.Fab")
			(effects
				(font
					(size 1.27 1.27)
				)
			)
		)
		(duplicate_pad_numbers_are_jumpers no)
		(fp_line
			(start 4.162044 -1.800098)
			(end 3.146044 -1.800098)
			(stroke
				(width 0.1524)
				(type default)
			)
			(layer "F.SilkS")
		)
		(fp_line
			(start 3.657092 0.199898)
			(end 3.149092 0.199898)
			(stroke
				(width 0.1524)
				(type default)
			)
			(layer "F.SilkS")
		)
		(fp_line
			(start 2.525014 2.525014)
			(end 2.021586 2.525014)
			(stroke
				(width 0.1524)
				(type default)
			)
			(layer "F.SilkS")
		)
		(fp_line
			(start 2.525014 2.022602)
			(end 2.525014 2.525014)
			(stroke
				(width 0.1524)
				(type default)
			)
			(layer "F.SilkS")
		)
		(fp_line
			(start 2.525014 -2.525014)
			(end 2.525014 -2.028698)
			(stroke
				(width 0.1524)
				(type default)
			)
			(layer "F.SilkS")
		)
		(fp_line
			(start 2.021586 -2.525014)
			(end 2.525014 -2.525014)
			(stroke
				(width 0.1524)
				(type default)
			)
			(layer "F.SilkS")
		)
		(fp_line
			(start 1.800098 3.1496)
			(end 1.800098 4.1656)
			(stroke
				(width 0.1524)
				(type default)
			)
			(layer "F.SilkS")
		)
		(fp_line
			(start -0.199898 3.149092)
			(end -0.199898 3.657092)
			(stroke
				(width 0.1524)
				(type default)
			)
			(layer "F.SilkS")
		)
		(fp_line
			(start -1.800098 -4.161536)
			(end -1.800098 -3.145536)
			(stroke
				(width 0.1524)
				(type default)
			)
			(layer "F.SilkS")
		)
		(fp_line
			(start -2.029714 2.525014)
			(end -2.525014 2.525014)
			(stroke
				(width 0.1524)
				(type default)
			)
			(layer "F.SilkS")
		)
		(fp_line
			(start -2.525014 2.525014)
			(end -2.525014 2.022602)
			(stroke
				(width 0.1524)
				(type default)
			)
			(layer "F.SilkS")
		)
		(fp_line
			(start -2.525014 -2.028698)
			(end -2.525014 -2.525014)
			(stroke
				(width 0.1524)
				(type default)
			)
			(layer "F.SilkS")
		)
		(fp_line
			(start -2.525014 -2.525014)
			(end -2.029714 -2.525014)
			(stroke
				(width 0.1524)
				(type default)
			)
			(layer "F.SilkS")
		)
		(fp_line
			(start -3.143758 -0.199898)
			(end -3.651758 -0.199898)
			(stroke
				(width 0.1524)
				(type default)
			)
			(layer "F.SilkS")
		)
		(fp_line
			(start -3.146044 1.800098)
			(end -4.162044 1.800098)
			(stroke
				(width 0.1524)
				(type default)
			)
			(layer "F.SilkS")
		)
		(fp_poly
			(pts
				(xy -3.085592 -1.800098) (xy -3.771392 -2.104898) (xy -3.771392 -1.495298)
			)
			(stroke
				(width 0)
				(type default)
			)
			(fill yes)
			(layer "F.SilkS")
		)
		(fp_poly
			(pts
				(xy -2.525014 2.525014) (xy -1.940814 2.525014) (xy -1.940814 3.076702) (xy 1.945386 3.076702) (xy 1.945386 2.525014)
				(xy 2.525014 2.525014) (xy 2.525014 1.959102) (xy 3.062986 1.959102) (xy 3.062986 -1.952498) (xy 2.525014 -1.952498)
				(xy 2.525014 -2.525014) (xy 1.945386 -2.525014) (xy 1.945386 -3.070098) (xy -1.940814 -3.070098)
				(xy -1.940814 -2.525014) (xy -2.525014 -2.525014) (xy -2.525014 -1.952498) (xy -3.060954 -1.952498)
				(xy -3.060954 1.959102) (xy -2.525014 1.959102)
			)
			(stroke
				(width 0)
				(type default)
			)
			(fill no)
			(layer "F.CrtYd")
		)
		(fp_line
			(start 4.162044 -1.800098)
			(end 3.146044 -1.800098)
			(stroke
				(width 0.1)
				(type default)
			)
			(layer "F.Fab")
		)
		(fp_line
			(start 3.657092 0.199898)
			(end 3.149092 0.199898)
			(stroke
				(width 0.1)
				(type default)
			)
			(layer "F.Fab")
		)
		(fp_line
			(start 2.525014 2.525014)
			(end -2.525014 2.525014)
			(stroke
				(width 0.1)
				(type default)
			)
			(layer "F.Fab")
		)
		(fp_line
			(start 2.525014 -2.525014)
			(end 2.525014 2.525014)
			(stroke
				(width 0.1)
				(type default)
			)
			(layer "F.Fab")
		)
		(fp_line
			(start 1.800098 3.1496)
			(end 1.800098 4.1656)
			(stroke
				(width 0.1)
				(type default)
			)
			(layer "F.Fab")
		)
		(fp_line
			(start 0.199898 -3.654044)
			(end 0.199898 -3.146044)
			(stroke
				(width 0.1)
				(type default)
			)
			(layer "F.Fab")
		)
		(fp_line
			(start -0.199898 3.149092)
			(end -0.199898 3.657092)
			(stroke
				(width 0.1)
				(type default)
			)
			(layer "F.Fab")
		)
		(fp_line
			(start -1.800098 -4.161536)
			(end -1.800098 -3.145536)
			(stroke
				(width 0.1)
				(type default)
			)
			(layer "F.Fab")
		)
		(fp_line
			(start -2.525014 2.525014)
			(end -2.525014 -2.525014)
			(stroke
				(width 0.1)
				(type default)
			)
			(layer "F.Fab")
		)
		(fp_line
			(start -2.525014 -2.525014)
			(end 2.525014 -2.525014)
			(stroke
				(width 0.1)
				(type default)
			)
			(layer "F.Fab")
		)
		(fp_line
			(start -3.143758 -0.199898)
			(end -3.651758 -0.199898)
			(stroke
				(width 0.1)
				(type default)
			)
			(layer "F.Fab")
		)
		(fp_line
			(start -3.146044 1.800098)
			(end -4.162044 1.800098)
			(stroke
				(width 0.1)
				(type default)
			)
			(layer "F.Fab")
		)
		(fp_poly
			(pts
				(xy -3.085592 -1.800098) (xy -3.771392 -2.104898) (xy -3.771392 -1.495298)
			)
			(stroke
				(width 0)
				(type default)
			)
			(fill yes)
			(layer "F.Fab")
		)
		(fp_text user "30"
			(at 4.251706 -1.356614 0)
			(unlocked yes)
			(layer "F.SilkS")
			(effects
				(font
					(size 0.635 0.4064)
					(thickness 0.1524)
				)
				(justify left)
			)
		)
		(fp_text user "21"
			(at 3.979164 1.6256 0)
			(unlocked yes)
			(layer "F.SilkS")
			(effects
				(font
					(size 0.635 0.4064)
					(thickness 0.1524)
				)
				(justify left)
			)
		)
		(fp_text user "20"
			(at 3.64744 2.611374 0)
			(unlocked yes)
			(layer "F.SilkS")
			(effects
				(font
					(size 0.635 0.4064)
					(thickness 0.1524)
				)
				(justify left)
			)
		)
		(fp_text user "31"
			(at 2.902204 -3.089148 0)
			(unlocked yes)
			(layer "F.SilkS")
			(effects
				(font
					(size 0.635 0.4064)
					(thickness 0.1524)
				)
				(justify left)
			)
		)
		(fp_text user "40"
			(at -0.677164 -3.549142 0)
			(unlocked yes)
			(layer "F.SilkS")
			(effects
				(font
					(size 0.635 0.4064)
					(thickness 0.1524)
				)
				(justify left)
			)
		)
		(fp_text user "11"
			(at -2.017776 2.829052 0)
			(unlocked yes)
			(layer "F.SilkS")
			(effects
				(font
					(size 0.635 0.4064)
					(thickness 0.1524)
				)
				(justify left)
			)
		)
		(fp_text user "10"
			(at -3.087116 1.229614 0)
			(unlocked yes)
			(layer "F.SilkS")
			(effects
				(font
					(size 0.635 0.4064)
					(thickness 0.1524)
				)
				(justify left)
			)
		)
		(fp_text user "1"
			(at -3.214116 -2.677668 0)
			(unlocked yes)
			(layer "F.SilkS")
			(effects
				(font
					(size 0.7874 0.5842)
					(thickness 0.1524)
				)
				(justify left)
			)
		)
		(fp_text user "21"
			(at 2.787142 2.4892 180)
			(unlocked yes)
			(layer "F.Fab")
			(effects
				(font
					(size 0.7874 0.5842)
					(thickness 0.000001)
				)
				(justify left)
			)
		)
		(fp_text user "30"
			(at 2.714244 -2.49174 180)
			(unlocked yes)
			(layer "F.Fab")
			(effects
				(font
					(size 0.7874 0.5842)
					(thickness 0.000001)
				)
				(justify left)
			)
		)
		(fp_text user "20"
			(at 1.961896 3.435096 180)
			(unlocked yes)
			(layer "F.Fab")
			(effects
				(font
					(size 0.7874 0.5842)
					(thickness 0.000001)
				)
				(justify left)
			)
		)
		(fp_text user "31"
			(at 1.866646 -3.44424 180)
			(unlocked yes)
			(layer "F.Fab")
			(effects
				(font
					(size 0.7874 0.5842)
					(thickness 0.000001)
				)
				(justify left)
			)
		)
		(fp_text user "11"
			(at -3.085846 3.308096 180)
			(unlocked yes)
			(layer "F.Fab")
			(effects
				(font
					(size 0.7874 0.5842)
					(thickness 0.000001)
				)
				(justify left)
			)
		)
		(fp_text user "40"
			(at -3.336544 -3.193542 180)
			(unlocked yes)
			(layer "F.Fab")
			(effects
				(font
					(size 0.7874 0.5842)
					(thickness 0.000001)
				)
				(justify left)
			)
		)
		(fp_text user "1"
			(at -3.546094 -2.393442 180)
			(unlocked yes)
			(layer "F.Fab")
			(effects
				(font
					(size 0.7874 0.5842)
					(thickness 0.000001)
				)
				(justify left)
			)
		)
		(fp_text user "10"
			(at -4.085844 2.50825 180)
			(unlocked yes)
			(layer "F.Fab")
			(effects
				(font
					(size 0.7874 0.5842)
					(thickness 0.000001)
				)
				(justify left)
			)
		)
		(pad "1" smd rect
			(at -2.542794 -1.800098 90)
			(size 0.1778 0.9144)
			(layers "F.Cu" "F.Mask" "F.Paste")
			(net "VR_PVCCP_NODE1_BOOT1")
		)
		(pad "2" smd rect
			(at -2.525014 -1.400048 90)
			(size 0.1778 0.9652)
			(layers "F.Cu" "F.Mask" "F.Paste")
			(net "VR_PVCCP_NODE1_TONSET")
		)
		(pad "3" smd rect
			(at -2.525014 -0.999998 90)
			(size 0.1778 0.9652)
			(layers "F.Cu" "F.Mask" "F.Paste")
			(net "VR_PVCCP_NODE1_ISEN1P_CC")
		)
		(pad "4" smd rect
			(at -2.525014 -0.599948 90)
			(size 0.1778 0.9652)
			(layers "F.Cu" "F.Mask" "F.Paste")
			(net "ISENSE_PVCCP_NODE1_ISEN1N")
		)
		(pad "5" smd rect
			(at -2.525014 -0.199898 90)
			(size 0.1778 0.9652)
			(layers "F.Cu" "F.Mask" "F.Paste")
			(net "VR_PVCCP_NODE1_COMP")
		)
		(pad "6" smd rect
			(at -2.525014 0.199898 90)
			(size 0.1778 0.9652)
			(layers "F.Cu" "F.Mask" "F.Paste")
			(net "VR_PVCCP_NODE1_FB")
		)
		(pad "7" smd rect
			(at -2.525014 0.599948 90)
			(size 0.1778 0.9652)
			(layers "F.Cu" "F.Mask" "F.Paste")
			(net "VR_PVCCP_NODE1_RGND")
		)
		(pad "8" smd rect
			(at -2.525014 0.999998 90)
			(size 0.1778 0.9652)
			(layers "F.Cu" "F.Mask" "F.Paste")
			(net "AGND_PVCCP_NODE1")
		)
		(pad "9" smd rect
			(at -2.525014 1.400048 90)
			(size 0.1778 0.9652)
			(layers "F.Cu" "F.Mask" "F.Paste")
			(net "VR_PVCCP_NODE1_VCC")
		)
		(pad "10" smd rect
			(at -2.542794 1.800098 90)
			(size 0.1778 0.9144)
			(layers "F.Cu" "F.Mask" "F.Paste")
			(net "GND")
		)
		(pad "11" smd rect
			(at -1.800098 2.542794 180)
			(size 0.1778 0.9144)
			(layers "F.Cu" "F.Mask" "F.Paste")
			(net "VR_PVCCP_NODE1_SETINI")
		)
		(pad "12" smd rect
			(at -1.400048 2.525014 180)
			(size 0.1778 0.9652)
			(layers "F.Cu" "F.Mask" "F.Paste")
			(net "VR_PVCCP_NODE1_TEMPMAX")
		)
		(pad "13" smd rect
			(at -0.999998 2.525014 180)
			(size 0.1778 0.9652)
			(layers "F.Cu" "F.Mask" "F.Paste")
			(net "VR_PVCCP_NODE1_ICCMAX")
		)
		(pad "14" smd rect
			(at -0.599948 2.525014 180)
			(size 0.1778 0.9652)
			(layers "F.Cu" "F.Mask" "F.Paste")
			(net "P5V_STB_NODE1")
		)
		(pad "15" smd rect
			(at -0.199898 2.525014 180)
			(size 0.1778 0.9652)
			(layers "F.Cu" "F.Mask" "F.Paste")
			(net "VR_PVCCP_NODE1_TSEN")
		)
		(pad "16" smd rect
			(at 0.199898 2.525014 180)
			(size 0.1778 0.9652)
			(layers "F.Cu" "F.Mask" "F.Paste")
			(net "VR_PVCCP_NODE1_OCSET")
		)
		(pad "17" smd rect
			(at 0.599948 2.525014 180)
			(size 0.1778 0.9652)
			(layers "F.Cu" "F.Mask" "F.Paste")
			(net "VR_PVCCP_NODE1_VCC")
		)
		(pad "18" smd rect
			(at 0.999998 2.525014 180)
			(size 0.1778 0.9652)
			(layers "F.Cu" "F.Mask" "F.Paste")
			(net "P5V_STB_NODE1")
		)
		(pad "19" smd rect
			(at 1.400048 2.525014 180)
			(size 0.1778 0.9652)
			(layers "F.Cu" "F.Mask" "F.Paste")
			(net "VR_PVCCP_NODE1_IBIAS")
		)
		(pad "20" smd rect
			(at 1.800098 2.542794 180)
			(size 0.1778 0.9144)
			(layers "F.Cu" "F.Mask" "F.Paste")
			(net "H_CPU_NODE1_VR_HOT_L")
		)
		(pad "21" smd rect
			(at 2.542794 1.800098 90)
			(size 0.1778 0.9144)
			(layers "F.Cu" "F.Mask" "F.Paste")
			(net "PWRGD_NODE1_PVCCP_PG")
		)
		(pad "22" smd rect
			(at 2.525014 1.400048 90)
			(size 0.1778 0.9652)
			(layers "F.Cu" "F.Mask" "F.Paste")
			(net "GND")
		)
		(pad "23" smd rect
			(at 2.525014 0.999998 90)
			(size 0.1778 0.9652)
			(layers "F.Cu" "F.Mask" "F.Paste")
			(net "SVID_CPU_NODE1_PVCCP_ALERT_L")
		)
		(pad "24" smd rect
			(at 2.525014 0.599948 90)
			(size 0.1778 0.9652)
			(layers "F.Cu" "F.Mask" "F.Paste")
			(net "SVID_CPU_NODE1_DAT_R")
		)
		(pad "25" smd rect
			(at 2.525014 0.199898 90)
			(size 0.1778 0.9652)
			(layers "F.Cu" "F.Mask" "F.Paste")
			(net "SVID_CPU_NODE1_CLK_R")
		)
		(pad "26" smd rect
			(at 2.525014 -0.199898 90)
			(size 0.1778 0.9652)
			(layers "F.Cu" "F.Mask" "F.Paste")
			(net "GND")
		)
		(pad "27" smd rect
			(at 2.525014 -0.599948 90)
			(size 0.1778 0.9652)
			(layers "F.Cu" "F.Mask" "F.Paste")
			(net "Net_1697")
		)
		(pad "28" smd rect
			(at 2.525014 -0.999998 90)
			(size 0.1778 0.9652)
			(layers "F.Cu" "F.Mask" "F.Paste")
			(net "Net_1696")
		)
		(pad "29" smd rect
			(at 2.525014 -1.400048 90)
			(size 0.1778 0.9652)
			(layers "F.Cu" "F.Mask" "F.Paste")
			(net "P5V_STB_NODE1")
		)
		(pad "30" smd rect
			(at 2.542794 -1.800098 90)
			(size 0.1778 0.9144)
			(layers "F.Cu" "F.Mask" "F.Paste")
			(net "P5V_STB_NODE1")
		)
		(pad "31" smd rect
			(at 1.800098 -2.542794 180)
			(size 0.1778 0.9144)
			(layers "F.Cu" "F.Mask" "F.Paste")
			(net "GND")
		)
		(pad "32" smd rect
			(at 1.400048 -2.525014 180)
			(size 0.1778 0.9652)
			(layers "F.Cu" "F.Mask" "F.Paste")
			(net "VR_PVCCP_NODE1_EN")
		)
		(pad "33" smd rect
			(at 0.999998 -2.525014 180)
			(size 0.1778 0.9652)
			(layers "F.Cu" "F.Mask" "F.Paste")
			(net "Net_1695")
		)
		(pad "34" smd rect
			(at 0.599948 -2.525014 180)
			(size 0.1778 0.9652)
			(layers "F.Cu" "F.Mask" "F.Paste")
			(net "Net_1700")
		)
		(pad "35" smd rect
			(at 0.199898 -2.525014 180)
			(size 0.1778 0.9652)
			(layers "F.Cu" "F.Mask" "F.Paste")
			(net "Net_1699")
		)
		(pad "36" smd rect
			(at -0.199898 -2.525014 180)
			(size 0.1778 0.9652)
			(layers "F.Cu" "F.Mask" "F.Paste")
			(net "Net_1698")
		)
		(pad "37" smd rect
			(at -0.599948 -2.525014 180)
			(size 0.1778 0.9652)
			(layers "F.Cu" "F.Mask" "F.Paste")
			(net "VR_PVCCP_NODE1_PVCC")
		)
		(pad "38" smd rect
			(at -0.999998 -2.525014 180)
			(size 0.1778 0.9652)
			(layers "F.Cu" "F.Mask" "F.Paste")
			(net "VR_PVCCP_NODE1_LGATE1")
		)
		(pad "39" smd rect
			(at -1.400048 -2.525014 180)
			(size 0.1778 0.9652)
			(layers "F.Cu" "F.Mask" "F.Paste")
			(net "VR_PVCCP_NODE1_PHASE1")
		)
		(pad "40" smd rect
			(at -1.800098 -2.542794 180)
			(size 0.1778 0.9144)
			(layers "F.Cu" "F.Mask" "F.Paste")
			(net "VR_PVCCP_NODE1_UGATE1")
		)
		(pad "TH" smd rect
			(at 0 0 180)
			(size 3.4036 3.4036)
			(layers "F.Cu" "F.Mask" "F.Paste")
			(net "GND")
		)
		(zone
			(layer "F.Cu")
			(hatch none 0.5)
			(connect_pads
				(clearance 0)
			)
			(min_thickness 0.25)
			(keepout
				(tracks allowed)
				(vias not_allowed)
				(pads allowed)
				(copperpour not_allowed)
				(footprints allowed)
			)
			(placement
				(enabled no)
				(sheetname "")
			)
			(fill
				(thermal_gap 0.5)
				(thermal_bridge_width 0.5)
				(island_removal_mode 0)
			)
			(polygon
				(pts
					(xy 109.437678 -136.653778) (xy 109.437678 -132.919978) (xy 109.234478 -132.919978) (xy 105.500678 -132.919978)
					(xy 105.500678 -133.123178) (xy 105.500678 -136.882378) (xy 105.703878 -136.882378) (xy 109.437678 -136.882378)
					(xy 109.437678 -136.856978) (xy 109.437678 -136.679178) (xy 105.703878 -136.679178) (xy 105.703878 -136.653778)
					(xy 105.703878 -133.123178) (xy 109.234478 -133.123178) (xy 109.234478 -136.653778)
				)
			)
		)
	)
	(footprint ""
		(layer "F.Cu")
		(at 115.826032 -17.575276)
		(property "Reference" "R1242"
			(at -1.89992 1.406398 0)
			(unlocked yes)
			(layer "F.SilkS")
			(effects
				(font
					(size 0.7874 0.5842)
					(thickness 0.1524)
				)
				(justify left)
			)
		)
		(property "Value" ""
			(at 0 0 0)
			(layer "F.Fab")
			(effects
				(font
					(size 1.27 1.27)
				)
			)
		)
		(duplicate_pad_numbers_are_jumpers no)
		(fp_line
			(start -0.7874 -0.4064)
			(end 0.7874 -0.4064)
			(stroke
				(width 0.1524)
				(type default)
			)
			(layer "F.SilkS")
		)
		(fp_line
			(start -0.7874 0.4064)
			(end -0.7874 -0.4064)
			(stroke
				(width 0.1524)
				(type default)
			)
			(layer "F.SilkS")
		)
		(fp_line
			(start 0.7874 -0.4064)
			(end 0.7874 0.4064)
			(stroke
				(width 0.1524)
				(type default)
			)
			(layer "F.SilkS")
		)
		(fp_line
			(start 0.7874 0.4064)
			(end -0.7874 0.4064)
			(stroke
				(width 0.1524)
				(type default)
			)
			(layer "F.SilkS")
		)
		(fp_poly
			(pts
				(xy -0.508 0.2794) (xy -0.508 0.2286) (xy -0.635 0.2286) (xy -0.635 -0.254) (xy -0.5334 -0.254)
				(xy -0.5334 -0.2794) (xy 0.5334 -0.2794) (xy 0.5334 -0.254) (xy 0.635 -0.254) (xy 0.635 0.254) (xy 0.5334 0.254)
				(xy 0.5334 0.2794)
			)
			(stroke
				(width 0)
				(type default)
			)
			(fill no)
			(layer "F.CrtYd")
		)
		(pad "1" smd rect
			(at 0.40005 0)
			(size 0.4572 0.508)
			(layers "F.Cu" "F.Mask" "F.Paste")
			(net "GND")
		)
		(pad "2" smd rect
			(at -0.40005 0)
			(size 0.4572 0.508)
			(layers "F.Cu" "F.Mask" "F.Paste")
			(net "FM_CPLD_NODE1_PVTT_DDR_EN")
		)
	)
	(footprint ""
		(layer "F.Cu")
		(at 146.78152 -100.391468 -90)
		(property "Reference" ""
			(at 0 0 270)
			(layer "F.SilkS")
			(hide yes)
			(effects
				(font
					(size 1.27 1.27)
				)
			)
		)
		(property "Value" ""
			(at 0 0 270)
			(layer "F.Fab")
			(effects
				(font
					(size 1.27 1.27)
				)
			)
		)
		(duplicate_pad_numbers_are_jumpers no)
		(fp_poly
			(pts
				(arc
					(start 0 -1.4986)
					(mid 0 1.4986)
					(end 0 -1.4986)
				)
			)
			(stroke
				(width 0)
				(type default)
			)
			(fill no)
			(layer "F.CrtYd")
		)
		(pad "1" smd circle
			(at 0 0 270)
			(size 0.9906 0.9906)
			(layers "F.Cu" "F.Mask" "F.Paste")
			(net "Net_31")
		)
		(zone
			(layer "F.Cu")
			(hatch none 0.5)
			(connect_pads
				(clearance 0)
			)
			(min_thickness 0.25)
			(keepout
				(tracks not_allowed)
				(vias allowed)
				(pads allowed)
				(copperpour not_allowed)
				(footprints allowed)
			)
			(placement
				(enabled no)
				(sheetname "")
			)
			(fill
				(thermal_gap 0.5)
				(thermal_bridge_width 0.5)
				(island_removal_mode 0)
			)
			(polygon
				(pts
					(arc
						(start 148.40712 -100.391468)
						(mid 145.15592 -100.391468)
						(end 148.40712 -100.391468)
					)
				)
			)
		)
	)
	(footprint ""
		(layer "F.Cu")
		(at 48.262794 -4.40309 90)
		(property "Reference" "PC72"
			(at -3.823462 -15.310612 90)
			(unlocked yes)
			(layer "F.SilkS")
			(effects
				(font
					(size 0.7874 0.5842)
					(thickness 0.1524)
				)
				(justify left)
			)
		)
		(property "Value" ""
			(at 0 0 90)
			(layer "F.Fab")
			(effects
				(font
					(size 1.27 1.27)
				)
			)
		)
		(duplicate_pad_numbers_are_jumpers no)
		(fp_line
			(start 2.2098 -0.9398)
			(end 2.2098 0.9398)
			(stroke
				(width 0.1524)
				(type default)
			)
			(layer "F.SilkS")
		)
		(fp_line
			(start 0 -0.9398)
			(end 0 0.9398)
			(stroke
				(width 0.1524)
				(type default)
			)
			(layer "F.SilkS")
		)
		(fp_line
			(start -2.2098 -0.9398)
			(end 2.2098 -0.9398)
			(stroke
				(width 0.1524)
				(type default)
			)
			(layer "F.SilkS")
		)
		(fp_line
			(start 2.2098 0.9398)
			(end -2.2098 0.9398)
			(stroke
				(width 0.1524)
				(type default)
			)
			(layer "F.SilkS")
		)
		(fp_line
			(start -2.2098 0.9398)
			(end -2.2098 -0.9398)
			(stroke
				(width 0.1524)
				(type default)
			)
			(layer "F.SilkS")
		)
		(fp_poly
			(pts
				(xy -1.6764 0.889) (xy -1.6764 0.7874) (xy -2.0574 0.7874) (xy -2.0574 -0.7874) (xy -1.6764 -0.7874)
				(xy -1.6764 -0.9398) (xy 1.6764 -0.9398) (xy 1.6764 -0.7874) (xy 2.0574 -0.7874) (xy 2.0574 0.7874)
				(xy 1.6764 0.7874) (xy 1.6764 0.9398) (xy -1.6764 0.9398)
			)
			(stroke
				(width 0)
				(type default)
			)
			(fill no)
			(layer "F.CrtYd")
		)
		(fp_line
			(start 1.700022 -0.899922)
			(end 1.700022 0.899922)
			(stroke
				(width 0.1)
				(type default)
			)
			(layer "F.Fab")
		)
		(fp_line
			(start -1.700022 -0.899922)
			(end 1.700022 -0.899922)
			(stroke
				(width 0.1)
				(type default)
			)
			(layer "F.Fab")
		)
		(fp_line
			(start 1.700022 0.899922)
			(end -1.700022 0.899922)
			(stroke
				(width 0.1)
				(type default)
			)
			(layer "F.Fab")
		)
		(fp_line
			(start -1.700022 0.899922)
			(end -1.700022 -0.899922)
			(stroke
				(width 0.1)
				(type default)
			)
			(layer "F.Fab")
		)
		(pad "1" smd rect
			(at 1.4732 0 90)
			(size 1.1684 1.5748)
			(layers "F.Cu" "F.Mask" "F.Paste")
			(net "SW_PV_VDDR_NODE1_VIN_FLT")
		)
		(pad "2" smd rect
			(at -1.4732 0 90)
			(size 1.1684 1.5748)
			(layers "F.Cu" "F.Mask" "F.Paste")
			(net "GND")
		)
	)
	(footprint ""
		(layer "F.Cu")
		(at 42.328084 -123.472702 90)
		(property "Reference" "R259"
			(at -1.245362 -1.558798 90)
			(unlocked yes)
			(layer "F.SilkS")
			(effects
				(font
					(size 0.7874 0.5842)
					(thickness 0.1524)
				)
				(justify left)
			)
		)
		(property "Value" ""
			(at 0 0 90)
			(layer "F.Fab")
			(effects
				(font
					(size 1.27 1.27)
				)
			)
		)
		(duplicate_pad_numbers_are_jumpers no)
		(fp_line
			(start 0.7874 -0.4064)
			(end 0.7874 0.4064)
			(stroke
				(width 0.1524)
				(type default)
			)
			(layer "F.SilkS")
		)
		(fp_line
			(start -0.7874 -0.4064)
			(end 0.7874 -0.4064)
			(stroke
				(width 0.1524)
				(type default)
			)
			(layer "F.SilkS")
		)
		(fp_line
			(start 0.7874 0.4064)
			(end -0.7874 0.4064)
			(stroke
				(width 0.1524)
				(type default)
			)
			(layer "F.SilkS")
		)
		(fp_line
			(start -0.7874 0.4064)
			(end -0.7874 -0.4064)
			(stroke
				(width 0.1524)
				(type default)
			)
			(layer "F.SilkS")
		)
		(fp_poly
			(pts
				(xy -0.508 0.2794) (xy -0.508 0.2286) (xy -0.635 0.2286) (xy -0.635 -0.254) (xy -0.5334 -0.254)
				(xy -0.5334 -0.2794) (xy 0.5334 -0.2794) (xy 0.5334 -0.254) (xy 0.635 -0.254) (xy 0.635 0.254) (xy 0.5334 0.254)
				(xy 0.5334 0.2794)
			)
			(stroke
				(width 0)
				(type default)
			)
			(fill no)
			(layer "F.CrtYd")
		)
		(pad "1" smd rect
			(at 0.40005 0 90)
			(size 0.4572 0.508)
			(layers "F.Cu" "F.Mask" "F.Paste")
			(net "BMC_NODE1_DDR_RST_L")
		)
		(pad "2" smd rect
			(at -0.40005 0 90)
			(size 0.4572 0.508)
			(layers "F.Cu" "F.Mask" "F.Paste")
			(net "P1V538_BMC_NODE1")
		)
	)
	(footprint ""
		(layer "F.Cu")
		(at 58.40476 -178.804824 180)
		(property "Reference" "U95"
			(at 8.534908 -132.653786 90)
			(unlocked yes)
			(layer "F.SilkS")
			(effects
				(font
					(size 0.7874 0.5842)
					(thickness 0.1524)
				)
			)
		)
		(property "Value" ""
			(at 0 0 180)
			(layer "F.Fab")
			(effects
				(font
					(size 1.27 1.27)
				)
			)
		)
		(duplicate_pad_numbers_are_jumpers no)
		(fp_line
			(start 1.651 1.905)
			(end -1.651 1.905)
			(stroke
				(width 0.1524)
				(type default)
			)
			(layer "F.SilkS")
		)
		(fp_line
			(start 1.651 -1.905)
			(end 1.651 1.905)
			(stroke
				(width 0.1524)
				(type default)
			)
			(layer "F.SilkS")
		)
		(fp_line
			(start -1.651 1.905)
			(end -1.651 -1.905)
			(stroke
				(width 0.1524)
				(type default)
			)
			(layer "F.SilkS")
		)
		(fp_line
			(start -1.651 -1.905)
			(end 1.651 -1.905)
			(stroke
				(width 0.1524)
				(type default)
			)
			(layer "F.SilkS")
		)
		(fp_poly
			(pts
				(xy -1.524 0.7112) (xy -1.524 1.7526) (xy -0.508 1.7526) (xy -0.508 0.6985) (xy 0.508 0.6985) (xy 0.508 1.7526)
				(xy 1.524 1.7526) (xy 1.524 0.6985) (xy 1.524 -0.6985) (xy 0.508 -0.6985) (xy 0.508 -1.7526) (xy -0.508 -1.7526)
				(xy -0.508 -0.6985) (xy -1.524 -0.6985) (xy -1.524 0.6985)
			)
			(stroke
				(width 0)
				(type default)
			)
			(fill no)
			(layer "F.CrtYd")
		)
		(fp_text user "S"
			(at 1.143508 2.741168 0)
			(unlocked yes)
			(layer "F.SilkS")
			(effects
				(font
					(size 0.635 0.4064)
					(thickness 0.1524)
				)
			)
		)
		(fp_text user "D"
			(at -0.114046 -2.4511 0)
			(unlocked yes)
			(layer "F.SilkS")
			(effects
				(font
					(size 0.635 0.4064)
					(thickness 0.1524)
				)
			)
		)
		(fp_text user "G"
			(at -1.396492 2.487168 0)
			(unlocked yes)
			(layer "F.SilkS")
			(effects
				(font
					(size 0.635 0.4064)
					(thickness 0.1524)
				)
			)
		)
		(pad "D" smd rect
			(at 0 -1.1176 180)
			(size 1.016 1.27)
			(layers "F.Cu" "F.Mask" "F.Paste")
			(net "PSU_DC_OK_N")
		)
		(pad "G" smd rect
			(at -1.016 1.1176 180)
			(size 1.016 1.27)
			(layers "F.Cu" "F.Mask" "F.Paste")
			(net "PSU3_DC_OK_R_BUF")
		)
		(pad "S" smd rect
			(at 1.016 1.1176 180)
			(size 1.016 1.27)
			(layers "F.Cu" "F.Mask" "F.Paste")
			(net "GND")
		)
	)
	(footprint ""
		(layer "F.Cu")
		(at 91.803982 -137.581894 90)
		(property "Reference" "R1084"
			(at 1.288542 -0.084328 90)
			(unlocked yes)
			(layer "F.SilkS")
			(effects
				(font
					(size 0.7874 0.5842)
					(thickness 0.1524)
				)
				(justify left)
			)
		)
		(property "Value" ""
			(at 0 0 90)
			(layer "F.Fab")
			(effects
				(font
					(size 1.27 1.27)
				)
			)
		)
		(duplicate_pad_numbers_are_jumpers no)
		(fp_line
			(start 0.7874 -0.4064)
			(end 0.7874 0.4064)
			(stroke
				(width 0.1524)
				(type default)
			)
			(layer "F.SilkS")
		)
		(fp_line
			(start -0.7874 -0.4064)
			(end 0.7874 -0.4064)
			(stroke
				(width 0.1524)
				(type default)
			)
			(layer "F.SilkS")
		)
		(fp_line
			(start 0.7874 0.4064)
			(end -0.7874 0.4064)
			(stroke
				(width 0.1524)
				(type default)
			)
			(layer "F.SilkS")
		)
		(fp_line
			(start -0.7874 0.4064)
			(end -0.7874 -0.4064)
			(stroke
				(width 0.1524)
				(type default)
			)
			(layer "F.SilkS")
		)
		(fp_poly
			(pts
				(xy -0.508 0.2794) (xy -0.508 0.2286) (xy -0.635 0.2286) (xy -0.635 -0.254) (xy -0.5334 -0.254)
				(xy -0.5334 -0.2794) (xy 0.5334 -0.2794) (xy 0.5334 -0.254) (xy 0.635 -0.254) (xy 0.635 0.254) (xy 0.5334 0.254)
				(xy 0.5334 0.2794)
			)
			(stroke
				(width 0)
				(type default)
			)
			(fill no)
			(layer "F.CrtYd")
		)
		(pad "1" smd rect
			(at 0.40005 0 90)
			(size 0.4572 0.508)
			(layers "F.Cu" "F.Mask" "F.Paste")
			(net "P3V3_STB_NODE1")
		)
		(pad "2" smd rect
			(at -0.40005 0 90)
			(size 0.4572 0.508)
			(layers "F.Cu" "F.Mask" "F.Paste")
			(net "PWRGD_NODE1_P1V05_SUS_PG")
		)
	)
	(footprint ""
		(layer "F.Cu")
		(at 123.701302 -54.466236 -90)
		(property "Reference" "U103"
			(at 2.357628 1.498854 0)
			(unlocked yes)
			(layer "F.SilkS")
			(effects
				(font
					(size 0.7874 0.5842)
					(thickness 0.1524)
				)
			)
		)
		(property "Value" ""
			(at 0 0 270)
			(layer "F.Fab")
			(effects
				(font
					(size 1.27 1.27)
				)
			)
		)
		(duplicate_pad_numbers_are_jumpers no)
		(fp_line
			(start -1.651 1.905)
			(end -1.651 -1.905)
			(stroke
				(width 0.1524)
				(type default)
			)
			(layer "F.SilkS")
		)
		(fp_line
			(start 1.651 1.905)
			(end -1.651 1.905)
			(stroke
				(width 0.1524)
				(type default)
			)
			(layer "F.SilkS")
		)
		(fp_line
			(start -1.651 -1.905)
			(end 1.651 -1.905)
			(stroke
				(width 0.1524)
				(type default)
			)
			(layer "F.SilkS")
		)
		(fp_line
			(start 1.651 -1.905)
			(end 1.651 1.905)
			(stroke
				(width 0.1524)
				(type default)
			)
			(layer "F.SilkS")
		)
		(fp_poly
			(pts
				(xy -1.524 0.7112) (xy -1.524 1.7526) (xy -0.508 1.7526) (xy -0.508 0.6985) (xy 0.508 0.6985) (xy 0.508 1.7526)
				(xy 1.524 1.7526) (xy 1.524 0.6985) (xy 1.524 -0.6985) (xy 0.508 -0.6985) (xy 0.508 -1.7526) (xy -0.508 -1.7526)
				(xy -0.508 -0.6985) (xy -1.524 -0.6985) (xy -1.524 0.6985)
			)
			(stroke
				(width 0)
				(type default)
			)
			(fill no)
			(layer "F.CrtYd")
		)
		(fp_text user "G"
			(at -1.165098 2.259076 0)
			(unlocked yes)
			(layer "F.SilkS")
			(effects
				(font
					(size 0.635 0.4064)
					(thickness 0.1524)
				)
			)
		)
		(fp_text user "S"
			(at 2.54254 -0.824738 0)
			(unlocked yes)
			(layer "F.SilkS")
			(effects
				(font
					(size 0.635 0.4064)
					(thickness 0.1524)
				)
			)
		)
		(fp_text user "D"
			(at 2.25552 -1.786128 0)
			(unlocked yes)
			(layer "F.SilkS")
			(effects
				(font
					(size 0.635 0.4064)
					(thickness 0.1524)
				)
			)
		)
		(pad "D" smd rect
			(at 0 -1.1176 270)
			(size 1.016 1.27)
			(layers "F.Cu" "F.Mask" "F.Paste")
			(net "COM4_EN_N")
		)
		(pad "G" smd rect
			(at -1.016 1.1176 270)
			(size 1.016 1.27)
			(layers "F.Cu" "F.Mask" "F.Paste")
			(net "CPLD_UART_RI_P3_N")
		)
		(pad "S" smd rect
			(at 1.016 1.1176 270)
			(size 1.016 1.27)
			(layers "F.Cu" "F.Mask" "F.Paste")
			(net "GND")
		)
	)
	(footprint ""
		(layer "F.Cu")
		(at 154.551126 -166.515288 180)
		(property "Reference" "R579"
			(at 5.148834 4.392676 0)
			(unlocked yes)
			(layer "F.SilkS")
			(effects
				(font
					(size 0.7874 0.5842)
					(thickness 0.1524)
				)
				(justify left)
			)
		)
		(property "Value" ""
			(at 0 0 180)
			(layer "F.Fab")
			(effects
				(font
					(size 1.27 1.27)
				)
			)
		)
		(duplicate_pad_numbers_are_jumpers no)
		(fp_line
			(start 0.7874 0.4064)
			(end -0.7874 0.4064)
			(stroke
				(width 0.1524)
				(type default)
			)
			(layer "F.SilkS")
		)
		(fp_line
			(start 0.7874 -0.4064)
			(end 0.7874 0.4064)
			(stroke
				(width 0.1524)
				(type default)
			)
			(layer "F.SilkS")
		)
		(fp_line
			(start -0.7874 0.4064)
			(end -0.7874 -0.4064)
			(stroke
				(width 0.1524)
				(type default)
			)
			(layer "F.SilkS")
		)
		(fp_line
			(start -0.7874 -0.4064)
			(end 0.7874 -0.4064)
			(stroke
				(width 0.1524)
				(type default)
			)
			(layer "F.SilkS")
		)
		(fp_poly
			(pts
				(xy -0.508 0.2794) (xy -0.508 0.2286) (xy -0.635 0.2286) (xy -0.635 -0.254) (xy -0.5334 -0.254)
				(xy -0.5334 -0.2794) (xy 0.5334 -0.2794) (xy 0.5334 -0.254) (xy 0.635 -0.254) (xy 0.635 0.254) (xy 0.5334 0.254)
				(xy 0.5334 0.2794)
			)
			(stroke
				(width 0)
				(type default)
			)
			(fill no)
			(layer "F.CrtYd")
		)
		(pad "1" smd rect
			(at 0.40005 0 180)
			(size 0.4572 0.508)
			(layers "F.Cu" "F.Mask" "F.Paste")
			(net "SPI_LAN2_NVM_SO")
		)
		(pad "2" smd rect
			(at -0.40005 0 180)
			(size 0.4572 0.508)
			(layers "F.Cu" "F.Mask" "F.Paste")
			(net "LAN2_NVM_SO_R")
		)
	)
	(footprint ""
		(layer "F.Cu")
		(at 58.606182 -173.527466 180)
		(property "Reference" "U86"
			(at 8.322818 -133.039612 90)
			(unlocked yes)
			(layer "F.SilkS")
			(effects
				(font
					(size 0.7874 0.5842)
					(thickness 0.1524)
				)
				(justify left)
			)
		)
		(property "Value" ""
			(at 0 0 180)
			(layer "F.Fab")
			(effects
				(font
					(size 1.27 1.27)
				)
			)
		)
		(duplicate_pad_numbers_are_jumpers no)
		(fp_line
			(start 1.549908 2.032)
			(end -1.549908 2.032)
			(stroke
				(width 0.1524)
				(type default)
			)
			(layer "F.SilkS")
		)
		(fp_line
			(start 1.549908 -2.032)
			(end 1.549908 2.032)
			(stroke
				(width 0.1524)
				(type default)
			)
			(layer "F.SilkS")
		)
		(fp_line
			(start -1.549908 2.032)
			(end -1.549908 -2.032)
			(stroke
				(width 0.1524)
				(type default)
			)
			(layer "F.SilkS")
		)
		(fp_line
			(start -1.549908 -2.032)
			(end 1.549908 -2.032)
			(stroke
				(width 0.1524)
				(type default)
			)
			(layer "F.SilkS")
		)
		(fp_poly
			(pts
				(xy -2.9464 1.016) (xy -2.9464 1.524) (xy -2.1844 1.27)
			)
			(stroke
				(width 0)
				(type default)
			)
			(fill yes)
			(layer "F.SilkS")
		)
		(fp_poly
			(pts
				(xy -1.549908 0.849884) (xy -1.2319 0.849884) (xy -1.2319 1.9431) (xy -1.1811 1.9431) (xy 1.1811 1.9431)
				(xy 1.2319 1.9431) (xy 1.2319 0.849884) (xy 1.549908 0.849884) (xy 1.549908 -0.849884) (xy 1.2319 -0.849884)
				(xy 1.2319 -1.9431) (xy 1.1811 -1.9431) (xy -1.1811 -1.9431) (xy -1.2319 -1.9431) (xy -1.2319 -0.849884)
				(xy -1.549908 -0.849884)
			)
			(stroke
				(width 0)
				(type default)
			)
			(fill no)
			(layer "F.CrtYd")
		)
		(fp_line
			(start 1.549908 0.849884)
			(end 1.549908 -0.849884)
			(stroke
				(width 0.1)
				(type default)
			)
			(layer "F.Fab")
		)
		(fp_line
			(start 1.549908 -0.849884)
			(end -1.549908 -0.849884)
			(stroke
				(width 0.1)
				(type default)
			)
			(layer "F.Fab")
		)
		(fp_line
			(start -1.549908 0.849884)
			(end 1.549908 0.849884)
			(stroke
				(width 0.1)
				(type default)
			)
			(layer "F.Fab")
		)
		(fp_line
			(start -1.549908 -0.849884)
			(end -1.549908 0.849884)
			(stroke
				(width 0.1)
				(type default)
			)
			(layer "F.Fab")
		)
		(fp_text user "3"
			(at 1.32207 2.510536 0)
			(unlocked yes)
			(layer "F.SilkS")
			(effects
				(font
					(size 0.635 0.4064)
					(thickness 0.1524)
				)
				(justify left)
			)
		)
		(fp_text user "4"
			(at 0.805942 -2.54508 0)
			(unlocked yes)
			(layer "F.SilkS")
			(effects
				(font
					(size 0.635 0.4064)
					(thickness 0.1524)
				)
				(justify left)
			)
		)
		(fp_text user "1"
			(at -1.165606 2.52222 0)
			(unlocked yes)
			(layer "F.SilkS")
			(effects
				(font
					(size 0.635 0.4064)
					(thickness 0.1524)
				)
				(justify left)
			)
		)
		(fp_text user "5"
			(at -1.838198 -2.59334 0)
			(unlocked yes)
			(layer "F.SilkS")
			(effects
				(font
					(size 0.635 0.4064)
					(thickness 0.1524)
				)
				(justify left)
			)
		)
		(pad "1" smd rect
			(at -0.94996 1.225042 180)
			(size 0.4572 1.3208)
			(layers "F.Cu" "F.Mask" "F.Paste")
			(net "Net_1707")
		)
		(pad "2" smd rect
			(at 0 1.225042 180)
			(size 0.4572 1.3208)
			(layers "F.Cu" "F.Mask" "F.Paste")
			(net "PSU3_DC_OK_R_BUF")
		)
		(pad "3" smd rect
			(at 0.94996 1.225042 180)
			(size 0.4572 1.3208)
			(layers "F.Cu" "F.Mask" "F.Paste")
			(net "GND")
		)
		(pad "4" smd rect
			(at 0.94996 -1.225042 180)
			(size 0.4572 1.3208)
			(layers "F.Cu" "F.Mask" "F.Paste")
			(net "PSU3_DC_OK")
		)
		(pad "5" smd rect
			(at -0.94996 -1.225042 180)
			(size 0.4572 1.3208)
			(layers "F.Cu" "F.Mask" "F.Paste")
			(net "P3V3_NODE1")
		)
	)
	(footprint ""
		(layer "F.Cu")
		(at 108.901738 -115.720368 180)
		(property "Reference" "PL8"
			(at -4.115054 -0.351028 90)
			(unlocked yes)
			(layer "F.SilkS")
			(effects
				(font
					(size 0.7874 0.5842)
					(thickness 0.1524)
				)
				(justify left)
			)
		)
		(property "Value" ""
			(at 0 0 180)
			(layer "F.Fab")
			(effects
				(font
					(size 1.27 1.27)
				)
			)
		)
		(duplicate_pad_numbers_are_jumpers no)
		(fp_line
			(start 3.359912 6.390132)
			(end 1.8542 6.390132)
			(stroke
				(width 0.1524)
				(type default)
			)
			(layer "F.SilkS")
		)
		(fp_line
			(start 3.359912 -0.849884)
			(end 3.359912 6.390132)
			(stroke
				(width 0.1524)
				(type default)
			)
			(layer "F.SilkS")
		)
		(fp_line
			(start 1.8542 -0.849884)
			(end 3.359912 -0.849884)
			(stroke
				(width 0.1524)
				(type default)
			)
			(layer "F.SilkS")
		)
		(fp_line
			(start -1.8542 6.390132)
			(end -3.359912 6.390132)
			(stroke
				(width 0.1524)
				(type default)
			)
			(layer "F.SilkS")
		)
		(fp_line
			(start -3.359912 6.390132)
			(end -3.359912 -0.849884)
			(stroke
				(width 0.1524)
				(type default)
			)
			(layer "F.SilkS")
		)
		(fp_line
			(start -3.359912 -0.849884)
			(end -1.8542 -0.849884)
			(stroke
				(width 0.1524)
				(type default)
			)
			(layer "F.SilkS")
		)
		(fp_poly
			(pts
				(xy -3.359912 -0.849884) (xy -3.359912 6.390132) (xy -1.7653 6.390132) (xy -1.7653 6.503924) (xy 1.7653 6.503924)
				(xy 1.7653 6.390132) (xy 3.359912 6.390132) (xy 3.359912 -0.849884) (xy 1.7653 -0.849884) (xy 1.7653 -0.963676)
				(xy -1.7653 -0.963676) (xy -1.7653 -0.849884)
			)
			(stroke
				(width 0)
				(type default)
			)
			(fill no)
			(layer "F.CrtYd")
		)
		(fp_line
			(start 3.359912 6.390132)
			(end -3.359912 6.390132)
			(stroke
				(width 0.1)
				(type default)
			)
			(layer "F.Fab")
		)
		(fp_line
			(start 3.359912 -0.849884)
			(end 3.359912 6.390132)
			(stroke
				(width 0.1)
				(type default)
			)
			(layer "F.Fab")
		)
		(fp_line
			(start -3.359912 6.390132)
			(end -3.359912 -0.849884)
			(stroke
				(width 0.1)
				(type default)
			)
			(layer "F.Fab")
		)
		(fp_line
			(start -3.359912 -0.849884)
			(end 3.359912 -0.849884)
			(stroke
				(width 0.1)
				(type default)
			)
			(layer "F.Fab")
		)
		(pad "1A" smd rect
			(at 0 0 90)
			(size 1.8288 3.429)
			(layers "F.Cu" "F.Mask" "F.Paste")
			(net "PV_VCCP_NODE1")
		)
		(pad "1B" smd rect
			(at 0 0.787908 90)
			(size 0.254 0.508)
			(layers "F.Cu" "F.Mask" "F.Paste")
			(net "ISENSE_PVCCP_NODE1_ISEN1N")
		)
		(pad "2A" smd rect
			(at 0 5.539994 90)
			(size 1.8288 3.429)
			(layers "F.Cu" "F.Mask" "F.Paste")
			(net "VR_PVCCP_NODE1_PHASE1")
		)
		(pad "2B" smd rect
			(at 0 4.753102 90)
			(size 0.254 0.508)
			(layers "F.Cu" "F.Mask" "F.Paste")
			(net "ISENSE_PVCCP_NODE1_ISEN1P")
		)
	)
	(footprint ""
		(layer "F.Cu")
		(at 58.000646 -75.799442)
		(property "Reference" "U2"
			(at -20.2438 -18.364708 0)
			(unlocked yes)
			(layer "F.SilkS")
			(effects
				(font
					(size 1.6002 1.1938)
					(thickness 0.1524)
				)
				(justify left)
			)
		)
		(property "Value" ""
			(at 0 0 0)
			(layer "F.Fab")
			(effects
				(font
					(size 1.27 1.27)
				)
			)
		)
		(duplicate_pad_numbers_are_jumpers no)
		(fp_line
			(start -20.030694 -17.020794)
			(end -20.030694 17.020794)
			(stroke
				(width 0.1524)
				(type default)
			)
			(layer "F.SilkS")
		)
		(fp_line
			(start -20.030694 17.020794)
			(end 20.030694 17.020794)
			(stroke
				(width 0.1524)
				(type default)
			)
			(layer "F.SilkS")
		)
		(fp_line
			(start -17.0307 -14.0208)
			(end -17.0307 14.0208)
			(stroke
				(width 0.1524)
				(type default)
			)
			(layer "F.SilkS")
		)
		(fp_line
			(start -17.0307 14.0208)
			(end 17.0307 14.0208)
			(stroke
				(width 0.1524)
				(type default)
			)
			(layer "F.SilkS")
		)
		(fp_line
			(start 17.0307 -14.0208)
			(end -17.0307 -14.0208)
			(stroke
				(width 0.1524)
				(type default)
			)
			(layer "F.SilkS")
		)
		(fp_line
			(start 17.0307 14.0208)
			(end 17.0307 -14.0208)
			(stroke
				(width 0.1524)
				(type default)
			)
			(layer "F.SilkS")
		)
		(fp_line
			(start 20.030694 -17.020794)
			(end -20.030694 -17.020794)
			(stroke
				(width 0.1524)
				(type default)
			)
			(layer "F.SilkS")
		)
		(fp_line
			(start 20.030694 -14.848332)
			(end 20.030694 -17.020794)
			(stroke
				(width 0.1524)
				(type default)
			)
			(layer "F.SilkS")
		)
		(fp_line
			(start 20.030694 0.657098)
			(end 20.030694 -13.606272)
			(stroke
				(width 0.1524)
				(type default)
			)
			(layer "F.SilkS")
		)
		(fp_line
			(start 20.030694 17.020794)
			(end 20.030694 2.21996)
			(stroke
				(width 0.1524)
				(type default)
			)
			(layer "F.SilkS")
		)
		(fp_poly
			(pts
				(xy -20.030694 -13.592302) (xy -18.811494 -14.836394) (xy -17.287494 -13.210794) (xy -16.195294 -14.302994)
				(xy -17.617694 -15.877794) (xy -16.373094 -17.020794) (xy -20.030694 -17.020794)
			)
			(stroke
				(width 0)
				(type default)
			)
			(fill yes)
			(layer "F.SilkS")
		)
		(fp_poly
			(pts
				(xy -17.0307 14.0208) (xy 17.0307 14.0208) (xy 17.0307 -14.0208) (xy -17.0307 -14.0208)
			)
			(stroke
				(width 0)
				(type default)
			)
			(fill no)
			(layer "F.CrtYd")
		)
		(fp_line
			(start -17.0307 -14.0208)
			(end -17.0307 14.0208)
			(stroke
				(width 0.1)
				(type default)
			)
			(layer "F.Fab")
		)
		(fp_line
			(start -17.0307 14.0208)
			(end 17.0307 14.0208)
			(stroke
				(width 0.1)
				(type default)
			)
			(layer "F.Fab")
		)
		(fp_line
			(start 17.0307 -14.0208)
			(end -17.0307 -14.0208)
			(stroke
				(width 0.1)
				(type default)
			)
			(layer "F.Fab")
		)
		(fp_line
			(start 17.0307 14.0208)
			(end 17.0307 -14.0208)
			(stroke
				(width 0.1)
				(type default)
			)
			(layer "F.Fab")
		)
		(fp_text user "AB"
			(at -19.5326 -2.910332 0)
			(unlocked yes)
			(layer "F.SilkS")
			(effects
				(font
					(size 0.635 0.4064)
					(thickness 0.1524)
				)
				(justify left)
			)
		)
		(fp_text user "AD"
			(at -19.5326 -1.767332 0)
			(unlocked yes)
			(layer "F.SilkS")
			(effects
				(font
					(size 0.635 0.4064)
					(thickness 0.1524)
				)
				(justify left)
			)
		)
		(fp_text user "AF"
			(at -19.5326 -0.624332 0)
			(unlocked yes)
			(layer "F.SilkS")
			(effects
				(font
					(size 0.635 0.4064)
					(thickness 0.1524)
				)
				(justify left)
			)
		)
		(fp_text user "AH"
			(at -19.5326 0.391668 0)
			(unlocked yes)
			(layer "F.SilkS")
			(effects
				(font
					(size 0.635 0.4064)
					(thickness 0.1524)
				)
				(justify left)
			)
		)
		(fp_text user "AK"
			(at -19.5326 1.280668 0)
			(unlocked yes)
			(layer "F.SilkS")
			(effects
				(font
					(size 0.635 0.4064)
					(thickness 0.1524)
				)
				(justify left)
			)
		)
		(fp_text user "AM"
			(at -19.5326 2.423668 0)
			(unlocked yes)
			(layer "F.SilkS")
			(effects
				(font
					(size 0.635 0.4064)
					(thickness 0.1524)
				)
				(justify left)
			)
		)
		(fp_text user "AP"
			(at -19.5326 3.439668 0)
			(unlocked yes)
			(layer "F.SilkS")
			(effects
				(font
					(size 0.635 0.4064)
					(thickness 0.1524)
				)
				(justify left)
			)
		)
		(fp_text user "AT"
			(at -19.5326 4.328668 0)
			(unlocked yes)
			(layer "F.SilkS")
			(effects
				(font
					(size 0.635 0.4064)
					(thickness 0.1524)
				)
				(justify left)
			)
		)
		(fp_text user "AV"
			(at -19.5326 5.217668 0)
			(unlocked yes)
			(layer "F.SilkS")
			(effects
				(font
					(size 0.635 0.4064)
					(thickness 0.1524)
				)
				(justify left)
			)
		)
		(fp_text user "AY"
			(at -19.5326 6.233668 0)
			(unlocked yes)
			(layer "F.SilkS")
			(effects
				(font
					(size 0.635 0.4064)
					(thickness 0.1524)
				)
				(justify left)
			)
		)
		(fp_text user "BB"
			(at -19.5326 7.122668 0)
			(unlocked yes)
			(layer "F.SilkS")
			(effects
				(font
					(size 0.635 0.4064)
					(thickness 0.1524)
				)
				(justify left)
			)
		)
		(fp_text user "BD"
			(at -19.5326 8.138668 0)
			(unlocked yes)
			(layer "F.SilkS")
			(effects
				(font
					(size 0.635 0.4064)
					(thickness 0.1524)
				)
				(justify left)
			)
		)
		(fp_text user "BF"
			(at -19.5326 9.027668 0)
			(unlocked yes)
			(layer "F.SilkS")
			(effects
				(font
					(size 0.635 0.4064)
					(thickness 0.1524)
				)
				(justify left)
			)
		)
		(fp_text user "BH"
			(at -19.5326 9.916668 0)
			(unlocked yes)
			(layer "F.SilkS")
			(effects
				(font
					(size 0.635 0.4064)
					(thickness 0.1524)
				)
				(justify left)
			)
		)
		(fp_text user "BK"
			(at -19.5326 11.059668 0)
			(unlocked yes)
			(layer "F.SilkS")
			(effects
				(font
					(size 0.635 0.4064)
					(thickness 0.1524)
				)
				(justify left)
			)
		)
		(fp_text user "BM"
			(at -19.5326 12.202668 0)
			(unlocked yes)
			(layer "F.SilkS")
			(effects
				(font
					(size 0.635 0.4064)
					(thickness 0.1524)
				)
				(justify left)
			)
		)
		(fp_text user "BP"
			(at -19.5326 13.218668 0)
			(unlocked yes)
			(layer "F.SilkS")
			(effects
				(font
					(size 0.635 0.4064)
					(thickness 0.1524)
				)
				(justify left)
			)
		)
		(fp_text user "B"
			(at -19.4564 -12.943332 0)
			(unlocked yes)
			(layer "F.SilkS")
			(effects
				(font
					(size 0.635 0.4064)
					(thickness 0.1524)
				)
				(justify left)
			)
		)
		(fp_text user "D"
			(at -19.4564 -12.054332 0)
			(unlocked yes)
			(layer "F.SilkS")
			(effects
				(font
					(size 0.635 0.4064)
					(thickness 0.1524)
				)
				(justify left)
			)
		)
		(fp_text user "F"
			(at -19.4564 -11.038332 0)
			(unlocked yes)
			(layer "F.SilkS")
			(effects
				(font
					(size 0.635 0.4064)
					(thickness 0.1524)
				)
				(justify left)
			)
		)
		(fp_text user "H"
			(at -19.4564 -10.149332 0)
			(unlocked yes)
			(layer "F.SilkS")
			(effects
				(font
					(size 0.635 0.4064)
					(thickness 0.1524)
				)
				(justify left)
			)
		)
		(fp_text user "K"
			(at -19.4564 -9.260332 0)
			(unlocked yes)
			(layer "F.SilkS")
			(effects
				(font
					(size 0.635 0.4064)
					(thickness 0.1524)
				)
				(justify left)
			)
		)
		(fp_text user "M"
			(at -19.4564 -8.117332 0)
			(unlocked yes)
			(layer "F.SilkS")
			(effects
				(font
					(size 0.635 0.4064)
					(thickness 0.1524)
				)
				(justify left)
			)
		)
		(fp_text user "P"
			(at -19.4564 -7.101332 0)
			(unlocked yes)
			(layer "F.SilkS")
			(effects
				(font
					(size 0.635 0.4064)
					(thickness 0.1524)
				)
				(justify left)
			)
		)
		(fp_text user "T"
			(at -19.4564 -6.085332 0)
			(unlocked yes)
			(layer "F.SilkS")
			(effects
				(font
					(size 0.635 0.4064)
					(thickness 0.1524)
				)
				(justify left)
			)
		)
		(fp_text user "V"
			(at -19.4564 -4.942332 0)
			(unlocked yes)
			(layer "F.SilkS")
			(effects
				(font
					(size 0.635 0.4064)
					(thickness 0.1524)
				)
				(justify left)
			)
		)
		(fp_text user "Y"
			(at -19.4564 -3.926332 0)
			(unlocked yes)
			(layer "F.SilkS")
			(effects
				(font
					(size 0.635 0.4064)
					(thickness 0.1524)
				)
				(justify left)
			)
		)
		(fp_text user "AA"
			(at -18.5166 -3.672332 0)
			(unlocked yes)
			(layer "F.SilkS")
			(effects
				(font
					(size 0.635 0.4064)
					(thickness 0.1524)
				)
				(justify left)
			)
		)
		(fp_text user "AC"
			(at -18.5166 -2.402332 0)
			(unlocked yes)
			(layer "F.SilkS")
			(effects
				(font
					(size 0.635 0.4064)
					(thickness 0.1524)
				)
				(justify left)
			)
		)
		(fp_text user "AE"
			(at -18.5166 -1.259332 0)
			(unlocked yes)
			(layer "F.SilkS")
			(effects
				(font
					(size 0.635 0.4064)
					(thickness 0.1524)
				)
				(justify left)
			)
		)
		(fp_text user "AG"
			(at -18.5166 -0.243332 0)
			(unlocked yes)
			(layer "F.SilkS")
			(effects
				(font
					(size 0.635 0.4064)
					(thickness 0.1524)
				)
				(justify left)
			)
		)
		(fp_text user "AJ"
			(at -18.5166 0.899668 0)
			(unlocked yes)
			(layer "F.SilkS")
			(effects
				(font
					(size 0.635 0.4064)
					(thickness 0.1524)
				)
				(justify left)
			)
		)
		(fp_text user "AL"
			(at -18.5166 1.788668 0)
			(unlocked yes)
			(layer "F.SilkS")
			(effects
				(font
					(size 0.635 0.4064)
					(thickness 0.1524)
				)
				(justify left)
			)
		)
		(fp_text user "AN"
			(at -18.5166 2.931668 0)
			(unlocked yes)
			(layer "F.SilkS")
			(effects
				(font
					(size 0.635 0.4064)
					(thickness 0.1524)
				)
				(justify left)
			)
		)
		(fp_text user "AR"
			(at -18.5166 3.820668 0)
			(unlocked yes)
			(layer "F.SilkS")
			(effects
				(font
					(size 0.635 0.4064)
					(thickness 0.1524)
				)
				(justify left)
			)
		)
		(fp_text user "AU"
			(at -18.5166 4.709668 0)
			(unlocked yes)
			(layer "F.SilkS")
			(effects
				(font
					(size 0.635 0.4064)
					(thickness 0.1524)
				)
				(justify left)
			)
		)
		(fp_text user "AW"
			(at -18.5166 5.598668 0)
			(unlocked yes)
			(layer "F.SilkS")
			(effects
				(font
					(size 0.635 0.4064)
					(thickness 0.1524)
				)
				(justify left)
			)
		)
		(fp_text user "BA"
			(at -18.5166 6.614668 0)
			(unlocked yes)
			(layer "F.SilkS")
			(effects
				(font
					(size 0.635 0.4064)
					(thickness 0.1524)
				)
				(justify left)
			)
		)
		(fp_text user "BC"
			(at -18.5166 7.630668 0)
			(unlocked yes)
			(layer "F.SilkS")
			(effects
				(font
					(size 0.635 0.4064)
					(thickness 0.1524)
				)
				(justify left)
			)
		)
		(fp_text user "BE"
			(at -18.5166 8.519668 0)
			(unlocked yes)
			(layer "F.SilkS")
			(effects
				(font
					(size 0.635 0.4064)
					(thickness 0.1524)
				)
				(justify left)
			)
		)
		(fp_text user "BG"
			(at -18.5166 9.408668 0)
			(unlocked yes)
			(layer "F.SilkS")
			(effects
				(font
					(size 0.635 0.4064)
					(thickness 0.1524)
				)
				(justify left)
			)
		)
		(fp_text user "BJ"
			(at -18.5166 10.551668 0)
			(unlocked yes)
			(layer "F.SilkS")
			(effects
				(font
					(size 0.635 0.4064)
					(thickness 0.1524)
				)
				(justify left)
			)
		)
		(fp_text user "BL"
			(at -18.5166 11.567668 0)
			(unlocked yes)
			(layer "F.SilkS")
			(effects
				(font
					(size 0.635 0.4064)
					(thickness 0.1524)
				)
				(justify left)
			)
		)
		(fp_text user "BN"
			(at -18.5166 12.710668 0)
			(unlocked yes)
			(layer "F.SilkS")
			(effects
				(font
					(size 0.635 0.4064)
					(thickness 0.1524)
				)
				(justify left)
			)
		)
		(fp_text user "A"
			(at -18.4404 -13.394182 0)
			(unlocked yes)
			(layer "F.SilkS")
			(effects
				(font
					(size 0.508 0.381)
					(thickness 0.000001)
				)
				(justify left)
			)
		)
		(fp_text user "C"
			(at -18.4404 -12.562332 0)
			(unlocked yes)
			(layer "F.SilkS")
			(effects
				(font
					(size 0.635 0.4064)
					(thickness 0.1524)
				)
				(justify left)
			)
		)
		(fp_text user "E"
			(at -18.4404 -11.673332 0)
			(unlocked yes)
			(layer "F.SilkS")
			(effects
				(font
					(size 0.635 0.4064)
					(thickness 0.1524)
				)
				(justify left)
			)
		)
		(fp_text user "G"
			(at -18.4404 -10.530332 0)
			(unlocked yes)
			(layer "F.SilkS")
			(effects
				(font
					(size 0.635 0.4064)
					(thickness 0.1524)
				)
				(justify left)
			)
		)
		(fp_text user "J"
			(at -18.4404 -9.641332 0)
			(unlocked yes)
			(layer "F.SilkS")
			(effects
				(font
					(size 0.635 0.4064)
					(thickness 0.1524)
				)
				(justify left)
			)
		)
		(fp_text user "L"
			(at -18.4404 -8.752332 0)
			(unlocked yes)
			(layer "F.SilkS")
			(effects
				(font
					(size 0.635 0.4064)
					(thickness 0.1524)
				)
				(justify left)
			)
		)
		(fp_text user "N"
			(at -18.4404 -7.736332 0)
			(unlocked yes)
			(layer "F.SilkS")
			(effects
				(font
					(size 0.635 0.4064)
					(thickness 0.1524)
				)
				(justify left)
			)
		)
		(fp_text user "R"
			(at -18.4404 -6.593332 0)
			(unlocked yes)
			(layer "F.SilkS")
			(effects
				(font
					(size 0.635 0.4064)
					(thickness 0.1524)
				)
				(justify left)
			)
		)
		(fp_text user "U"
			(at -18.4404 -5.577332 0)
			(unlocked yes)
			(layer "F.SilkS")
			(effects
				(font
					(size 0.635 0.4064)
					(thickness 0.1524)
				)
				(justify left)
			)
		)
		(fp_text user "W"
			(at -18.4404 -4.561332 0)
			(unlocked yes)
			(layer "F.SilkS")
			(effects
				(font
					(size 0.635 0.4064)
					(thickness 0.1524)
				)
				(justify left)
			)
		)
		(fp_text user "1"
			(at -16.4084 -15.102332 0)
			(unlocked yes)
			(layer "F.SilkS")
			(effects
				(font
					(size 0.635 0.4064)
					(thickness 0.1524)
				)
				(justify left)
			)
		)
		(fp_text user "2"
			(at -16.0274 -16.245332 0)
			(unlocked yes)
			(layer "F.SilkS")
			(effects
				(font
					(size 0.635 0.4064)
					(thickness 0.1524)
				)
				(justify left)
			)
		)
		(fp_text user "3"
			(at -15.6464 -15.102332 0)
			(unlocked yes)
			(layer "F.SilkS")
			(effects
				(font
					(size 0.635 0.4064)
					(thickness 0.1524)
				)
				(justify left)
			)
		)
		(fp_text user "4"
			(at -15.1384 -16.245332 0)
			(unlocked yes)
			(layer "F.SilkS")
			(effects
				(font
					(size 0.635 0.4064)
					(thickness 0.1524)
				)
				(justify left)
			)
		)
		(fp_text user "5"
			(at -14.7574 -15.102332 0)
			(unlocked yes)
			(layer "F.SilkS")
			(effects
				(font
					(size 0.635 0.4064)
					(thickness 0.1524)
				)
				(justify left)
			)
		)
		(fp_text user "6"
			(at -14.2494 -16.245332 0)
			(unlocked yes)
			(layer "F.SilkS")
			(effects
				(font
					(size 0.635 0.4064)
					(thickness 0.1524)
				)
				(justify left)
			)
		)
		(fp_text user "7"
			(at -13.6144 -15.102332 0)
			(unlocked yes)
			(layer "F.SilkS")
			(effects
				(font
					(size 0.635 0.4064)
					(thickness 0.1524)
				)
				(justify left)
			)
		)
		(fp_text user "8"
			(at -13.2334 -16.245332 0)
			(unlocked yes)
			(layer "F.SilkS")
			(effects
				(font
					(size 0.635 0.4064)
					(thickness 0.1524)
				)
				(justify left)
			)
		)
		(fp_text user "9"
			(at -12.5984 -15.102332 0)
			(unlocked yes)
			(layer "F.SilkS")
			(effects
				(font
					(size 0.635 0.4064)
					(thickness 0.1524)
				)
				(justify left)
			)
		)
		(fp_text user "10"
			(at -12.4206 -16.245332 0)
			(unlocked yes)
			(layer "F.SilkS")
			(effects
				(font
					(size 0.635 0.4064)
					(thickness 0.1524)
				)
				(justify left)
			)
		)
		(fp_text user "11"
			(at -11.7856 -15.102332 0)
			(unlocked yes)
			(layer "F.SilkS")
			(effects
				(font
					(size 0.635 0.4064)
					(thickness 0.1524)
				)
				(justify left)
			)
		)
		(fp_text user "12"
			(at -11.2776 -16.245332 0)
			(unlocked yes)
			(layer "F.SilkS")
			(effects
				(font
					(size 0.635 0.4064)
					(thickness 0.1524)
				)
				(justify left)
			)
		)
		(fp_text user "13"
			(at -10.6426 -15.102332 0)
			(unlocked yes)
			(layer "F.SilkS")
			(effects
				(font
					(size 0.635 0.4064)
					(thickness 0.1524)
				)
				(justify left)
			)
		)
		(fp_text user "14"
			(at -10.2616 -16.245332 0)
			(unlocked yes)
			(layer "F.SilkS")
			(effects
				(font
					(size 0.635 0.4064)
					(thickness 0.1524)
				)
				(justify left)
			)
		)
		(fp_text user "15"
			(at -9.6266 -15.102332 0)
			(unlocked yes)
			(layer "F.SilkS")
			(effects
				(font
					(size 0.635 0.4064)
					(thickness 0.1524)
				)
				(justify left)
			)
		)
		(fp_text user "16"
			(at -9.2456 -16.245332 0)
			(unlocked yes)
			(layer "F.SilkS")
			(effects
				(font
					(size 0.635 0.4064)
					(thickness 0.1524)
				)
				(justify left)
			)
		)
		(fp_text user "17"
			(at -8.6106 -15.102332 0)
			(unlocked yes)
			(layer "F.SilkS")
			(effects
				(font
					(size 0.635 0.4064)
					(thickness 0.1524)
				)
				(justify left)
			)
		)
		(fp_text user "18"
			(at -8.2296 -16.245332 0)
			(unlocked yes)
			(layer "F.SilkS")
			(effects
				(font
					(size 0.635 0.4064)
					(thickness 0.1524)
				)
				(justify left)
			)
		)
		(fp_text user "19"
			(at -7.7216 -15.102332 0)
			(unlocked yes)
			(layer "F.SilkS")
			(effects
				(font
					(size 0.635 0.4064)
					(thickness 0.1524)
				)
				(justify left)
			)
		)
		(fp_text user "20"
			(at -7.2136 -16.245332 0)
			(unlocked yes)
			(layer "F.SilkS")
			(effects
				(font
					(size 0.635 0.4064)
					(thickness 0.1524)
				)
				(justify left)
			)
		)
		(fp_text user "21"
			(at -6.7056 -15.102332 0)
			(unlocked yes)
			(layer "F.SilkS")
			(effects
				(font
					(size 0.635 0.4064)
					(thickness 0.1524)
				)
				(justify left)
			)
		)
		(fp_text user "22"
			(at -6.1976 -16.245332 0)
			(unlocked yes)
			(layer "F.SilkS")
			(effects
				(font
					(size 0.635 0.4064)
					(thickness 0.1524)
				)
				(justify left)
			)
		)
		(fp_text user "23"
			(at -5.6896 -15.102332 0)
			(unlocked yes)
			(layer "F.SilkS")
			(effects
				(font
					(size 0.635 0.4064)
					(thickness 0.1524)
				)
				(justify left)
			)
		)
		(fp_text user "24"
			(at -5.1816 -16.245332 0)
			(unlocked yes)
			(layer "F.SilkS")
			(effects
				(font
					(size 0.635 0.4064)
					(thickness 0.1524)
				)
				(justify left)
			)
		)
		(fp_text user "25"
			(at -4.6736 -15.102332 0)
			(unlocked yes)
			(layer "F.SilkS")
			(effects
				(font
					(size 0.635 0.4064)
					(thickness 0.1524)
				)
				(justify left)
			)
		)
		(fp_text user "26"
			(at -4.1656 -16.245332 0)
			(unlocked yes)
			(layer "F.SilkS")
			(effects
				(font
					(size 0.635 0.4064)
					(thickness 0.1524)
				)
				(justify left)
			)
		)
		(fp_text user "27"
			(at -3.6576 -15.102332 0)
			(unlocked yes)
			(layer "F.SilkS")
			(effects
				(font
					(size 0.635 0.4064)
					(thickness 0.1524)
				)
				(justify left)
			)
		)
		(fp_text user "28"
			(at -3.1496 -16.245332 0)
			(unlocked yes)
			(layer "F.SilkS")
			(effects
				(font
					(size 0.635 0.4064)
					(thickness 0.1524)
				)
				(justify left)
			)
		)
		(fp_text user "29"
			(at -2.7686 -15.102332 0)
			(unlocked yes)
			(layer "F.SilkS")
			(effects
				(font
					(size 0.635 0.4064)
					(thickness 0.1524)
				)
				(justify left)
			)
		)
		(fp_text user "30"
			(at -2.1336 -16.245332 0)
			(unlocked yes)
			(layer "F.SilkS")
			(effects
				(font
					(size 0.635 0.4064)
					(thickness 0.1524)
				)
				(justify left)
			)
		)
		(fp_text user "31"
			(at -1.7526 -15.102332 0)
			(unlocked yes)
			(layer "F.SilkS")
			(effects
				(font
					(size 0.635 0.4064)
					(thickness 0.1524)
				)
				(justify left)
			)
		)
		(fp_text user "32"
			(at -1.2446 -16.245332 0)
			(unlocked yes)
			(layer "F.SilkS")
			(effects
				(font
					(size 0.635 0.4064)
					(thickness 0.1524)
				)
				(justify left)
			)
		)
		(fp_text user "33"
			(at -0.8636 -15.102332 0)
			(unlocked yes)
			(layer "F.SilkS")
			(effects
				(font
					(size 0.635 0.4064)
					(thickness 0.1524)
				)
				(justify left)
			)
		)
		(fp_text user "34"
			(at -0.2286 -16.245332 0)
			(unlocked yes)
			(layer "F.SilkS")
			(effects
				(font
					(size 0.635 0.4064)
					(thickness 0.1524)
				)
				(justify left)
			)
		)
		(fp_text user "35"
			(at 0.1524 -15.102332 0)
			(unlocked yes)
			(layer "F.SilkS")
			(effects
				(font
					(size 0.635 0.4064)
					(thickness 0.1524)
				)
				(justify left)
			)
		)
		(fp_text user "36"
			(at 0.7874 -16.245332 0)
			(unlocked yes)
			(layer "F.SilkS")
			(effects
				(font
					(size 0.635 0.4064)
					(thickness 0.1524)
				)
				(justify left)
			)
		)
		(fp_text user "37"
			(at 1.4224 -15.102332 0)
			(unlocked yes)
			(layer "F.SilkS")
			(effects
				(font
					(size 0.635 0.4064)
					(thickness 0.1524)
				)
				(justify left)
			)
		)
		(fp_text user "38"
			(at 1.8034 -16.245332 0)
			(unlocked yes)
			(layer "F.SilkS")
			(effects
				(font
					(size 0.635 0.4064)
					(thickness 0.1524)
				)
				(justify left)
			)
		)
		(fp_text user "39"
			(at 2.5654 -15.102332 0)
			(unlocked yes)
			(layer "F.SilkS")
			(effects
				(font
					(size 0.635 0.4064)
					(thickness 0.1524)
				)
				(justify left)
			)
		)
		(fp_text user "40"
			(at 2.8194 -16.245332 0)
			(unlocked yes)
			(layer "F.SilkS")
			(effects
				(font
					(size 0.635 0.4064)
					(thickness 0.1524)
				)
				(justify left)
			)
		)
		(fp_text user "41"
			(at 3.4544 -15.102332 0)
			(unlocked yes)
			(layer "F.SilkS")
			(effects
				(font
					(size 0.635 0.4064)
					(thickness 0.1524)
				)
				(justify left)
			)
		)
		(fp_text user "42"
			(at 3.8354 -16.245332 0)
			(unlocked yes)
			(layer "F.SilkS")
			(effects
				(font
					(size 0.635 0.4064)
					(thickness 0.1524)
				)
				(justify left)
			)
		)
		(fp_text user "43"
			(at 4.3434 -15.102332 0)
			(unlocked yes)
			(layer "F.SilkS")
			(effects
				(font
					(size 0.635 0.4064)
					(thickness 0.1524)
				)
				(justify left)
			)
		)
		(fp_text user "44"
			(at 4.7244 -16.245332 0)
			(unlocked yes)
			(layer "F.SilkS")
			(effects
				(font
					(size 0.635 0.4064)
					(thickness 0.1524)
				)
				(justify left)
			)
		)
		(fp_text user "45"
			(at 5.4864 -15.102332 0)
			(unlocked yes)
			(layer "F.SilkS")
			(effects
				(font
					(size 0.635 0.4064)
					(thickness 0.1524)
				)
				(justify left)
			)
		)
		(fp_text user "46"
			(at 5.7404 -16.245332 0)
			(unlocked yes)
			(layer "F.SilkS")
			(effects
				(font
					(size 0.635 0.4064)
					(thickness 0.1524)
				)
				(justify left)
			)
		)
		(fp_text user "47"
			(at 6.5024 -15.102332 0)
			(unlocked yes)
			(layer "F.SilkS")
			(effects
				(font
					(size 0.635 0.4064)
					(thickness 0.1524)
				)
				(justify left)
			)
		)
		(fp_text user "48"
			(at 6.688074 -16.032734 0)
			(unlocked yes)
			(layer "F.SilkS")
			(effects
				(font
					(size 0.635 0.4064)
					(thickness 0.1524)
				)
				(justify left)
			)
		)
		(fp_text user "49"
			(at 7.3914 -15.102332 0)
			(unlocked yes)
			(layer "F.SilkS")
			(effects
				(font
					(size 0.635 0.4064)
					(thickness 0.1524)
				)
				(justify left)
			)
		)
		(fp_text user "50"
			(at 7.706614 -15.983458 0)
			(unlocked yes)
			(layer "F.SilkS")
			(effects
				(font
					(size 0.635 0.4064)
					(thickness 0.1524)
				)
				(justify left)
			)
		)
		(fp_text user "51"
			(at 8.2804 -15.102332 0)
			(unlocked yes)
			(layer "F.SilkS")
			(effects
				(font
					(size 0.635 0.4064)
					(thickness 0.1524)
				)
				(justify left)
			)
		)
		(fp_text user "52"
			(at 8.783574 -15.901162 0)
			(unlocked yes)
			(layer "F.SilkS")
			(effects
				(font
					(size 0.635 0.4064)
					(thickness 0.1524)
				)
				(justify left)
			)
		)
		(fp_text user "53"
			(at 9.1694 -15.102332 0)
			(unlocked yes)
			(layer "F.SilkS")
			(effects
				(font
					(size 0.635 0.4064)
					(thickness 0.1524)
				)
				(justify left)
			)
		)
		(fp_text user "54"
			(at 9.76122 -16.014954 0)
			(unlocked yes)
			(layer "F.SilkS")
			(effects
				(font
					(size 0.635 0.4064)
					(thickness 0.1524)
				)
				(justify left)
			)
		)
		(fp_text user "55"
			(at 10.1854 -15.102332 0)
			(unlocked yes)
			(layer "F.SilkS")
			(effects
				(font
					(size 0.635 0.4064)
					(thickness 0.1524)
				)
				(justify left)
			)
		)
		(fp_text user "56"
			(at 10.77722 -16.014954 0)
			(unlocked yes)
			(layer "F.SilkS")
			(effects
				(font
					(size 0.635 0.4064)
					(thickness 0.1524)
				)
				(justify left)
			)
		)
		(fp_text user "57"
			(at 11.0744 -15.102332 0)
			(unlocked yes)
			(layer "F.SilkS")
			(effects
				(font
					(size 0.635 0.4064)
					(thickness 0.1524)
				)
				(justify left)
			)
		)
		(fp_text user "58"
			(at 11.79322 -16.014954 0)
			(unlocked yes)
			(layer "F.SilkS")
			(effects
				(font
					(size 0.635 0.4064)
					(thickness 0.1524)
				)
				(justify left)
			)
		)
		(fp_text user "59"
			(at 12.0904 -15.102332 0)
			(unlocked yes)
			(layer "F.SilkS")
			(effects
				(font
					(size 0.635 0.4064)
					(thickness 0.1524)
				)
				(justify left)
			)
		)
		(fp_text user "60"
			(at 12.80922 -16.014954 0)
			(unlocked yes)
			(layer "F.SilkS")
			(effects
				(font
					(size 0.635 0.4064)
					(thickness 0.1524)
				)
				(justify left)
			)
		)
		(fp_text user "61"
			(at 13.1064 -15.102332 0)
			(unlocked yes)
			(layer "F.SilkS")
			(effects
				(font
					(size 0.635 0.4064)
					(thickness 0.1524)
				)
				(justify left)
			)
		)
		(fp_text user "62"
			(at 13.7414 -15.973806 0)
			(unlocked yes)
			(layer "F.SilkS")
			(effects
				(font
					(size 0.635 0.4064)
					(thickness 0.1524)
				)
				(justify left)
			)
		)
		(fp_text user "63"
			(at 14.1224 -15.102332 0)
			(unlocked yes)
			(layer "F.SilkS")
			(effects
				(font
					(size 0.635 0.4064)
					(thickness 0.1524)
				)
				(justify left)
			)
		)
		(fp_text user "64"
			(at 14.7574 -15.973806 0)
			(unlocked yes)
			(layer "F.SilkS")
			(effects
				(font
					(size 0.635 0.4064)
					(thickness 0.1524)
				)
				(justify left)
			)
		)
		(fp_text user "65"
			(at 15.1384 -15.102332 0)
			(unlocked yes)
			(layer "F.SilkS")
			(effects
				(font
					(size 0.635 0.4064)
					(thickness 0.1524)
				)
				(justify left)
			)
		)
		(fp_text user "66"
			(at 15.7734 -15.973806 0)
			(unlocked yes)
			(layer "F.SilkS")
			(effects
				(font
					(size 0.635 0.4064)
					(thickness 0.1524)
				)
				(justify left)
			)
		)
		(fp_text user "BP"
			(at -19.5326 13.275818 0)
			(unlocked yes)
			(layer "F.Fab")
			(effects
				(font
					(size 0.508 0.381)
					(thickness 0.000001)
				)
				(justify left)
			)
		)
		(fp_text user "A"
			(at -18.4404 -13.394182 0)
			(unlocked yes)
			(layer "F.Fab")
			(effects
				(font
					(size 0.508 0.381)
					(thickness 0.000001)
				)
				(justify left)
			)
		)
		(fp_text user "1"
			(at -16.4084 -15.045182 0)
			(unlocked yes)
			(layer "F.Fab")
			(effects
				(font
					(size 0.508 0.381)
					(thickness 0.000001)
				)
				(justify left)
			)
		)
		(fp_text user "66"
			(at 15.7734 -16.188182 0)
			(unlocked yes)
			(layer "F.Fab")
			(effects
				(font
					(size 0.508 0.381)
					(thickness 0.000001)
				)
				(justify left)
			)
		)
		(pad "A5" smd circle
			(at -14.485366 -13.110972)
			(size 0.4064 0.4064)
			(layers "F.Cu" "F.Mask" "F.Paste")
			(net "GND")
		)
		(pad "A6" smd circle
			(at -13.672566 -13.110972)
			(size 0.4064 0.4064)
			(layers "F.Cu" "F.Mask" "F.Paste")
			(net "GND")
		)
		(pad "A8" smd oval
			(at -12.859766 -13.110972)
			(size 0.2794 0.3429)
			(layers "F.Cu" "F.Mask" "F.Paste")
			(net "GND")
		)
		(pad "A9" smd oval
			(at -12.173458 -13.249402)
			(size 0.254 0.3429)
			(layers "F.Cu" "F.Mask" "F.Paste")
			(net "GND")
		)
		(pad "A12" smd oval
			(at -10.547858 -13.249402)
			(size 0.254 0.3429)
			(layers "F.Cu" "F.Mask" "F.Paste")
			(net "GND")
		)
		(pad "A15" smd oval
			(at -9.109202 -13.249402)
			(size 0.254 0.3429)
			(layers "F.Cu" "F.Mask" "F.Paste")
			(net "GND")
		)
		(pad "A18" smd oval
			(at -7.670546 -13.249402)
			(size 0.254 0.3429)
			(layers "F.Cu" "F.Mask" "F.Paste")
			(net "GND")
		)
		(pad "A21" smd oval
			(at -6.044946 -13.249402)
			(size 0.254 0.3429)
			(layers "F.Cu" "F.Mask" "F.Paste")
			(net "GND")
		)
		(pad "A24" smd oval
			(at -4.60629 -13.249402)
			(size 0.254 0.3429)
			(layers "F.Cu" "F.Mask" "F.Paste")
			(net "GND")
		)
		(pad "A27" smd oval
			(at -3.167634 -13.249402)
			(size 0.254 0.3429)
			(layers "F.Cu" "F.Mask" "F.Paste")
			(net "GND")
		)
		(pad "A30" smd oval
			(at -1.542034 -13.249402)
			(size 0.254 0.3429)
			(layers "F.Cu" "F.Mask" "F.Paste")
			(net "GND")
		)
		(pad "A33" smd oval
			(at -0.103378 -13.249402)
			(size 0.254 0.3429)
			(layers "F.Cu" "F.Mask" "F.Paste")
			(net "GND")
		)
		(pad "A36" smd oval
			(at 1.335278 -13.249402)
			(size 0.254 0.3429)
			(layers "F.Cu" "F.Mask" "F.Paste")
			(net "GND")
		)
		(pad "A39" smd oval
			(at 2.960878 -13.249402)
			(size 0.254 0.3429)
			(layers "F.Cu" "F.Mask" "F.Paste")
			(net "GND")
		)
		(pad "A42" smd oval
			(at 4.399534 -13.249402)
			(size 0.254 0.3429)
			(layers "F.Cu" "F.Mask" "F.Paste")
			(net "GND")
		)
		(pad "A45" smd oval
			(at 5.83819 -13.249402)
			(size 0.254 0.3429)
			(layers "F.Cu" "F.Mask" "F.Paste")
			(net "GND")
		)
		(pad "A48" smd oval
			(at 7.46379 -13.249402)
			(size 0.254 0.3429)
			(layers "F.Cu" "F.Mask" "F.Paste")
			(net "SPC_CPU_NODE1_DTR_L")
		)
		(pad "A51" smd oval
			(at 8.902446 -13.249402)
			(size 0.254 0.3429)
			(layers "F.Cu" "F.Mask" "F.Paste")
			(net "TP_CPU_NODE1_C2F_LP_MODE")
		)
		(pad "A54" smd oval
			(at 10.341102 -13.249402)
			(size 0.254 0.3429)
			(layers "F.Cu" "F.Mask" "F.Paste")
			(net "GND")
		)
		(pad "A57" smd oval
			(at 11.966702 -13.249402)
			(size 0.254 0.3429)
			(layers "F.Cu" "F.Mask" "F.Paste")
			(net "GND")
		)
		(pad "A59" smd oval
			(at 12.859766 -13.110972)
			(size 0.2794 0.3429)
			(layers "F.Cu" "F.Mask" "F.Paste")
			(net "GND")
		)
		(pad "A61" smd circle
			(at 13.672566 -13.110972)
			(size 0.4064 0.4064)
			(layers "F.Cu" "F.Mask" "F.Paste")
			(net "GND")
		)
		(pad "A62" smd circle
			(at 14.485366 -13.110972)
			(size 0.4064 0.4064)
			(layers "F.Cu" "F.Mask" "F.Paste")
			(net "GND")
		)
		(pad "A64" smd circle
			(at 15.298166 -13.110972)
			(size 0.4064 0.4064)
			(layers "F.Cu" "F.Mask" "F.Paste")
			(net "GND")
		)
		(pad "A66" smd circle
			(at 16.110966 -13.110972)
			(size 0.4064 0.4064)
			(layers "F.Cu" "F.Mask" "F.Paste")
			(net "GND")
		)
		(pad "AA3" smd circle
			(at -15.247112 -3.216402)
			(size 0.3048 0.3048)
			(layers "F.Cu" "F.Mask" "F.Paste")
			(net "GND")
		)
		(pad "AA5" smd circle
			(at -14.013688 -3.186176)
			(size 0.3048 0.3048)
			(layers "F.Cu" "F.Mask" "F.Paste")
			(net "GND")
		)
		(pad "AA21" smd circle
			(at -6.00075 -3.2004)
			(size 0.381 0.381)
			(layers "F.Cu" "F.Mask" "F.Paste")
			(net "P1V5_NODE1_AA21")
		)
		(pad "AA23" smd circle
			(at -5.20065 -3.2004)
			(size 0.381 0.381)
			(layers "F.Cu" "F.Mask" "F.Paste")
			(net "PD_NODE1_NTB_RCOMP")
		)
		(pad "AA25" smd circle
			(at -4.40055 -3.2004)
			(size 0.381 0.381)
			(layers "F.Cu" "F.Mask" "F.Paste")
			(net "GND")
		)
		(pad "AA26" smd circle
			(at -3.60045 -3.2004)
			(size 0.381 0.381)
			(layers "F.Cu" "F.Mask" "F.Paste")
			(net "GND")
		)
		(pad "AA28" smd circle
			(at -2.80035 -3.2004)
			(size 0.381 0.381)
			(layers "F.Cu" "F.Mask" "F.Paste")
			(net "P1V5_NODE1")
		)
		(pad "AA29" smd circle
			(at -2.00025 -3.2004)
			(size 0.381 0.381)
			(layers "F.Cu" "F.Mask" "F.Paste")
			(net "GND")
		)
		(pad "AA31" smd circle
			(at -1.20015 -3.2004)
			(size 0.381 0.381)
			(layers "F.Cu" "F.Mask" "F.Paste")
			(net "P1V05_NODE1")
		)
		(pad "AA32" smd circle
			(at -0.40005 -3.2004)
			(size 0.381 0.381)
			(layers "F.Cu" "F.Mask" "F.Paste")
			(net "GND")
		)
		(pad "AA34" smd circle
			(at 0.40005 -3.2004)
			(size 0.381 0.381)
			(layers "F.Cu" "F.Mask" "F.Paste")
			(net "P1V05_NODE1")
		)
		(pad "AA36" smd circle
			(at 1.20015 -3.2004)
			(size 0.381 0.381)
			(layers "F.Cu" "F.Mask" "F.Paste")
			(net "GND")
		)
		(pad "AA38" smd circle
			(at 2.00025 -3.2004)
			(size 0.381 0.381)
			(layers "F.Cu" "F.Mask" "F.Paste")
			(net "P1V05_NODE1")
		)
		(pad "AA39" smd circle
			(at 2.80035 -3.2004)
			(size 0.381 0.381)
			(layers "F.Cu" "F.Mask" "F.Paste")
			(net "GND")
		)
		(pad "AA41" smd circle
			(at 3.60045 -3.2004)
			(size 0.381 0.381)
			(layers "F.Cu" "F.Mask" "F.Paste")
			(net "P1V05_NODE1")
		)
		(pad "AA42" smd circle
			(at 4.40055 -3.2004)
			(size 0.381 0.381)
			(layers "F.Cu" "F.Mask" "F.Paste")
			(net "GND")
		)
		(pad "AA44" smd circle
			(at 5.20065 -3.2004)
			(size 0.381 0.381)
			(layers "F.Cu" "F.Mask" "F.Paste")
			(net "PV_VCCP_NODE1")
		)
		(pad "AA46" smd circle
			(at 6.00075 -3.2004)
			(size 0.381 0.381)
			(layers "F.Cu" "F.Mask" "F.Paste")
			(net "PV_VCCP_NODE1")
		)
		(pad "AA47" smd circle
			(at 6.841998 -3.156204)
			(size 0.3048 0.3048)
			(layers "F.Cu" "F.Mask" "F.Paste")
			(net "GND")
		)
		(pad "AA62" smd circle
			(at 14.08049 -3.38836)
			(size 0.3048 0.3048)
			(layers "F.Cu" "F.Mask" "F.Paste")
			(net "XDP_SOC_CPU_NODE1_TRST_L")
		)
		(pad "AA64" smd circle
			(at 15.242794 -3.398266)
			(size 0.3048 0.3048)
			(layers "F.Cu" "F.Mask" "F.Paste")
			(net "XDP_SOC_CPU_NODE1_TDO")
		)
		(pad "AA66" smd oval
			(at 16.249396 -3.167888 90)
			(size 0.254 0.3429)
			(layers "F.Cu" "F.Mask" "F.Paste")
			(net "XDP_SOC_CPU_NODE1_TDI")
		)
		(pad "AB1" smd oval
			(at -16.249396 -2.960624 270)
			(size 0.254 0.3429)
			(layers "F.Cu" "F.Mask" "F.Paste")
			(net "GND")
		)
		(pad "AB2" smd circle
			(at -15.640812 -2.61112)
			(size 0.3048 0.3048)
			(layers "F.Cu" "F.Mask" "F.Paste")
			(net "PD_CPU_NODE1_RP2_PERP")
		)
		(pad "AB4" smd circle
			(at -14.90091 -2.605024)
			(size 0.3048 0.3048)
			(layers "F.Cu" "F.Mask" "F.Paste")
			(net "PD_CPU_NODE1_RP2_PERN")
		)
		(pad "AB5" smd circle
			(at -14.204442 -2.507996)
			(size 0.3048 0.3048)
			(layers "F.Cu" "F.Mask" "F.Paste")
			(net "PD_CPU_NODE1_RP2_PERP")
		)
		(pad "AB20" smd circle
			(at -6.841998 -2.916428)
			(size 0.3048 0.3048)
			(layers "F.Cu" "F.Mask" "F.Paste")
			(net "GND")
		)
		(pad "AB62" smd circle
			(at 14.204442 -2.69494)
			(size 0.3048 0.3048)
			(layers "F.Cu" "F.Mask" "F.Paste")
			(net "SVID_CPU_NODE1_PVCCP_CLK")
		)
		(pad "AB63" smd circle
			(at 14.90091 -2.786888)
			(size 0.3048 0.3048)
			(layers "F.Cu" "F.Mask" "F.Paste")
			(net "SVID_CPU_NODE1_PVCCP_ALERT_R_L")
		)
		(pad "AB65" smd circle
			(at 15.639034 -2.818384)
			(size 0.3048 0.3048)
			(layers "F.Cu" "F.Mask" "F.Paste")
			(net "GND")
		)
		(pad "AC8" smd circle
			(at -12.963398 -2.216404)
			(size 0.3048 0.3048)
			(layers "F.Cu" "F.Mask" "F.Paste")
			(net "GND")
		)
		(pad "AC9" smd circle
			(at -12.201398 -2.216404)
			(size 0.3048 0.3048)
			(layers "F.Cu" "F.Mask" "F.Paste")
			(net "Net_380")
		)
		(pad "AC11" smd circle
			(at -11.439398 -2.216404)
			(size 0.3048 0.3048)
			(layers "F.Cu" "F.Mask" "F.Paste")
			(net "Net_393")
		)
		(pad "AC12" smd circle
			(at -10.677398 -2.216404)
			(size 0.3048 0.3048)
			(layers "F.Cu" "F.Mask" "F.Paste")
			(net "GND")
		)
		(pad "AC14" smd circle
			(at -9.915398 -2.216404)
			(size 0.3048 0.3048)
			(layers "F.Cu" "F.Mask" "F.Paste")
			(net "Net_396")
		)
		(pad "AC15" smd circle
			(at -9.153398 -2.216404)
			(size 0.3048 0.3048)
			(layers "F.Cu" "F.Mask" "F.Paste")
			(net "Net_371")
		)
		(pad "AC17" smd circle
			(at -8.391398 -2.216404)
			(size 0.3048 0.3048)
			(layers "F.Cu" "F.Mask" "F.Paste")
			(net "GND")
		)
		(pad "AC18" smd circle
			(at -7.629398 -2.216404)
			(size 0.3048 0.3048)
			(layers "F.Cu" "F.Mask" "F.Paste")
			(net "P1V05_NODE1")
		)
		(pad "AC20" smd circle
			(at -6.929374 -2.216404)
			(size 0.3048 0.3048)
			(layers "F.Cu" "F.Mask" "F.Paste")
			(net "P1V05_NODE1")
		)
		(pad "AC21" smd circle
			(at -6.00075 -2.4003)
			(size 0.381 0.381)
			(layers "F.Cu" "F.Mask" "F.Paste")
			(net "P1V05_NODE1")
		)
		(pad "AC23" smd circle
			(at -5.20065 -2.4003)
			(size 0.381 0.381)
			(layers "F.Cu" "F.Mask" "F.Paste")
			(net "P1V05_NODE1")
		)
		(pad "AC25" smd circle
			(at -4.40055 -2.4003)
			(size 0.381 0.381)
			(layers "F.Cu" "F.Mask" "F.Paste")
			(net "P1V05_NODE1")
		)
		(pad "AC26" smd circle
			(at -3.60045 -2.4003)
			(size 0.381 0.381)
			(layers "F.Cu" "F.Mask" "F.Paste")
			(net "P1V05_NODE1")
		)
		(pad "AC28" smd circle
			(at -2.80035 -2.4003)
			(size 0.381 0.381)
			(layers "F.Cu" "F.Mask" "F.Paste")
			(net "GND")
		)
		(pad "AC29" smd circle
			(at -2.00025 -2.4003)
			(size 0.381 0.381)
			(layers "F.Cu" "F.Mask" "F.Paste")
			(net "GND")
		)
		(pad "AC31" smd circle
			(at -1.20015 -2.4003)
			(size 0.381 0.381)
			(layers "F.Cu" "F.Mask" "F.Paste")
			(net "P1V05_NODE1")
		)
		(pad "AC32" smd circle
			(at -0.40005 -2.4003)
			(size 0.381 0.381)
			(layers "F.Cu" "F.Mask" "F.Paste")
			(net "GND")
		)
		(pad "AC34" smd circle
			(at 0.40005 -2.4003)
			(size 0.381 0.381)
			(layers "F.Cu" "F.Mask" "F.Paste")
			(net "P1V05_NODE1")
		)
		(pad "AC36" smd circle
			(at 1.20015 -2.4003)
			(size 0.381 0.381)
			(layers "F.Cu" "F.Mask" "F.Paste")
			(net "P1V05_NODE1")
		)
		(pad "AC38" smd circle
			(at 2.00025 -2.4003)
			(size 0.381 0.381)
			(layers "F.Cu" "F.Mask" "F.Paste")
			(net "A_CPU0_NODE1_THERMDC")
		)
		(pad "AC39" smd circle
			(at 2.80035 -2.4003)
			(size 0.381 0.381)
			(layers "F.Cu" "F.Mask" "F.Paste")
			(net "GND")
		)
		(pad "AC41" smd circle
			(at 3.60045 -2.4003)
			(size 0.381 0.381)
			(layers "F.Cu" "F.Mask" "F.Paste")
			(net "TP_CPU_NODE1_VCCCPU0VIDSI0GT1P0")
		)
		(pad "AC42" smd circle
			(at 4.40055 -2.4003)
			(size 0.381 0.381)
			(layers "F.Cu" "F.Mask" "F.Paste")
			(net "TP_CPU_NODE1_VCCCPU0VIDSI0GT1_1")
		)
		(pad "AC44" smd circle
			(at 5.20065 -2.4003)
			(size 0.381 0.381)
			(layers "F.Cu" "F.Mask" "F.Paste")
			(net "PV_VCCP_NODE1")
		)
		(pad "AC46" smd circle
			(at 6.00075 -2.4003)
			(size 0.381 0.381)
			(layers "F.Cu" "F.Mask" "F.Paste")
			(net "GND")
		)
		(pad "AC47" smd circle
			(at 6.929374 -2.45618)
			(size 0.3048 0.3048)
			(layers "F.Cu" "F.Mask" "F.Paste")
			(net "A_CPU_NODE1_LV_GPIO_RCOMP")
		)
		(pad "AC49" smd circle
			(at 7.629398 -2.45618)
			(size 0.3048 0.3048)
			(layers "F.Cu" "F.Mask" "F.Paste")
			(net "P1V05_VCCPLLCPU0SIO_NODE1")
		)
		(pad "AC50" smd circle
			(at 8.391398 -2.45618)
			(size 0.3048 0.3048)
			(layers "F.Cu" "F.Mask" "F.Paste")
			(net "GND")
		)
		(pad "AC52" smd circle
			(at 9.153398 -2.45618)
			(size 0.3048 0.3048)
			(layers "F.Cu" "F.Mask" "F.Paste")
			(net "XDP_CPU_NODE1_PRDY_L")
		)
		(pad "AC53" smd circle
			(at 9.915398 -2.45618)
			(size 0.3048 0.3048)
			(layers "F.Cu" "F.Mask" "F.Paste")
			(net "FM_CPU_NODE1_JTAG_POK")
		)
		(pad "AC55" smd circle
			(at 10.677398 -2.45618)
			(size 0.3048 0.3048)
			(layers "F.Cu" "F.Mask" "F.Paste")
			(net "GND")
		)
		(pad "AC56" smd circle
			(at 11.439398 -2.45618)
			(size 0.3048 0.3048)
			(layers "F.Cu" "F.Mask" "F.Paste")
			(net "H_CPU_NODE1_PROCHOT_R")
		)
		(pad "AC58" smd circle
			(at 12.201398 -2.45618)
			(size 0.3048 0.3048)
			(layers "F.Cu" "F.Mask" "F.Paste")
			(net "SVID_CPU_NODE1_PVCCP_DAT_R")
		)
		(pad "AC59" smd circle
			(at 12.963398 -2.45618)
			(size 0.3048 0.3048)
			(layers "F.Cu" "F.Mask" "F.Paste")
			(net "GND")
		)
		(pad "AD2" smd circle
			(at -15.639034 -1.684528)
			(size 0.3048 0.3048)
			(layers "F.Cu" "F.Mask" "F.Paste")
			(net "PD_CPU_NODE1_RP2_PERP")
		)
		(pad "AD4" smd circle
			(at -14.90091 -1.716024)
			(size 0.3048 0.3048)
			(layers "F.Cu" "F.Mask" "F.Paste")
			(net "PD_CPU_NODE1_RP2_PERN")
		)
		(pad "AD5" smd circle
			(at -14.204442 -1.807972)
			(size 0.3048 0.3048)
			(layers "F.Cu" "F.Mask" "F.Paste")
			(net "PD_CPU_NODE1_RP2_PERN")
		)
		(pad "AD8" smd circle
			(at -12.963398 -1.51638)
			(size 0.3048 0.3048)
			(layers "F.Cu" "F.Mask" "F.Paste")
			(net "GND")
		)
		(pad "AD9" smd circle
			(at -12.201398 -1.51638)
			(size 0.3048 0.3048)
			(layers "F.Cu" "F.Mask" "F.Paste")
			(net "Net_388")
		)
		(pad "AD11" smd circle
			(at -11.439398 -1.51638)
			(size 0.3048 0.3048)
			(layers "F.Cu" "F.Mask" "F.Paste")
			(net "Net_375")
		)
		(pad "AD12" smd circle
			(at -10.677398 -1.51638)
			(size 0.3048 0.3048)
			(layers "F.Cu" "F.Mask" "F.Paste")
			(net "GND")
		)
		(pad "AD14" smd circle
			(at -9.915398 -1.51638)
			(size 0.3048 0.3048)
			(layers "F.Cu" "F.Mask" "F.Paste")
			(net "Net_394")
		)
		(pad "AD15" smd circle
			(at -9.153398 -1.51638)
			(size 0.3048 0.3048)
			(layers "F.Cu" "F.Mask" "F.Paste")
			(net "Net_392")
		)
		(pad "AD17" smd circle
			(at -8.391398 -1.51638)
			(size 0.3048 0.3048)
			(layers "F.Cu" "F.Mask" "F.Paste")
			(net "GND")
		)
		(pad "AD18" smd circle
			(at -7.629398 -1.51638)
			(size 0.3048 0.3048)
			(layers "F.Cu" "F.Mask" "F.Paste")
			(net "P1V05_NODE1")
		)
		(pad "AD20" smd circle
			(at -6.929374 -1.51638)
			(size 0.3048 0.3048)
			(layers "F.Cu" "F.Mask" "F.Paste")
			(net "P1V05_NODE1")
		)
		(pad "AD21" smd circle
			(at -6.00075 -1.6002)
			(size 0.381 0.381)
			(layers "F.Cu" "F.Mask" "F.Paste")
			(net "GND")
		)
		(pad "AD23" smd circle
			(at -5.20065 -1.6002)
			(size 0.381 0.381)
			(layers "F.Cu" "F.Mask" "F.Paste")
			(net "P1V8_VCCASFRHPLL_NODE1")
		)
		(pad "AD25" smd circle
			(at -4.40055 -1.6002)
			(size 0.381 0.381)
			(layers "F.Cu" "F.Mask" "F.Paste")
			(net "P1V8_VCCASFRHPLL_NODE1")
		)
		(pad "AD26" smd circle
			(at -3.60045 -1.6002)
			(size 0.381 0.381)
			(layers "F.Cu" "F.Mask" "F.Paste")
			(net "GND")
		)
		(pad "AD28" smd circle
			(at -2.80035 -1.6002)
			(size 0.381 0.381)
			(layers "F.Cu" "F.Mask" "F.Paste")
			(net "P1V05_NODE1")
		)
		(pad "AD29" smd circle
			(at -2.00025 -1.6002)
			(size 0.381 0.381)
			(layers "F.Cu" "F.Mask" "F.Paste")
			(net "P1V05_NODE1")
		)
		(pad "AD31" smd circle
			(at -1.20015 -1.6002)
			(size 0.381 0.381)
			(layers "F.Cu" "F.Mask" "F.Paste")
			(net "GND")
		)
		(pad "AD32" smd circle
			(at -0.40005 -1.6002)
			(size 0.381 0.381)
			(layers "F.Cu" "F.Mask" "F.Paste")
			(net "P1V05_NODE1")
		)
		(pad "AD34" smd circle
			(at 0.40005 -1.6002)
			(size 0.381 0.381)
			(layers "F.Cu" "F.Mask" "F.Paste")
			(net "GND")
		)
		(pad "AD36" smd circle
			(at 1.20015 -1.6002)
			(size 0.381 0.381)
			(layers "F.Cu" "F.Mask" "F.Paste")
			(net "GND")
		)
		(pad "AD38" smd circle
			(at 2.00025 -1.6002)
			(size 0.381 0.381)
			(layers "F.Cu" "F.Mask" "F.Paste")
			(net "GND")
		)
		(pad "AD39" smd circle
			(at 2.80035 -1.6002)
			(size 0.381 0.381)
			(layers "F.Cu" "F.Mask" "F.Paste")
			(net "A_CPU0_NODE1_THERMDA")
		)
		(pad "AD41" smd circle
			(at 3.60045 -1.6002)
			(size 0.381 0.381)
			(layers "F.Cu" "F.Mask" "F.Paste")
			(net "VSENSE_VCC_CPU_NODE1")
		)
		(pad "AD42" smd circle
			(at 4.40055 -1.6002)
			(size 0.381 0.381)
			(layers "F.Cu" "F.Mask" "F.Paste")
			(net "GND")
		)
		(pad "AD44" smd circle
			(at 5.20065 -1.6002)
			(size 0.381 0.381)
			(layers "F.Cu" "F.Mask" "F.Paste")
			(net "GND")
		)
		(pad "AD46" smd circle
			(at 6.00075 -1.6002)
			(size 0.381 0.381)
			(layers "F.Cu" "F.Mask" "F.Paste")
			(net "GND")
		)
		(pad "AD47" smd circle
			(at 6.929374 -1.756156)
			(size 0.3048 0.3048)
			(layers "F.Cu" "F.Mask" "F.Paste")
			(net "P1V05_VCCPLLCPU1SIO_NODE1")
		)
		(pad "AD49" smd circle
			(at 7.629398 -1.756156)
			(size 0.3048 0.3048)
			(layers "F.Cu" "F.Mask" "F.Paste")
			(net "PD_CPU_NODE1_SPD_EN_L")
		)
		(pad "AD50" smd circle
			(at 8.391398 -1.756156)
			(size 0.3048 0.3048)
			(layers "F.Cu" "F.Mask" "F.Paste")
			(net "GND")
		)
		(pad "AD52" smd circle
			(at 9.153398 -1.756156)
			(size 0.3048 0.3048)
			(layers "F.Cu" "F.Mask" "F.Paste")
			(net "PD_CPU_NODE1_HVMGEAR_SEL")
		)
		(pad "AD53" smd circle
			(at 9.915398 -1.756156)
			(size 0.3048 0.3048)
			(layers "F.Cu" "F.Mask" "F.Paste")
			(net "PD_CPU_NODE1_MEM_SPEED1")
		)
		(pad "AD55" smd circle
			(at 10.677398 -1.756156)
			(size 0.3048 0.3048)
			(layers "F.Cu" "F.Mask" "F.Paste")
			(net "GND")
		)
		(pad "AD56" smd circle
			(at 11.439398 -1.756156)
			(size 0.3048 0.3048)
			(layers "F.Cu" "F.Mask" "F.Paste")
			(net "PU_CPU_NODE1_MEM_SPEED0")
		)
		(pad "AD58" smd circle
			(at 12.201398 -1.756156)
			(size 0.3048 0.3048)
			(layers "F.Cu" "F.Mask" "F.Paste")
			(net "PWRGD_CPU_NODE1_EPWRGOOD")
		)
		(pad "AD59" smd circle
			(at 12.963398 -1.756156)
			(size 0.3048 0.3048)
			(layers "F.Cu" "F.Mask" "F.Paste")
			(net "GND")
		)
		(pad "AD62" smd circle
			(at 14.204442 -1.994916)
			(size 0.3048 0.3048)
			(layers "F.Cu" "F.Mask" "F.Paste")
			(net "XDP_SOC_CPU_NODE1_TCK")
		)
		(pad "AD63" smd circle
			(at 14.90091 -1.897888)
			(size 0.3048 0.3048)
			(layers "F.Cu" "F.Mask" "F.Paste")
			(net "XDP_SOC_CPU_NODE1_TMS")
		)
		(pad "AD65" smd circle
			(at 15.640812 -1.891792)
			(size 0.3048 0.3048)
			(layers "F.Cu" "F.Mask" "F.Paste")
			(net "GND")
		)
		(pad "AD66" smd oval
			(at 16.249396 -1.542288 90)
			(size 0.254 0.3429)
			(layers "F.Cu" "F.Mask" "F.Paste")
			(net "GND")
		)
		(pad "AE1" smd oval
			(at -16.249396 -1.335024 270)
			(size 0.254 0.3429)
			(layers "F.Cu" "F.Mask" "F.Paste")
			(net "GND")
		)
		(pad "AE3" smd circle
			(at -15.242794 -1.104646)
			(size 0.3048 0.3048)
			(layers "F.Cu" "F.Mask" "F.Paste")
			(net "GND")
		)
		(pad "AE5" smd circle
			(at -14.08049 -1.114552)
			(size 0.3048 0.3048)
			(layers "F.Cu" "F.Mask" "F.Paste")
			(net "GND")
		)
		(pad "AE47" smd circle
			(at 6.841998 -1.056132)
			(size 0.3048 0.3048)
			(layers "F.Cu" "F.Mask" "F.Paste")
			(net "GND")
		)
		(pad "AE62" smd circle
			(at 14.013688 -1.316736)
			(size 0.3048 0.3048)
			(layers "F.Cu" "F.Mask" "F.Paste")
			(net "XDP_CPU_NODE1_PREQ_L")
		)
		(pad "AE64" smd circle
			(at 15.247112 -1.28651)
			(size 0.3048 0.3048)
			(layers "F.Cu" "F.Mask" "F.Paste")
			(net "A_CPU_NODE1_AE64_PU")
		)
		(pad "AF2" smd circle
			(at -15.752318 -0.617728)
			(size 0.3048 0.3048)
			(layers "F.Cu" "F.Mask" "F.Paste")
			(net "PD_CPU_NODE1_RP1_PERN")
		)
		(pad "AF4" smd circle
			(at -14.794738 -0.564896)
			(size 0.3048 0.3048)
			(layers "F.Cu" "F.Mask" "F.Paste")
			(net "PD_CPU_NODE1_RP1_PERP")
		)
		(pad "AF20" smd circle
			(at -6.841998 -0.816356)
			(size 0.3048 0.3048)
			(layers "F.Cu" "F.Mask" "F.Paste")
			(net "GND")
		)
		(pad "AF21" smd circle
			(at -6.00075 -0.8001)
			(size 0.381 0.381)
			(layers "F.Cu" "F.Mask" "F.Paste")
			(net "GND")
		)
		(pad "AF23" smd circle
			(at -5.20065 -0.8001)
			(size 0.381 0.381)
			(layers "F.Cu" "F.Mask" "F.Paste")
			(net "P3V3_NODE1")
		)
		(pad "AF25" smd circle
			(at -4.40055 -0.8001)
			(size 0.381 0.381)
			(layers "F.Cu" "F.Mask" "F.Paste")
			(net "GND")
		)
		(pad "AF26" smd circle
			(at -3.60045 -0.8001)
			(size 0.381 0.381)
			(layers "F.Cu" "F.Mask" "F.Paste")
			(net "GND")
		)
		(pad "AF28" smd circle
			(at -2.80035 -0.8001)
			(size 0.381 0.381)
			(layers "F.Cu" "F.Mask" "F.Paste")
			(net "P1V5_NODE1")
		)
		(pad "AF29" smd circle
			(at -2.00025 -0.8001)
			(size 0.381 0.381)
			(layers "F.Cu" "F.Mask" "F.Paste")
			(net "GND")
		)
		(pad "AF31" smd circle
			(at -1.20015 -0.8001)
			(size 0.381 0.381)
			(layers "F.Cu" "F.Mask" "F.Paste")
			(net "P1V05_NODE1")
		)
		(pad "AF32" smd circle
			(at -0.40005 -0.8001)
			(size 0.381 0.381)
			(layers "F.Cu" "F.Mask" "F.Paste")
			(net "GND")
		)
		(pad "AF34" smd circle
			(at 0.40005 -0.8001)
			(size 0.381 0.381)
			(layers "F.Cu" "F.Mask" "F.Paste")
			(net "GND")
		)
		(pad "AF36" smd circle
			(at 1.20015 -0.8001)
			(size 0.381 0.381)
			(layers "F.Cu" "F.Mask" "F.Paste")
			(net "P1V05_NODE1")
		)
		(pad "AF38" smd circle
			(at 2.00025 -0.8001)
			(size 0.381 0.381)
			(layers "F.Cu" "F.Mask" "F.Paste")
			(net "A_CPU1_NODE1_THERMDC")
		)
		(pad "AF39" smd circle
			(at 2.80035 -0.8001)
			(size 0.381 0.381)
			(layers "F.Cu" "F.Mask" "F.Paste")
			(net "GND")
		)
		(pad "AF41" smd circle
			(at 3.60045 -0.8001)
			(size 0.381 0.381)
			(layers "F.Cu" "F.Mask" "F.Paste")
			(net "VSENSE_VSS_CPU_NODE1")
		)
		(pad "AF42" smd circle
			(at 4.40055 -0.8001)
			(size 0.381 0.381)
			(layers "F.Cu" "F.Mask" "F.Paste")
			(net "GND")
		)
		(pad "AF44" smd circle
			(at 5.20065 -0.8001)
			(size 0.381 0.381)
			(layers "F.Cu" "F.Mask" "F.Paste")
			(net "GND")
		)
		(pad "AF46" smd circle
			(at 6.00075 -0.8001)
			(size 0.381 0.381)
			(layers "F.Cu" "F.Mask" "F.Paste")
			(net "GND")
		)
		(pad "AF62" smd circle
			(at 14.063218 -0.614426)
			(size 0.3048 0.3048)
			(layers "F.Cu" "F.Mask" "F.Paste")
			(net "GND")
		)
		(pad "AF63" smd circle
			(at 14.751558 -0.783336)
			(size 0.3048 0.3048)
			(layers "F.Cu" "F.Mask" "F.Paste")
			(net "Net_444")
		)
		(pad "AF65" smd circle
			(at 15.805658 -0.863092)
			(size 0.3048 0.3048)
			(layers "F.Cu" "F.Mask" "F.Paste")
			(net "GND")
		)
		(pad "AG5" smd circle
			(at -14.063218 -0.407162)
			(size 0.3048 0.3048)
			(layers "F.Cu" "F.Mask" "F.Paste")
			(net "PD_CPU_NODE1_RP1_PERP")
		)
		(pad "AG7" smd circle
			(at -13.344398 -0.230124)
			(size 0.3048 0.3048)
			(layers "F.Cu" "F.Mask" "F.Paste")
			(net "GND")
		)
		(pad "AG8" smd circle
			(at -12.582398 -0.230124)
			(size 0.3048 0.3048)
			(layers "F.Cu" "F.Mask" "F.Paste")
			(net "Net_386")
		)
		(pad "AG10" smd circle
			(at -11.820398 -0.230124)
			(size 0.3048 0.3048)
			(layers "F.Cu" "F.Mask" "F.Paste")
			(net "Net_379")
		)
		(pad "AG11" smd circle
			(at -11.058398 -0.230124)
			(size 0.3048 0.3048)
			(layers "F.Cu" "F.Mask" "F.Paste")
			(net "GND")
		)
		(pad "AG13" smd circle
			(at -10.296398 -0.230124)
			(size 0.3048 0.3048)
			(layers "F.Cu" "F.Mask" "F.Paste")
			(net "Net_374")
		)
		(pad "AG14" smd circle
			(at -9.534398 -0.230124)
			(size 0.3048 0.3048)
			(layers "F.Cu" "F.Mask" "F.Paste")
			(net "Net_373")
		)
		(pad "AG16" smd circle
			(at -8.772398 -0.230124)
			(size 0.3048 0.3048)
			(layers "F.Cu" "F.Mask" "F.Paste")
			(net "GND")
		)
		(pad "AG17" smd circle
			(at -8.010398 -0.230124)
			(size 0.3048 0.3048)
			(layers "F.Cu" "F.Mask" "F.Paste")
			(net "GND")
		)
		(pad "AG19" smd circle
			(at -7.248398 -0.230124)
			(size 0.3048 0.3048)
			(layers "F.Cu" "F.Mask" "F.Paste")
			(net "GND")
		)
		(pad "AG21" smd circle
			(at -6.00075 0)
			(size 0.381 0.381)
			(layers "F.Cu" "F.Mask" "F.Paste")
			(net "GND")
		)
		(pad "AG23" smd circle
			(at -5.20065 0)
			(size 0.381 0.381)
			(layers "F.Cu" "F.Mask" "F.Paste")
			(net "TP_P1V8_VCCABGTS_NODE1")
		)
		(pad "AG25" smd circle
			(at -4.40055 0)
			(size 0.381 0.381)
			(layers "F.Cu" "F.Mask" "F.Paste")
			(net "GND")
		)
		(pad "AG26" smd circle
			(at -3.60045 0)
			(size 0.381 0.381)
			(layers "F.Cu" "F.Mask" "F.Paste")
			(net "GND")
		)
		(pad "AG28" smd circle
			(at -2.80035 0)
			(size 0.381 0.381)
			(layers "F.Cu" "F.Mask" "F.Paste")
			(net "P1V8_NODE1")
		)
		(pad "AG29" smd circle
			(at -2.00025 0)
			(size 0.381 0.381)
			(layers "F.Cu" "F.Mask" "F.Paste")
			(net "P1V05_NODE1")
		)
		(pad "AG31" smd circle
			(at -1.20015 0)
			(size 0.381 0.381)
			(layers "F.Cu" "F.Mask" "F.Paste")
			(net "GND")
		)
		(pad "AG32" smd circle
			(at -0.40005 0)
			(size 0.381 0.381)
			(layers "F.Cu" "F.Mask" "F.Paste")
			(net "P1V05_NODE1")
		)
		(pad "AG34" smd circle
			(at 0.40005 0)
			(size 0.381 0.381)
			(layers "F.Cu" "F.Mask" "F.Paste")
			(net "P1V05_NODE1")
		)
		(pad "AG36" smd circle
			(at 1.20015 0)
			(size 0.381 0.381)
			(layers "F.Cu" "F.Mask" "F.Paste")
			(net "P1V05_NODE1")
		)
		(pad "AG38" smd circle
			(at 2.00025 0)
			(size 0.381 0.381)
			(layers "F.Cu" "F.Mask" "F.Paste")
			(net "GND")
		)
		(pad "AG39" smd circle
			(at 2.80035 0)
			(size 0.381 0.381)
			(layers "F.Cu" "F.Mask" "F.Paste")
			(net "A_CPU1_NODE1_THERMDA")
		)
		(pad "AG41" smd circle
			(at 3.60045 0)
			(size 0.381 0.381)
			(layers "F.Cu" "F.Mask" "F.Paste")
			(net "TP_CPU_NODE1_VCCCPU1VIDSI0GT1P0")
		)
		(pad "AG42" smd circle
			(at 4.40055 0)
			(size 0.381 0.381)
			(layers "F.Cu" "F.Mask" "F.Paste")
			(net "TP_CPU_NODE1_VCCCPU1VIDSI0GT1_1")
		)
		(pad "AG44" smd circle
			(at 5.20065 0)
			(size 0.381 0.381)
			(layers "F.Cu" "F.Mask" "F.Paste")
			(net "GND")
		)
		(pad "AG46" smd circle
			(at 6.00075 0)
			(size 0.381 0.381)
			(layers "F.Cu" "F.Mask" "F.Paste")
			(net "GND")
		)
		(pad "AG48" smd circle
			(at 7.248398 -0.4699)
			(size 0.3048 0.3048)
			(layers "F.Cu" "F.Mask" "F.Paste")
			(net "PD_CPU_NODE1_PUNIT_ST_ADDR0")
		)
		(pad "AG50" smd circle
			(at 8.010398 -0.4699)
			(size 0.3048 0.3048)
			(layers "F.Cu" "F.Mask" "F.Paste")
			(net "TP_CPU1_NODE1_HFPLL")
		)
		(pad "AG51" smd circle
			(at 8.772398 -0.4699)
			(size 0.3048 0.3048)
			(layers "F.Cu" "F.Mask" "F.Paste")
			(net "GND")
		)
		(pad "AG53" smd circle
			(at 9.534398 -0.4699)
			(size 0.3048 0.3048)
			(layers "F.Cu" "F.Mask" "F.Paste")
			(net "Net_449")
		)
		(pad "AG54" smd circle
			(at 10.296398 -0.4699)
			(size 0.3048 0.3048)
			(layers "F.Cu" "F.Mask" "F.Paste")
			(net "TP_CPU_NODE1_IERR_LV")
		)
		(pad "AG56" smd circle
			(at 11.058398 -0.4699)
			(size 0.3048 0.3048)
			(layers "F.Cu" "F.Mask" "F.Paste")
			(net "GND")
		)
		(pad "AG57" smd circle
			(at 11.820398 -0.4699)
			(size 0.3048 0.3048)
			(layers "F.Cu" "F.Mask" "F.Paste")
			(net "Net_299")
		)
		(pad "AG59" smd circle
			(at 12.582398 -0.4699)
			(size 0.3048 0.3048)
			(layers "F.Cu" "F.Mask" "F.Paste")
			(net "H_CPU_NODE1_THRMTRIP_L")
		)
		(pad "AG60" smd circle
			(at 13.344398 -0.4699)
			(size 0.3048 0.3048)
			(layers "F.Cu" "F.Mask" "F.Paste")
			(net "Net_446")
		)
		(pad "AG63" smd circle
			(at 14.542516 -0.103632)
			(size 0.3048 0.3048)
			(layers "F.Cu" "F.Mask" "F.Paste")
			(net "Net_439")
		)
		(pad "AG64" smd circle
			(at 15.304516 -0.052832)
			(size 0.3048 0.3048)
			(layers "F.Cu" "F.Mask" "F.Paste")
			(net "Net_445")
		)
		(pad "AG66" smd oval
			(at 16.249396 -0.103632 90)
			(size 0.254 0.3429)
			(layers "F.Cu" "F.Mask" "F.Paste")
			(net "Net_447")
		)
		(pad "AH1" smd oval
			(at -16.249396 0.103632 270)
			(size 0.254 0.3429)
			(layers "F.Cu" "F.Mask" "F.Paste")
			(net "PD_CPU_NODE1_RP1_PERN")
		)
		(pad "AH3" smd circle
			(at -15.304516 0.052832)
			(size 0.3048 0.3048)
			(layers "F.Cu" "F.Mask" "F.Paste")
			(net "PD_CPU_NODE1_RP1_PERP")
		)
		(pad "AH4" smd circle
			(at -14.542516 0.103632)
			(size 0.3048 0.3048)
			(layers "F.Cu" "F.Mask" "F.Paste")
			(net "PD_CPU_NODE1_RP1_PERN")
		)
		(pad "AH7" smd circle
			(at -13.344398 0.4699)
			(size 0.3048 0.3048)
			(layers "F.Cu" "F.Mask" "F.Paste")
			(net "GND")
		)
		(pad "AH8" smd circle
			(at -12.582398 0.4699)
			(size 0.3048 0.3048)
			(layers "F.Cu" "F.Mask" "F.Paste")
			(net "Net_398")
		)
		(pad "AH10" smd circle
			(at -11.820398 0.4699)
			(size 0.3048 0.3048)
			(layers "F.Cu" "F.Mask" "F.Paste")
			(net "Net_400")
		)
		(pad "AH11" smd circle
			(at -11.058398 0.4699)
			(size 0.3048 0.3048)
			(layers "F.Cu" "F.Mask" "F.Paste")
			(net "GND")
		)
		(pad "AH13" smd circle
			(at -10.296398 0.4699)
			(size 0.3048 0.3048)
			(layers "F.Cu" "F.Mask" "F.Paste")
			(net "Net_397")
		)
		(pad "AH14" smd circle
			(at -9.534398 0.4699)
			(size 0.3048 0.3048)
			(layers "F.Cu" "F.Mask" "F.Paste")
			(net "Net_372")
		)
		(pad "AH16" smd circle
			(at -8.772398 0.4699)
			(size 0.3048 0.3048)
			(layers "F.Cu" "F.Mask" "F.Paste")
			(net "GND")
		)
		(pad "AH17" smd circle
			(at -8.010398 0.4699)
			(size 0.3048 0.3048)
			(layers "F.Cu" "F.Mask" "F.Paste")
			(net "GND")
		)
		(pad "AH19" smd circle
			(at -7.248398 0.4699)
			(size 0.3048 0.3048)
			(layers "F.Cu" "F.Mask" "F.Paste")
			(net "GND")
		)
		(pad "AH48" smd circle
			(at 7.248398 0.230124)
			(size 0.3048 0.3048)
			(layers "F.Cu" "F.Mask" "F.Paste")
			(net "PD_CPU_NODE1_PUNIT_ST_ADDR1")
		)
		(pad "AH50" smd circle
			(at 8.010398 0.230124)
			(size 0.3048 0.3048)
			(layers "F.Cu" "F.Mask" "F.Paste")
			(net "TP_CPU0_NODE1_HFPLL")
		)
		(pad "AH51" smd circle
			(at 8.772398 0.230124)
			(size 0.3048 0.3048)
			(layers "F.Cu" "F.Mask" "F.Paste")
			(net "GND")
		)
		(pad "AH53" smd circle
			(at 9.534398 0.230124)
			(size 0.3048 0.3048)
			(layers "F.Cu" "F.Mask" "F.Paste")
			(net "FM_CPU_NODE1_OWDTOUT")
		)
		(pad "AH54" smd circle
			(at 10.296398 0.230124)
			(size 0.3048 0.3048)
			(layers "F.Cu" "F.Mask" "F.Paste")
			(net "Net_448")
		)
		(pad "AH56" smd circle
			(at 11.058398 0.230124)
			(size 0.3048 0.3048)
			(layers "F.Cu" "F.Mask" "F.Paste")
			(net "GND")
		)
		(pad "AH57" smd circle
			(at 11.820398 0.230124)
			(size 0.3048 0.3048)
			(layers "F.Cu" "F.Mask" "F.Paste")
			(net "Net_440")
		)
		(pad "AH59" smd circle
			(at 12.582398 0.230124)
			(size 0.3048 0.3048)
			(layers "F.Cu" "F.Mask" "F.Paste")
			(net "Net_441")
		)
		(pad "AH60" smd circle
			(at 13.344398 0.230124)
			(size 0.3048 0.3048)
			(layers "F.Cu" "F.Mask" "F.Paste")
			(net "GND")
		)
		(pad "AH62" smd circle
			(at 14.063218 0.407162)
			(size 0.3048 0.3048)
			(layers "F.Cu" "F.Mask" "F.Paste")
			(net "Net_443")
		)
		(pad "AJ2" smd circle
			(at -15.805658 0.863092)
			(size 0.3048 0.3048)
			(layers "F.Cu" "F.Mask" "F.Paste")
			(net "GND")
		)
		(pad "AJ4" smd circle
			(at -14.751558 0.783336)
			(size 0.3048 0.3048)
			(layers "F.Cu" "F.Mask" "F.Paste")
			(net "GND")
		)
		(pad "AJ5" smd circle
			(at -14.063218 0.614426)
			(size 0.3048 0.3048)
			(layers "F.Cu" "F.Mask" "F.Paste")
			(net "GND")
		)
		(pad "AJ21" smd circle
			(at -6.00075 0.8001)
			(size 0.381 0.381)
			(layers "F.Cu" "F.Mask" "F.Paste")
			(net "P1V5_NODE1_AJ21")
		)
		(pad "AJ23" smd circle
			(at -5.20065 0.8001)
			(size 0.381 0.381)
			(layers "F.Cu" "F.Mask" "F.Paste")
			(net "PD_CPU_NODE1_AJ23")
		)
		(pad "AJ25" smd circle
			(at -4.40055 0.8001)
			(size 0.381 0.381)
			(layers "F.Cu" "F.Mask" "F.Paste")
			(net "GND")
		)
		(pad "AJ26" smd circle
			(at -3.60045 0.8001)
			(size 0.381 0.381)
			(layers "F.Cu" "F.Mask" "F.Paste")
			(net "GND")
		)
		(pad "AJ28" smd circle
			(at -2.80035 0.8001)
			(size 0.381 0.381)
			(layers "F.Cu" "F.Mask" "F.Paste")
			(net "P1V5_NODE1")
		)
		(pad "AJ29" smd circle
			(at -2.00025 0.8001)
			(size 0.381 0.381)
			(layers "F.Cu" "F.Mask" "F.Paste")
			(net "GND")
		)
		(pad "AJ31" smd circle
			(at -1.20015 0.8001)
			(size 0.381 0.381)
			(layers "F.Cu" "F.Mask" "F.Paste")
			(net "P1V05_NODE1")
		)
		(pad "AJ32" smd circle
			(at -0.40005 0.8001)
			(size 0.381 0.381)
			(layers "F.Cu" "F.Mask" "F.Paste")
			(net "GND")
		)
		(pad "AJ34" smd circle
			(at 0.40005 0.8001)
			(size 0.381 0.381)
			(layers "F.Cu" "F.Mask" "F.Paste")
			(net "P1V05_NODE1")
		)
		(pad "AJ36" smd circle
			(at 1.20015 0.8001)
			(size 0.381 0.381)
			(layers "F.Cu" "F.Mask" "F.Paste")
			(net "GND")
		)
		(pad "AJ38" smd circle
			(at 2.00025 0.8001)
			(size 0.381 0.381)
			(layers "F.Cu" "F.Mask" "F.Paste")
			(net "P1V05_NODE1")
		)
		(pad "AJ39" smd circle
			(at 2.80035 0.8001)
			(size 0.381 0.381)
			(layers "F.Cu" "F.Mask" "F.Paste")
			(net "GND")
		)
		(pad "AJ41" smd circle
			(at 3.60045 0.8001)
			(size 0.381 0.381)
			(layers "F.Cu" "F.Mask" "F.Paste")
			(net "P1V05_NODE1")
		)
		(pad "AJ42" smd circle
			(at 4.40055 0.8001)
			(size 0.381 0.381)
			(layers "F.Cu" "F.Mask" "F.Paste")
			(net "GND")
		)
		(pad "AJ44" smd circle
			(at 5.20065 0.8001)
			(size 0.381 0.381)
			(layers "F.Cu" "F.Mask" "F.Paste")
			(net "P1V05_NODE1")
		)
		(pad "AJ46" smd circle
			(at 6.00075 0.8001)
			(size 0.381 0.381)
			(layers "F.Cu" "F.Mask" "F.Paste")
			(net "GND")
		)
		(pad "AJ47" smd circle
			(at 6.841998 0.816356)
			(size 0.3048 0.3048)
			(layers "F.Cu" "F.Mask" "F.Paste")
			(net "GND")
		)
		(pad "AJ63" smd circle
			(at 14.794738 0.564896)
			(size 0.3048 0.3048)
			(layers "F.Cu" "F.Mask" "F.Paste")
			(net "Net_436")
		)
		(pad "AJ65" smd circle
			(at 15.752318 0.617728)
			(size 0.3048 0.3048)
			(layers "F.Cu" "F.Mask" "F.Paste")
			(net "Net_438")
		)
		(pad "AK3" smd circle
			(at -15.247112 1.28651)
			(size 0.3048 0.3048)
			(layers "F.Cu" "F.Mask" "F.Paste")
			(net "GND")
		)
		(pad "AK5" smd circle
			(at -14.013688 1.316736)
			(size 0.3048 0.3048)
			(layers "F.Cu" "F.Mask" "F.Paste")
			(net "GND")
		)
		(pad "AK20" smd circle
			(at -6.841998 1.056132)
			(size 0.3048 0.3048)
			(layers "F.Cu" "F.Mask" "F.Paste")
			(net "GND")
		)
		(pad "AK62" smd circle
			(at 14.08049 1.114552)
			(size 0.3048 0.3048)
			(layers "F.Cu" "F.Mask" "F.Paste")
			(net "GND")
		)
		(pad "AK64" smd circle
			(at 15.242794 1.104646)
			(size 0.3048 0.3048)
			(layers "F.Cu" "F.Mask" "F.Paste")
			(net "GND")
		)
		(pad "AK66" smd oval
			(at 16.249396 1.335024 90)
			(size 0.254 0.3429)
			(layers "F.Cu" "F.Mask" "F.Paste")
			(net "GND")
		)
		(pad "AL1" smd oval
			(at -16.249396 1.542288 270)
			(size 0.254 0.3429)
			(layers "F.Cu" "F.Mask" "F.Paste")
			(net "GND")
		)
		(pad "AL2" smd circle
			(at -15.640812 1.891792)
			(size 0.3048 0.3048)
			(layers "F.Cu" "F.Mask" "F.Paste")
			(net "PD_CPU_NODE1_RP1_PERP")
		)
		(pad "AL4" smd circle
			(at -14.90091 1.897888)
			(size 0.3048 0.3048)
			(layers "F.Cu" "F.Mask" "F.Paste")
			(net "PD_CPU_NODE1_RP1_PERN")
		)
		(pad "AL5" smd circle
			(at -14.204442 1.994916)
			(size 0.3048 0.3048)
			(layers "F.Cu" "F.Mask" "F.Paste")
			(net "PD_CPU_NODE1_AL5")
		)
		(pad "AL8" smd circle
			(at -12.963398 1.756156)
			(size 0.3048 0.3048)
			(layers "F.Cu" "F.Mask" "F.Paste")
			(net "GND")
		)
		(pad "AL9" smd circle
			(at -12.201398 1.756156)
			(size 0.3048 0.3048)
			(layers "F.Cu" "F.Mask" "F.Paste")
			(net "Net_384")
		)
		(pad "AL11" smd circle
			(at -11.439398 1.756156)
			(size 0.3048 0.3048)
			(layers "F.Cu" "F.Mask" "F.Paste")
			(net "Net_376")
		)
		(pad "AL12" smd circle
			(at -10.677398 1.756156)
			(size 0.3048 0.3048)
			(layers "F.Cu" "F.Mask" "F.Paste")
			(net "GND")
		)
		(pad "AL14" smd circle
			(at -9.915398 1.756156)
			(size 0.3048 0.3048)
			(layers "F.Cu" "F.Mask" "F.Paste")
			(net "Net_389")
		)
		(pad "AL15" smd circle
			(at -9.153398 1.756156)
			(size 0.3048 0.3048)
			(layers "F.Cu" "F.Mask" "F.Paste")
			(net "Net_390")
		)
		(pad "AL17" smd circle
			(at -8.391398 1.756156)
			(size 0.3048 0.3048)
			(layers "F.Cu" "F.Mask" "F.Paste")
			(net "GND")
		)
		(pad "AL18" smd circle
			(at -7.629398 1.756156)
			(size 0.3048 0.3048)
			(layers "F.Cu" "F.Mask" "F.Paste")
			(net "P1V05_NODE1")
		)
		(pad "AL20" smd circle
			(at -6.929374 1.756156)
			(size 0.3048 0.3048)
			(layers "F.Cu" "F.Mask" "F.Paste")
			(net "P1V05_NODE1")
		)
		(pad "AL21" smd circle
			(at -6.00075 1.6002)
			(size 0.381 0.381)
			(layers "F.Cu" "F.Mask" "F.Paste")
			(net "P1V05_NODE1")
		)
		(pad "AL23" smd circle
			(at -5.20065 1.6002)
			(size 0.381 0.381)
			(layers "F.Cu" "F.Mask" "F.Paste")
			(net "P1V05_NODE1")
		)
		(pad "AL25" smd circle
			(at -4.40055 1.6002)
			(size 0.381 0.381)
			(layers "F.Cu" "F.Mask" "F.Paste")
			(net "P1V05_NODE1")
		)
		(pad "AL26" smd circle
			(at -3.60045 1.6002)
			(size 0.381 0.381)
			(layers "F.Cu" "F.Mask" "F.Paste")
			(net "P1V05_NODE1")
		)
		(pad "AL28" smd circle
			(at -2.80035 1.6002)
			(size 0.381 0.381)
			(layers "F.Cu" "F.Mask" "F.Paste")
			(net "P1V05_NODE1")
		)
		(pad "AL29" smd circle
			(at -2.00025 1.6002)
			(size 0.381 0.381)
			(layers "F.Cu" "F.Mask" "F.Paste")
			(net "P1V05_NODE1")
		)
		(pad "AL31" smd circle
			(at -1.20015 1.6002)
			(size 0.381 0.381)
			(layers "F.Cu" "F.Mask" "F.Paste")
			(net "GND")
		)
		(pad "AL32" smd circle
			(at -0.40005 1.6002)
			(size 0.381 0.381)
			(layers "F.Cu" "F.Mask" "F.Paste")
			(net "P1V05_NODE1")
		)
		(pad "AL34" smd circle
			(at 0.40005 1.6002)
			(size 0.381 0.381)
			(layers "F.Cu" "F.Mask" "F.Paste")
			(net "GND")
		)
		(pad "AL36" smd circle
			(at 1.20015 1.6002)
			(size 0.381 0.381)
			(layers "F.Cu" "F.Mask" "F.Paste")
			(net "P1V05_NODE1")
		)
		(pad "AL38" smd circle
			(at 2.00025 1.6002)
			(size 0.381 0.381)
			(layers "F.Cu" "F.Mask" "F.Paste")
			(net "GND")
		)
		(pad "AL39" smd circle
			(at 2.80035 1.6002)
			(size 0.381 0.381)
			(layers "F.Cu" "F.Mask" "F.Paste")
			(net "P1V05_NODE1")
		)
		(pad "AL41" smd circle
			(at 3.60045 1.6002)
			(size 0.381 0.381)
			(layers "F.Cu" "F.Mask" "F.Paste")
			(net "GND")
		)
		(pad "AL42" smd circle
			(at 4.40055 1.6002)
			(size 0.381 0.381)
			(layers "F.Cu" "F.Mask" "F.Paste")
			(net "P1V05_NODE1")
		)
		(pad "AL44" smd circle
			(at 5.20065 1.6002)
			(size 0.381 0.381)
			(layers "F.Cu" "F.Mask" "F.Paste")
			(net "GND")
		)
		(pad "AL46" smd circle
			(at 6.00075 1.6002)
			(size 0.381 0.381)
			(layers "F.Cu" "F.Mask" "F.Paste")
			(net "GND")
		)
		(pad "AL47" smd circle
			(at 6.929374 1.51638)
			(size 0.3048 0.3048)
			(layers "F.Cu" "F.Mask" "F.Paste")
			(net "P1V05_NODE1")
		)
		(pad "AL49" smd circle
			(at 7.629398 1.51638)
			(size 0.3048 0.3048)
			(layers "F.Cu" "F.Mask" "F.Paste")
			(net "P1V05_NODE1")
		)
		(pad "AL50" smd circle
			(at 8.391398 1.51638)
			(size 0.3048 0.3048)
			(layers "F.Cu" "F.Mask" "F.Paste")
			(net "GND")
		)
		(pad "AL52" smd circle
			(at 9.153398 1.51638)
			(size 0.3048 0.3048)
			(layers "F.Cu" "F.Mask" "F.Paste")
			(net "XDP_CPU_NODE1_VISA16")
		)
		(pad "AL53" smd circle
			(at 9.915398 1.51638)
			(size 0.3048 0.3048)
			(layers "F.Cu" "F.Mask" "F.Paste")
			(net "XDP_CPU_NODE1_VISA15")
		)
		(pad "AL55" smd circle
			(at 10.677398 1.51638)
			(size 0.3048 0.3048)
			(layers "F.Cu" "F.Mask" "F.Paste")
			(net "GND")
		)
		(pad "AL56" smd circle
			(at 11.439398 1.51638)
			(size 0.3048 0.3048)
			(layers "F.Cu" "F.Mask" "F.Paste")
			(net "Net_442")
		)
		(pad "AL58" smd circle
			(at 12.201398 1.51638)
			(size 0.3048 0.3048)
			(layers "F.Cu" "F.Mask" "F.Paste")
			(net "Net_437")
		)
		(pad "AL59" smd circle
			(at 12.963398 1.51638)
			(size 0.3048 0.3048)
			(layers "F.Cu" "F.Mask" "F.Paste")
			(net "GND")
		)
		(pad "AL62" smd circle
			(at 14.204442 1.807972)
			(size 0.3048 0.3048)
			(layers "F.Cu" "F.Mask" "F.Paste")
			(net "M1_DQ_NODE1_DQ62")
		)
		(pad "AL63" smd circle
			(at 14.90091 1.716024)
			(size 0.3048 0.3048)
			(layers "F.Cu" "F.Mask" "F.Paste")
			(net "M1_DQ_NODE1_DQ60")
		)
		(pad "AL65" smd circle
			(at 15.639034 1.684528)
			(size 0.3048 0.3048)
			(layers "F.Cu" "F.Mask" "F.Paste")
			(net "M1_DQ_NODE1_DQ63")
		)
		(pad "AM8" smd circle
			(at -12.963398 2.45618)
			(size 0.3048 0.3048)
			(layers "F.Cu" "F.Mask" "F.Paste")
			(net "GND")
		)
		(pad "AM9" smd circle
			(at -12.201398 2.45618)
			(size 0.3048 0.3048)
			(layers "F.Cu" "F.Mask" "F.Paste")
			(net "Net_382")
		)
		(pad "AM11" smd circle
			(at -11.439398 2.45618)
			(size 0.3048 0.3048)
			(layers "F.Cu" "F.Mask" "F.Paste")
			(net "Net_383")
		)
		(pad "AM12" smd circle
			(at -10.677398 2.45618)
			(size 0.3048 0.3048)
			(layers "F.Cu" "F.Mask" "F.Paste")
			(net "GND")
		)
		(pad "AM14" smd circle
			(at -9.915398 2.45618)
			(size 0.3048 0.3048)
			(layers "F.Cu" "F.Mask" "F.Paste")
			(net "Net_454")
		)
		(pad "AM15" smd circle
			(at -9.153398 2.45618)
			(size 0.3048 0.3048)
			(layers "F.Cu" "F.Mask" "F.Paste")
			(net "Net_391")
		)
		(pad "AM17" smd circle
			(at -8.391398 2.45618)
			(size 0.3048 0.3048)
			(layers "F.Cu" "F.Mask" "F.Paste")
			(net "GND")
		)
		(pad "AM18" smd circle
			(at -7.629398 2.45618)
			(size 0.3048 0.3048)
			(layers "F.Cu" "F.Mask" "F.Paste")
			(net "GND")
		)
		(pad "AM20" smd circle
			(at -6.929374 2.45618)
			(size 0.3048 0.3048)
			(layers "F.Cu" "F.Mask" "F.Paste")
			(net "GND")
		)
		(pad "AM21" smd circle
			(at -6.00075 2.4003)
			(size 0.381 0.381)
			(layers "F.Cu" "F.Mask" "F.Paste")
			(net "P1V5_NODE1_AM21")
		)
		(pad "AM23" smd circle
			(at -5.20065 2.4003)
			(size 0.381 0.381)
			(layers "F.Cu" "F.Mask" "F.Paste")
			(net "PD_CPU_NODE1_AM23")
		)
		(pad "AM25" smd circle
			(at -4.40055 2.4003)
			(size 0.381 0.381)
			(layers "F.Cu" "F.Mask" "F.Paste")
			(net "GND")
		)
		(pad "AM26" smd circle
			(at -3.60045 2.4003)
			(size 0.381 0.381)
			(layers "F.Cu" "F.Mask" "F.Paste")
			(net "GND")
		)
		(pad "AM28" smd circle
			(at -2.80035 2.4003)
			(size 0.381 0.381)
			(layers "F.Cu" "F.Mask" "F.Paste")
			(net "P1V5_NODE1")
		)
		(pad "AM29" smd circle
			(at -2.00025 2.4003)
			(size 0.381 0.381)
			(layers "F.Cu" "F.Mask" "F.Paste")
			(net "GND")
		)
		(pad "AM31" smd circle
			(at -1.20015 2.4003)
			(size 0.381 0.381)
			(layers "F.Cu" "F.Mask" "F.Paste")
			(net "P1V05_NODE1")
		)
		(pad "AM32" smd circle
			(at -0.40005 2.4003)
			(size 0.381 0.381)
			(layers "F.Cu" "F.Mask" "F.Paste")
			(net "GND")
		)
		(pad "AM34" smd circle
			(at 0.40005 2.4003)
			(size 0.381 0.381)
			(layers "F.Cu" "F.Mask" "F.Paste")
			(net "P1V05_NODE1")
		)
		(pad "AM36" smd circle
			(at 1.20015 2.4003)
			(size 0.381 0.381)
			(layers "F.Cu" "F.Mask" "F.Paste")
			(net "GND")
		)
		(pad "AM38" smd circle
			(at 2.00025 2.4003)
			(size 0.381 0.381)
			(layers "F.Cu" "F.Mask" "F.Paste")
			(net "P1V05_NODE1")
		)
		(pad "AM39" smd circle
			(at 2.80035 2.4003)
			(size 0.381 0.381)
			(layers "F.Cu" "F.Mask" "F.Paste")
			(net "GND")
		)
		(pad "AM41" smd circle
			(at 3.60045 2.4003)
			(size 0.381 0.381)
			(layers "F.Cu" "F.Mask" "F.Paste")
			(net "P1V05_NODE1")
		)
		(pad "AM42" smd circle
			(at 4.40055 2.4003)
			(size 0.381 0.381)
			(layers "F.Cu" "F.Mask" "F.Paste")
			(net "GND")
		)
		(pad "AM44" smd circle
			(at 5.20065 2.4003)
			(size 0.381 0.381)
			(layers "F.Cu" "F.Mask" "F.Paste")
			(net "GND")
		)
		(pad "AM46" smd circle
			(at 6.00075 2.4003)
			(size 0.381 0.381)
			(layers "F.Cu" "F.Mask" "F.Paste")
			(net "GND")
		)
		(pad "AM47" smd circle
			(at 6.929374 2.216404)
			(size 0.3048 0.3048)
			(layers "F.Cu" "F.Mask" "F.Paste")
			(net "GND")
		)
		(pad "AM49" smd circle
			(at 7.629398 2.216404)
			(size 0.3048 0.3048)
			(layers "F.Cu" "F.Mask" "F.Paste")
			(net "GND")
		)
		(pad "AM50" smd circle
			(at 8.391398 2.216404)
			(size 0.3048 0.3048)
			(layers "F.Cu" "F.Mask" "F.Paste")
			(net "GND")
		)
		(pad "AM52" smd circle
			(at 9.153398 2.216404)
			(size 0.3048 0.3048)
			(layers "F.Cu" "F.Mask" "F.Paste")
			(net "XDP_CPU_NODE1_VISA10")
		)
		(pad "AM53" smd circle
			(at 9.915398 2.216404)
			(size 0.3048 0.3048)
			(layers "F.Cu" "F.Mask" "F.Paste")
			(net "XDP_CPU_NODE1_VISA9")
		)
		(pad "AM55" smd circle
			(at 10.677398 2.216404)
			(size 0.3048 0.3048)
			(layers "F.Cu" "F.Mask" "F.Paste")
			(net "GND")
		)
		(pad "AM56" smd circle
			(at 11.439398 2.216404)
			(size 0.3048 0.3048)
			(layers "F.Cu" "F.Mask" "F.Paste")
			(net "XDP_CPU_NODE1_VISA13")
		)
		(pad "AM58" smd circle
			(at 12.201398 2.216404)
			(size 0.3048 0.3048)
			(layers "F.Cu" "F.Mask" "F.Paste")
			(net "XDP_CPU_NODE1_VISA12")
		)
		(pad "AM59" smd circle
			(at 12.963398 2.216404)
			(size 0.3048 0.3048)
			(layers "F.Cu" "F.Mask" "F.Paste")
			(net "GND")
		)
		(pad "AN2" smd circle
			(at -15.639034 2.818384)
			(size 0.3048 0.3048)
			(layers "F.Cu" "F.Mask" "F.Paste")
			(net "PD_CPU_NODE1_RP1_PERN")
		)
		(pad "AN4" smd circle
			(at -14.90091 2.786888)
			(size 0.3048 0.3048)
			(layers "F.Cu" "F.Mask" "F.Paste")
			(net "PD_CPU_NODE1_RP1_PERP")
		)
		(pad "AN5" smd circle
			(at -14.204442 2.69494)
			(size 0.3048 0.3048)
			(layers "F.Cu" "F.Mask" "F.Paste")
			(net "PD_CPU_NODE1_AN5")
		)
		(pad "AN47" smd circle
			(at 6.841998 2.916428)
			(size 0.3048 0.3048)
			(layers "F.Cu" "F.Mask" "F.Paste")
			(net "GND")
		)
		(pad "AN62" smd circle
			(at 14.204442 2.507996)
			(size 0.3048 0.3048)
			(layers "F.Cu" "F.Mask" "F.Paste")
			(net "GND")
		)
		(pad "AN63" smd circle
			(at 14.90091 2.605024)
			(size 0.3048 0.3048)
			(layers "F.Cu" "F.Mask" "F.Paste")
			(net "M_DDR3_NODE1_DQS7P")
		)
		(pad "AN65" smd circle
			(at 15.640812 2.61112)
			(size 0.3048 0.3048)
			(layers "F.Cu" "F.Mask" "F.Paste")
			(net "M1_DQ_NODE1_DQ59")
		)
		(pad "AN66" smd oval
			(at 16.249396 2.960624 90)
			(size 0.254 0.3429)
			(layers "F.Cu" "F.Mask" "F.Paste")
			(net "GND")
		)
		(pad "AP1" smd oval
			(at -16.249396 3.167888 270)
			(size 0.254 0.3429)
			(layers "F.Cu" "F.Mask" "F.Paste")
			(net "GND")
		)
		(pad "AP3" smd circle
			(at -15.242794 3.398266)
			(size 0.3048 0.3048)
			(layers "F.Cu" "F.Mask" "F.Paste")
			(net "GND")
		)
		(pad "AP5" smd circle
			(at -14.08049 3.38836)
			(size 0.3048 0.3048)
			(layers "F.Cu" "F.Mask" "F.Paste")
			(net "GND")
		)
		(pad "AP20" smd circle
			(at -6.841998 3.156204)
			(size 0.3048 0.3048)
			(layers "F.Cu" "F.Mask" "F.Paste")
			(net "P1V05_NODE1")
		)
		(pad "AP21" smd circle
			(at -6.00075 3.2004)
			(size 0.381 0.381)
			(layers "F.Cu" "F.Mask" "F.Paste")
			(net "P1V05_NODE1")
		)
		(pad "AP23" smd circle
			(at -5.20065 3.2004)
			(size 0.381 0.381)
			(layers "F.Cu" "F.Mask" "F.Paste")
			(net "P1V05_NODE1")
		)
		(pad "AP25" smd circle
			(at -4.40055 3.2004)
			(size 0.381 0.381)
			(layers "F.Cu" "F.Mask" "F.Paste")
			(net "P1V05_NODE1")
		)
		(pad "AP26" smd circle
			(at -3.60045 3.2004)
			(size 0.381 0.381)
			(layers "F.Cu" "F.Mask" "F.Paste")
			(net "P1V05_NODE1")
		)
		(pad "AP28" smd circle
			(at -2.80035 3.2004)
			(size 0.381 0.381)
			(layers "F.Cu" "F.Mask" "F.Paste")
			(net "P1V05_NODE1")
		)
		(pad "AP29" smd circle
			(at -2.00025 3.2004)
			(size 0.381 0.381)
			(layers "F.Cu" "F.Mask" "F.Paste")
			(net "P1V05_NODE1")
		)
		(pad "AP31" smd circle
			(at -1.20015 3.2004)
			(size 0.381 0.381)
			(layers "F.Cu" "F.Mask" "F.Paste")
			(net "GND")
		)
		(pad "AP32" smd circle
			(at -0.40005 3.2004)
			(size 0.381 0.381)
			(layers "F.Cu" "F.Mask" "F.Paste")
			(net "P1V05_NODE1")
		)
		(pad "AP34" smd circle
			(at 0.40005 3.2004)
			(size 0.381 0.381)
			(layers "F.Cu" "F.Mask" "F.Paste")
			(net "GND")
		)
		(pad "AP36" smd circle
			(at 1.20015 3.2004)
			(size 0.381 0.381)
			(layers "F.Cu" "F.Mask" "F.Paste")
			(net "P1V05_NODE1")
		)
		(pad "AP38" smd circle
			(at 2.00025 3.2004)
			(size 0.381 0.381)
			(layers "F.Cu" "F.Mask" "F.Paste")
			(net "P1V05_NODE1")
		)
		(pad "AP39" smd circle
			(at 2.80035 3.2004)
			(size 0.381 0.381)
			(layers "F.Cu" "F.Mask" "F.Paste")
			(net "P1V05_NODE1")
		)
		(pad "AP41" smd circle
			(at 3.60045 3.2004)
			(size 0.381 0.381)
			(layers "F.Cu" "F.Mask" "F.Paste")
			(net "P1V05_NODE1")
		)
		(pad "AP42" smd circle
			(at 4.40055 3.2004)
			(size 0.381 0.381)
			(layers "F.Cu" "F.Mask" "F.Paste")
			(net "P1V05_NODE1")
		)
		(pad "AP44" smd circle
			(at 5.20065 3.2004)
			(size 0.381 0.381)
			(layers "F.Cu" "F.Mask" "F.Paste")
			(net "P1V05_NODE1")
		)
		(pad "AP46" smd circle
			(at 6.00075 3.2004)
			(size 0.381 0.381)
			(layers "F.Cu" "F.Mask" "F.Paste")
			(net "P1V05_NODE1")
		)
		(pad "AP62" smd circle
			(at 14.013688 3.186176)
			(size 0.3048 0.3048)
			(layers "F.Cu" "F.Mask" "F.Paste")
			(net "GND")
		)
		(pad "AP64" smd circle
			(at 15.247112 3.216402)
			(size 0.3048 0.3048)
			(layers "F.Cu" "F.Mask" "F.Paste")
			(net "M_DDR3_NODE1_DQS7N")
		)
		(pad "AR2" smd circle
			(at -15.752318 3.885184)
			(size 0.3048 0.3048)
			(layers "F.Cu" "F.Mask" "F.Paste")
			(net "PD_CPU_NODE1_RP1_PERN")
		)
		(pad "AR4" smd circle
			(at -14.794738 3.938016)
			(size 0.3048 0.3048)
			(layers "F.Cu" "F.Mask" "F.Paste")
			(net "PD_CPU_NODE1_RP1_PERP")
		)
		(pad "AR7" smd circle
			(at -13.344398 3.742436)
			(size 0.3048 0.3048)
			(layers "F.Cu" "F.Mask" "F.Paste")
			(net "GND")
		)
		(pad "AR8" smd circle
			(at -12.582398 3.742436)
			(size 0.3048 0.3048)
			(layers "F.Cu" "F.Mask" "F.Paste")
			(net "Net_385")
		)
		(pad "AR10" smd circle
			(at -11.820398 3.742436)
			(size 0.3048 0.3048)
			(layers "F.Cu" "F.Mask" "F.Paste")
			(net "Net_453")
		)
		(pad "AR11" smd circle
			(at -11.058398 3.742436)
			(size 0.3048 0.3048)
			(layers "F.Cu" "F.Mask" "F.Paste")
			(net "GND")
		)
		(pad "AR13" smd circle
			(at -10.296398 3.742436)
			(size 0.3048 0.3048)
			(layers "F.Cu" "F.Mask" "F.Paste")
			(net "GND")
		)
		(pad "AR14" smd circle
			(at -9.534398 3.742436)
			(size 0.3048 0.3048)
			(layers "F.Cu" "F.Mask" "F.Paste")
			(net "Net_378")
		)
		(pad "AR16" smd circle
			(at -8.772398 3.742436)
			(size 0.3048 0.3048)
			(layers "F.Cu" "F.Mask" "F.Paste")
			(net "Net_381")
		)
		(pad "AR17" smd circle
			(at -8.010398 3.742436)
			(size 0.3048 0.3048)
			(layers "F.Cu" "F.Mask" "F.Paste")
			(net "GND")
		)
		(pad "AR19" smd circle
			(at -7.248398 3.742436)
			(size 0.3048 0.3048)
			(layers "F.Cu" "F.Mask" "F.Paste")
			(net "P1V05_NODE1")
		)
		(pad "AR48" smd circle
			(at 7.248398 3.50266)
			(size 0.3048 0.3048)
			(layers "F.Cu" "F.Mask" "F.Paste")
			(net "P1V05_NODE1")
		)
		(pad "AR50" smd circle
			(at 8.010398 3.50266)
			(size 0.3048 0.3048)
			(layers "F.Cu" "F.Mask" "F.Paste")
			(net "P1V05_NODE1")
		)
		(pad "AR51" smd circle
			(at 8.772398 3.50266)
			(size 0.3048 0.3048)
			(layers "F.Cu" "F.Mask" "F.Paste")
			(net "GND")
		)
		(pad "AR53" smd circle
			(at 9.534398 3.50266)
			(size 0.3048 0.3048)
			(layers "F.Cu" "F.Mask" "F.Paste")
			(net "XDP_CPU_NODE1_VISA1")
		)
		(pad "AR54" smd circle
			(at 10.296398 3.50266)
			(size 0.3048 0.3048)
			(layers "F.Cu" "F.Mask" "F.Paste")
			(net "XDP_CPU_NODE1_VISA4")
		)
		(pad "AR56" smd circle
			(at 11.058398 3.50266)
			(size 0.3048 0.3048)
			(layers "F.Cu" "F.Mask" "F.Paste")
			(net "GND")
		)
		(pad "AR57" smd circle
			(at 11.820398 3.50266)
			(size 0.3048 0.3048)
			(layers "F.Cu" "F.Mask" "F.Paste")
			(net "XDP_CPU_NODE1_VISA7")
		)
		(pad "AR59" smd circle
			(at 12.582398 3.50266)
			(size 0.3048 0.3048)
			(layers "F.Cu" "F.Mask" "F.Paste")
			(net "XDP_CPU_NODE1_VISA11")
		)
		(pad "AR60" smd circle
			(at 13.344398 3.50266)
			(size 0.3048 0.3048)
			(layers "F.Cu" "F.Mask" "F.Paste")
			(net "XDP_CPU_NODE1_VISA8")
		)
		(pad "AR62" smd circle
			(at 14.063218 3.888486)
			(size 0.3048 0.3048)
			(layers "F.Cu" "F.Mask" "F.Paste")
			(net "GND")
		)
		(pad "AR63" smd circle
			(at 14.751558 3.719576)
			(size 0.3048 0.3048)
			(layers "F.Cu" "F.Mask" "F.Paste")
			(net "M1_DQ_NODE1_DQ61")
		)
		(pad "AR65" smd circle
			(at 15.805658 3.63982)
			(size 0.3048 0.3048)
			(layers "F.Cu" "F.Mask" "F.Paste")
			(net "M1_DQ_NODE1_DQ58")
		)
		(pad "AT5" smd circle
			(at -14.063218 4.09575)
			(size 0.3048 0.3048)
			(layers "F.Cu" "F.Mask" "F.Paste")
			(net "PD_CPU_NODE1_RP1_PERN")
		)
		(pad "AT7" smd circle
			(at -13.344398 4.44246)
			(size 0.3048 0.3048)
			(layers "F.Cu" "F.Mask" "F.Paste")
			(net "GND")
		)
		(pad "AT8" smd circle
			(at -12.582398 4.44246)
			(size 0.3048 0.3048)
			(layers "F.Cu" "F.Mask" "F.Paste")
			(net "Net_387")
		)
		(pad "AT10" smd circle
			(at -11.820398 4.44246)
			(size 0.3048 0.3048)
			(layers "F.Cu" "F.Mask" "F.Paste")
			(net "Net_377")
		)
		(pad "AT11" smd circle
			(at -11.058398 4.44246)
			(size 0.3048 0.3048)
			(layers "F.Cu" "F.Mask" "F.Paste")
			(net "GND")
		)
		(pad "AT13" smd circle
			(at -10.296398 4.44246)
			(size 0.3048 0.3048)
			(layers "F.Cu" "F.Mask" "F.Paste")
			(net "Net_395")
		)
		(pad "AT14" smd circle
			(at -9.534398 4.44246)
			(size 0.3048 0.3048)
			(layers "F.Cu" "F.Mask" "F.Paste")
			(net "Net_450")
		)
		(pad "AT16" smd circle
			(at -8.772398 4.44246)
			(size 0.3048 0.3048)
			(layers "F.Cu" "F.Mask" "F.Paste")
			(net "GND")
		)
		(pad "AT17" smd circle
			(at -8.010398 4.44246)
			(size 0.3048 0.3048)
			(layers "F.Cu" "F.Mask" "F.Paste")
			(net "GND")
		)
		(pad "AT19" smd circle
			(at -7.248398 4.44246)
			(size 0.3048 0.3048)
			(layers "F.Cu" "F.Mask" "F.Paste")
			(net "GND")
		)
		(pad "AT21" smd circle
			(at -6.00075 4.0005)
			(size 0.381 0.381)
			(layers "F.Cu" "F.Mask" "F.Paste")
			(net "P1V5_NODE1")
		)
		(pad "AT23" smd circle
			(at -5.20065 4.0005)
			(size 0.381 0.381)
			(layers "F.Cu" "F.Mask" "F.Paste")
			(net "A_NODE1_RP0_RCOMP")
		)
		(pad "AT25" smd circle
			(at -4.40055 4.0005)
			(size 0.381 0.381)
			(layers "F.Cu" "F.Mask" "F.Paste")
			(net "GND")
		)
		(pad "AT26" smd circle
			(at -3.60045 4.0005)
			(size 0.381 0.381)
			(layers "F.Cu" "F.Mask" "F.Paste")
			(net "GND")
		)
		(pad "AT28" smd circle
			(at -2.80035 4.0005)
			(size 0.381 0.381)
			(layers "F.Cu" "F.Mask" "F.Paste")
			(net "P1V5_NODE1")
		)
		(pad "AT29" smd circle
			(at -2.00025 4.0005)
			(size 0.381 0.381)
			(layers "F.Cu" "F.Mask" "F.Paste")
			(net "GND")
		)
		(pad "AT31" smd circle
			(at -1.20015 4.0005)
			(size 0.381 0.381)
			(layers "F.Cu" "F.Mask" "F.Paste")
			(net "P1V05_NODE1")
		)
		(pad "AT32" smd circle
			(at -0.40005 4.0005)
			(size 0.381 0.381)
			(layers "F.Cu" "F.Mask" "F.Paste")
			(net "GND")
		)
		(pad "AT34" smd circle
			(at 0.40005 4.0005)
			(size 0.381 0.381)
			(layers "F.Cu" "F.Mask" "F.Paste")
			(net "P1V05_NODE1")
		)
		(pad "AT36" smd circle
			(at 1.20015 4.0005)
			(size 0.381 0.381)
			(layers "F.Cu" "F.Mask" "F.Paste")
			(net "GND")
		)
		(pad "AT38" smd circle
			(at 2.00025 4.0005)
			(size 0.381 0.381)
			(layers "F.Cu" "F.Mask" "F.Paste")
			(net "GND")
		)
		(pad "AT39" smd circle
			(at 2.80035 4.0005)
			(size 0.381 0.381)
			(layers "F.Cu" "F.Mask" "F.Paste")
			(net "GND")
		)
		(pad "AT41" smd circle
			(at 3.60045 4.0005)
			(size 0.381 0.381)
			(layers "F.Cu" "F.Mask" "F.Paste")
			(net "GND")
		)
		(pad "AT42" smd circle
			(at 4.40055 4.0005)
			(size 0.381 0.381)
			(layers "F.Cu" "F.Mask" "F.Paste")
			(net "GND")
		)
		(pad "AT44" smd circle
			(at 5.20065 4.0005)
			(size 0.381 0.381)
			(layers "F.Cu" "F.Mask" "F.Paste")
			(net "GND")
		)
		(pad "AT46" smd circle
			(at 6.00075 4.0005)
			(size 0.381 0.381)
			(layers "F.Cu" "F.Mask" "F.Paste")
			(net "GND")
		)
		(pad "AT48" smd circle
			(at 7.248398 4.202684)
			(size 0.3048 0.3048)
			(layers "F.Cu" "F.Mask" "F.Paste")
			(net "GND")
		)
		(pad "AT50" smd circle
			(at 8.010398 4.202684)
			(size 0.3048 0.3048)
			(layers "F.Cu" "F.Mask" "F.Paste")
			(net "GND")
		)
		(pad "AT51" smd circle
			(at 8.772398 4.202684)
			(size 0.3048 0.3048)
			(layers "F.Cu" "F.Mask" "F.Paste")
			(net "GND")
		)
		(pad "AT53" smd circle
			(at 9.534398 4.202684)
			(size 0.3048 0.3048)
			(layers "F.Cu" "F.Mask" "F.Paste")
			(net "XDP_CPU_NODE1_VISA0")
		)
		(pad "AT54" smd circle
			(at 10.296398 4.202684)
			(size 0.3048 0.3048)
			(layers "F.Cu" "F.Mask" "F.Paste")
			(net "XDP_CPU_NODE1_VISA3")
		)
		(pad "AT56" smd circle
			(at 11.058398 4.202684)
			(size 0.3048 0.3048)
			(layers "F.Cu" "F.Mask" "F.Paste")
			(net "GND")
		)
		(pad "AT57" smd circle
			(at 11.820398 4.202684)
			(size 0.3048 0.3048)
			(layers "F.Cu" "F.Mask" "F.Paste")
			(net "XDP_CPU_NODE1_VISA6")
		)
		(pad "AT59" smd circle
			(at 12.582398 4.202684)
			(size 0.3048 0.3048)
			(layers "F.Cu" "F.Mask" "F.Paste")
			(net "XDP_CPU_NODE1_VISA2")
		)
		(pad "AT60" smd circle
			(at 13.344398 4.202684)
			(size 0.3048 0.3048)
			(layers "F.Cu" "F.Mask" "F.Paste")
			(net "XDP_CPU_NODE1_VISA5")
		)
		(pad "AT63" smd circle
			(at 14.542516 4.39928)
			(size 0.3048 0.3048)
			(layers "F.Cu" "F.Mask" "F.Paste")
			(net "M1_DQ_NODE1_DQ56")
		)
		(pad "AT64" smd circle
			(at 15.304516 4.45008)
			(size 0.3048 0.3048)
			(layers "F.Cu" "F.Mask" "F.Paste")
			(net "M1_DQ_NODE1_DQ57")
		)
		(pad "AT66" smd oval
			(at 16.249396 4.39928 90)
			(size 0.254 0.3429)
			(layers "F.Cu" "F.Mask" "F.Paste")
			(net "GND")
		)
		(pad "AU1" smd oval
			(at -16.249396 4.606544 270)
			(size 0.254 0.3429)
			(layers "F.Cu" "F.Mask" "F.Paste")
			(net "PD_CPU_NODE1_RP1_PERN")
		)
		(pad "AU3" smd circle
			(at -15.304516 4.555744)
			(size 0.3048 0.3048)
			(layers "F.Cu" "F.Mask" "F.Paste")
			(net "PD_CPU_NODE1_RP1_PERP")
		)
		(pad "AU4" smd circle
			(at -14.542516 4.606544)
			(size 0.3048 0.3048)
			(layers "F.Cu" "F.Mask" "F.Paste")
			(net "GND")
		)
		(pad "AU21" smd circle
			(at -6.00075 4.8006)
			(size 0.381 0.381)
			(layers "F.Cu" "F.Mask" "F.Paste")
			(net "GND")
		)
		(pad "AU23" smd circle
			(at -5.20065 4.8006)
			(size 0.381 0.381)
			(layers "F.Cu" "F.Mask" "F.Paste")
			(net "P1V05_NODE1")
		)
		(pad "AU25" smd circle
			(at -4.40055 4.8006)
			(size 0.381 0.381)
			(layers "F.Cu" "F.Mask" "F.Paste")
			(net "P1V05_NODE1")
		)
		(pad "AU26" smd circle
			(at -3.60045 4.8006)
			(size 0.381 0.381)
			(layers "F.Cu" "F.Mask" "F.Paste")
			(net "P1V05_NODE1")
		)
		(pad "AU28" smd circle
			(at -2.80035 4.8006)
			(size 0.381 0.381)
			(layers "F.Cu" "F.Mask" "F.Paste")
			(net "P1V05_NODE1")
		)
		(pad "AU29" smd circle
			(at -2.00025 4.8006)
			(size 0.381 0.381)
			(layers "F.Cu" "F.Mask" "F.Paste")
			(net "P1V05_NODE1")
		)
		(pad "AU31" smd circle
			(at -1.20015 4.8006)
			(size 0.381 0.381)
			(layers "F.Cu" "F.Mask" "F.Paste")
			(net "GND")
		)
		(pad "AU32" smd circle
			(at -0.40005 4.8006)
			(size 0.381 0.381)
			(layers "F.Cu" "F.Mask" "F.Paste")
			(net "P1V05_NODE1")
		)
		(pad "AU34" smd circle
			(at 0.40005 4.8006)
			(size 0.381 0.381)
			(layers "F.Cu" "F.Mask" "F.Paste")
			(net "GND")
		)
		(pad "AU36" smd circle
			(at 1.20015 4.8006)
			(size 0.381 0.381)
			(layers "F.Cu" "F.Mask" "F.Paste")
			(net "P1V05_NODE1")
		)
		(pad "AU38" smd circle
			(at 2.00025 4.8006)
			(size 0.381 0.381)
			(layers "F.Cu" "F.Mask" "F.Paste")
			(net "P1V05_NODE1")
		)
		(pad "AU39" smd circle
			(at 2.80035 4.8006)
			(size 0.381 0.381)
			(layers "F.Cu" "F.Mask" "F.Paste")
			(net "P1V05_NODE1")
		)
		(pad "AU41" smd circle
			(at 3.60045 4.8006)
			(size 0.381 0.381)
			(layers "F.Cu" "F.Mask" "F.Paste")
			(net "P1V05_NODE1")
		)
		(pad "AU42" smd circle
			(at 4.40055 4.8006)
			(size 0.381 0.381)
			(layers "F.Cu" "F.Mask" "F.Paste")
			(net "P1V05_NODE1")
		)
		(pad "AU44" smd circle
			(at 5.20065 4.8006)
			(size 0.381 0.381)
			(layers "F.Cu" "F.Mask" "F.Paste")
			(net "P1V05_NODE1")
		)
		(pad "AU46" smd circle
			(at 6.00075 4.8006)
			(size 0.381 0.381)
			(layers "F.Cu" "F.Mask" "F.Paste")
			(net "P1V05_NODE1")
		)
		(pad "AU47" smd circle
			(at 6.726174 4.8006)
			(size 0.3048 0.3048)
			(layers "F.Cu" "F.Mask" "F.Paste")
			(net "P1V05_NODE1")
		)
		(pad "AU62" smd circle
			(at 14.063218 4.910074)
			(size 0.3048 0.3048)
			(layers "F.Cu" "F.Mask" "F.Paste")
			(net "GND")
		)
		(pad "AV2" smd circle
			(at -15.805658 5.366004)
			(size 0.3048 0.3048)
			(layers "F.Cu" "F.Mask" "F.Paste")
			(net "PD_CPU_NODE1_RP1_PERP")
		)
		(pad "AV4" smd circle
			(at -14.751558 5.286248)
			(size 0.3048 0.3048)
			(layers "F.Cu" "F.Mask" "F.Paste")
			(net "GND")
		)
		(pad "AV5" smd circle
			(at -14.063218 5.117338)
			(size 0.3048 0.3048)
			(layers "F.Cu" "F.Mask" "F.Paste")
			(net "GND")
		)
		(pad "AV63" smd circle
			(at 14.794738 5.067808)
			(size 0.3048 0.3048)
			(layers "F.Cu" "F.Mask" "F.Paste")
			(net "GND")
		)
		(pad "AV65" smd circle
			(at 15.752318 5.12064)
			(size 0.3048 0.3048)
			(layers "F.Cu" "F.Mask" "F.Paste")
			(net "GND")
		)
		(pad "AW3" smd circle
			(at -15.247112 5.789422)
			(size 0.3048 0.3048)
			(layers "F.Cu" "F.Mask" "F.Paste")
			(net "GND")
		)
		(pad "AW5" smd circle
			(at -14.013688 5.819648)
			(size 0.3048 0.3048)
			(layers "F.Cu" "F.Mask" "F.Paste")
			(net "GND")
		)
		(pad "AW8" smd circle
			(at -12.963398 5.728716)
			(size 0.3048 0.3048)
			(layers "F.Cu" "F.Mask" "F.Paste")
			(net "GND")
		)
		(pad "AW9" smd circle
			(at -12.201398 5.728716)
			(size 0.3048 0.3048)
			(layers "F.Cu" "F.Mask" "F.Paste")
			(net "TP_CPU_NODE1_RP0_PETP7")
		)
		(pad "AW11" smd circle
			(at -11.439398 5.728716)
			(size 0.3048 0.3048)
			(layers "F.Cu" "F.Mask" "F.Paste")
			(net "TP_CPU_NODE1_RP0_PETN7")
		)
		(pad "AW12" smd circle
			(at -10.677398 5.728716)
			(size 0.3048 0.3048)
			(layers "F.Cu" "F.Mask" "F.Paste")
			(net "GND")
		)
		(pad "AW14" smd circle
			(at -9.915398 5.728716)
			(size 0.3048 0.3048)
			(layers "F.Cu" "F.Mask" "F.Paste")
			(net "Net_451")
		)
		(pad "AW15" smd circle
			(at -9.153398 5.728716)
			(size 0.3048 0.3048)
			(layers "F.Cu" "F.Mask" "F.Paste")
			(net "Net_452")
		)
		(pad "AW17" smd circle
			(at -8.175244 5.772404)
			(size 0.3048 0.3048)
			(layers "F.Cu" "F.Mask" "F.Paste")
			(net "GND")
		)
		(pad "AW19" smd circle
			(at -7.47522 5.772404)
			(size 0.3048 0.3048)
			(layers "F.Cu" "F.Mask" "F.Paste")
			(net "GND")
		)
		(pad "AW20" smd circle
			(at -6.80085 5.500624)
			(size 0.3048 0.3048)
			(layers "F.Cu" "F.Mask" "F.Paste")
			(net "GND")
		)
		(pad "AW21" smd circle
			(at -5.900674 5.500624)
			(size 0.3048 0.3048)
			(layers "F.Cu" "F.Mask" "F.Paste")
			(net "P1V05_NODE1")
		)
		(pad "AW23" smd circle
			(at -5.20065 5.500624)
			(size 0.3048 0.3048)
			(layers "F.Cu" "F.Mask" "F.Paste")
			(net "P1V05_NODE1")
		)
		(pad "AW25" smd circle
			(at -4.202684 5.772404)
			(size 0.3048 0.3048)
			(layers "F.Cu" "F.Mask" "F.Paste")
			(net "GND")
		)
		(pad "AW26" smd circle
			(at -3.50266 5.772404)
			(size 0.3048 0.3048)
			(layers "F.Cu" "F.Mask" "F.Paste")
			(net "GND")
		)
		(pad "AW28" smd circle
			(at -2.80035 5.500624)
			(size 0.3048 0.3048)
			(layers "F.Cu" "F.Mask" "F.Paste")
			(net "GND")
		)
		(pad "AW30" smd circle
			(at -1.900174 5.500624)
			(size 0.3048 0.3048)
			(layers "F.Cu" "F.Mask" "F.Paste")
			(net "GND")
		)
		(pad "AW31" smd circle
			(at -1.20015 5.500624)
			(size 0.3048 0.3048)
			(layers "F.Cu" "F.Mask" "F.Paste")
			(net "GND")
		)
		(pad "AW32" smd circle
			(at -0.230124 5.772404)
			(size 0.3048 0.3048)
			(layers "F.Cu" "F.Mask" "F.Paste")
			(net "P1V05_VCCACLK_DDR3_NODE1")
		)
		(pad "AW34" smd circle
			(at 0.4699 5.772404)
			(size 0.3048 0.3048)
			(layers "F.Cu" "F.Mask" "F.Paste")
			(net "GND")
		)
		(pad "AW36" smd circle
			(at 1.20015 5.500624)
			(size 0.3048 0.3048)
			(layers "F.Cu" "F.Mask" "F.Paste")
			(net "GND")
		)
		(pad "AW38" smd circle
			(at 2.100326 5.500624)
			(size 0.3048 0.3048)
			(layers "F.Cu" "F.Mask" "F.Paste")
			(net "GND")
		)
		(pad "AW39" smd circle
			(at 2.80035 5.500624)
			(size 0.3048 0.3048)
			(layers "F.Cu" "F.Mask" "F.Paste")
			(net "GND")
		)
		(pad "AW41" smd circle
			(at 3.742436 5.772404)
			(size 0.3048 0.3048)
			(layers "F.Cu" "F.Mask" "F.Paste")
			(net "GND")
		)
		(pad "AW42" smd circle
			(at 4.44246 5.772404)
			(size 0.3048 0.3048)
			(layers "F.Cu" "F.Mask" "F.Paste")
			(net "GND")
		)
		(pad "AW44" smd circle
			(at 5.20065 5.500624)
			(size 0.3048 0.3048)
			(layers "F.Cu" "F.Mask" "F.Paste")
			(net "GND")
		)
		(pad "AW46" smd circle
			(at 6.00075 5.500624)
			(size 0.3048 0.3048)
			(layers "F.Cu" "F.Mask" "F.Paste")
			(net "P1V05_NODE1")
		)
		(pad "AW47" smd circle
			(at 6.700774 5.500624)
			(size 0.3048 0.3048)
			(layers "F.Cu" "F.Mask" "F.Paste")
			(net "P1V05_NODE1")
		)
		(pad "AW49" smd circle
			(at 7.714996 5.772404)
			(size 0.3048 0.3048)
			(layers "F.Cu" "F.Mask" "F.Paste")
			(net "GND")
		)
		(pad "AW50" smd circle
			(at 8.41502 5.772404)
			(size 0.3048 0.3048)
			(layers "F.Cu" "F.Mask" "F.Paste")
			(net "GND")
		)
		(pad "AW52" smd circle
			(at 9.153398 5.48894)
			(size 0.3048 0.3048)
			(layers "F.Cu" "F.Mask" "F.Paste")
			(net "GND")
		)
		(pad "AW53" smd circle
			(at 9.915398 5.48894)
			(size 0.3048 0.3048)
			(layers "F.Cu" "F.Mask" "F.Paste")
			(net "GND")
		)
		(pad "AW55" smd circle
			(at 10.677398 5.48894)
			(size 0.3048 0.3048)
			(layers "F.Cu" "F.Mask" "F.Paste")
			(net "GND")
		)
		(pad "AW56" smd circle
			(at 11.439398 5.48894)
			(size 0.3048 0.3048)
			(layers "F.Cu" "F.Mask" "F.Paste")
			(net "XDP_CPU_NODE1_VISA14")
		)
		(pad "AW58" smd circle
			(at 12.201398 5.48894)
			(size 0.3048 0.3048)
			(layers "F.Cu" "F.Mask" "F.Paste")
			(net "XDP_CPU_NODE1_VISA17")
		)
		(pad "AW59" smd circle
			(at 12.963398 5.48894)
			(size 0.3048 0.3048)
			(layers "F.Cu" "F.Mask" "F.Paste")
			(net "GND")
		)
		(pad "AW62" smd circle
			(at 14.08049 5.617464)
			(size 0.3048 0.3048)
			(layers "F.Cu" "F.Mask" "F.Paste")
			(net "M1_DQ_NODE1_DQ51")
		)
		(pad "AW64" smd circle
			(at 15.242794 5.607558)
			(size 0.3048 0.3048)
			(layers "F.Cu" "F.Mask" "F.Paste")
			(net "M1_DQ_NODE1_DQ53")
		)
		(pad "AW66" smd oval
			(at 16.249396 5.837936 90)
			(size 0.254 0.3429)
			(layers "F.Cu" "F.Mask" "F.Paste")
			(net "GND")
		)
		(pad "AY1" smd oval
			(at -16.249396 6.0452 270)
			(size 0.254 0.3429)
			(layers "F.Cu" "F.Mask" "F.Paste")
			(net "GND")
		)
		(pad "AY2" smd circle
			(at -15.640812 6.394704)
			(size 0.3048 0.3048)
			(layers "F.Cu" "F.Mask" "F.Paste")
			(net "TP_CPU_NODE1_RP0_PERP7")
		)
		(pad "AY4" smd circle
			(at -14.90091 6.4008)
			(size 0.3048 0.3048)
			(layers "F.Cu" "F.Mask" "F.Paste")
			(net "TP_CPU_NODE1_RP0_PERN7")
		)
		(pad "AY5" smd circle
			(at -14.204442 6.497828)
			(size 0.3048 0.3048)
			(layers "F.Cu" "F.Mask" "F.Paste")
			(net "P2E_CPU_PCIE_SW_NODE1_RX_DN")
		)
		(pad "AY8" smd circle
			(at -12.963398 6.42874)
			(size 0.3048 0.3048)
			(layers "F.Cu" "F.Mask" "F.Paste")
			(net "GND")
		)
		(pad "AY9" smd circle
			(at -12.201398 6.42874)
			(size 0.3048 0.3048)
			(layers "F.Cu" "F.Mask" "F.Paste")
			(net "P2E_CPU_PCIE_SW_NODE1_TX_C_DN")
		)
		(pad "AY11" smd circle
			(at -11.439398 6.42874)
			(size 0.3048 0.3048)
			(layers "F.Cu" "F.Mask" "F.Paste")
			(net "P2E_CPU_PCIE_SW_NODE1_TX_C_DP")
		)
		(pad "AY12" smd circle
			(at -10.677398 6.42874)
			(size 0.3048 0.3048)
			(layers "F.Cu" "F.Mask" "F.Paste")
			(net "GND")
		)
		(pad "AY14" smd circle
			(at -9.915398 6.42874)
			(size 0.3048 0.3048)
			(layers "F.Cu" "F.Mask" "F.Paste")
			(net "GND")
		)
		(pad "AY15" smd circle
			(at -9.153398 6.42874)
			(size 0.3048 0.3048)
			(layers "F.Cu" "F.Mask" "F.Paste")
			(net "GND")
		)
		(pad "AY19" smd circle
			(at -7.47522 6.534404)
			(size 0.3048 0.3048)
			(layers "F.Cu" "F.Mask" "F.Paste")
			(net "GND")
		)
		(pad "AY21" smd circle
			(at -6.188964 6.153404)
			(size 0.3048 0.3048)
			(layers "F.Cu" "F.Mask" "F.Paste")
			(net "P1V05_NODE1")
		)
		(pad "AY23" smd circle
			(at -5.48894 6.153404)
			(size 0.3048 0.3048)
			(layers "F.Cu" "F.Mask" "F.Paste")
			(net "P1V05_NODE1")
		)
		(pad "AY29" smd circle
			(at -2.216404 6.153404)
			(size 0.3048 0.3048)
			(layers "F.Cu" "F.Mask" "F.Paste")
			(net "GND")
		)
		(pad "AY30" smd circle
			(at -1.51638 6.153404)
			(size 0.3048 0.3048)
			(layers "F.Cu" "F.Mask" "F.Paste")
			(net "GND")
		)
		(pad "AY37" smd circle
			(at 1.756156 6.153404)
			(size 0.3048 0.3048)
			(layers "F.Cu" "F.Mask" "F.Paste")
			(net "GND")
		)
		(pad "AY38" smd circle
			(at 2.45618 6.153404)
			(size 0.3048 0.3048)
			(layers "F.Cu" "F.Mask" "F.Paste")
			(net "P1V05_VCCPLL_DDR3_NODE1")
		)
		(pad "AY45" smd circle
			(at 5.728716 6.153404)
			(size 0.3048 0.3048)
			(layers "F.Cu" "F.Mask" "F.Paste")
			(net "GND")
		)
		(pad "AY46" smd circle
			(at 6.42874 6.153404)
			(size 0.3048 0.3048)
			(layers "F.Cu" "F.Mask" "F.Paste")
			(net "GND")
		)
		(pad "AY52" smd circle
			(at 9.153398 6.188964)
			(size 0.3048 0.3048)
			(layers "F.Cu" "F.Mask" "F.Paste")
			(net "GND")
		)
		(pad "AY53" smd circle
			(at 9.915398 6.188964)
			(size 0.3048 0.3048)
			(layers "F.Cu" "F.Mask" "F.Paste")
			(net "GND")
		)
		(pad "AY55" smd circle
			(at 10.677398 6.188964)
			(size 0.3048 0.3048)
			(layers "F.Cu" "F.Mask" "F.Paste")
			(net "GND")
		)
		(pad "AY56" smd circle
			(at 11.439398 6.188964)
			(size 0.3048 0.3048)
			(layers "F.Cu" "F.Mask" "F.Paste")
			(net "GND")
		)
		(pad "AY58" smd circle
			(at 12.201398 6.188964)
			(size 0.3048 0.3048)
			(layers "F.Cu" "F.Mask" "F.Paste")
			(net "GND")
		)
		(pad "AY59" smd circle
			(at 12.963398 6.188964)
			(size 0.3048 0.3048)
			(layers "F.Cu" "F.Mask" "F.Paste")
			(net "GND")
		)
		(pad "AY62" smd circle
			(at 14.204442 6.310884)
			(size 0.3048 0.3048)
			(layers "F.Cu" "F.Mask" "F.Paste")
			(net "GND")
		)
		(pad "AY63" smd circle
			(at 14.90091 6.218936)
			(size 0.3048 0.3048)
			(layers "F.Cu" "F.Mask" "F.Paste")
			(net "M1_DQ_NODE1_DQ52")
		)
		(pad "AY65" smd circle
			(at 15.639034 6.18744)
			(size 0.3048 0.3048)
			(layers "F.Cu" "F.Mask" "F.Paste")
			(net "M1_DQ_NODE1_DQ49")
		)
		(pad "B10" smd circle
			(at -11.823954 -12.63904)
			(size 0.3048 0.3048)
			(layers "F.Cu" "F.Mask" "F.Paste")
			(net "PD_NODE1_NTB_PERP")
		)
		(pad "B12" smd circle
			(at -10.897362 -12.640818)
			(size 0.3048 0.3048)
			(layers "F.Cu" "F.Mask" "F.Paste")
			(net "PD_NODE1_NTB_PERN")
		)
		(pad "B14" smd circle
			(at -9.868662 -12.805664)
			(size 0.3048 0.3048)
			(layers "F.Cu" "F.Mask" "F.Paste")
			(net "GND")
		)
		(pad "B17" smd circle
			(at -8.387842 -12.752324)
			(size 0.3048 0.3048)
			(layers "F.Cu" "F.Mask" "F.Paste")
			(net "PD_NODE1_NTB_PERP")
		)
		(pad "B19" smd circle
			(at -7.321042 -12.63904)
			(size 0.3048 0.3048)
			(layers "F.Cu" "F.Mask" "F.Paste")
			(net "PD_NODE1_NTB_PERN")
		)
		(pad "B21" smd circle
			(at -6.39445 -12.640818)
			(size 0.3048 0.3048)
			(layers "F.Cu" "F.Mask" "F.Paste")
			(net "PD_NODE1_NTB_PERN")
		)
		(pad "B23" smd circle
			(at -5.36575 -12.805664)
			(size 0.3048 0.3048)
			(layers "F.Cu" "F.Mask" "F.Paste")
			(net "GND")
		)
		(pad "B26" smd circle
			(at -3.88493 -12.752324)
			(size 0.3048 0.3048)
			(layers "F.Cu" "F.Mask" "F.Paste")
			(net "PD_NODE1_NTB_PERN")
		)
		(pad "B28" smd circle
			(at -2.81813 -12.63904)
			(size 0.3048 0.3048)
			(layers "F.Cu" "F.Mask" "F.Paste")
			(net "PD_CPU_NODE1_DFX_GPIO_GRP0_2")
		)
		(pad "B30" smd circle
			(at -1.891538 -12.640818)
			(size 0.3048 0.3048)
			(layers "F.Cu" "F.Mask" "F.Paste")
			(net "PD_CPU_NODE1_DFX_GPIO_GRP0_3")
		)
		(pad "B32" smd circle
			(at -0.862838 -12.805664)
			(size 0.3048 0.3048)
			(layers "F.Cu" "F.Mask" "F.Paste")
			(net "GND")
		)
		(pad "B35" smd circle
			(at 0.617982 -12.752324)
			(size 0.3048 0.3048)
			(layers "F.Cu" "F.Mask" "F.Paste")
			(net "PD_CPU_NODE1_DFX_GPIO_GRP1_4")
		)
		(pad "B37" smd circle
			(at 1.684782 -12.63904)
			(size 0.3048 0.3048)
			(layers "F.Cu" "F.Mask" "F.Paste")
			(net "GND")
		)
		(pad "B39" smd circle
			(at 2.611374 -12.640818)
			(size 0.3048 0.3048)
			(layers "F.Cu" "F.Mask" "F.Paste")
			(net "TP_CPU_NODE1_RSVD_MVT0")
		)
		(pad "B41" smd circle
			(at 3.640074 -12.805664)
			(size 0.3048 0.3048)
			(layers "F.Cu" "F.Mask" "F.Paste")
			(net "A_CPU_NODE1_NTB_CROSSLK_MODE")
		)
		(pad "B44" smd circle
			(at 5.120894 -12.752324)
			(size 0.3048 0.3048)
			(layers "F.Cu" "F.Mask" "F.Paste")
			(net "LPC_CPU_NODE1_R_CLKOUT0")
		)
		(pad "B46" smd circle
			(at 6.187694 -12.63904)
			(size 0.3048 0.3048)
			(layers "F.Cu" "F.Mask" "F.Paste")
			(net "GND")
		)
		(pad "B48" smd circle
			(at 7.114286 -12.640818)
			(size 0.3048 0.3048)
			(layers "F.Cu" "F.Mask" "F.Paste")
			(net "SPC_CPU_NODE1_RI_L")
		)
		(pad "B50" smd circle
			(at 8.142986 -12.805664)
			(size 0.3048 0.3048)
			(layers "F.Cu" "F.Mask" "F.Paste")
			(net "GND")
		)
		(pad "B53" smd circle
			(at 9.623806 -12.752324)
			(size 0.3048 0.3048)
			(layers "F.Cu" "F.Mask" "F.Paste")
			(net "TP_CPU_NODE1_ADR_COMPLETE")
		)
		(pad "B55" smd circle
			(at 10.690606 -12.63904)
			(size 0.3048 0.3048)
			(layers "F.Cu" "F.Mask" "F.Paste")
			(net "LAN1_DISABLE_N")
		)
		(pad "B57" smd circle
			(at 11.617198 -12.640818)
			(size 0.3048 0.3048)
			(layers "F.Cu" "F.Mask" "F.Paste")
			(net "PU_CPU_NODE1_BRD_ID0")
		)
		(pad "BA17" smd circle
			(at -8.175244 6.534404)
			(size 0.3048 0.3048)
			(layers "F.Cu" "F.Mask" "F.Paste")
			(net "GND")
		)
		(pad "BA21" smd circle
			(at -6.188964 6.915404)
			(size 0.3048 0.3048)
			(layers "F.Cu" "F.Mask" "F.Paste")
			(net "GND")
		)
		(pad "BA23" smd circle
			(at -5.48894 6.915404)
			(size 0.3048 0.3048)
			(layers "F.Cu" "F.Mask" "F.Paste")
			(net "GND")
		)
		(pad "BA25" smd circle
			(at -4.202684 6.534404)
			(size 0.3048 0.3048)
			(layers "F.Cu" "F.Mask" "F.Paste")
			(net "M1_DQ_NODE1_DQ17")
		)
		(pad "BA26" smd circle
			(at -3.50266 6.534404)
			(size 0.3048 0.3048)
			(layers "F.Cu" "F.Mask" "F.Paste")
			(net "GND")
		)
		(pad "BA29" smd circle
			(at -2.216404 6.915404)
			(size 0.3048 0.3048)
			(layers "F.Cu" "F.Mask" "F.Paste")
			(net "M1_DQ_NODE1_DQ22")
		)
		(pad "BA30" smd circle
			(at -1.51638 6.915404)
			(size 0.3048 0.3048)
			(layers "F.Cu" "F.Mask" "F.Paste")
			(net "GND")
		)
		(pad "BA32" smd circle
			(at -0.230124 6.534404)
			(size 0.3048 0.3048)
			(layers "F.Cu" "F.Mask" "F.Paste")
			(net "P1V05_VCCACLK_DDR3_NODE1")
		)
		(pad "BA34" smd circle
			(at 0.4699 6.534404)
			(size 0.3048 0.3048)
			(layers "F.Cu" "F.Mask" "F.Paste")
			(net "P1V5_SFRPLL_NODE1")
		)
		(pad "BA37" smd circle
			(at 1.756156 6.915404)
			(size 0.3048 0.3048)
			(layers "F.Cu" "F.Mask" "F.Paste")
			(net "GND")
		)
		(pad "BA38" smd circle
			(at 2.45618 6.915404)
			(size 0.3048 0.3048)
			(layers "F.Cu" "F.Mask" "F.Paste")
			(net "P1V05_VCCPLL_DDR3_NODE1")
		)
		(pad "BA41" smd circle
			(at 3.742436 6.534404)
			(size 0.3048 0.3048)
			(layers "F.Cu" "F.Mask" "F.Paste")
			(net "PV_VDDR_VCCCLK_DDR3_NODE1")
		)
		(pad "BA42" smd circle
			(at 4.44246 6.534404)
			(size 0.3048 0.3048)
			(layers "F.Cu" "F.Mask" "F.Paste")
			(net "GND")
		)
		(pad "BA45" smd circle
			(at 5.728716 6.915404)
			(size 0.3048 0.3048)
			(layers "F.Cu" "F.Mask" "F.Paste")
			(net "GND")
		)
		(pad "BA46" smd circle
			(at 6.42874 6.915404)
			(size 0.3048 0.3048)
			(layers "F.Cu" "F.Mask" "F.Paste")
			(net "GND")
		)
		(pad "BA49" smd circle
			(at 7.714996 6.534404)
			(size 0.3048 0.3048)
			(layers "F.Cu" "F.Mask" "F.Paste")
			(net "GND")
		)
		(pad "BA50" smd circle
			(at 8.41502 6.534404)
			(size 0.3048 0.3048)
			(layers "F.Cu" "F.Mask" "F.Paste")
			(net "M_DDR3_NODE1_ECC5")
		)
		(pad "BB2" smd circle
			(at -15.639034 7.321296)
			(size 0.3048 0.3048)
			(layers "F.Cu" "F.Mask" "F.Paste")
			(net "TP_CPU_NODE1_RP0_PERN5")
		)
		(pad "BB4" smd circle
			(at -14.90091 7.2898)
			(size 0.3048 0.3048)
			(layers "F.Cu" "F.Mask" "F.Paste")
			(net "TP_CPU_NODE1_RP0_PERP5")
		)
		(pad "BB5" smd circle
			(at -14.204442 7.197852)
			(size 0.3048 0.3048)
			(layers "F.Cu" "F.Mask" "F.Paste")
			(net "P2E_CPU_PCIE_SW_NODE1_RX_DP")
		)
		(pad "BB17" smd circle
			(at -8.175244 7.296404)
			(size 0.3048 0.3048)
			(layers "F.Cu" "F.Mask" "F.Paste")
			(net "TP_CPU_NODE1_RP0_PETN1")
		)
		(pad "BB19" smd circle
			(at -7.47522 7.296404)
			(size 0.3048 0.3048)
			(layers "F.Cu" "F.Mask" "F.Paste")
			(net "P2E_CPU_SATA_NODE1_TX_C_DN")
		)
		(pad "BB25" smd circle
			(at -4.202684 7.296404)
			(size 0.3048 0.3048)
			(layers "F.Cu" "F.Mask" "F.Paste")
			(net "M1_DQ_NODE1_DQ21")
		)
		(pad "BB26" smd circle
			(at -3.50266 7.296404)
			(size 0.3048 0.3048)
			(layers "F.Cu" "F.Mask" "F.Paste")
			(net "M1_DQ_NODE1_DQ19")
		)
		(pad "BB32" smd circle
			(at -0.230124 7.296404)
			(size 0.3048 0.3048)
			(layers "F.Cu" "F.Mask" "F.Paste")
			(net "GND")
		)
		(pad "BB34" smd circle
			(at 0.4699 7.296404)
			(size 0.3048 0.3048)
			(layers "F.Cu" "F.Mask" "F.Paste")
			(net "P1V5_SFRPLL_NODE1")
		)
		(pad "BB41" smd circle
			(at 3.742436 7.296404)
			(size 0.3048 0.3048)
			(layers "F.Cu" "F.Mask" "F.Paste")
			(net "PV_VDDR_VCCCLK_DDR3_NODE1")
		)
		(pad "BB42" smd circle
			(at 4.44246 7.296404)
			(size 0.3048 0.3048)
			(layers "F.Cu" "F.Mask" "F.Paste")
			(net "GND")
		)
		(pad "BB49" smd circle
			(at 7.714996 7.296404)
			(size 0.3048 0.3048)
			(layers "F.Cu" "F.Mask" "F.Paste")
			(net "M_DDR3_NODE1_ECC1")
		)
		(pad "BB50" smd circle
			(at 8.41502 7.296404)
			(size 0.3048 0.3048)
			(layers "F.Cu" "F.Mask" "F.Paste")
			(net "GND")
		)
		(pad "BB53" smd circle
			(at 9.534398 7.47522)
			(size 0.3048 0.3048)
			(layers "F.Cu" "F.Mask" "F.Paste")
			(net "GND")
		)
		(pad "BB54" smd circle
			(at 10.296398 7.47522)
			(size 0.3048 0.3048)
			(layers "F.Cu" "F.Mask" "F.Paste")
			(net "GND")
		)
		(pad "BB56" smd circle
			(at 11.058398 7.47522)
			(size 0.3048 0.3048)
			(layers "F.Cu" "F.Mask" "F.Paste")
			(net "GND")
		)
		(pad "BB57" smd circle
			(at 11.820398 7.47522)
			(size 0.3048 0.3048)
			(layers "F.Cu" "F.Mask" "F.Paste")
			(net "M1_DQ_NODE1_DQ44")
		)
		(pad "BB59" smd circle
			(at 12.582398 7.47522)
			(size 0.3048 0.3048)
			(layers "F.Cu" "F.Mask" "F.Paste")
			(net "M1_DQ_NODE1_DQ41")
		)
		(pad "BB60" smd circle
			(at 13.344398 7.47522)
			(size 0.3048 0.3048)
			(layers "F.Cu" "F.Mask" "F.Paste")
			(net "M1_DQ_NODE1_DQ45")
		)
		(pad "BB62" smd circle
			(at 14.204442 7.010908)
			(size 0.3048 0.3048)
			(layers "F.Cu" "F.Mask" "F.Paste")
			(net "GND")
		)
		(pad "BB63" smd circle
			(at 14.90091 7.107936)
			(size 0.3048 0.3048)
			(layers "F.Cu" "F.Mask" "F.Paste")
			(net "M_DDR3_NODE1_DQS6P")
		)
		(pad "BB65" smd circle
			(at 15.640812 7.114032)
			(size 0.3048 0.3048)
			(layers "F.Cu" "F.Mask" "F.Paste")
			(net "M_DDR3_NODE1_DQS6N")
		)
		(pad "BB66" smd oval
			(at 16.249396 7.463536 90)
			(size 0.254 0.3429)
			(layers "F.Cu" "F.Mask" "F.Paste")
			(net "GND")
		)
		(pad "BC1" smd oval
			(at -16.249396 7.6708 270)
			(size 0.254 0.3429)
			(layers "F.Cu" "F.Mask" "F.Paste")
			(net "GND")
		)
		(pad "BC3" smd circle
			(at -15.242794 7.901178)
			(size 0.3048 0.3048)
			(layers "F.Cu" "F.Mask" "F.Paste")
			(net "GND")
		)
		(pad "BC5" smd circle
			(at -14.08049 7.891272)
			(size 0.3048 0.3048)
			(layers "F.Cu" "F.Mask" "F.Paste")
			(net "GND")
		)
		(pad "BC7" smd circle
			(at -13.344398 7.714996)
			(size 0.3048 0.3048)
			(layers "F.Cu" "F.Mask" "F.Paste")
			(net "GND")
		)
		(pad "BC8" smd circle
			(at -12.582398 7.714996)
			(size 0.3048 0.3048)
			(layers "F.Cu" "F.Mask" "F.Paste")
			(net "TP_CPU_NODE1_RP0_PETP5")
		)
		(pad "BC10" smd circle
			(at -11.820398 7.714996)
			(size 0.3048 0.3048)
			(layers "F.Cu" "F.Mask" "F.Paste")
			(net "TP_CPU_NODE1_RP0_PETN5")
		)
		(pad "BC11" smd circle
			(at -11.058398 7.714996)
			(size 0.3048 0.3048)
			(layers "F.Cu" "F.Mask" "F.Paste")
			(net "GND")
		)
		(pad "BC13" smd circle
			(at -10.296398 7.714996)
			(size 0.3048 0.3048)
			(layers "F.Cu" "F.Mask" "F.Paste")
			(net "GND")
		)
		(pad "BC15" smd circle
			(at -9.4615 7.677404)
			(size 0.3048 0.3048)
			(layers "F.Cu" "F.Mask" "F.Paste")
			(net "GND")
		)
		(pad "BC21" smd circle
			(at -6.188964 7.677404)
			(size 0.3048 0.3048)
			(layers "F.Cu" "F.Mask" "F.Paste")
			(net "GND")
		)
		(pad "BC23" smd circle
			(at -5.48894 7.677404)
			(size 0.3048 0.3048)
			(layers "F.Cu" "F.Mask" "F.Paste")
			(net "GND")
		)
		(pad "BC29" smd circle
			(at -2.216404 7.677404)
			(size 0.3048 0.3048)
			(layers "F.Cu" "F.Mask" "F.Paste")
			(net "GND")
		)
		(pad "BC30" smd circle
			(at -1.51638 7.677404)
			(size 0.3048 0.3048)
			(layers "F.Cu" "F.Mask" "F.Paste")
			(net "GND")
		)
		(pad "BC37" smd circle
			(at 1.756156 7.677404)
			(size 0.3048 0.3048)
			(layers "F.Cu" "F.Mask" "F.Paste")
			(net "GND")
		)
		(pad "BC38" smd circle
			(at 2.45618 7.677404)
			(size 0.3048 0.3048)
			(layers "F.Cu" "F.Mask" "F.Paste")
			(net "M_NODE1_DIMM_RST_L")
		)
		(pad "BC45" smd circle
			(at 5.728716 7.677404)
			(size 0.3048 0.3048)
			(layers "F.Cu" "F.Mask" "F.Paste")
			(net "GND")
		)
		(pad "BC46" smd circle
			(at 6.42874 7.677404)
			(size 0.3048 0.3048)
			(layers "F.Cu" "F.Mask" "F.Paste")
			(net "GND")
		)
		(pad "BC62" smd circle
			(at 14.013688 7.689088)
			(size 0.3048 0.3048)
			(layers "F.Cu" "F.Mask" "F.Paste")
			(net "GND")
		)
		(pad "BC64" smd circle
			(at 15.247112 7.719314)
			(size 0.3048 0.3048)
			(layers "F.Cu" "F.Mask" "F.Paste")
			(net "M1_DQ_NODE1_DQ55")
		)
		(pad "BD2" smd circle
			(at -15.752318 8.388096)
			(size 0.3048 0.3048)
			(layers "F.Cu" "F.Mask" "F.Paste")
			(net "P2E_CPU_NIC2_NODE1_RX_DP")
		)
		(pad "BD4" smd circle
			(at -14.794738 8.440928)
			(size 0.3048 0.3048)
			(layers "F.Cu" "F.Mask" "F.Paste")
			(net "P2E_CPU_NIC2_NODE1_RX_DN")
		)
		(pad "BD7" smd circle
			(at -13.344398 8.41502)
			(size 0.3048 0.3048)
			(layers "F.Cu" "F.Mask" "F.Paste")
			(net "GND")
		)
		(pad "BD8" smd circle
			(at -12.582398 8.41502)
			(size 0.3048 0.3048)
			(layers "F.Cu" "F.Mask" "F.Paste")
			(net "P2E_CPU_NIC2_NODE1_TX_C_DN")
		)
		(pad "BD10" smd circle
			(at -11.820398 8.41502)
			(size 0.3048 0.3048)
			(layers "F.Cu" "F.Mask" "F.Paste")
			(net "P2E_CPU_NIC2_NODE1_TX_C_DP")
		)
		(pad "BD13" smd circle
			(at -10.161524 8.439404)
			(size 0.3048 0.3048)
			(layers "F.Cu" "F.Mask" "F.Paste")
			(net "M1_DQ_NODE1_DQ6")
		)
		(pad "BD15" smd circle
			(at -9.4615 8.439404)
			(size 0.3048 0.3048)
			(layers "F.Cu" "F.Mask" "F.Paste")
			(net "GND")
		)
		(pad "BD17" smd circle
			(at -8.175244 8.058404)
			(size 0.3048 0.3048)
			(layers "F.Cu" "F.Mask" "F.Paste")
			(net "TP_CPU_NODE1_RP0_PETP1")
		)
		(pad "BD19" smd circle
			(at -7.47522 8.058404)
			(size 0.3048 0.3048)
			(layers "F.Cu" "F.Mask" "F.Paste")
			(net "P2E_CPU_SATA_NODE1_TX_C_DP")
		)
		(pad "BD21" smd circle
			(at -6.188964 8.439404)
			(size 0.3048 0.3048)
			(layers "F.Cu" "F.Mask" "F.Paste")
			(net "GND")
		)
		(pad "BD23" smd circle
			(at -5.48894 8.439404)
			(size 0.3048 0.3048)
			(layers "F.Cu" "F.Mask" "F.Paste")
			(net "GND")
		)
		(pad "BD25" smd circle
			(at -4.202684 8.058404)
			(size 0.3048 0.3048)
			(layers "F.Cu" "F.Mask" "F.Paste")
			(net "GND")
		)
		(pad "BD26" smd circle
			(at -3.50266 8.058404)
			(size 0.3048 0.3048)
			(layers "F.Cu" "F.Mask" "F.Paste")
			(net "M_DDR3_NODE1_DQS2N")
		)
		(pad "BD29" smd circle
			(at -2.216404 8.439404)
			(size 0.3048 0.3048)
			(layers "F.Cu" "F.Mask" "F.Paste")
			(net "GND")
		)
		(pad "BD30" smd circle
			(at -1.51638 8.439404)
			(size 0.3048 0.3048)
			(layers "F.Cu" "F.Mask" "F.Paste")
			(net "GND")
		)
		(pad "BD32" smd circle
			(at -0.230124 8.058404)
			(size 0.3048 0.3048)
			(layers "F.Cu" "F.Mask" "F.Paste")
			(net "GND")
		)
		(pad "BD34" smd circle
			(at 0.4699 8.058404)
			(size 0.3048 0.3048)
			(layers "F.Cu" "F.Mask" "F.Paste")
			(net "GND")
		)
		(pad "BD37" smd circle
			(at 1.756156 8.439404)
			(size 0.3048 0.3048)
			(layers "F.Cu" "F.Mask" "F.Paste")
			(net "PV_VDDR_NODE1")
		)
		(pad "BD38" smd circle
			(at 2.45618 8.439404)
			(size 0.3048 0.3048)
			(layers "F.Cu" "F.Mask" "F.Paste")
			(net "PV_VDDR_NODE1")
		)
		(pad "BD41" smd circle
			(at 3.742436 8.058404)
			(size 0.3048 0.3048)
			(layers "F.Cu" "F.Mask" "F.Paste")
			(net "M_DDR3_NODE1_CK0P")
		)
		(pad "BD42" smd circle
			(at 4.44246 8.058404)
			(size 0.3048 0.3048)
			(layers "F.Cu" "F.Mask" "F.Paste")
			(net "M_DDR3_NODE1_CK0N")
		)
		(pad "BD45" smd circle
			(at 5.728716 8.439404)
			(size 0.3048 0.3048)
			(layers "F.Cu" "F.Mask" "F.Paste")
			(net "PV_VDDR_NODE1")
		)
		(pad "BD46" smd circle
			(at 6.42874 8.439404)
			(size 0.3048 0.3048)
			(layers "F.Cu" "F.Mask" "F.Paste")
			(net "GND")
		)
		(pad "BD49" smd circle
			(at 7.714996 8.058404)
			(size 0.3048 0.3048)
			(layers "F.Cu" "F.Mask" "F.Paste")
			(net "M_DDR3_NODE1_ECC4")
		)
		(pad "BD50" smd circle
			(at 8.41502 8.058404)
			(size 0.3048 0.3048)
			(layers "F.Cu" "F.Mask" "F.Paste")
			(net "M_DDR3_NODE1_ECC3")
		)
		(pad "BD53" smd circle
			(at 9.701276 8.439404)
			(size 0.3048 0.3048)
			(layers "F.Cu" "F.Mask" "F.Paste")
			(net "GND")
		)
		(pad "BD54" smd circle
			(at 10.4013 8.439404)
			(size 0.3048 0.3048)
			(layers "F.Cu" "F.Mask" "F.Paste")
			(net "GND")
		)
		(pad "BD59" smd circle
			(at 12.582398 8.175244)
			(size 0.3048 0.3048)
			(layers "F.Cu" "F.Mask" "F.Paste")
			(net "GND")
		)
		(pad "BD60" smd circle
			(at 13.344398 8.175244)
			(size 0.3048 0.3048)
			(layers "F.Cu" "F.Mask" "F.Paste")
			(net "M1_DQ_NODE1_DQ43")
		)
		(pad "BD62" smd circle
			(at 14.063218 8.391398)
			(size 0.3048 0.3048)
			(layers "F.Cu" "F.Mask" "F.Paste")
			(net "GND")
		)
		(pad "BD63" smd circle
			(at 14.751558 8.222488)
			(size 0.3048 0.3048)
			(layers "F.Cu" "F.Mask" "F.Paste")
			(net "M1_DQ_NODE1_DQ54")
		)
		(pad "BD65" smd circle
			(at 15.805658 8.142732)
			(size 0.3048 0.3048)
			(layers "F.Cu" "F.Mask" "F.Paste")
			(net "M1_DQ_NODE1_DQ48")
		)
		(pad "BE5" smd circle
			(at -14.063218 8.598662)
			(size 0.3048 0.3048)
			(layers "F.Cu" "F.Mask" "F.Paste")
			(net "CLK_100M_PCIE_RP0_NODE1_DP")
		)
		(pad "BE17" smd circle
			(at -8.175244 8.820404)
			(size 0.3048 0.3048)
			(layers "F.Cu" "F.Mask" "F.Paste")
			(net "GND")
		)
		(pad "BE19" smd circle
			(at -7.47522 8.820404)
			(size 0.3048 0.3048)
			(layers "F.Cu" "F.Mask" "F.Paste")
			(net "GND")
		)
		(pad "BE25" smd circle
			(at -4.202684 8.820404)
			(size 0.3048 0.3048)
			(layers "F.Cu" "F.Mask" "F.Paste")
			(net "GND")
		)
		(pad "BE26" smd circle
			(at -3.50266 8.820404)
			(size 0.3048 0.3048)
			(layers "F.Cu" "F.Mask" "F.Paste")
			(net "M_DDR3_NODE1_DQS2P")
		)
		(pad "BE32" smd circle
			(at -0.230124 8.820404)
			(size 0.3048 0.3048)
			(layers "F.Cu" "F.Mask" "F.Paste")
			(net "PV_VDDR_NODE1")
		)
		(pad "BE34" smd circle
			(at 0.4699 8.820404)
			(size 0.3048 0.3048)
			(layers "F.Cu" "F.Mask" "F.Paste")
			(net "PV_VDDR_NODE1")
		)
		(pad "BE41" smd circle
			(at 3.742436 8.820404)
			(size 0.3048 0.3048)
			(layers "F.Cu" "F.Mask" "F.Paste")
			(net "PV_VDDR_NODE1")
		)
		(pad "BE42" smd circle
			(at 4.44246 8.820404)
			(size 0.3048 0.3048)
			(layers "F.Cu" "F.Mask" "F.Paste")
			(net "PV_VDDR_NODE1")
		)
		(pad "BE49" smd circle
			(at 7.714996 8.820404)
			(size 0.3048 0.3048)
			(layers "F.Cu" "F.Mask" "F.Paste")
			(net "M_DDR3_NODE1_DQSECCP")
		)
		(pad "BE50" smd circle
			(at 8.41502 8.820404)
			(size 0.3048 0.3048)
			(layers "F.Cu" "F.Mask" "F.Paste")
			(net "GND")
		)
		(pad "BE57" smd circle
			(at 11.687556 8.820404)
			(size 0.3048 0.3048)
			(layers "F.Cu" "F.Mask" "F.Paste")
			(net "M1_DQ_NODE1_DQ47")
		)
		(pad "BE63" smd circle
			(at 14.542516 8.902192)
			(size 0.3048 0.3048)
			(layers "F.Cu" "F.Mask" "F.Paste")
			(net "GND")
		)
		(pad "BE64" smd circle
			(at 15.304516 8.952992)
			(size 0.3048 0.3048)
			(layers "F.Cu" "F.Mask" "F.Paste")
			(net "M1_DQ_NODE1_DQ50")
		)
		(pad "BE66" smd oval
			(at 16.249396 8.902192 90)
			(size 0.254 0.3429)
			(layers "F.Cu" "F.Mask" "F.Paste")
			(net "GND")
		)
		(pad "BF1" smd oval
			(at -16.249396 9.109456 270)
			(size 0.254 0.3429)
			(layers "F.Cu" "F.Mask" "F.Paste")
			(net "TP_CPU_NODE1_RP0_PERN3")
		)
		(pad "BF3" smd circle
			(at -15.304516 9.058656)
			(size 0.3048 0.3048)
			(layers "F.Cu" "F.Mask" "F.Paste")
			(net "TP_CPU_NODE1_RP0_PERP3")
		)
		(pad "BF4" smd circle
			(at -14.542516 9.109456)
			(size 0.3048 0.3048)
			(layers "F.Cu" "F.Mask" "F.Paste")
			(net "CLK_100M_PCIE_RP0_NODE1_DN")
		)
		(pad "BF13" smd circle
			(at -10.161524 9.201404)
			(size 0.3048 0.3048)
			(layers "F.Cu" "F.Mask" "F.Paste")
			(net "M1_DQ_NODE1_DQ7")
		)
		(pad "BF15" smd circle
			(at -9.4615 9.201404)
			(size 0.3048 0.3048)
			(layers "F.Cu" "F.Mask" "F.Paste")
			(net "GND")
		)
		(pad "BF21" smd circle
			(at -6.188964 9.201404)
			(size 0.3048 0.3048)
			(layers "F.Cu" "F.Mask" "F.Paste")
			(net "M1_DQ_NODE1_DQ1")
		)
		(pad "BF23" smd circle
			(at -5.48894 9.201404)
			(size 0.3048 0.3048)
			(layers "F.Cu" "F.Mask" "F.Paste")
			(net "GND")
		)
		(pad "BF29" smd circle
			(at -2.216404 9.201404)
			(size 0.3048 0.3048)
			(layers "F.Cu" "F.Mask" "F.Paste")
			(net "GND")
		)
		(pad "BF30" smd circle
			(at -1.51638 9.201404)
			(size 0.3048 0.3048)
			(layers "F.Cu" "F.Mask" "F.Paste")
			(net "GND")
		)
		(pad "BF37" smd circle
			(at 1.756156 9.201404)
			(size 0.3048 0.3048)
			(layers "F.Cu" "F.Mask" "F.Paste")
			(net "M_DDR3_NODE1_MON2P")
		)
		(pad "BF38" smd circle
			(at 2.45618 9.201404)
			(size 0.3048 0.3048)
			(layers "F.Cu" "F.Mask" "F.Paste")
			(net "M_DDR3_NODE1_MON2N")
		)
		(pad "BF45" smd circle
			(at 5.728716 9.201404)
			(size 0.3048 0.3048)
			(layers "F.Cu" "F.Mask" "F.Paste")
			(net "CLK_100M_DDR3_NODE1_DN")
		)
		(pad "BF46" smd circle
			(at 6.42874 9.201404)
			(size 0.3048 0.3048)
			(layers "F.Cu" "F.Mask" "F.Paste")
			(net "GND")
		)
		(pad "BF53" smd circle
			(at 9.701276 9.201404)
			(size 0.3048 0.3048)
			(layers "F.Cu" "F.Mask" "F.Paste")
			(net "GND")
		)
		(pad "BF54" smd circle
			(at 10.4013 9.201404)
			(size 0.3048 0.3048)
			(layers "F.Cu" "F.Mask" "F.Paste")
			(net "GND")
		)
		(pad "BF62" smd circle
			(at 14.063218 9.412986)
			(size 0.3048 0.3048)
			(layers "F.Cu" "F.Mask" "F.Paste")
			(net "M_DDR3_NODE1_DQS5N")
		)
		(pad "BG1" smd oval
			(at -16.110966 9.859772)
			(size 0.3429 0.2794)
			(layers "F.Cu" "F.Mask" "F.Paste")
			(net "GND")
		)
		(pad "BG4" smd circle
			(at -14.751558 9.78916)
			(size 0.3048 0.3048)
			(layers "F.Cu" "F.Mask" "F.Paste")
			(net "GND")
		)
		(pad "BG5" smd circle
			(at -14.063218 9.62025)
			(size 0.3048 0.3048)
			(layers "F.Cu" "F.Mask" "F.Paste")
			(net "GND")
		)
		(pad "BG8" smd circle
			(at -12.963398 9.701276)
			(size 0.3048 0.3048)
			(layers "F.Cu" "F.Mask" "F.Paste")
			(net "TP_CPU_NODE1_RP0_PETP3")
		)
		(pad "BG9" smd circle
			(at -12.201398 9.701276)
			(size 0.3048 0.3048)
			(layers "F.Cu" "F.Mask" "F.Paste")
			(net "TP_CPU_NODE1_RP0_PETN3")
		)
		(pad "BG11" smd circle
			(at -11.44778 9.582404)
			(size 0.3048 0.3048)
			(layers "F.Cu" "F.Mask" "F.Paste")
			(net "GND")
		)
		(pad "BG13" smd circle
			(at -10.161524 9.963404)
			(size 0.3048 0.3048)
			(layers "F.Cu" "F.Mask" "F.Paste")
			(net "M1_DQ_NODE1_DQ0")
		)
		(pad "BG15" smd circle
			(at -9.4615 9.963404)
			(size 0.3048 0.3048)
			(layers "F.Cu" "F.Mask" "F.Paste")
			(net "M1_DQ_NODE1_DQ2")
		)
		(pad "BG17" smd circle
			(at -8.175244 9.582404)
			(size 0.3048 0.3048)
			(layers "F.Cu" "F.Mask" "F.Paste")
			(net "M_DDR3_NODE1_DQS0P")
		)
		(pad "BG19" smd circle
			(at -7.47522 9.582404)
			(size 0.3048 0.3048)
			(layers "F.Cu" "F.Mask" "F.Paste")
			(net "M1_DQ_NODE1_DQ4")
		)
		(pad "BG21" smd circle
			(at -6.188964 9.963404)
			(size 0.3048 0.3048)
			(layers "F.Cu" "F.Mask" "F.Paste")
			(net "M1_DQ_NODE1_DQ5")
		)
		(pad "BG23" smd circle
			(at -5.48894 9.963404)
			(size 0.3048 0.3048)
			(layers "F.Cu" "F.Mask" "F.Paste")
			(net "GND")
		)
		(pad "BG25" smd circle
			(at -4.202684 9.582404)
			(size 0.3048 0.3048)
			(layers "F.Cu" "F.Mask" "F.Paste")
			(net "M1_DQ_NODE1_DQ18")
		)
		(pad "BG26" smd circle
			(at -3.50266 9.582404)
			(size 0.3048 0.3048)
			(layers "F.Cu" "F.Mask" "F.Paste")
			(net "GND")
		)
		(pad "BG29" smd circle
			(at -2.216404 9.963404)
			(size 0.3048 0.3048)
			(layers "F.Cu" "F.Mask" "F.Paste")
			(net "M1_DQ_NODE1_DQ23")
		)
		(pad "BG30" smd circle
			(at -1.51638 9.963404)
			(size 0.3048 0.3048)
			(layers "F.Cu" "F.Mask" "F.Paste")
			(net "GND")
		)
		(pad "BG32" smd circle
			(at -0.230124 9.582404)
			(size 0.3048 0.3048)
			(layers "F.Cu" "F.Mask" "F.Paste")
			(net "PWRGD_NODE1_DDR3_SYSPWRGD")
		)
		(pad "BG34" smd circle
			(at 0.4699 9.582404)
			(size 0.3048 0.3048)
			(layers "F.Cu" "F.Mask" "F.Paste")
			(net "M_DDR3_NODE1_DQPU")
		)
		(pad "BG37" smd circle
			(at 1.756156 9.963404)
			(size 0.3048 0.3048)
			(layers "F.Cu" "F.Mask" "F.Paste")
			(net "M_DDR3_NODE1_MON1P")
		)
		(pad "BG38" smd circle
			(at 2.45618 9.963404)
			(size 0.3048 0.3048)
			(layers "F.Cu" "F.Mask" "F.Paste")
			(net "M_DDR3_NODE1_MON1N")
		)
		(pad "BG41" smd circle
			(at 3.742436 9.582404)
			(size 0.3048 0.3048)
			(layers "F.Cu" "F.Mask" "F.Paste")
			(net "M_DDR3_NODE1_CK1P")
		)
		(pad "BG42" smd circle
			(at 4.44246 9.582404)
			(size 0.3048 0.3048)
			(layers "F.Cu" "F.Mask" "F.Paste")
			(net "M_DDR3_NODE1_CK1N")
		)
		(pad "BG45" smd circle
			(at 5.728716 9.963404)
			(size 0.3048 0.3048)
			(layers "F.Cu" "F.Mask" "F.Paste")
			(net "CLK_100M_DDR3_NODE1_DP")
		)
		(pad "BG46" smd circle
			(at 6.42874 9.963404)
			(size 0.3048 0.3048)
			(layers "F.Cu" "F.Mask" "F.Paste")
			(net "GND")
		)
		(pad "BG49" smd circle
			(at 7.714996 9.582404)
			(size 0.3048 0.3048)
			(layers "F.Cu" "F.Mask" "F.Paste")
			(net "M_DDR3_NODE1_DQSECCN")
		)
		(pad "BG50" smd circle
			(at 8.41502 9.582404)
			(size 0.3048 0.3048)
			(layers "F.Cu" "F.Mask" "F.Paste")
			(net "M_DDR3_NODE1_ECC0")
		)
		(pad "BG53" smd circle
			(at 9.701276 9.963404)
			(size 0.3048 0.3048)
			(layers "F.Cu" "F.Mask" "F.Paste")
			(net "GND")
		)
		(pad "BG54" smd circle
			(at 10.4013 9.963404)
			(size 0.3048 0.3048)
			(layers "F.Cu" "F.Mask" "F.Paste")
			(net "GND")
		)
		(pad "BG57" smd circle
			(at 11.687556 9.582404)
			(size 0.3048 0.3048)
			(layers "F.Cu" "F.Mask" "F.Paste")
			(net "GND")
		)
		(pad "BG58" smd circle
			(at 12.38758 9.582404)
			(size 0.3048 0.3048)
			(layers "F.Cu" "F.Mask" "F.Paste")
			(net "M1_DQ_NODE1_DQ42")
		)
		(pad "BG63" smd circle
			(at 14.751558 9.581896)
			(size 0.3048 0.3048)
			(layers "F.Cu" "F.Mask" "F.Paste")
			(net "GND")
		)
		(pad "BG66" smd oval
			(at 16.110966 9.859772)
			(size 0.3429 0.2794)
			(layers "F.Cu" "F.Mask" "F.Paste")
			(net "GND")
		)
		(pad "BH3" smd circle
			(at -15.297912 10.317734)
			(size 0.3048 0.3048)
			(layers "F.Cu" "F.Mask" "F.Paste")
			(net "P2E_CPU_NIC1_NODE1_RX_DP")
		)
		(pad "BH5" smd circle
			(at -14.013688 10.32256)
			(size 0.3048 0.3048)
			(layers "F.Cu" "F.Mask" "F.Paste")
			(net "GND")
		)
		(pad "BH8" smd circle
			(at -12.582398 10.344404)
			(size 0.3048 0.3048)
			(layers "F.Cu" "F.Mask" "F.Paste")
			(net "P2E_CPU_NIC1_NODE1_TX_C_DP")
		)
		(pad "BH11" smd circle
			(at -11.44778 10.344404)
			(size 0.3048 0.3048)
			(layers "F.Cu" "F.Mask" "F.Paste")
			(net "GND")
		)
		(pad "BH17" smd circle
			(at -8.175244 10.344404)
			(size 0.3048 0.3048)
			(layers "F.Cu" "F.Mask" "F.Paste")
			(net "M_DDR3_NODE1_DQS0N")
		)
		(pad "BH19" smd circle
			(at -7.47522 10.344404)
			(size 0.3048 0.3048)
			(layers "F.Cu" "F.Mask" "F.Paste")
			(net "M1_DQ_NODE1_DQ3")
		)
		(pad "BH25" smd circle
			(at -4.202684 10.344404)
			(size 0.3048 0.3048)
			(layers "F.Cu" "F.Mask" "F.Paste")
			(net "M1_DQ_NODE1_DQ16")
		)
		(pad "BH26" smd circle
			(at -3.50266 10.344404)
			(size 0.3048 0.3048)
			(layers "F.Cu" "F.Mask" "F.Paste")
			(net "M1_DQ_NODE1_DQ20")
		)
		(pad "BH32" smd circle
			(at -0.230124 10.344404)
			(size 0.3048 0.3048)
			(layers "F.Cu" "F.Mask" "F.Paste")
			(net "M_DDR3_NODE1_ODTPU")
		)
		(pad "BH34" smd circle
			(at 0.4699 10.344404)
			(size 0.3048 0.3048)
			(layers "F.Cu" "F.Mask" "F.Paste")
			(net "M_DDR3_NODE1_CMDPU")
		)
		(pad "BH41" smd circle
			(at 3.742436 10.344404)
			(size 0.3048 0.3048)
			(layers "F.Cu" "F.Mask" "F.Paste")
			(net "N29180194")
		)
		(pad "BH42" smd circle
			(at 4.44246 10.344404)
			(size 0.3048 0.3048)
			(layers "F.Cu" "F.Mask" "F.Paste")
			(net "PWRGD_NODE1_DDR3_DRAM_POK")
		)
		(pad "BH49" smd circle
			(at 7.714996 10.344404)
			(size 0.3048 0.3048)
			(layers "F.Cu" "F.Mask" "F.Paste")
			(net "M_DDR3_NODE1_ECC6")
		)
		(pad "BH50" smd circle
			(at 8.41502 10.344404)
			(size 0.3048 0.3048)
			(layers "F.Cu" "F.Mask" "F.Paste")
			(net "GND")
		)
		(pad "BH57" smd circle
			(at 11.687556 10.344404)
			(size 0.3048 0.3048)
			(layers "F.Cu" "F.Mask" "F.Paste")
			(net "M1_DQ_NODE1_DQ46")
		)
		(pad "BH58" smd circle
			(at 12.38758 10.344404)
			(size 0.3048 0.3048)
			(layers "F.Cu" "F.Mask" "F.Paste")
			(net "M1_DQ_NODE1_DQ40")
		)
		(pad "BH60" smd circle
			(at 13.344398 10.161524)
			(size 0.3048 0.3048)
			(layers "F.Cu" "F.Mask" "F.Paste")
			(net "GND")
		)
		(pad "BH62" smd circle
			(at 14.08049 10.120376)
			(size 0.3048 0.3048)
			(layers "F.Cu" "F.Mask" "F.Paste")
			(net "M_DDR3_NODE1_DQS5P")
		)
		(pad "BH64" smd circle
			(at 15.297912 10.11047)
			(size 0.3048 0.3048)
			(layers "F.Cu" "F.Mask" "F.Paste")
			(net "GND")
		)
		(pad "BJ1" smd circle
			(at -16.110966 10.672572)
			(size 0.4064 0.4064)
			(layers "F.Cu" "F.Mask" "F.Paste")
			(net "GND")
		)
		(pad "BJ4" smd circle
			(at -14.90091 10.903712)
			(size 0.3048 0.3048)
			(layers "F.Cu" "F.Mask" "F.Paste")
			(net "P2E_CPU_NIC1_NODE1_RX_DN")
		)
		(pad "BJ62" smd circle
			(at 14.204442 10.813796)
			(size 0.3048 0.3048)
			(layers "F.Cu" "F.Mask" "F.Paste")
			(net "GND")
		)
		(pad "BJ63" smd circle
			(at 14.90091 10.696448)
			(size 0.3048 0.3048)
			(layers "F.Cu" "F.Mask" "F.Paste")
			(net "GND")
		)
		(pad "BJ66" smd circle
			(at 16.110966 10.672572)
			(size 0.4064 0.4064)
			(layers "F.Cu" "F.Mask" "F.Paste")
			(net "GND")
		)
		(pad "BK1" smd circle
			(at -16.110966 11.485372)
			(size 0.4064 0.4064)
			(layers "F.Cu" "F.Mask" "F.Paste")
			(net "GND")
		)
		(pad "BK3" smd circle
			(at -15.298166 11.485372)
			(size 0.4064 0.4064)
			(layers "F.Cu" "F.Mask" "F.Paste")
			(net "GND")
		)
		(pad "BK5" smd circle
			(at -14.485366 11.485372)
			(size 0.4064 0.4064)
			(layers "F.Cu" "F.Mask" "F.Paste")
			(net "GND")
		)
		(pad "BK6" smd circle
			(at -13.916152 11.063224)
			(size 0.3048 0.3048)
			(layers "F.Cu" "F.Mask" "F.Paste")
			(net "GND")
		)
		(pad "BK8" smd circle
			(at -12.894564 11.063224)
			(size 0.3048 0.3048)
			(layers "F.Cu" "F.Mask" "F.Paste")
			(net "GND")
		)
		(pad "BK9" smd circle
			(at -12.192254 11.013694)
			(size 0.3048 0.3048)
			(layers "F.Cu" "F.Mask" "F.Paste")
			(net "P2E_CPU_NIC1_NODE1_TX_C_DN")
		)
		(pad "BK10" smd circle
			(at -11.514074 11.204448)
			(size 0.3048 0.3048)
			(layers "F.Cu" "F.Mask" "F.Paste")
			(net "GND")
		)
		(pad "BK12" smd circle
			(at -10.81405 11.204448)
			(size 0.3048 0.3048)
			(layers "F.Cu" "F.Mask" "F.Paste")
			(net "GND")
		)
		(pad "BK13" smd circle
			(at -10.12063 11.073638)
			(size 0.3048 0.3048)
			(layers "F.Cu" "F.Mask" "F.Paste")
			(net "GND")
		)
		(pad "BK15" smd circle
			(at -9.41324 11.063224)
			(size 0.3048 0.3048)
			(layers "F.Cu" "F.Mask" "F.Paste")
			(net "GND")
		)
		(pad "BK17" smd circle
			(at -8.391652 11.063224)
			(size 0.3048 0.3048)
			(layers "F.Cu" "F.Mask" "F.Paste")
			(net "GND")
		)
		(pad "BK18" smd circle
			(at -7.689342 11.013694)
			(size 0.3048 0.3048)
			(layers "F.Cu" "F.Mask" "F.Paste")
			(net "GND")
		)
		(pad "BK19" smd circle
			(at -7.011162 11.204448)
			(size 0.3048 0.3048)
			(layers "F.Cu" "F.Mask" "F.Paste")
			(net "GND")
		)
		(pad "BK21" smd circle
			(at -6.311138 11.204448)
			(size 0.3048 0.3048)
			(layers "F.Cu" "F.Mask" "F.Paste")
			(net "GND")
		)
		(pad "BK22" smd circle
			(at -5.617718 11.073638)
			(size 0.3048 0.3048)
			(layers "F.Cu" "F.Mask" "F.Paste")
			(net "GND")
		)
		(pad "BK24" smd circle
			(at -4.910328 11.063224)
			(size 0.3048 0.3048)
			(layers "F.Cu" "F.Mask" "F.Paste")
			(net "GND")
		)
		(pad "BK26" smd circle
			(at -3.88874 11.063224)
			(size 0.3048 0.3048)
			(layers "F.Cu" "F.Mask" "F.Paste")
			(net "GND")
		)
		(pad "BK27" smd circle
			(at -3.18643 11.013694)
			(size 0.3048 0.3048)
			(layers "F.Cu" "F.Mask" "F.Paste")
			(net "GND")
		)
		(pad "BK28" smd circle
			(at -2.50825 11.204448)
			(size 0.3048 0.3048)
			(layers "F.Cu" "F.Mask" "F.Paste")
			(net "GND")
		)
		(pad "BK30" smd circle
			(at -1.808226 11.204448)
			(size 0.3048 0.3048)
			(layers "F.Cu" "F.Mask" "F.Paste")
			(net "GND")
		)
		(pad "BK31" smd circle
			(at -1.114806 11.073638)
			(size 0.3048 0.3048)
			(layers "F.Cu" "F.Mask" "F.Paste")
			(net "GND")
		)
		(pad "BK32" smd circle
			(at -0.407416 11.063224)
			(size 0.3048 0.3048)
			(layers "F.Cu" "F.Mask" "F.Paste")
			(net "PV_VDDR_NODE1")
		)
		(pad "BK35" smd circle
			(at 0.614172 11.063224)
			(size 0.3048 0.3048)
			(layers "F.Cu" "F.Mask" "F.Paste")
			(net "PV_VDDR_NODE1")
		)
		(pad "BK36" smd circle
			(at 1.316482 11.013694)
			(size 0.3048 0.3048)
			(layers "F.Cu" "F.Mask" "F.Paste")
			(net "GND")
		)
		(pad "BK37" smd circle
			(at 1.994662 11.204448)
			(size 0.3048 0.3048)
			(layers "F.Cu" "F.Mask" "F.Paste")
			(net "PV_VDDR_NODE1")
		)
		(pad "BK39" smd circle
			(at 2.694686 11.204448)
			(size 0.3048 0.3048)
			(layers "F.Cu" "F.Mask" "F.Paste")
			(net "PV_VDDR_NODE1")
		)
		(pad "BK40" smd circle
			(at 3.388106 11.073638)
			(size 0.3048 0.3048)
			(layers "F.Cu" "F.Mask" "F.Paste")
			(net "M_DDR3_NODE1_MA0")
		)
		(pad "BK42" smd circle
			(at 4.095496 11.063224)
			(size 0.3048 0.3048)
			(layers "F.Cu" "F.Mask" "F.Paste")
			(net "GND")
		)
		(pad "BK44" smd circle
			(at 5.117084 11.063224)
			(size 0.3048 0.3048)
			(layers "F.Cu" "F.Mask" "F.Paste")
			(net "PV_VDDR_NODE1")
		)
		(pad "BK45" smd circle
			(at 5.819394 11.013694)
			(size 0.3048 0.3048)
			(layers "F.Cu" "F.Mask" "F.Paste")
			(net "M_DDR3_NODE1_CKE1")
		)
		(pad "BK46" smd circle
			(at 6.497574 11.204448)
			(size 0.3048 0.3048)
			(layers "F.Cu" "F.Mask" "F.Paste")
			(net "PV_VDDR_NODE1")
		)
		(pad "BK48" smd circle
			(at 7.197598 11.204448)
			(size 0.3048 0.3048)
			(layers "F.Cu" "F.Mask" "F.Paste")
			(net "GND")
		)
		(pad "BK49" smd circle
			(at 7.891018 11.080496)
			(size 0.3048 0.3048)
			(layers "F.Cu" "F.Mask" "F.Paste")
			(net "M_DDR3_NODE1_ECC7")
		)
		(pad "BK51" smd circle
			(at 8.598408 11.063224)
			(size 0.3048 0.3048)
			(layers "F.Cu" "F.Mask" "F.Paste")
			(net "M_DDR3_NODE1_ECC2")
		)
		(pad "BK53" smd circle
			(at 9.619996 11.063224)
			(size 0.3048 0.3048)
			(layers "F.Cu" "F.Mask" "F.Paste")
			(net "GND")
		)
		(pad "BK54" smd circle
			(at 10.322306 11.013694)
			(size 0.3048 0.3048)
			(layers "F.Cu" "F.Mask" "F.Paste")
			(net "GND")
		)
		(pad "BK56" smd circle
			(at 11.000486 11.204448)
			(size 0.3048 0.3048)
			(layers "F.Cu" "F.Mask" "F.Paste")
			(net "GND")
		)
		(pad "BK57" smd circle
			(at 11.70051 11.204448)
			(size 0.3048 0.3048)
			(layers "F.Cu" "F.Mask" "F.Paste")
			(net "GND")
		)
		(pad "BK58" smd circle
			(at 12.39393 11.080496)
			(size 0.3048 0.3048)
			(layers "F.Cu" "F.Mask" "F.Paste")
			(net "GND")
		)
		(pad "BK60" smd circle
			(at 13.101574 11.063224)
			(size 0.3048 0.3048)
			(layers "F.Cu" "F.Mask" "F.Paste")
			(net "GND")
		)
		(pad "BK62" smd circle
			(at 14.485366 11.485372)
			(size 0.4064 0.4064)
			(layers "F.Cu" "F.Mask" "F.Paste")
			(net "GND")
		)
		(pad "BK64" smd circle
			(at 15.298166 11.485372)
			(size 0.4064 0.4064)
			(layers "F.Cu" "F.Mask" "F.Paste")
			(net "GND")
		)
		(pad "BK66" smd circle
			(at 16.110966 11.485372)
			(size 0.4064 0.4064)
			(layers "F.Cu" "F.Mask" "F.Paste")
			(net "GND")
		)
		(pad "BL7" smd circle
			(at -13.405358 11.542522)
			(size 0.3048 0.3048)
			(layers "F.Cu" "F.Mask" "F.Paste")
			(net "TP_CPU_NODE1_RP0_PERP1")
		)
		(pad "BL8" smd circle
			(at -12.725654 11.751564)
			(size 0.3048 0.3048)
			(layers "F.Cu" "F.Mask" "F.Paste")
			(net "GND")
		)
		(pad "BL10" smd circle
			(at -11.611102 11.900916)
			(size 0.3048 0.3048)
			(layers "F.Cu" "F.Mask" "F.Paste")
			(net "GND")
		)
		(pad "BL12" smd circle
			(at -10.722102 11.900916)
			(size 0.3048 0.3048)
			(layers "F.Cu" "F.Mask" "F.Paste")
			(net "GND")
		)
		(pad "BL14" smd circle
			(at -9.570974 11.794744)
			(size 0.3048 0.3048)
			(layers "F.Cu" "F.Mask" "F.Paste")
			(net "M1_DQ_NODE1_DQ14")
		)
		(pad "BL16" smd circle
			(at -8.902446 11.542522)
			(size 0.3048 0.3048)
			(layers "F.Cu" "F.Mask" "F.Paste")
			(net "GND")
		)
		(pad "BL17" smd circle
			(at -8.222742 11.751564)
			(size 0.3048 0.3048)
			(layers "F.Cu" "F.Mask" "F.Paste")
			(net "M1_DQ_NODE1_DQ15")
		)
		(pad "BL19" smd circle
			(at -7.10819 11.900916)
			(size 0.3048 0.3048)
			(layers "F.Cu" "F.Mask" "F.Paste")
			(net "M1_DQ_NODE1_DQ9")
		)
		(pad "BL21" smd circle
			(at -6.21919 11.900916)
			(size 0.3048 0.3048)
			(layers "F.Cu" "F.Mask" "F.Paste")
			(net "GND")
		)
		(pad "BL23" smd circle
			(at -5.068062 11.794744)
			(size 0.3048 0.3048)
			(layers "F.Cu" "F.Mask" "F.Paste")
			(net "M1_DQ_NODE1_DQ30")
		)
		(pad "BL25" smd circle
			(at -4.399534 11.542522)
			(size 0.3048 0.3048)
			(layers "F.Cu" "F.Mask" "F.Paste")
			(net "GND")
		)
		(pad "BL26" smd circle
			(at -3.71983 11.751564)
			(size 0.3048 0.3048)
			(layers "F.Cu" "F.Mask" "F.Paste")
			(net "M1_DQ_NODE1_DQ31")
		)
		(pad "BL28" smd circle
			(at -2.605278 11.900916)
			(size 0.3048 0.3048)
			(layers "F.Cu" "F.Mask" "F.Paste")
			(net "M1_DQ_NODE1_DQ29")
		)
		(pad "BL30" smd circle
			(at -1.716278 11.900916)
			(size 0.3048 0.3048)
			(layers "F.Cu" "F.Mask" "F.Paste")
			(net "GND")
		)
		(pad "BL32" smd circle
			(at -0.56515 11.794744)
			(size 0.3048 0.3048)
			(layers "F.Cu" "F.Mask" "F.Paste")
			(net "M_DDR3_NODE1_MA12")
		)
		(pad "BL34" smd circle
			(at 0.103378 11.542522)
			(size 0.3048 0.3048)
			(layers "F.Cu" "F.Mask" "F.Paste")
			(net "M_DDR3_NODE1_MA11")
		)
		(pad "BL35" smd circle
			(at 0.783082 11.751564)
			(size 0.3048 0.3048)
			(layers "F.Cu" "F.Mask" "F.Paste")
			(net "M_DDR3_NODE1_MA7")
		)
		(pad "BL37" smd circle
			(at 1.897634 11.900916)
			(size 0.3048 0.3048)
			(layers "F.Cu" "F.Mask" "F.Paste")
			(net "M_DDR3_NODE1_MA3")
		)
		(pad "BL39" smd circle
			(at 2.786634 11.900916)
			(size 0.3048 0.3048)
			(layers "F.Cu" "F.Mask" "F.Paste")
			(net "M_DDR3_NODE1_MA1")
		)
		(pad "BL41" smd circle
			(at 3.937762 11.794744)
			(size 0.3048 0.3048)
			(layers "F.Cu" "F.Mask" "F.Paste")
			(net "M_DDR3_NODE1_BS1")
		)
		(pad "BL43" smd circle
			(at 4.60629 11.542522)
			(size 0.3048 0.3048)
			(layers "F.Cu" "F.Mask" "F.Paste")
			(net "M_DDR3_NODE1_BS0")
		)
		(pad "BL44" smd circle
			(at 5.285994 11.751564)
			(size 0.3048 0.3048)
			(layers "F.Cu" "F.Mask" "F.Paste")
			(net "M_DDR3_NODE1_WE_L")
		)
		(pad "BL46" smd circle
			(at 6.400546 11.900916)
			(size 0.3048 0.3048)
			(layers "F.Cu" "F.Mask" "F.Paste")
			(net "M_DDR3_NODE1_CKE0")
		)
		(pad "BL48" smd circle
			(at 7.289546 11.900916)
			(size 0.3048 0.3048)
			(layers "F.Cu" "F.Mask" "F.Paste")
			(net "M_DDR3_NODE1_ODT0")
		)
		(pad "BL50" smd circle
			(at 8.440674 11.794744)
			(size 0.3048 0.3048)
			(layers "F.Cu" "F.Mask" "F.Paste")
			(net "GND")
		)
		(pad "BL52" smd circle
			(at 9.109202 11.542522)
			(size 0.3048 0.3048)
			(layers "F.Cu" "F.Mask" "F.Paste")
			(net "GND")
		)
		(pad "BL53" smd circle
			(at 9.788906 11.751564)
			(size 0.3048 0.3048)
			(layers "F.Cu" "F.Mask" "F.Paste")
			(net "M1_DQ_NODE1_DQ38")
		)
		(pad "BL55" smd circle
			(at 10.903458 11.900916)
			(size 0.3048 0.3048)
			(layers "F.Cu" "F.Mask" "F.Paste")
			(net "M_DDR3_NODE1_DQS4P")
		)
		(pad "BL57" smd circle
			(at 11.792458 11.900916)
			(size 0.3048 0.3048)
			(layers "F.Cu" "F.Mask" "F.Paste")
			(net "M1_DQ_NODE1_DQ36")
		)
		(pad "BL59" smd circle
			(at 12.932664 11.751564)
			(size 0.3048 0.3048)
			(layers "F.Cu" "F.Mask" "F.Paste")
			(net "M1_DQ_NODE1_DQ37")
		)
		(pad "BL61" smd circle
			(at 13.612368 11.542522)
			(size 0.3048 0.3048)
			(layers "F.Cu" "F.Mask" "F.Paste")
			(net "GND")
		)
		(pad "BM1" smd circle
			(at -16.110966 12.298172)
			(size 0.4064 0.4064)
			(layers "F.Cu" "F.Mask" "F.Paste")
			(net "GND")
		)
		(pad "BM3" smd circle
			(at -15.298166 12.298172)
			(size 0.4064 0.4064)
			(layers "F.Cu" "F.Mask" "F.Paste")
			(net "TP_CPU_NODE1_RP0_PLLMON1")
		)
		(pad "BM5" smd circle
			(at -14.485366 12.298172)
			(size 0.4064 0.4064)
			(layers "F.Cu" "F.Mask" "F.Paste")
			(net "TP_CPU_NODE1_RP0_PLLMON0")
		)
		(pad "BM7" smd circle
			(at -13.405358 12.304522)
			(size 0.3048 0.3048)
			(layers "F.Cu" "F.Mask" "F.Paste")
			(net "TP_CPU_NODE1_RP0_PERN1")
		)
		(pad "BM9" smd circle
			(at -12.22248 12.247118)
			(size 0.3048 0.3048)
			(layers "F.Cu" "F.Mask" "F.Paste")
			(net "P2E_CPU_SATA_NODE1_RX_DN")
		)
		(pad "BM13" smd circle
			(at -10.110724 12.2428)
			(size 0.3048 0.3048)
			(layers "F.Cu" "F.Mask" "F.Paste")
			(net "M1_DQ_NODE1_DQ8")
		)
		(pad "BM16" smd circle
			(at -8.953246 12.304522)
			(size 0.3048 0.3048)
			(layers "F.Cu" "F.Mask" "F.Paste")
			(net "M_DDR3_NODE1_DQS1N")
		)
		(pad "BM18" smd circle
			(at -7.719568 12.247118)
			(size 0.3048 0.3048)
			(layers "F.Cu" "F.Mask" "F.Paste")
			(net "M1_DQ_NODE1_DQ11")
		)
		(pad "BM22" smd circle
			(at -5.607812 12.2428)
			(size 0.3048 0.3048)
			(layers "F.Cu" "F.Mask" "F.Paste")
			(net "M1_DQ_NODE1_DQ24")
		)
		(pad "BM25" smd circle
			(at -4.450334 12.304522)
			(size 0.3048 0.3048)
			(layers "F.Cu" "F.Mask" "F.Paste")
			(net "M_DDR3_NODE1_DQS3N")
		)
		(pad "BM27" smd circle
			(at -3.216656 12.247118)
			(size 0.3048 0.3048)
			(layers "F.Cu" "F.Mask" "F.Paste")
			(net "M1_DQ_NODE1_DQ27")
		)
		(pad "BM31" smd circle
			(at -1.1049 12.2428)
			(size 0.3048 0.3048)
			(layers "F.Cu" "F.Mask" "F.Paste")
			(net "M_DDR3_NODE1_MA14")
		)
		(pad "BM34" smd circle
			(at 0.052578 12.304522)
			(size 0.3048 0.3048)
			(layers "F.Cu" "F.Mask" "F.Paste")
			(net "M_DDR3_NODE1_MA9")
		)
		(pad "BM36" smd circle
			(at 1.286256 12.247118)
			(size 0.3048 0.3048)
			(layers "F.Cu" "F.Mask" "F.Paste")
			(net "PV_VDDR_NODE1")
		)
		(pad "BM40" smd circle
			(at 3.398012 12.2428)
			(size 0.3048 0.3048)
			(layers "F.Cu" "F.Mask" "F.Paste")
			(net "PV_VDDR_NODE1")
		)
		(pad "BM43" smd circle
			(at 4.55549 12.304522)
			(size 0.3048 0.3048)
			(layers "F.Cu" "F.Mask" "F.Paste")
			(net "PV_VDDR_NODE1")
		)
		(pad "BM45" smd circle
			(at 5.789168 12.247118)
			(size 0.3048 0.3048)
			(layers "F.Cu" "F.Mask" "F.Paste")
			(net "PV_VDDR_NODE1")
		)
		(pad "BM49" smd circle
			(at 7.900924 12.2428)
			(size 0.3048 0.3048)
			(layers "F.Cu" "F.Mask" "F.Paste")
			(net "PV_VDDR_NODE1")
		)
		(pad "BM52" smd circle
			(at 9.058402 12.304522)
			(size 0.3048 0.3048)
			(layers "F.Cu" "F.Mask" "F.Paste")
			(net "M1_DQ_NODE1_DQ32")
		)
		(pad "BM54" smd circle
			(at 10.29208 12.247118)
			(size 0.3048 0.3048)
			(layers "F.Cu" "F.Mask" "F.Paste")
			(net "M1_DQ_NODE1_DQ39")
		)
		(pad "BM58" smd circle
			(at 12.403836 12.2428)
			(size 0.3048 0.3048)
			(layers "F.Cu" "F.Mask" "F.Paste")
			(net "M1_DQ_NODE1_DQ33")
		)
		(pad "BM61" smd circle
			(at 13.612368 12.304522)
			(size 0.3048 0.3048)
			(layers "F.Cu" "F.Mask" "F.Paste")
			(net "GND")
		)
		(pad "BM62" smd circle
			(at 14.485366 12.298172)
			(size 0.4064 0.4064)
			(layers "F.Cu" "F.Mask" "F.Paste")
			(net "GND")
		)
		(pad "BM64" smd circle
			(at 15.298166 12.298172)
			(size 0.4064 0.4064)
			(layers "F.Cu" "F.Mask" "F.Paste")
			(net "GND")
		)
		(pad "BM66" smd circle
			(at 16.110966 12.298172)
			(size 0.4064 0.4064)
			(layers "F.Cu" "F.Mask" "F.Paste")
			(net "GND")
		)
		(pad "BN10" smd circle
			(at -11.617198 12.640818)
			(size 0.3048 0.3048)
			(layers "F.Cu" "F.Mask" "F.Paste")
			(net "P2E_CPU_SATA_NODE1_RX_DP")
		)
		(pad "BN12" smd circle
			(at -10.690606 12.63904)
			(size 0.3048 0.3048)
			(layers "F.Cu" "F.Mask" "F.Paste")
			(net "GND")
		)
		(pad "BN14" smd circle
			(at -9.623806 12.752324)
			(size 0.3048 0.3048)
			(layers "F.Cu" "F.Mask" "F.Paste")
			(net "M1_DQ_NODE1_DQ10")
		)
		(pad "BN17" smd circle
			(at -8.142986 12.805664)
			(size 0.3048 0.3048)
			(layers "F.Cu" "F.Mask" "F.Paste")
			(net "M_DDR3_NODE1_DQS1P")
		)
		(pad "BN19" smd circle
			(at -7.114286 12.640818)
			(size 0.3048 0.3048)
			(layers "F.Cu" "F.Mask" "F.Paste")
			(net "M1_DQ_NODE1_DQ13")
		)
		(pad "BN21" smd circle
			(at -6.187694 12.63904)
			(size 0.3048 0.3048)
			(layers "F.Cu" "F.Mask" "F.Paste")
			(net "GND")
		)
		(pad "BN23" smd circle
			(at -5.120894 12.752324)
			(size 0.3048 0.3048)
			(layers "F.Cu" "F.Mask" "F.Paste")
			(net "M1_DQ_NODE1_DQ26")
		)
		(pad "BN26" smd circle
			(at -3.640074 12.805664)
			(size 0.3048 0.3048)
			(layers "F.Cu" "F.Mask" "F.Paste")
			(net "M_DDR3_NODE1_DQS3P")
		)
		(pad "BN28" smd circle
			(at -2.611374 12.640818)
			(size 0.3048 0.3048)
			(layers "F.Cu" "F.Mask" "F.Paste")
			(net "M1_DQ_NODE1_DQ25")
		)
		(pad "BN30" smd circle
			(at -1.684782 12.63904)
			(size 0.3048 0.3048)
			(layers "F.Cu" "F.Mask" "F.Paste")
			(net "GND")
		)
		(pad "BN32" smd circle
			(at -0.617982 12.752324)
			(size 0.3048 0.3048)
			(layers "F.Cu" "F.Mask" "F.Paste")
			(net "M_DDR3_NODE1_BS2")
		)
		(pad "BN35" smd circle
			(at 0.862838 12.805664)
			(size 0.3048 0.3048)
			(layers "F.Cu" "F.Mask" "F.Paste")
			(net "M_DDR3_NODE1_MA8")
		)
		(pad "BN37" smd circle
			(at 1.891538 12.640818)
			(size 0.3048 0.3048)
			(layers "F.Cu" "F.Mask" "F.Paste")
			(net "M_DDR3_NODE1_MA5")
		)
		(pad "BN39" smd circle
			(at 2.81813 12.63904)
			(size 0.3048 0.3048)
			(layers "F.Cu" "F.Mask" "F.Paste")
			(net "M_DDR3_NODE1_MA4")
		)
		(pad "BN41" smd circle
			(at 3.88493 12.752324)
			(size 0.3048 0.3048)
			(layers "F.Cu" "F.Mask" "F.Paste")
			(net "M_DDR3_NODE1_MA10")
		)
		(pad "BN44" smd circle
			(at 5.36575 12.805664)
			(size 0.3048 0.3048)
			(layers "F.Cu" "F.Mask" "F.Paste")
			(net "M_DDR3_NODE1_CS0_L")
		)
		(pad "BN46" smd circle
			(at 6.39445 12.640818)
			(size 0.3048 0.3048)
			(layers "F.Cu" "F.Mask" "F.Paste")
			(net "M_DDR3_NODE1_CAS_L")
		)
		(pad "BN48" smd circle
			(at 7.321042 12.63904)
			(size 0.3048 0.3048)
			(layers "F.Cu" "F.Mask" "F.Paste")
			(net "M_DDR3_NODE1_MA13")
		)
		(pad "BN50" smd circle
			(at 8.387842 12.752324)
			(size 0.3048 0.3048)
			(layers "F.Cu" "F.Mask" "F.Paste")
			(net "GND")
		)
		(pad "BN53" smd circle
			(at 9.868662 12.805664)
			(size 0.3048 0.3048)
			(layers "F.Cu" "F.Mask" "F.Paste")
			(net "M1_DQ_NODE1_DQ34")
		)
		(pad "BN55" smd circle
			(at 10.897362 12.640818)
			(size 0.3048 0.3048)
			(layers "F.Cu" "F.Mask" "F.Paste")
			(net "M_DDR3_NODE1_DQS4N")
		)
		(pad "BN57" smd circle
			(at 11.823954 12.63904)
			(size 0.3048 0.3048)
			(layers "F.Cu" "F.Mask" "F.Paste")
			(net "M1_DQ_NODE1_DQ35")
		)
		(pad "BP1" smd circle
			(at -16.110966 13.110972)
			(size 0.4064 0.4064)
			(layers "F.Cu" "F.Mask" "F.Paste")
			(net "GND")
		)
		(pad "BP3" smd circle
			(at -15.298166 13.110972)
			(size 0.4064 0.4064)
			(layers "F.Cu" "F.Mask" "F.Paste")
			(net "GND")
		)
		(pad "BP5" smd circle
			(at -14.485366 13.110972)
			(size 0.4064 0.4064)
			(layers "F.Cu" "F.Mask" "F.Paste")
			(net "GND")
		)
		(pad "BP6" smd circle
			(at -13.672566 13.110972)
			(size 0.4064 0.4064)
			(layers "F.Cu" "F.Mask" "F.Paste")
			(net "GND")
		)
		(pad "BP8" smd oval
			(at -12.859766 13.110972)
			(size 0.2794 0.3429)
			(layers "F.Cu" "F.Mask" "F.Paste")
			(net "GND")
		)
		(pad "BP10" smd oval
			(at -11.966702 13.249402)
			(size 0.254 0.3429)
			(layers "F.Cu" "F.Mask" "F.Paste")
			(net "GND")
		)
		(pad "BP13" smd oval
			(at -10.341102 13.249402)
			(size 0.254 0.3429)
			(layers "F.Cu" "F.Mask" "F.Paste")
			(net "M1_DQ_NODE1_DQ12")
		)
		(pad "BP16" smd oval
			(at -8.902446 13.249402)
			(size 0.254 0.3429)
			(layers "F.Cu" "F.Mask" "F.Paste")
			(net "GND")
		)
		(pad "BP19" smd oval
			(at -7.46379 13.249402)
			(size 0.254 0.3429)
			(layers "F.Cu" "F.Mask" "F.Paste")
			(net "GND")
		)
		(pad "BP22" smd oval
			(at -5.83819 13.249402)
			(size 0.254 0.3429)
			(layers "F.Cu" "F.Mask" "F.Paste")
			(net "M1_DQ_NODE1_DQ28")
		)
		(pad "BP25" smd oval
			(at -4.399534 13.249402)
			(size 0.254 0.3429)
			(layers "F.Cu" "F.Mask" "F.Paste")
			(net "GND")
		)
		(pad "BP28" smd oval
			(at -2.960878 13.249402)
			(size 0.254 0.3429)
			(layers "F.Cu" "F.Mask" "F.Paste")
			(net "GND")
		)
		(pad "BP31" smd oval
			(at -1.335278 13.249402)
			(size 0.254 0.3429)
			(layers "F.Cu" "F.Mask" "F.Paste")
			(net "M_DDR3_NODE1_MA15")
		)
		(pad "BP34" smd oval
			(at 0.103378 13.249402)
			(size 0.254 0.3429)
			(layers "F.Cu" "F.Mask" "F.Paste")
			(net "PV_VDDR_NODE1")
		)
		(pad "BP37" smd oval
			(at 1.542034 13.249402)
			(size 0.254 0.3429)
			(layers "F.Cu" "F.Mask" "F.Paste")
			(net "M_DDR3_NODE1_MA6")
		)
		(pad "BP40" smd oval
			(at 3.167634 13.249402)
			(size 0.254 0.3429)
			(layers "F.Cu" "F.Mask" "F.Paste")
			(net "M_DDR3_NODE1_MA2")
		)
		(pad "BP43" smd oval
			(at 4.60629 13.249402)
			(size 0.254 0.3429)
			(layers "F.Cu" "F.Mask" "F.Paste")
			(net "M_DDR3_NODE1_RAS_L")
		)
		(pad "BP46" smd oval
			(at 6.044946 13.249402)
			(size 0.254 0.3429)
			(layers "F.Cu" "F.Mask" "F.Paste")
			(net "M_DDR3_NODE1_CS1_L")
		)
		(pad "BP49" smd oval
			(at 7.670546 13.249402)
			(size 0.254 0.3429)
			(layers "F.Cu" "F.Mask" "F.Paste")
			(net "M_DDR3_NODE1_ODT1")
		)
		(pad "BP52" smd oval
			(at 9.109202 13.249402)
			(size 0.254 0.3429)
			(layers "F.Cu" "F.Mask" "F.Paste")
			(net "GND")
		)
		(pad "BP55" smd oval
			(at 10.547858 13.249402)
			(size 0.254 0.3429)
			(layers "F.Cu" "F.Mask" "F.Paste")
			(net "GND")
		)
		(pad "BP58" smd oval
			(at 12.173458 13.249402)
			(size 0.254 0.3429)
			(layers "F.Cu" "F.Mask" "F.Paste")
			(net "GND")
		)
		(pad "BP59" smd oval
			(at 12.859766 13.110972)
			(size 0.2794 0.3429)
			(layers "F.Cu" "F.Mask" "F.Paste")
			(net "GND")
		)
		(pad "BP61" smd circle
			(at 13.672566 13.110972)
			(size 0.4064 0.4064)
			(layers "F.Cu" "F.Mask" "F.Paste")
			(net "GND")
		)
		(pad "BP62" smd circle
			(at 14.485366 13.110972)
			(size 0.4064 0.4064)
			(layers "F.Cu" "F.Mask" "F.Paste")
			(net "GND")
		)
		(pad "BP64" smd circle
			(at 15.298166 13.110972)
			(size 0.4064 0.4064)
			(layers "F.Cu" "F.Mask" "F.Paste")
			(net "GND")
		)
		(pad "BP66" smd circle
			(at 16.110966 13.110972)
			(size 0.4064 0.4064)
			(layers "F.Cu" "F.Mask" "F.Paste")
			(net "GND")
		)
		(pad "C3" smd circle
			(at -15.298166 -12.298172)
			(size 0.4064 0.4064)
			(layers "F.Cu" "F.Mask" "F.Paste")
			(net "GND")
		)
		(pad "C5" smd circle
			(at -14.485366 -12.298172)
			(size 0.4064 0.4064)
			(layers "F.Cu" "F.Mask" "F.Paste")
			(net "GND")
		)
		(pad "C6" smd circle
			(at -13.612368 -12.304522)
			(size 0.3048 0.3048)
			(layers "F.Cu" "F.Mask" "F.Paste")
			(net "GND")
		)
		(pad "C9" smd circle
			(at -12.403836 -12.2428)
			(size 0.3048 0.3048)
			(layers "F.Cu" "F.Mask" "F.Paste")
			(net "GND")
		)
		(pad "C13" smd circle
			(at -10.29208 -12.247118)
			(size 0.3048 0.3048)
			(layers "F.Cu" "F.Mask" "F.Paste")
			(net "GND")
		)
		(pad "C15" smd circle
			(at -9.058402 -12.304522)
			(size 0.3048 0.3048)
			(layers "F.Cu" "F.Mask" "F.Paste")
			(net "PD_NODE1_NTB_PERP")
		)
		(pad "C18" smd circle
			(at -7.900924 -12.2428)
			(size 0.3048 0.3048)
			(layers "F.Cu" "F.Mask" "F.Paste")
			(net "GND")
		)
		(pad "C22" smd circle
			(at -5.789168 -12.247118)
			(size 0.3048 0.3048)
			(layers "F.Cu" "F.Mask" "F.Paste")
			(net "GND")
		)
		(pad "C24" smd circle
			(at -4.55549 -12.304522)
			(size 0.3048 0.3048)
			(layers "F.Cu" "F.Mask" "F.Paste")
			(net "PD_NODE1_NTB_PERP")
		)
		(pad "C27" smd circle
			(at -3.398012 -12.2428)
			(size 0.3048 0.3048)
			(layers "F.Cu" "F.Mask" "F.Paste")
			(net "GND")
		)
		(pad "C31" smd circle
			(at -1.286256 -12.247118)
			(size 0.3048 0.3048)
			(layers "F.Cu" "F.Mask" "F.Paste")
			(net "PU_CPU_NODE1_DFX_GPIO_GRP1_6")
		)
		(pad "C33" smd circle
			(at -0.052578 -12.304522)
			(size 0.3048 0.3048)
			(layers "F.Cu" "F.Mask" "F.Paste")
			(net "PD_CPU_NODE1_DFX_GPIO_GRP1_0")
		)
		(pad "C36" smd circle
			(at 1.1049 -12.2428)
			(size 0.3048 0.3048)
			(layers "F.Cu" "F.Mask" "F.Paste")
			(net "TP_CPU0_NODE1_SFRANAD")
		)
		(pad "C40" smd circle
			(at 3.216656 -12.247118)
			(size 0.3048 0.3048)
			(layers "F.Cu" "F.Mask" "F.Paste")
			(net "SPI_CPU_NODE1_CS0_R_L")
		)
		(pad "C42" smd circle
			(at 4.450334 -12.304522)
			(size 0.3048 0.3048)
			(layers "F.Cu" "F.Mask" "F.Paste")
			(net "LPC_CPU_NODE1_CLKRUN_L")
		)
		(pad "C45" smd circle
			(at 5.607812 -12.2428)
			(size 0.3048 0.3048)
			(layers "F.Cu" "F.Mask" "F.Paste")
			(net "LPC_CPU_NODE1_R_CLKOUT1")
		)
		(pad "C49" smd circle
			(at 7.719568 -12.247118)
			(size 0.3048 0.3048)
			(layers "F.Cu" "F.Mask" "F.Paste")
			(net "SPC_CPU_NODE1_CTS_L")
		)
		(pad "C51" smd circle
			(at 8.953246 -12.304522)
			(size 0.3048 0.3048)
			(layers "F.Cu" "F.Mask" "F.Paste")
			(net "H_CPU_NODE1_ERR2_R")
		)
		(pad "C54" smd circle
			(at 10.110724 -12.2428)
			(size 0.3048 0.3048)
			(layers "F.Cu" "F.Mask" "F.Paste")
			(net "GND")
		)
		(pad "C58" smd circle
			(at 12.22248 -12.247118)
			(size 0.3048 0.3048)
			(layers "F.Cu" "F.Mask" "F.Paste")
			(net "GND")
		)
		(pad "C60" smd circle
			(at 13.405358 -12.304522)
			(size 0.3048 0.3048)
			(layers "F.Cu" "F.Mask" "F.Paste")
			(net "GND")
		)
		(pad "C62" smd circle
			(at 14.485366 -12.298172)
			(size 0.4064 0.4064)
			(layers "F.Cu" "F.Mask" "F.Paste")
			(net "GND")
		)
		(pad "C64" smd circle
			(at 15.298166 -12.298172)
			(size 0.4064 0.4064)
			(layers "F.Cu" "F.Mask" "F.Paste")
			(net "GND")
		)
		(pad "C66" smd circle
			(at 16.110966 -12.298172)
			(size 0.4064 0.4064)
			(layers "F.Cu" "F.Mask" "F.Paste")
			(net "GND")
		)
		(pad "D6" smd circle
			(at -13.612368 -11.542522)
			(size 0.3048 0.3048)
			(layers "F.Cu" "F.Mask" "F.Paste")
			(net "GND")
		)
		(pad "D8" smd circle
			(at -12.932664 -11.751564)
			(size 0.3048 0.3048)
			(layers "F.Cu" "F.Mask" "F.Paste")
			(net "GND")
		)
		(pad "D10" smd circle
			(at -11.792458 -11.900916)
			(size 0.3048 0.3048)
			(layers "F.Cu" "F.Mask" "F.Paste")
			(net "PD_NODE1_NTB_PERN")
		)
		(pad "D12" smd circle
			(at -10.903458 -11.900916)
			(size 0.3048 0.3048)
			(layers "F.Cu" "F.Mask" "F.Paste")
			(net "PD_NODE1_NTB_PERN")
		)
		(pad "D14" smd circle
			(at -9.788906 -11.751564)
			(size 0.3048 0.3048)
			(layers "F.Cu" "F.Mask" "F.Paste")
			(net "GND")
		)
		(pad "D15" smd circle
			(at -9.109202 -11.542522)
			(size 0.3048 0.3048)
			(layers "F.Cu" "F.Mask" "F.Paste")
			(net "PD_NODE1_NTB_PERN")
		)
		(pad "D17" smd circle
			(at -8.440674 -11.794744)
			(size 0.3048 0.3048)
			(layers "F.Cu" "F.Mask" "F.Paste")
			(net "PD_NODE1_NTB_PERN")
		)
		(pad "D19" smd circle
			(at -7.289546 -11.900916)
			(size 0.3048 0.3048)
			(layers "F.Cu" "F.Mask" "F.Paste")
			(net "PD_NODE1_NTB_PERP")
		)
		(pad "D21" smd circle
			(at -6.400546 -11.900916)
			(size 0.3048 0.3048)
			(layers "F.Cu" "F.Mask" "F.Paste")
			(net "PD_NODE1_NTB_PERP")
		)
		(pad "D23" smd circle
			(at -5.285994 -11.751564)
			(size 0.3048 0.3048)
			(layers "F.Cu" "F.Mask" "F.Paste")
			(net "PD_NODE1_NTB_PERP")
		)
		(pad "D24" smd circle
			(at -4.60629 -11.542522)
			(size 0.3048 0.3048)
			(layers "F.Cu" "F.Mask" "F.Paste")
			(net "PD_NODE1_NTB_PERP")
		)
		(pad "D26" smd circle
			(at -3.937762 -11.794744)
			(size 0.3048 0.3048)
			(layers "F.Cu" "F.Mask" "F.Paste")
			(net "PD_NODE1_NTB_PERN")
		)
		(pad "D28" smd circle
			(at -2.786634 -11.900916)
			(size 0.3048 0.3048)
			(layers "F.Cu" "F.Mask" "F.Paste")
			(net "PD_CPU_NODE1_DFX_GPIO_GRP0_1")
		)
		(pad "D30" smd circle
			(at -1.897634 -11.900916)
			(size 0.3048 0.3048)
			(layers "F.Cu" "F.Mask" "F.Paste")
			(net "PD_CPU_NODE1_DFX_GPIO_GRP0_0")
		)
		(pad "D32" smd circle
			(at -0.783082 -11.751564)
			(size 0.3048 0.3048)
			(layers "F.Cu" "F.Mask" "F.Paste")
			(net "GND")
		)
		(pad "D33" smd circle
			(at -0.103378 -11.542522)
			(size 0.3048 0.3048)
			(layers "F.Cu" "F.Mask" "F.Paste")
			(net "PD_CPU_NODE1_DFX_GPIO_GRP1_1")
		)
		(pad "D35" smd circle
			(at 0.56515 -11.794744)
			(size 0.3048 0.3048)
			(layers "F.Cu" "F.Mask" "F.Paste")
			(net "TP_CPU1_NODE1_SFRANAD")
		)
		(pad "D37" smd circle
			(at 1.716278 -11.900916)
			(size 0.3048 0.3048)
			(layers "F.Cu" "F.Mask" "F.Paste")
			(net "GND")
		)
		(pad "D39" smd circle
			(at 2.605278 -11.900916)
			(size 0.3048 0.3048)
			(layers "F.Cu" "F.Mask" "F.Paste")
			(net "GND")
		)
		(pad "D41" smd circle
			(at 3.71983 -11.751564)
			(size 0.3048 0.3048)
			(layers "F.Cu" "F.Mask" "F.Paste")
			(net "GND")
		)
		(pad "D42" smd circle
			(at 4.399534 -11.542522)
			(size 0.3048 0.3048)
			(layers "F.Cu" "F.Mask" "F.Paste")
			(net "SPI_CPU_NODE1_MOSI_R")
		)
		(pad "D44" smd circle
			(at 5.068062 -11.794744)
			(size 0.3048 0.3048)
			(layers "F.Cu" "F.Mask" "F.Paste")
			(net "LPC_CPU_NODE1_FRAME_L_R")
		)
		(pad "D46" smd circle
			(at 6.21919 -11.900916)
			(size 0.3048 0.3048)
			(layers "F.Cu" "F.Mask" "F.Paste")
			(net "GND")
		)
		(pad "D48" smd circle
			(at 7.10819 -11.900916)
			(size 0.3048 0.3048)
			(layers "F.Cu" "F.Mask" "F.Paste")
			(net "Net_295")
		)
		(pad "D50" smd circle
			(at 8.222742 -11.751564)
			(size 0.3048 0.3048)
			(layers "F.Cu" "F.Mask" "F.Paste")
			(net "GND")
		)
		(pad "D51" smd circle
			(at 8.902446 -11.542522)
			(size 0.3048 0.3048)
			(layers "F.Cu" "F.Mask" "F.Paste")
			(net "H_CPU_NODE1_ERR1_R")
		)
		(pad "D53" smd circle
			(at 9.570974 -11.794744)
			(size 0.3048 0.3048)
			(layers "F.Cu" "F.Mask" "F.Paste")
			(net "TP_CPU_D53")
		)
		(pad "D55" smd circle
			(at 10.722102 -11.900916)
			(size 0.3048 0.3048)
			(layers "F.Cu" "F.Mask" "F.Paste")
			(net "PD_CPU_NODE1_NODE_ID")
		)
		(pad "D57" smd circle
			(at 11.611102 -11.900916)
			(size 0.3048 0.3048)
			(layers "F.Cu" "F.Mask" "F.Paste")
			(net "LAN2_DISABLE_N")
		)
		(pad "D59" smd circle
			(at 12.725654 -11.751564)
			(size 0.3048 0.3048)
			(layers "F.Cu" "F.Mask" "F.Paste")
			(net "GND")
		)
		(pad "D60" smd circle
			(at 13.405358 -11.542522)
			(size 0.3048 0.3048)
			(layers "F.Cu" "F.Mask" "F.Paste")
			(net "GND")
		)
		(pad "E1" smd circle
			(at -16.110966 -11.485372)
			(size 0.4064 0.4064)
			(layers "F.Cu" "F.Mask" "F.Paste")
			(net "GND")
		)
		(pad "E3" smd circle
			(at -15.298166 -11.485372)
			(size 0.4064 0.4064)
			(layers "F.Cu" "F.Mask" "F.Paste")
			(net "GND")
		)
		(pad "E5" smd circle
			(at -14.485366 -11.485372)
			(size 0.4064 0.4064)
			(layers "F.Cu" "F.Mask" "F.Paste")
			(net "GND")
		)
		(pad "E7" smd circle
			(at -13.101574 -11.063224)
			(size 0.3048 0.3048)
			(layers "F.Cu" "F.Mask" "F.Paste")
			(net "GND")
		)
		(pad "E9" smd circle
			(at -12.39393 -11.080496)
			(size 0.3048 0.3048)
			(layers "F.Cu" "F.Mask" "F.Paste")
			(net "GND")
		)
		(pad "E10" smd circle
			(at -11.70051 -11.204448)
			(size 0.3048 0.3048)
			(layers "F.Cu" "F.Mask" "F.Paste")
			(net "PD_NODE1_NTB_PERP")
		)
		(pad "E12" smd circle
			(at -11.000486 -11.204448)
			(size 0.3048 0.3048)
			(layers "F.Cu" "F.Mask" "F.Paste")
			(net "PD_NODE1_NTB_PERP")
		)
		(pad "E13" smd circle
			(at -10.322306 -11.013694)
			(size 0.3048 0.3048)
			(layers "F.Cu" "F.Mask" "F.Paste")
			(net "GND")
		)
		(pad "E14" smd circle
			(at -9.619996 -11.063224)
			(size 0.3048 0.3048)
			(layers "F.Cu" "F.Mask" "F.Paste")
			(net "GND")
		)
		(pad "E16" smd circle
			(at -8.598408 -11.063224)
			(size 0.3048 0.3048)
			(layers "F.Cu" "F.Mask" "F.Paste")
			(net "GND")
		)
		(pad "E18" smd circle
			(at -7.891018 -11.080496)
			(size 0.3048 0.3048)
			(layers "F.Cu" "F.Mask" "F.Paste")
			(net "GND")
		)
		(pad "E19" smd circle
			(at -7.197598 -11.204448)
			(size 0.3048 0.3048)
			(layers "F.Cu" "F.Mask" "F.Paste")
			(net "PD_NODE1_NTB_PERP")
		)
		(pad "E21" smd circle
			(at -6.497574 -11.204448)
			(size 0.3048 0.3048)
			(layers "F.Cu" "F.Mask" "F.Paste")
			(net "PD_NODE1_NTB_PERN")
		)
		(pad "E22" smd circle
			(at -5.819394 -11.013694)
			(size 0.3048 0.3048)
			(layers "F.Cu" "F.Mask" "F.Paste")
			(net "GND")
		)
		(pad "E23" smd circle
			(at -5.117084 -11.063224)
			(size 0.3048 0.3048)
			(layers "F.Cu" "F.Mask" "F.Paste")
			(net "PD_NODE1_NTB_PERN")
		)
		(pad "E25" smd circle
			(at -4.095496 -11.063224)
			(size 0.3048 0.3048)
			(layers "F.Cu" "F.Mask" "F.Paste")
			(net "GND")
		)
		(pad "E27" smd circle
			(at -3.388106 -11.080496)
			(size 0.3048 0.3048)
			(layers "F.Cu" "F.Mask" "F.Paste")
			(net "GND")
		)
		(pad "E28" smd circle
			(at -2.694686 -11.204448)
			(size 0.3048 0.3048)
			(layers "F.Cu" "F.Mask" "F.Paste")
			(net "PD_CPU_NODE1_DFX_GPIO_GRP0_6")
		)
		(pad "E30" smd circle
			(at -1.994662 -11.204448)
			(size 0.3048 0.3048)
			(layers "F.Cu" "F.Mask" "F.Paste")
			(net "GND")
		)
		(pad "E31" smd circle
			(at -1.316482 -11.013694)
			(size 0.3048 0.3048)
			(layers "F.Cu" "F.Mask" "F.Paste")
			(net "PU_CPU_NODE1_DFX_GPIO_GRP1_5")
		)
		(pad "E32" smd circle
			(at -0.614172 -11.063224)
			(size 0.3048 0.3048)
			(layers "F.Cu" "F.Mask" "F.Paste")
			(net "GND")
		)
		(pad "E34" smd circle
			(at 0.407416 -11.063224)
			(size 0.3048 0.3048)
			(layers "F.Cu" "F.Mask" "F.Paste")
			(net "GND")
		)
		(pad "E36" smd circle
			(at 1.114806 -11.073638)
			(size 0.3048 0.3048)
			(layers "F.Cu" "F.Mask" "F.Paste")
			(net "TP_CPU_NODE1_EXTBGREF")
		)
		(pad "E37" smd circle
			(at 1.808226 -11.204448)
			(size 0.3048 0.3048)
			(layers "F.Cu" "F.Mask" "F.Paste")
			(net "GND")
		)
		(pad "E39" smd circle
			(at 2.50825 -11.204448)
			(size 0.3048 0.3048)
			(layers "F.Cu" "F.Mask" "F.Paste")
			(net "TP_SPI_CPU_NODE1_CS1_L")
		)
		(pad "E40" smd circle
			(at 3.18643 -11.013694)
			(size 0.3048 0.3048)
			(layers "F.Cu" "F.Mask" "F.Paste")
			(net "SPI_CPU_NODE1_MISO")
		)
		(pad "E41" smd circle
			(at 3.88874 -11.063224)
			(size 0.3048 0.3048)
			(layers "F.Cu" "F.Mask" "F.Paste")
			(net "GND")
		)
		(pad "E43" smd circle
			(at 4.910328 -11.063224)
			(size 0.3048 0.3048)
			(layers "F.Cu" "F.Mask" "F.Paste")
			(net "GND")
		)
		(pad "E45" smd circle
			(at 5.617718 -11.080496)
			(size 0.3048 0.3048)
			(layers "F.Cu" "F.Mask" "F.Paste")
			(net "GND")
		)
		(pad "E46" smd circle
			(at 6.311138 -11.204448)
			(size 0.3048 0.3048)
			(layers "F.Cu" "F.Mask" "F.Paste")
			(net "GND")
		)
		(pad "E48" smd circle
			(at 7.011162 -11.204448)
			(size 0.3048 0.3048)
			(layers "F.Cu" "F.Mask" "F.Paste")
			(net "Net_297")
		)
		(pad "E49" smd circle
			(at 7.689342 -11.013694)
			(size 0.3048 0.3048)
			(layers "F.Cu" "F.Mask" "F.Paste")
			(net "Net_300")
		)
		(pad "E50" smd circle
			(at 8.391652 -11.063224)
			(size 0.3048 0.3048)
			(layers "F.Cu" "F.Mask" "F.Paste")
			(net "GND")
		)
		(pad "E52" smd circle
			(at 9.41324 -11.063224)
			(size 0.3048 0.3048)
			(layers "F.Cu" "F.Mask" "F.Paste")
			(net "PD_CPU_NODE1_BOOTDEVSEL")
		)
		(pad "E54" smd circle
			(at 10.12063 -11.080496)
			(size 0.3048 0.3048)
			(layers "F.Cu" "F.Mask" "F.Paste")
			(net "GND")
		)
		(pad "E55" smd circle
			(at 10.81405 -11.204448)
			(size 0.3048 0.3048)
			(layers "F.Cu" "F.Mask" "F.Paste")
			(net "PCIE_SW_P0_ERR")
		)
		(pad "E57" smd circle
			(at 11.514074 -11.204448)
			(size 0.3048 0.3048)
			(layers "F.Cu" "F.Mask" "F.Paste")
			(net "CPU_NODE1_PROCHOT_N")
		)
		(pad "E58" smd circle
			(at 12.192254 -11.013694)
			(size 0.3048 0.3048)
			(layers "F.Cu" "F.Mask" "F.Paste")
			(net "GND")
		)
		(pad "E59" smd circle
			(at 12.894564 -11.063224)
			(size 0.3048 0.3048)
			(layers "F.Cu" "F.Mask" "F.Paste")
			(net "TP_CPU_E59")
		)
		(pad "E61" smd circle
			(at 13.916152 -11.063224)
			(size 0.3048 0.3048)
			(layers "F.Cu" "F.Mask" "F.Paste")
			(net "GND")
		)
		(pad "E62" smd circle
			(at 14.485366 -11.485372)
			(size 0.4064 0.4064)
			(layers "F.Cu" "F.Mask" "F.Paste")
			(net "GND")
		)
		(pad "E64" smd circle
			(at 15.298166 -11.485372)
			(size 0.4064 0.4064)
			(layers "F.Cu" "F.Mask" "F.Paste")
			(net "GND")
		)
		(pad "E66" smd circle
			(at 16.110966 -11.485372)
			(size 0.4064 0.4064)
			(layers "F.Cu" "F.Mask" "F.Paste")
			(net "GND")
		)
		(pad "F1" smd circle
			(at -16.110966 -10.672572)
			(size 0.4064 0.4064)
			(layers "F.Cu" "F.Mask" "F.Paste")
			(net "TP_CPU_NODE1_HPLL_MONP")
		)
		(pad "F4" smd circle
			(at -14.90091 -10.696448)
			(size 0.3048 0.3048)
			(layers "F.Cu" "F.Mask" "F.Paste")
			(net "GND")
		)
		(pad "F5" smd circle
			(at -14.204442 -10.813796)
			(size 0.3048 0.3048)
			(layers "F.Cu" "F.Mask" "F.Paste")
			(net "PD_NODE1_NTB_PERN")
		)
		(pad "F63" smd circle
			(at 14.90091 -10.903712)
			(size 0.3048 0.3048)
			(layers "F.Cu" "F.Mask" "F.Paste")
			(net "GND")
		)
		(pad "F66" smd circle
			(at 16.110966 -10.672572)
			(size 0.4064 0.4064)
			(layers "F.Cu" "F.Mask" "F.Paste")
			(net "GND")
		)
		(pad "G3" smd circle
			(at -15.297912 -10.11047)
			(size 0.3048 0.3048)
			(layers "F.Cu" "F.Mask" "F.Paste")
			(net "GND")
		)
		(pad "G5" smd circle
			(at -14.08049 -10.120376)
			(size 0.3048 0.3048)
			(layers "F.Cu" "F.Mask" "F.Paste")
			(net "PD_NODE1_NTB_PERP")
		)
		(pad "G7" smd circle
			(at -13.344398 -10.161524)
			(size 0.3048 0.3048)
			(layers "F.Cu" "F.Mask" "F.Paste")
			(net "GND")
		)
		(pad "G9" smd circle
			(at -12.38758 -10.344404)
			(size 0.3048 0.3048)
			(layers "F.Cu" "F.Mask" "F.Paste")
			(net "PD_NODE1_NTB_PERN")
		)
		(pad "G10" smd circle
			(at -11.687556 -10.344404)
			(size 0.3048 0.3048)
			(layers "F.Cu" "F.Mask" "F.Paste")
			(net "GND")
		)
		(pad "G17" smd circle
			(at -8.41502 -10.344404)
			(size 0.3048 0.3048)
			(layers "F.Cu" "F.Mask" "F.Paste")
			(net "Net_419")
		)
		(pad "G18" smd circle
			(at -7.714996 -10.344404)
			(size 0.3048 0.3048)
			(layers "F.Cu" "F.Mask" "F.Paste")
			(net "Net_423")
		)
		(pad "G25" smd circle
			(at -4.44246 -10.344404)
			(size 0.3048 0.3048)
			(layers "F.Cu" "F.Mask" "F.Paste")
			(net "Net_403")
		)
		(pad "G26" smd circle
			(at -3.742436 -10.344404)
			(size 0.3048 0.3048)
			(layers "F.Cu" "F.Mask" "F.Paste")
			(net "Net_406")
		)
		(pad "G32" smd circle
			(at -0.4699 -10.344404)
			(size 0.3048 0.3048)
			(layers "F.Cu" "F.Mask" "F.Paste")
			(net "PD_CPU_NODE1_DFX_GPIO_GRP1_7")
		)
		(pad "G34" smd circle
			(at 0.230124 -10.344404)
			(size 0.3048 0.3048)
			(layers "F.Cu" "F.Mask" "F.Paste")
			(net "PD_CPU_NODE1_DFX_GPIO_GRP1_2")
		)
		(pad "G41" smd circle
			(at 3.50266 -10.344404)
			(size 0.3048 0.3048)
			(layers "F.Cu" "F.Mask" "F.Paste")
			(net "LPC_CPU_NODE1_LAD1_R")
		)
		(pad "G42" smd circle
			(at 4.202684 -10.344404)
			(size 0.3048 0.3048)
			(layers "F.Cu" "F.Mask" "F.Paste")
			(net "LPC_CPU_NODE1_LAD0_R")
		)
		(pad "G48" smd circle
			(at 7.47522 -10.344404)
			(size 0.3048 0.3048)
			(layers "F.Cu" "F.Mask" "F.Paste")
			(net "GND")
		)
		(pad "G50" smd circle
			(at 8.175244 -10.344404)
			(size 0.3048 0.3048)
			(layers "F.Cu" "F.Mask" "F.Paste")
			(net "GND")
		)
		(pad "G56" smd circle
			(at 11.44778 -10.344404)
			(size 0.3048 0.3048)
			(layers "F.Cu" "F.Mask" "F.Paste")
			(net "GND")
		)
		(pad "G59" smd circle
			(at 12.582398 -10.344404)
			(size 0.3048 0.3048)
			(layers "F.Cu" "F.Mask" "F.Paste")
			(net "GND")
		)
		(pad "G62" smd circle
			(at 14.013688 -10.32256)
			(size 0.3048 0.3048)
			(layers "F.Cu" "F.Mask" "F.Paste")
			(net "USB_NODE1_SMI_L")
		)
		(pad "G64" smd circle
			(at 15.297912 -10.317734)
			(size 0.3048 0.3048)
			(layers "F.Cu" "F.Mask" "F.Paste")
			(net "H_CPU_NODE1_ERR0")
		)
		(pad "H1" smd oval
			(at -16.110966 -9.859772)
			(size 0.3429 0.2794)
			(layers "F.Cu" "F.Mask" "F.Paste")
			(net "TP_CPU_NODE1_HPLL_MONN")
		)
		(pad "H4" smd circle
			(at -14.751558 -9.581896)
			(size 0.3048 0.3048)
			(layers "F.Cu" "F.Mask" "F.Paste")
			(net "GND")
		)
		(pad "H9" smd circle
			(at -12.38758 -9.582404)
			(size 0.3048 0.3048)
			(layers "F.Cu" "F.Mask" "F.Paste")
			(net "PD_NODE1_NTB_PERP")
		)
		(pad "H10" smd circle
			(at -11.687556 -9.582404)
			(size 0.3048 0.3048)
			(layers "F.Cu" "F.Mask" "F.Paste")
			(net "PD_NODE1_NTB_PERN")
		)
		(pad "H13" smd circle
			(at -10.4013 -9.963404)
			(size 0.3048 0.3048)
			(layers "F.Cu" "F.Mask" "F.Paste")
			(net "Net_421")
		)
		(pad "H14" smd circle
			(at -9.701276 -9.963404)
			(size 0.3048 0.3048)
			(layers "F.Cu" "F.Mask" "F.Paste")
			(net "PD_NODE1_NTB_CLKINN")
		)
		(pad "H17" smd circle
			(at -8.41502 -9.582404)
			(size 0.3048 0.3048)
			(layers "F.Cu" "F.Mask" "F.Paste")
			(net "Net_418")
		)
		(pad "H18" smd circle
			(at -7.714996 -9.582404)
			(size 0.3048 0.3048)
			(layers "F.Cu" "F.Mask" "F.Paste")
			(net "Net_433")
		)
		(pad "H21" smd circle
			(at -6.42874 -9.963404)
			(size 0.3048 0.3048)
			(layers "F.Cu" "F.Mask" "F.Paste")
			(net "GND")
		)
		(pad "H22" smd circle
			(at -5.728716 -9.963404)
			(size 0.3048 0.3048)
			(layers "F.Cu" "F.Mask" "F.Paste")
			(net "GND")
		)
		(pad "H25" smd circle
			(at -4.44246 -9.582404)
			(size 0.3048 0.3048)
			(layers "F.Cu" "F.Mask" "F.Paste")
			(net "Net_429")
		)
		(pad "H26" smd circle
			(at -3.742436 -9.582404)
			(size 0.3048 0.3048)
			(layers "F.Cu" "F.Mask" "F.Paste")
			(net "Net_405")
		)
		(pad "H29" smd circle
			(at -2.45618 -9.963404)
			(size 0.3048 0.3048)
			(layers "F.Cu" "F.Mask" "F.Paste")
			(net "GND")
		)
		(pad "H30" smd circle
			(at -1.756156 -9.963404)
			(size 0.3048 0.3048)
			(layers "F.Cu" "F.Mask" "F.Paste")
			(net "FM_NODE1_DFX_GPIO_GRP05")
		)
		(pad "H32" smd circle
			(at -0.4699 -9.582404)
			(size 0.3048 0.3048)
			(layers "F.Cu" "F.Mask" "F.Paste")
			(net "PD_CPU_NODE1_DFX_GPIO_GRP0_4")
		)
		(pad "H34" smd circle
			(at 0.230124 -9.582404)
			(size 0.3048 0.3048)
			(layers "F.Cu" "F.Mask" "F.Paste")
			(net "PU_CPU_NODE1_DFX_GPIO_GRP1_3")
		)
		(pad "H37" smd circle
			(at 1.51638 -9.963404)
			(size 0.3048 0.3048)
			(layers "F.Cu" "F.Mask" "F.Paste")
			(net "TP_CPU_NODE1_RSVD_MVT1")
		)
		(pad "H38" smd circle
			(at 2.216404 -9.963404)
			(size 0.3048 0.3048)
			(layers "F.Cu" "F.Mask" "F.Paste")
			(net "Net_401")
		)
		(pad "H41" smd circle
			(at 3.50266 -9.582404)
			(size 0.3048 0.3048)
			(layers "F.Cu" "F.Mask" "F.Paste")
			(net "LPC_CPU_NODE1_LAD3_R")
		)
		(pad "H42" smd circle
			(at 4.202684 -9.582404)
			(size 0.3048 0.3048)
			(layers "F.Cu" "F.Mask" "F.Paste")
			(net "LPC_CPU_NODE1_LAD2_R")
		)
		(pad "H44" smd circle
			(at 5.48894 -9.963404)
			(size 0.3048 0.3048)
			(layers "F.Cu" "F.Mask" "F.Paste")
			(net "GND")
		)
		(pad "H46" smd circle
			(at 6.188964 -9.963404)
			(size 0.3048 0.3048)
			(layers "F.Cu" "F.Mask" "F.Paste")
			(net "SPC_CPU_NODE1_DCD_L")
		)
		(pad "H48" smd circle
			(at 7.47522 -9.582404)
			(size 0.3048 0.3048)
			(layers "F.Cu" "F.Mask" "F.Paste")
			(net "H_CPU_NODE1_ERR0_R")
		)
		(pad "H50" smd circle
			(at 8.175244 -9.582404)
			(size 0.3048 0.3048)
			(layers "F.Cu" "F.Mask" "F.Paste")
			(net "SPC_CPU_NODE1_RTS_L")
		)
		(pad "H52" smd circle
			(at 9.4615 -9.963404)
			(size 0.3048 0.3048)
			(layers "F.Cu" "F.Mask" "F.Paste")
			(net "CPU_RSV_1_R")
		)
		(pad "H54" smd circle
			(at 10.161524 -9.963404)
			(size 0.3048 0.3048)
			(layers "F.Cu" "F.Mask" "F.Paste")
			(net "SMB_TEMP1_NODE1_ALERT_L")
		)
		(pad "H56" smd circle
			(at 11.44778 -9.582404)
			(size 0.3048 0.3048)
			(layers "F.Cu" "F.Mask" "F.Paste")
			(net "H_CPU_NODE1_ERR1")
		)
		(pad "H58" smd circle
			(at 12.201398 -9.701276)
			(size 0.3048 0.3048)
			(layers "F.Cu" "F.Mask" "F.Paste")
			(net "GND")
		)
		(pad "H59" smd circle
			(at 12.963398 -9.701276)
			(size 0.3048 0.3048)
			(layers "F.Cu" "F.Mask" "F.Paste")
			(net "NODE1_BIOS_MB_REV_ID2")
		)
		(pad "H62" smd circle
			(at 14.063218 -9.62025)
			(size 0.3048 0.3048)
			(layers "F.Cu" "F.Mask" "F.Paste")
			(net "GND")
		)
		(pad "H63" smd circle
			(at 14.751558 -9.78916)
			(size 0.3048 0.3048)
			(layers "F.Cu" "F.Mask" "F.Paste")
			(net "GND")
		)
		(pad "H66" smd oval
			(at 16.110966 -9.859772)
			(size 0.3429 0.2794)
			(layers "F.Cu" "F.Mask" "F.Paste")
			(net "GND")
		)
		(pad "J5" smd circle
			(at -14.063218 -9.412986)
			(size 0.3048 0.3048)
			(layers "F.Cu" "F.Mask" "F.Paste")
			(net "GND")
		)
		(pad "J13" smd circle
			(at -10.4013 -9.201404)
			(size 0.3048 0.3048)
			(layers "F.Cu" "F.Mask" "F.Paste")
			(net "Net_424")
		)
		(pad "J14" smd circle
			(at -9.701276 -9.201404)
			(size 0.3048 0.3048)
			(layers "F.Cu" "F.Mask" "F.Paste")
			(net "PD_NODE1_NTB_CLKINP")
		)
		(pad "J21" smd circle
			(at -6.42874 -9.201404)
			(size 0.3048 0.3048)
			(layers "F.Cu" "F.Mask" "F.Paste")
			(net "Net_410")
		)
		(pad "J22" smd circle
			(at -5.728716 -9.201404)
			(size 0.3048 0.3048)
			(layers "F.Cu" "F.Mask" "F.Paste")
			(net "Net_415")
		)
		(pad "J29" smd circle
			(at -2.45618 -9.201404)
			(size 0.3048 0.3048)
			(layers "F.Cu" "F.Mask" "F.Paste")
			(net "GND")
		)
		(pad "J30" smd circle
			(at -1.756156 -9.201404)
			(size 0.3048 0.3048)
			(layers "F.Cu" "F.Mask" "F.Paste")
			(net "PD_CPU_NODE1_DFX_GPIO_GRP0_7")
		)
		(pad "J37" smd circle
			(at 1.51638 -9.201404)
			(size 0.3048 0.3048)
			(layers "F.Cu" "F.Mask" "F.Paste")
			(net "H_CPU_NODE1_THRM_LS_L")
		)
		(pad "J38" smd circle
			(at 2.216404 -9.201404)
			(size 0.3048 0.3048)
			(layers "F.Cu" "F.Mask" "F.Paste")
			(net "SPI_CPU_NODE1_SCLK_R")
		)
		(pad "J44" smd circle
			(at 5.48894 -9.201404)
			(size 0.3048 0.3048)
			(layers "F.Cu" "F.Mask" "F.Paste")
			(net "SPC_CPU_NODE1_DSR_L")
		)
		(pad "J46" smd circle
			(at 6.188964 -9.201404)
			(size 0.3048 0.3048)
			(layers "F.Cu" "F.Mask" "F.Paste")
			(net "IRQ_CPU_NODE1_SERIAL_R")
		)
		(pad "J52" smd circle
			(at 9.4615 -9.201404)
			(size 0.3048 0.3048)
			(layers "F.Cu" "F.Mask" "F.Paste")
			(net "GND")
		)
		(pad "J54" smd circle
			(at 10.161524 -9.201404)
			(size 0.3048 0.3048)
			(layers "F.Cu" "F.Mask" "F.Paste")
			(net "GND")
		)
		(pad "J63" smd circle
			(at 14.542516 -9.109456)
			(size 0.3048 0.3048)
			(layers "F.Cu" "F.Mask" "F.Paste")
			(net "FM_CPLD_NODE1_SYS_PG")
		)
		(pad "J64" smd circle
			(at 15.304516 -9.058656)
			(size 0.3048 0.3048)
			(layers "F.Cu" "F.Mask" "F.Paste")
			(net "VR_CPU_NODE1_INTVRMEN")
		)
		(pad "J66" smd oval
			(at 16.249396 -9.109456 90)
			(size 0.254 0.3429)
			(layers "F.Cu" "F.Mask" "F.Paste")
			(net "GND")
		)
		(pad "K1" smd oval
			(at -16.249396 -8.902192 270)
			(size 0.254 0.3429)
			(layers "F.Cu" "F.Mask" "F.Paste")
			(net "GND")
		)
		(pad "K3" smd circle
			(at -15.304516 -8.952992)
			(size 0.3048 0.3048)
			(layers "F.Cu" "F.Mask" "F.Paste")
			(net "PD_NODE1_NTB_PERN")
		)
		(pad "K4" smd circle
			(at -14.542516 -8.902192)
			(size 0.3048 0.3048)
			(layers "F.Cu" "F.Mask" "F.Paste")
			(net "PD_NODE1_NTB_PERP")
		)
		(pad "K10" smd circle
			(at -11.687556 -8.820404)
			(size 0.3048 0.3048)
			(layers "F.Cu" "F.Mask" "F.Paste")
			(net "PD_NODE1_NTB_PERP")
		)
		(pad "K17" smd circle
			(at -8.41502 -8.820404)
			(size 0.3048 0.3048)
			(layers "F.Cu" "F.Mask" "F.Paste")
			(net "GND")
		)
		(pad "K18" smd circle
			(at -7.714996 -8.820404)
			(size 0.3048 0.3048)
			(layers "F.Cu" "F.Mask" "F.Paste")
			(net "GND")
		)
		(pad "K25" smd circle
			(at -4.44246 -8.820404)
			(size 0.3048 0.3048)
			(layers "F.Cu" "F.Mask" "F.Paste")
			(net "GND")
		)
		(pad "K26" smd circle
			(at -3.742436 -8.820404)
			(size 0.3048 0.3048)
			(layers "F.Cu" "F.Mask" "F.Paste")
			(net "GND")
		)
		(pad "K32" smd circle
			(at -0.4699 -8.820404)
			(size 0.3048 0.3048)
			(layers "F.Cu" "F.Mask" "F.Paste")
			(net "GND")
		)
		(pad "K34" smd circle
			(at 0.230124 -8.820404)
			(size 0.3048 0.3048)
			(layers "F.Cu" "F.Mask" "F.Paste")
			(net "GND")
		)
		(pad "K41" smd circle
			(at 3.50266 -8.820404)
			(size 0.3048 0.3048)
			(layers "F.Cu" "F.Mask" "F.Paste")
			(net "GND")
		)
		(pad "K42" smd circle
			(at 4.202684 -8.820404)
			(size 0.3048 0.3048)
			(layers "F.Cu" "F.Mask" "F.Paste")
			(net "GND")
		)
		(pad "K48" smd circle
			(at 7.47522 -8.820404)
			(size 0.3048 0.3048)
			(layers "F.Cu" "F.Mask" "F.Paste")
			(net "CPLD_ROW_LATCH")
		)
		(pad "K50" smd circle
			(at 8.175244 -8.820404)
			(size 0.3048 0.3048)
			(layers "F.Cu" "F.Mask" "F.Paste")
			(net "CPLD_ROW_EN")
		)
		(pad "K62" smd circle
			(at 14.063218 -8.598662)
			(size 0.3048 0.3048)
			(layers "F.Cu" "F.Mask" "F.Paste")
			(net "TP_CPU_NODE1_K62")
		)
		(pad "L2" smd circle
			(at -15.805658 -8.142732)
			(size 0.3048 0.3048)
			(layers "F.Cu" "F.Mask" "F.Paste")
			(net "PD_NODE1_NTB_PERN")
		)
		(pad "L4" smd circle
			(at -14.751558 -8.222488)
			(size 0.3048 0.3048)
			(layers "F.Cu" "F.Mask" "F.Paste")
			(net "PD_NODE1_NTB_PERP")
		)
		(pad "L5" smd circle
			(at -14.063218 -8.391398)
			(size 0.3048 0.3048)
			(layers "F.Cu" "F.Mask" "F.Paste")
			(net "GND")
		)
		(pad "L7" smd circle
			(at -13.344398 -8.175244)
			(size 0.3048 0.3048)
			(layers "F.Cu" "F.Mask" "F.Paste")
			(net "GND")
		)
		(pad "L8" smd circle
			(at -12.582398 -8.175244)
			(size 0.3048 0.3048)
			(layers "F.Cu" "F.Mask" "F.Paste")
			(net "GND")
		)
		(pad "L13" smd circle
			(at -10.4013 -8.439404)
			(size 0.3048 0.3048)
			(layers "F.Cu" "F.Mask" "F.Paste")
			(net "GND")
		)
		(pad "L14" smd circle
			(at -9.701276 -8.439404)
			(size 0.3048 0.3048)
			(layers "F.Cu" "F.Mask" "F.Paste")
			(net "GND")
		)
		(pad "L17" smd circle
			(at -8.41502 -8.058404)
			(size 0.3048 0.3048)
			(layers "F.Cu" "F.Mask" "F.Paste")
			(net "Net_425")
		)
		(pad "L18" smd circle
			(at -7.714996 -8.058404)
			(size 0.3048 0.3048)
			(layers "F.Cu" "F.Mask" "F.Paste")
			(net "Net_420")
		)
		(pad "L21" smd circle
			(at -6.42874 -8.439404)
			(size 0.3048 0.3048)
			(layers "F.Cu" "F.Mask" "F.Paste")
			(net "Net_414")
		)
		(pad "L22" smd circle
			(at -5.728716 -8.439404)
			(size 0.3048 0.3048)
			(layers "F.Cu" "F.Mask" "F.Paste")
			(net "Net_435")
		)
		(pad "L25" smd circle
			(at -4.44246 -8.058404)
			(size 0.3048 0.3048)
			(layers "F.Cu" "F.Mask" "F.Paste")
			(net "Net_432")
		)
		(pad "L26" smd circle
			(at -3.742436 -8.058404)
			(size 0.3048 0.3048)
			(layers "F.Cu" "F.Mask" "F.Paste")
			(net "Net_434")
		)
		(pad "L29" smd circle
			(at -2.45618 -8.439404)
			(size 0.3048 0.3048)
			(layers "F.Cu" "F.Mask" "F.Paste")
			(net "GND")
		)
		(pad "L30" smd circle
			(at -1.756156 -8.439404)
			(size 0.3048 0.3048)
			(layers "F.Cu" "F.Mask" "F.Paste")
			(net "GND")
		)
		(pad "L32" smd circle
			(at -0.4699 -8.058404)
			(size 0.3048 0.3048)
			(layers "F.Cu" "F.Mask" "F.Paste")
			(net "P1V8_NODE1")
		)
		(pad "L34" smd circle
			(at 0.230124 -8.058404)
			(size 0.3048 0.3048)
			(layers "F.Cu" "F.Mask" "F.Paste")
			(net "GND")
		)
		(pad "L37" smd circle
			(at 1.51638 -8.439404)
			(size 0.3048 0.3048)
			(layers "F.Cu" "F.Mask" "F.Paste")
			(net "GND")
		)
		(pad "L38" smd circle
			(at 2.216404 -8.439404)
			(size 0.3048 0.3048)
			(layers "F.Cu" "F.Mask" "F.Paste")
			(net "GND")
		)
		(pad "L41" smd circle
			(at 3.50266 -8.058404)
			(size 0.3048 0.3048)
			(layers "F.Cu" "F.Mask" "F.Paste")
			(net "P1V8_SUS_NODE1")
		)
		(pad "L42" smd circle
			(at 4.202684 -8.058404)
			(size 0.3048 0.3048)
			(layers "F.Cu" "F.Mask" "F.Paste")
			(net "P3V3_SUS_NODE1")
		)
		(pad "L44" smd circle
			(at 5.48894 -8.439404)
			(size 0.3048 0.3048)
			(layers "F.Cu" "F.Mask" "F.Paste")
			(net "GND")
		)
		(pad "L46" smd circle
			(at 6.188964 -8.439404)
			(size 0.3048 0.3048)
			(layers "F.Cu" "F.Mask" "F.Paste")
			(net "GND")
		)
		(pad "L48" smd circle
			(at 7.47522 -8.058404)
			(size 0.3048 0.3048)
			(layers "F.Cu" "F.Mask" "F.Paste")
			(net "GND")
		)
		(pad "L50" smd circle
			(at 8.175244 -8.058404)
			(size 0.3048 0.3048)
			(layers "F.Cu" "F.Mask" "F.Paste")
			(net "GND")
		)
		(pad "L52" smd circle
			(at 9.4615 -8.439404)
			(size 0.3048 0.3048)
			(layers "F.Cu" "F.Mask" "F.Paste")
			(net "NODE1_BIOS_MB_REV_ID1")
		)
		(pad "L54" smd circle
			(at 10.161524 -8.439404)
			(size 0.3048 0.3048)
			(layers "F.Cu" "F.Mask" "F.Paste")
			(net "H_CPU_NODE1_ERR2")
		)
		(pad "L57" smd circle
			(at 11.820398 -8.41502)
			(size 0.3048 0.3048)
			(layers "F.Cu" "F.Mask" "F.Paste")
			(net "GND")
		)
		(pad "L59" smd circle
			(at 12.582398 -8.41502)
			(size 0.3048 0.3048)
			(layers "F.Cu" "F.Mask" "F.Paste")
			(net "VR_NODE1_VDDR_1V5_CNTL")
		)
		(pad "L60" smd circle
			(at 13.344398 -8.41502)
			(size 0.3048 0.3048)
			(layers "F.Cu" "F.Mask" "F.Paste")
			(net "SPI_CPU_NODE1_WP_R_L")
		)
		(pad "L63" smd circle
			(at 14.794738 -8.440928)
			(size 0.3048 0.3048)
			(layers "F.Cu" "F.Mask" "F.Paste")
			(net "FM_CPLD_NODE1_CPU_RSMRST_L")
		)
		(pad "L65" smd circle
			(at 15.752318 -8.388096)
			(size 0.3048 0.3048)
			(layers "F.Cu" "F.Mask" "F.Paste")
			(net "A_CPU_NODE1_RTC_EXTPAD")
		)
		(pad "M3" smd circle
			(at -15.247112 -7.719314)
			(size 0.3048 0.3048)
			(layers "F.Cu" "F.Mask" "F.Paste")
			(net "GND")
		)
		(pad "M5" smd circle
			(at -14.013688 -7.689088)
			(size 0.3048 0.3048)
			(layers "F.Cu" "F.Mask" "F.Paste")
			(net "GND")
		)
		(pad "M21" smd circle
			(at -6.42874 -7.677404)
			(size 0.3048 0.3048)
			(layers "F.Cu" "F.Mask" "F.Paste")
			(net "GND")
		)
		(pad "M22" smd circle
			(at -5.728716 -7.677404)
			(size 0.3048 0.3048)
			(layers "F.Cu" "F.Mask" "F.Paste")
			(net "GND")
		)
		(pad "M29" smd circle
			(at -2.45618 -7.677404)
			(size 0.3048 0.3048)
			(layers "F.Cu" "F.Mask" "F.Paste")
			(net "GND")
		)
		(pad "M30" smd circle
			(at -1.756156 -7.677404)
			(size 0.3048 0.3048)
			(layers "F.Cu" "F.Mask" "F.Paste")
			(net "GND")
		)
		(pad "M37" smd circle
			(at 1.51638 -7.677404)
			(size 0.3048 0.3048)
			(layers "F.Cu" "F.Mask" "F.Paste")
			(net "P3V3_NODE1")
		)
		(pad "M38" smd circle
			(at 2.216404 -7.677404)
			(size 0.3048 0.3048)
			(layers "F.Cu" "F.Mask" "F.Paste")
			(net "A_CPU_NODE1_HV_GPIO_RCOMP")
		)
		(pad "M44" smd circle
			(at 5.48894 -7.677404)
			(size 0.3048 0.3048)
			(layers "F.Cu" "F.Mask" "F.Paste")
			(net "P3V3_RTC_NODE1")
		)
		(pad "M46" smd circle
			(at 6.188964 -7.677404)
			(size 0.3048 0.3048)
			(layers "F.Cu" "F.Mask" "F.Paste")
			(net "PD_CPU_NODE1_BRD_ID1")
		)
		(pad "M52" smd circle
			(at 9.4615 -7.677404)
			(size 0.3048 0.3048)
			(layers "F.Cu" "F.Mask" "F.Paste")
			(net "TP_CPU_NODE1_M52")
		)
		(pad "M54" smd circle
			(at 10.296398 -7.714996 270)
			(size 0.3048 0.3048)
			(layers "F.Cu" "F.Mask" "F.Paste")
			(net "FM_CPU_NODE1_RSTRDY_L")
		)
		(pad "M56" smd circle
			(at 11.058398 -7.714996)
			(size 0.3048 0.3048)
			(layers "F.Cu" "F.Mask" "F.Paste")
			(net "FM_CPLD_NODE1_PWR_BTN_CPU")
		)
		(pad "M57" smd circle
			(at 11.820398 -7.714996)
			(size 0.3048 0.3048)
			(layers "F.Cu" "F.Mask" "F.Paste")
			(net "GND")
		)
		(pad "M59" smd circle
			(at 12.582398 -7.714996)
			(size 0.3048 0.3048)
			(layers "F.Cu" "F.Mask" "F.Paste")
			(net "Net_298")
		)
		(pad "M60" smd circle
			(at 13.344398 -7.714996)
			(size 0.3048 0.3048)
			(layers "F.Cu" "F.Mask" "F.Paste")
			(net "SMB_BMC_NODE1_HSC_ALERT_L")
		)
		(pad "M62" smd circle
			(at 14.08049 -7.891272)
			(size 0.3048 0.3048)
			(layers "F.Cu" "F.Mask" "F.Paste")
			(net "GND")
		)
		(pad "M64" smd circle
			(at 15.242794 -7.901178)
			(size 0.3048 0.3048)
			(layers "F.Cu" "F.Mask" "F.Paste")
			(net "GND")
		)
		(pad "M66" smd oval
			(at 16.249396 -7.6708 90)
			(size 0.254 0.3429)
			(layers "F.Cu" "F.Mask" "F.Paste")
			(net "GND")
		)
		(pad "N1" smd oval
			(at -16.249396 -7.463536 270)
			(size 0.254 0.3429)
			(layers "F.Cu" "F.Mask" "F.Paste")
			(net "GND")
		)
		(pad "N2" smd circle
			(at -15.640812 -7.114032)
			(size 0.3048 0.3048)
			(layers "F.Cu" "F.Mask" "F.Paste")
			(net "PD_CPU_NODE1_RP2_PERN")
		)
		(pad "N4" smd circle
			(at -14.90091 -7.107936)
			(size 0.3048 0.3048)
			(layers "F.Cu" "F.Mask" "F.Paste")
			(net "PD_CPU_NODE1_RP2_PERP")
		)
		(pad "N5" smd circle
			(at -14.204442 -7.010908)
			(size 0.3048 0.3048)
			(layers "F.Cu" "F.Mask" "F.Paste")
			(net "PD_CPU_NODE1_RP2_PERP")
		)
		(pad "N7" smd circle
			(at -13.344398 -7.47522)
			(size 0.3048 0.3048)
			(layers "F.Cu" "F.Mask" "F.Paste")
			(net "GND")
		)
		(pad "N8" smd circle
			(at -12.582398 -7.47522)
			(size 0.3048 0.3048)
			(layers "F.Cu" "F.Mask" "F.Paste")
			(net "Net_431")
		)
		(pad "N10" smd circle
			(at -11.820398 -7.47522)
			(size 0.3048 0.3048)
			(layers "F.Cu" "F.Mask" "F.Paste")
			(net "Net_428")
		)
		(pad "N11" smd circle
			(at -11.058398 -7.47522)
			(size 0.3048 0.3048)
			(layers "F.Cu" "F.Mask" "F.Paste")
			(net "GND")
		)
		(pad "N13" smd circle
			(at -10.296398 -7.47522)
			(size 0.3048 0.3048)
			(layers "F.Cu" "F.Mask" "F.Paste")
			(net "Net_417")
		)
		(pad "N14" smd circle
			(at -9.534398 -7.47522)
			(size 0.3048 0.3048)
			(layers "F.Cu" "F.Mask" "F.Paste")
			(net "Net_416")
		)
		(pad "N17" smd circle
			(at -8.41502 -7.296404)
			(size 0.3048 0.3048)
			(layers "F.Cu" "F.Mask" "F.Paste")
			(net "Net_422")
		)
		(pad "N18" smd circle
			(at -7.714996 -7.296404)
			(size 0.3048 0.3048)
			(layers "F.Cu" "F.Mask" "F.Paste")
			(net "Net_427")
		)
		(pad "N25" smd circle
			(at -4.44246 -7.296404)
			(size 0.3048 0.3048)
			(layers "F.Cu" "F.Mask" "F.Paste")
			(net "Net_430")
		)
		(pad "N26" smd circle
			(at -3.742436 -7.296404)
			(size 0.3048 0.3048)
			(layers "F.Cu" "F.Mask" "F.Paste")
			(net "Net_426")
		)
		(pad "N32" smd circle
			(at -0.4699 -7.296404)
			(size 0.3048 0.3048)
			(layers "F.Cu" "F.Mask" "F.Paste")
			(net "P1V8_NODE1")
		)
		(pad "N34" smd circle
			(at 0.230124 -7.296404)
			(size 0.3048 0.3048)
			(layers "F.Cu" "F.Mask" "F.Paste")
			(net "GND")
		)
		(pad "N41" smd circle
			(at 3.50266 -7.296404)
			(size 0.3048 0.3048)
			(layers "F.Cu" "F.Mask" "F.Paste")
			(net "P1V8_SUS_NODE1")
		)
		(pad "N42" smd circle
			(at 4.202684 -7.296404)
			(size 0.3048 0.3048)
			(layers "F.Cu" "F.Mask" "F.Paste")
			(net "P3V3_SUS_NODE1")
		)
		(pad "N48" smd circle
			(at 7.47522 -7.296404)
			(size 0.3048 0.3048)
			(layers "F.Cu" "F.Mask" "F.Paste")
			(net "NODE1_BIOS_MB_REV_ID0")
		)
		(pad "N50" smd circle
			(at 8.175244 -7.296404)
			(size 0.3048 0.3048)
			(layers "F.Cu" "F.Mask" "F.Paste")
			(net "Net_296")
		)
		(pad "N62" smd circle
			(at 14.204442 -7.197852)
			(size 0.3048 0.3048)
			(layers "F.Cu" "F.Mask" "F.Paste")
			(net "RST_CPU_NODE1_SRTCRST_L")
		)
		(pad "N63" smd circle
			(at 14.90091 -7.2898)
			(size 0.3048 0.3048)
			(layers "F.Cu" "F.Mask" "F.Paste")
			(net "GND")
		)
		(pad "N65" smd circle
			(at 15.639034 -7.321296)
			(size 0.3048 0.3048)
			(layers "F.Cu" "F.Mask" "F.Paste")
			(net "XTAL_CPU_NODE1_X2PAD")
		)
		(pad "P17" smd circle
			(at -8.41502 -6.534404)
			(size 0.3048 0.3048)
			(layers "F.Cu" "F.Mask" "F.Paste")
			(net "GND")
		)
		(pad "P18" smd circle
			(at -7.714996 -6.534404)
			(size 0.3048 0.3048)
			(layers "F.Cu" "F.Mask" "F.Paste")
			(net "GND")
		)
		(pad "P21" smd circle
			(at -6.42874 -6.915404)
			(size 0.3048 0.3048)
			(layers "F.Cu" "F.Mask" "F.Paste")
			(net "A_SOC_NODE1_THERMDC")
		)
		(pad "P22" smd circle
			(at -5.728716 -6.915404)
			(size 0.3048 0.3048)
			(layers "F.Cu" "F.Mask" "F.Paste")
			(net "TP_CPU_NODE1_SOC_THERMATP1")
		)
		(pad "P25" smd circle
			(at -4.44246 -6.534404)
			(size 0.3048 0.3048)
			(layers "F.Cu" "F.Mask" "F.Paste")
			(net "GND")
		)
		(pad "P26" smd circle
			(at -3.742436 -6.534404)
			(size 0.3048 0.3048)
			(layers "F.Cu" "F.Mask" "F.Paste")
			(net "GND")
		)
		(pad "P29" smd circle
			(at -2.45618 -6.915404)
			(size 0.3048 0.3048)
			(layers "F.Cu" "F.Mask" "F.Paste")
			(net "GND")
		)
		(pad "P30" smd circle
			(at -1.756156 -6.915404)
			(size 0.3048 0.3048)
			(layers "F.Cu" "F.Mask" "F.Paste")
			(net "GND")
		)
		(pad "P32" smd circle
			(at -0.4699 -6.534404)
			(size 0.3048 0.3048)
			(layers "F.Cu" "F.Mask" "F.Paste")
			(net "P1V8_NODE1")
		)
		(pad "P34" smd circle
			(at 0.230124 -6.534404)
			(size 0.3048 0.3048)
			(layers "F.Cu" "F.Mask" "F.Paste")
			(net "A_CPU_NODE1_MV_GPIO_RCOMP")
		)
		(pad "P37" smd circle
			(at 1.51638 -6.915404)
			(size 0.3048 0.3048)
			(layers "F.Cu" "F.Mask" "F.Paste")
			(net "P3V3_NODE1")
		)
		(pad "P38" smd circle
			(at 2.216404 -6.915404)
			(size 0.3048 0.3048)
			(layers "F.Cu" "F.Mask" "F.Paste")
			(net "GND")
		)
		(pad "P41" smd circle
			(at 3.50266 -6.534404)
			(size 0.3048 0.3048)
			(layers "F.Cu" "F.Mask" "F.Paste")
			(net "P1V8_SUS_NODE1")
		)
		(pad "P42" smd circle
			(at 4.202684 -6.534404)
			(size 0.3048 0.3048)
			(layers "F.Cu" "F.Mask" "F.Paste")
			(net "P3V3_SUS_NODE1")
		)
		(pad "P44" smd circle
			(at 5.48894 -6.915404)
			(size 0.3048 0.3048)
			(layers "F.Cu" "F.Mask" "F.Paste")
			(net "P3V3_RTC_NODE1")
		)
		(pad "P46" smd circle
			(at 6.188964 -6.915404)
			(size 0.3048 0.3048)
			(layers "F.Cu" "F.Mask" "F.Paste")
			(net "CLK_14M_CPU_NODE1")
		)
		(pad "P48" smd circle
			(at 7.47522 -6.534404)
			(size 0.3048 0.3048)
			(layers "F.Cu" "F.Mask" "F.Paste")
			(net "P1V05_SUS_NODE1")
		)
		(pad "P50" smd circle
			(at 8.175244 -6.534404)
			(size 0.3048 0.3048)
			(layers "F.Cu" "F.Mask" "F.Paste")
			(net "CONSOLE_SELECT_N")
		)
		(pad "R2" smd circle
			(at -15.639034 -6.18744)
			(size 0.3048 0.3048)
			(layers "F.Cu" "F.Mask" "F.Paste")
			(net "PD_CPU_NODE1_RP2_PERN")
		)
		(pad "R4" smd circle
			(at -14.90091 -6.218936)
			(size 0.3048 0.3048)
			(layers "F.Cu" "F.Mask" "F.Paste")
			(net "PD_CPU_NODE1_RP2_PERP")
		)
		(pad "R5" smd circle
			(at -14.204442 -6.310884)
			(size 0.3048 0.3048)
			(layers "F.Cu" "F.Mask" "F.Paste")
			(net "PD_CPU_NODE1_RP2_PERN")
		)
		(pad "R8" smd circle
			(at -12.963398 -6.188964)
			(size 0.3048 0.3048)
			(layers "F.Cu" "F.Mask" "F.Paste")
			(net "GND")
		)
		(pad "R9" smd circle
			(at -12.201398 -6.188964)
			(size 0.3048 0.3048)
			(layers "F.Cu" "F.Mask" "F.Paste")
			(net "Net_411")
		)
		(pad "R11" smd circle
			(at -11.439398 -6.188964)
			(size 0.3048 0.3048)
			(layers "F.Cu" "F.Mask" "F.Paste")
			(net "Net_409")
		)
		(pad "R12" smd circle
			(at -10.677398 -6.188964)
			(size 0.3048 0.3048)
			(layers "F.Cu" "F.Mask" "F.Paste")
			(net "GND")
		)
		(pad "R14" smd circle
			(at -9.915398 -6.188964)
			(size 0.3048 0.3048)
			(layers "F.Cu" "F.Mask" "F.Paste")
			(net "Net_413")
		)
		(pad "R15" smd circle
			(at -9.153398 -6.188964)
			(size 0.3048 0.3048)
			(layers "F.Cu" "F.Mask" "F.Paste")
			(net "Net_412")
		)
		(pad "R21" smd circle
			(at -6.42874 -6.153404)
			(size 0.3048 0.3048)
			(layers "F.Cu" "F.Mask" "F.Paste")
			(net "A_SOC_NODE1_THERMDA")
		)
		(pad "R22" smd circle
			(at -5.728716 -6.153404)
			(size 0.3048 0.3048)
			(layers "F.Cu" "F.Mask" "F.Paste")
			(net "A_CPU_NODE1_SOC_THERMREFNPAD")
		)
		(pad "R29" smd circle
			(at -2.45618 -6.153404)
			(size 0.3048 0.3048)
			(layers "F.Cu" "F.Mask" "F.Paste")
			(net "GND")
		)
		(pad "R30" smd circle
			(at -1.756156 -6.153404)
			(size 0.3048 0.3048)
			(layers "F.Cu" "F.Mask" "F.Paste")
			(net "GND")
		)
		(pad "R37" smd circle
			(at 1.51638 -6.153404)
			(size 0.3048 0.3048)
			(layers "F.Cu" "F.Mask" "F.Paste")
			(net "P3V3_NODE1")
		)
		(pad "R38" smd circle
			(at 2.216404 -6.153404)
			(size 0.3048 0.3048)
			(layers "F.Cu" "F.Mask" "F.Paste")
			(net "GND")
		)
		(pad "R44" smd circle
			(at 5.48894 -6.153404)
			(size 0.3048 0.3048)
			(layers "F.Cu" "F.Mask" "F.Paste")
			(net "P3V3_RTC_NODE1")
		)
		(pad "R46" smd circle
			(at 6.188964 -6.153404)
			(size 0.3048 0.3048)
			(layers "F.Cu" "F.Mask" "F.Paste")
			(net "GND")
		)
		(pad "R52" smd circle
			(at 9.153398 -6.42874)
			(size 0.3048 0.3048)
			(layers "F.Cu" "F.Mask" "F.Paste")
			(net "GND")
		)
		(pad "R53" smd circle
			(at 9.915398 -6.42874)
			(size 0.3048 0.3048)
			(layers "F.Cu" "F.Mask" "F.Paste")
			(net "GND")
		)
		(pad "R55" smd circle
			(at 10.677398 -6.42874)
			(size 0.3048 0.3048)
			(layers "F.Cu" "F.Mask" "F.Paste")
			(net "GND")
		)
		(pad "R56" smd circle
			(at 11.439398 -6.42874)
			(size 0.3048 0.3048)
			(layers "F.Cu" "F.Mask" "F.Paste")
			(net "FM_CPU_NODE1_SLPMODE")
		)
		(pad "R58" smd circle
			(at 12.201398 -6.42874)
			(size 0.3048 0.3048)
			(layers "F.Cu" "F.Mask" "F.Paste")
			(net "FM_CPU_NODE1_SLPRDY_L")
		)
		(pad "R59" smd circle
			(at 12.963398 -6.42874)
			(size 0.3048 0.3048)
			(layers "F.Cu" "F.Mask" "F.Paste")
			(net "GND")
		)
		(pad "R62" smd circle
			(at 14.204442 -6.497828)
			(size 0.3048 0.3048)
			(layers "F.Cu" "F.Mask" "F.Paste")
			(net "N32265582")
		)
		(pad "R63" smd circle
			(at 14.90091 -6.4008)
			(size 0.3048 0.3048)
			(layers "F.Cu" "F.Mask" "F.Paste")
			(net "LPC_CPU_NODE1_CLK0_DS")
		)
		(pad "R65" smd circle
			(at 15.640812 -6.394704)
			(size 0.3048 0.3048)
			(layers "F.Cu" "F.Mask" "F.Paste")
			(net "XTAL_CPU_NODE1_X1PAD")
		)
		(pad "R66" smd oval
			(at 16.249396 -6.0452 90)
			(size 0.254 0.3429)
			(layers "F.Cu" "F.Mask" "F.Paste")
			(net "GND")
		)
		(pad "T1" smd oval
			(at -16.249396 -5.837936 270)
			(size 0.254 0.3429)
			(layers "F.Cu" "F.Mask" "F.Paste")
			(net "GND")
		)
		(pad "T3" smd circle
			(at -15.242794 -5.607558)
			(size 0.3048 0.3048)
			(layers "F.Cu" "F.Mask" "F.Paste")
			(net "GND")
		)
		(pad "T5" smd circle
			(at -14.08049 -5.617464)
			(size 0.3048 0.3048)
			(layers "F.Cu" "F.Mask" "F.Paste")
			(net "GND")
		)
		(pad "T17" smd circle
			(at -8.41502 -5.772404)
			(size 0.3048 0.3048)
			(layers "F.Cu" "F.Mask" "F.Paste")
			(net "GND")
		)
		(pad "T18" smd circle
			(at -7.714996 -5.772404)
			(size 0.3048 0.3048)
			(layers "F.Cu" "F.Mask" "F.Paste")
			(net "TP_CPU_NODE1_SOC_THERMATP0")
		)
		(pad "T20" smd circle
			(at -6.700774 -5.500624)
			(size 0.3048 0.3048)
			(layers "F.Cu" "F.Mask" "F.Paste")
			(net "GND")
		)
		(pad "T21" smd circle
			(at -6.00075 -5.500624)
			(size 0.3048 0.3048)
			(layers "F.Cu" "F.Mask" "F.Paste")
			(net "GND")
		)
		(pad "T23" smd circle
			(at -5.20065 -5.500624)
			(size 0.3048 0.3048)
			(layers "F.Cu" "F.Mask" "F.Paste")
			(net "GND")
		)
		(pad "T25" smd circle
			(at -4.44246 -5.772404)
			(size 0.3048 0.3048)
			(layers "F.Cu" "F.Mask" "F.Paste")
			(net "GND")
		)
		(pad "T26" smd circle
			(at -3.742436 -5.772404)
			(size 0.3048 0.3048)
			(layers "F.Cu" "F.Mask" "F.Paste")
			(net "GND")
		)
		(pad "T28" smd circle
			(at -2.80035 -5.500624)
			(size 0.3048 0.3048)
			(layers "F.Cu" "F.Mask" "F.Paste")
			(net "GND")
		)
		(pad "T29" smd circle
			(at -2.100326 -5.500624)
			(size 0.3048 0.3048)
			(layers "F.Cu" "F.Mask" "F.Paste")
			(net "GND")
		)
		(pad "T31" smd circle
			(at -1.20015 -5.500624)
			(size 0.3048 0.3048)
			(layers "F.Cu" "F.Mask" "F.Paste")
			(net "GND")
		)
		(pad "T32" smd circle
			(at -0.4699 -5.772404)
			(size 0.3048 0.3048)
			(layers "F.Cu" "F.Mask" "F.Paste")
			(net "P1V8_NODE1")
		)
		(pad "T34" smd circle
			(at 0.230124 -5.772404)
			(size 0.3048 0.3048)
			(layers "F.Cu" "F.Mask" "F.Paste")
			(net "GND")
		)
		(pad "T36" smd circle
			(at 1.20015 -5.500624)
			(size 0.3048 0.3048)
			(layers "F.Cu" "F.Mask" "F.Paste")
			(net "P3V3_NODE1")
		)
		(pad "T37" smd circle
			(at 1.900174 -5.500624)
			(size 0.3048 0.3048)
			(layers "F.Cu" "F.Mask" "F.Paste")
			(net "GND")
		)
		(pad "T39" smd circle
			(at 2.80035 -5.500624)
			(size 0.3048 0.3048)
			(layers "F.Cu" "F.Mask" "F.Paste")
			(net "GND")
		)
		(pad "T41" smd circle
			(at 3.50266 -5.772404)
			(size 0.3048 0.3048)
			(layers "F.Cu" "F.Mask" "F.Paste")
			(net "GND")
		)
		(pad "T42" smd circle
			(at 4.202684 -5.772404)
			(size 0.3048 0.3048)
			(layers "F.Cu" "F.Mask" "F.Paste")
			(net "P3V3_SUS_NODE1")
		)
		(pad "T44" smd circle
			(at 5.20065 -5.500624)
			(size 0.3048 0.3048)
			(layers "F.Cu" "F.Mask" "F.Paste")
			(net "P3V3_RTC_NODE1")
		)
		(pad "T45" smd circle
			(at 5.900674 -5.500624)
			(size 0.3048 0.3048)
			(layers "F.Cu" "F.Mask" "F.Paste")
			(net "GND")
		)
		(pad "T47" smd circle
			(at 6.80085 -5.500624)
			(size 0.3048 0.3048)
			(layers "F.Cu" "F.Mask" "F.Paste")
			(net "P1V05_SUS_NODE1")
		)
		(pad "T48" smd circle
			(at 7.47522 -5.772404)
			(size 0.3048 0.3048)
			(layers "F.Cu" "F.Mask" "F.Paste")
			(net "P1V05_SUS_NODE1")
		)
		(pad "T50" smd circle
			(at 8.175244 -5.772404)
			(size 0.3048 0.3048)
			(layers "F.Cu" "F.Mask" "F.Paste")
			(net "GND")
		)
		(pad "T52" smd circle
			(at 9.153398 -5.728716)
			(size 0.3048 0.3048)
			(layers "F.Cu" "F.Mask" "F.Paste")
			(net "CLK_33K_CPU_NODE1_SUSCLK_RR")
		)
		(pad "T53" smd circle
			(at 9.915398 -5.728716)
			(size 0.3048 0.3048)
			(layers "F.Cu" "F.Mask" "F.Paste")
			(net "FM_CPU_NODE1_RSTWARN")
		)
		(pad "T55" smd circle
			(at 10.677398 -5.728716)
			(size 0.3048 0.3048)
			(layers "F.Cu" "F.Mask" "F.Paste")
			(net "GND")
		)
		(pad "T56" smd circle
			(at 11.439398 -5.728716)
			(size 0.3048 0.3048)
			(layers "F.Cu" "F.Mask" "F.Paste")
			(net "IRQ_LVC3_CPU_NODE1_WAKE_L")
		)
		(pad "T58" smd circle
			(at 12.201398 -5.728716)
			(size 0.3048 0.3048)
			(layers "F.Cu" "F.Mask" "F.Paste")
			(net "FM_CPLD_NODE1_CPU_RESET_L")
		)
		(pad "T59" smd circle
			(at 12.963398 -5.728716)
			(size 0.3048 0.3048)
			(layers "F.Cu" "F.Mask" "F.Paste")
			(net "GND")
		)
		(pad "T62" smd circle
			(at 14.013688 -5.819648)
			(size 0.3048 0.3048)
			(layers "F.Cu" "F.Mask" "F.Paste")
			(net "GND")
		)
		(pad "T64" smd circle
			(at 15.247112 -5.789422)
			(size 0.3048 0.3048)
			(layers "F.Cu" "F.Mask" "F.Paste")
			(net "GND")
		)
		(pad "U2" smd circle
			(at -15.752318 -5.12064)
			(size 0.3048 0.3048)
			(layers "F.Cu" "F.Mask" "F.Paste")
			(net "PD_CPU_NODE1_RP2_PERN")
		)
		(pad "U4" smd circle
			(at -14.794738 -5.067808)
			(size 0.3048 0.3048)
			(layers "F.Cu" "F.Mask" "F.Paste")
			(net "PD_CPU_NODE1_RP2_PERP")
		)
		(pad "U8" smd circle
			(at -12.963398 -5.48894)
			(size 0.3048 0.3048)
			(layers "F.Cu" "F.Mask" "F.Paste")
			(net "GND")
		)
		(pad "U9" smd circle
			(at -12.201398 -5.48894)
			(size 0.3048 0.3048)
			(layers "F.Cu" "F.Mask" "F.Paste")
			(net "Net_408")
		)
		(pad "U11" smd circle
			(at -11.439398 -5.48894)
			(size 0.3048 0.3048)
			(layers "F.Cu" "F.Mask" "F.Paste")
			(net "Net_407")
		)
		(pad "U12" smd circle
			(at -10.677398 -5.48894)
			(size 0.3048 0.3048)
			(layers "F.Cu" "F.Mask" "F.Paste")
			(net "GND")
		)
		(pad "U14" smd circle
			(at -9.915398 -5.48894)
			(size 0.3048 0.3048)
			(layers "F.Cu" "F.Mask" "F.Paste")
			(net "Net_404")
		)
		(pad "U15" smd circle
			(at -9.153398 -5.48894)
			(size 0.3048 0.3048)
			(layers "F.Cu" "F.Mask" "F.Paste")
			(net "Net_402")
		)
		(pad "U62" smd circle
			(at 14.063218 -5.117338)
			(size 0.3048 0.3048)
			(layers "F.Cu" "F.Mask" "F.Paste")
			(net "PV_VCCP_NODE1")
		)
		(pad "U63" smd circle
			(at 14.751558 -5.286248)
			(size 0.3048 0.3048)
			(layers "F.Cu" "F.Mask" "F.Paste")
			(net "PV_VCCP_NODE1")
		)
		(pad "U65" smd circle
			(at 15.805658 -5.366004)
			(size 0.3048 0.3048)
			(layers "F.Cu" "F.Mask" "F.Paste")
			(net "PV_VCCP_NODE1")
		)
		(pad "V5" smd circle
			(at -14.063218 -4.910074)
			(size 0.3048 0.3048)
			(layers "F.Cu" "F.Mask" "F.Paste")
			(net "PD_CPU_NODE1_RP2_PERP")
		)
		(pad "V20" smd circle
			(at -6.726174 -4.8006 180)
			(size 0.3048 0.3048)
			(layers "F.Cu" "F.Mask" "F.Paste")
			(net "CLK_100M_CPU_NODE1_DN")
		)
		(pad "V21" smd circle
			(at -6.00075 -4.8006)
			(size 0.381 0.381)
			(layers "F.Cu" "F.Mask" "F.Paste")
			(net "CLK_100M_CPU_NODE1_DP")
		)
		(pad "V23" smd circle
			(at -5.20065 -4.8006)
			(size 0.381 0.381)
			(layers "F.Cu" "F.Mask" "F.Paste")
			(net "GND")
		)
		(pad "V25" smd circle
			(at -4.40055 -4.8006)
			(size 0.381 0.381)
			(layers "F.Cu" "F.Mask" "F.Paste")
			(net "GND")
		)
		(pad "V26" smd circle
			(at -3.60045 -4.8006)
			(size 0.381 0.381)
			(layers "F.Cu" "F.Mask" "F.Paste")
			(net "GND")
		)
		(pad "V28" smd circle
			(at -2.80035 -4.8006)
			(size 0.381 0.381)
			(layers "F.Cu" "F.Mask" "F.Paste")
			(net "GND")
		)
		(pad "V29" smd circle
			(at -2.00025 -4.8006)
			(size 0.381 0.381)
			(layers "F.Cu" "F.Mask" "F.Paste")
			(net "GND")
		)
		(pad "V31" smd circle
			(at -1.20015 -4.8006)
			(size 0.381 0.381)
			(layers "F.Cu" "F.Mask" "F.Paste")
			(net "GND")
		)
		(pad "V32" smd circle
			(at -0.40005 -4.8006)
			(size 0.381 0.381)
			(layers "F.Cu" "F.Mask" "F.Paste")
			(net "P1V8_NODE1")
		)
		(pad "V34" smd circle
			(at 0.40005 -4.8006)
			(size 0.381 0.381)
			(layers "F.Cu" "F.Mask" "F.Paste")
			(net "GND")
		)
		(pad "V36" smd circle
			(at 1.20015 -4.8006)
			(size 0.381 0.381)
			(layers "F.Cu" "F.Mask" "F.Paste")
			(net "P3V3_NODE1")
		)
		(pad "V38" smd circle
			(at 2.00025 -4.8006)
			(size 0.381 0.381)
			(layers "F.Cu" "F.Mask" "F.Paste")
			(net "GND")
		)
		(pad "V39" smd circle
			(at 2.80035 -4.8006)
			(size 0.381 0.381)
			(layers "F.Cu" "F.Mask" "F.Paste")
			(net "GND")
		)
		(pad "V41" smd circle
			(at 3.60045 -4.8006)
			(size 0.381 0.381)
			(layers "F.Cu" "F.Mask" "F.Paste")
			(net "GND")
		)
		(pad "V42" smd circle
			(at 4.40055 -4.8006)
			(size 0.381 0.381)
			(layers "F.Cu" "F.Mask" "F.Paste")
			(net "GND")
		)
		(pad "V44" smd circle
			(at 5.20065 -4.8006)
			(size 0.381 0.381)
			(layers "F.Cu" "F.Mask" "F.Paste")
			(net "GND")
		)
		(pad "V46" smd circle
			(at 6.00075 -4.8006)
			(size 0.381 0.381)
			(layers "F.Cu" "F.Mask" "F.Paste")
			(net "GND")
		)
		(pad "V63" smd circle
			(at 14.542516 -4.606544)
			(size 0.3048 0.3048)
			(layers "F.Cu" "F.Mask" "F.Paste")
			(net "PV_VCCP_NODE1")
		)
		(pad "V64" smd circle
			(at 15.304516 -4.555744)
			(size 0.3048 0.3048)
			(layers "F.Cu" "F.Mask" "F.Paste")
			(net "PV_VCCP_NODE1")
		)
		(pad "V66" smd oval
			(at 16.249396 -4.606544 90)
			(size 0.254 0.3429)
			(layers "F.Cu" "F.Mask" "F.Paste")
			(net "PV_VCCP_NODE1")
		)
		(pad "W1" smd oval
			(at -16.249396 -4.39928 270)
			(size 0.254 0.3429)
			(layers "F.Cu" "F.Mask" "F.Paste")
			(net "PD_CPU_NODE1_W1")
		)
		(pad "W3" smd circle
			(at -15.304516 -4.45008)
			(size 0.3048 0.3048)
			(layers "F.Cu" "F.Mask" "F.Paste")
			(net "GND")
		)
		(pad "W4" smd circle
			(at -14.542516 -4.39928)
			(size 0.3048 0.3048)
			(layers "F.Cu" "F.Mask" "F.Paste")
			(net "PD_CPU_NODE1_RP2_PERN")
		)
		(pad "W7" smd circle
			(at -13.344398 -4.202684)
			(size 0.3048 0.3048)
			(layers "F.Cu" "F.Mask" "F.Paste")
			(net "GND")
		)
		(pad "W8" smd circle
			(at -12.582398 -4.202684)
			(size 0.3048 0.3048)
			(layers "F.Cu" "F.Mask" "F.Paste")
			(net "Net_399")
		)
		(pad "W10" smd circle
			(at -11.820398 -4.202684)
			(size 0.3048 0.3048)
			(layers "F.Cu" "F.Mask" "F.Paste")
			(net "GND")
		)
		(pad "W11" smd circle
			(at -11.058398 -4.202684)
			(size 0.3048 0.3048)
			(layers "F.Cu" "F.Mask" "F.Paste")
			(net "SMB_CPU_NODE1_XDP_CLK_R")
		)
		(pad "W13" smd circle
			(at -10.296398 -4.202684)
			(size 0.3048 0.3048)
			(layers "F.Cu" "F.Mask" "F.Paste")
			(net "SMB_CPU_NODE1_MEM_ICS_DAT_R")
		)
		(pad "W14" smd circle
			(at -9.534398 -4.202684)
			(size 0.3048 0.3048)
			(layers "F.Cu" "F.Mask" "F.Paste")
			(net "GND")
		)
		(pad "W16" smd circle
			(at -8.772398 -4.202684)
			(size 0.3048 0.3048)
			(layers "F.Cu" "F.Mask" "F.Paste")
			(net "SMB_CPU_NODE1_BMC_DAT_RR")
		)
		(pad "W17" smd circle
			(at -8.010398 -4.202684)
			(size 0.3048 0.3048)
			(layers "F.Cu" "F.Mask" "F.Paste")
			(net "SMB_CPU_NODE1_XDP_DAT_R")
		)
		(pad "W19" smd circle
			(at -7.248398 -4.202684)
			(size 0.3048 0.3048)
			(layers "F.Cu" "F.Mask" "F.Paste")
			(net "GND")
		)
		(pad "W21" smd circle
			(at -6.00075 -4.0005)
			(size 0.381 0.381)
			(layers "F.Cu" "F.Mask" "F.Paste")
			(net "GND")
		)
		(pad "W23" smd circle
			(at -5.20065 -4.0005)
			(size 0.381 0.381)
			(layers "F.Cu" "F.Mask" "F.Paste")
			(net "GND")
		)
		(pad "W25" smd circle
			(at -4.40055 -4.0005)
			(size 0.381 0.381)
			(layers "F.Cu" "F.Mask" "F.Paste")
			(net "GND")
		)
		(pad "W26" smd circle
			(at -3.60045 -4.0005)
			(size 0.381 0.381)
			(layers "F.Cu" "F.Mask" "F.Paste")
			(net "GND")
		)
		(pad "W28" smd circle
			(at -2.80035 -4.0005)
			(size 0.381 0.381)
			(layers "F.Cu" "F.Mask" "F.Paste")
			(net "GND")
		)
		(pad "W29" smd circle
			(at -2.00025 -4.0005)
			(size 0.381 0.381)
			(layers "F.Cu" "F.Mask" "F.Paste")
			(net "GND")
		)
		(pad "W31" smd circle
			(at -1.20015 -4.0005)
			(size 0.381 0.381)
			(layers "F.Cu" "F.Mask" "F.Paste")
			(net "GND")
		)
		(pad "W32" smd circle
			(at -0.40005 -4.0005)
			(size 0.381 0.381)
			(layers "F.Cu" "F.Mask" "F.Paste")
			(net "P1V05_NODE1")
		)
		(pad "W34" smd circle
			(at 0.40005 -4.0005)
			(size 0.381 0.381)
			(layers "F.Cu" "F.Mask" "F.Paste")
			(net "GND")
		)
		(pad "W36" smd circle
			(at 1.20015 -4.0005)
			(size 0.381 0.381)
			(layers "F.Cu" "F.Mask" "F.Paste")
			(net "P1V05_NODE1")
		)
		(pad "W38" smd circle
			(at 2.00025 -4.0005)
			(size 0.381 0.381)
			(layers "F.Cu" "F.Mask" "F.Paste")
			(net "GND")
		)
		(pad "W39" smd circle
			(at 2.80035 -4.0005)
			(size 0.381 0.381)
			(layers "F.Cu" "F.Mask" "F.Paste")
			(net "P1V05_NODE1")
		)
		(pad "W41" smd circle
			(at 3.60045 -4.0005)
			(size 0.381 0.381)
			(layers "F.Cu" "F.Mask" "F.Paste")
			(net "GND")
		)
		(pad "W42" smd circle
			(at 4.40055 -4.0005)
			(size 0.381 0.381)
			(layers "F.Cu" "F.Mask" "F.Paste")
			(net "P1V05_NODE1")
		)
		(pad "W44" smd circle
			(at 5.20065 -4.0005)
			(size 0.381 0.381)
			(layers "F.Cu" "F.Mask" "F.Paste")
			(net "PV_VCCP_NODE1")
		)
		(pad "W46" smd circle
			(at 6.00075 -4.0005)
			(size 0.381 0.381)
			(layers "F.Cu" "F.Mask" "F.Paste")
			(net "PV_VCCP_NODE1")
		)
		(pad "W48" smd circle
			(at 7.248398 -4.44246)
			(size 0.3048 0.3048)
			(layers "F.Cu" "F.Mask" "F.Paste")
			(net "PV_VCCP_NODE1")
		)
		(pad "W50" smd circle
			(at 8.010398 -4.44246)
			(size 0.3048 0.3048)
			(layers "F.Cu" "F.Mask" "F.Paste")
			(net "PV_VCCP_NODE1")
		)
		(pad "W51" smd circle
			(at 8.772398 -4.44246)
			(size 0.3048 0.3048)
			(layers "F.Cu" "F.Mask" "F.Paste")
			(net "GND")
		)
		(pad "W53" smd circle
			(at 9.534398 -4.44246)
			(size 0.3048 0.3048)
			(layers "F.Cu" "F.Mask" "F.Paste")
			(net "PV_VCCP_NODE1")
		)
		(pad "W54" smd circle
			(at 10.296398 -4.44246)
			(size 0.3048 0.3048)
			(layers "F.Cu" "F.Mask" "F.Paste")
			(net "PV_VCCP_NODE1")
		)
		(pad "W56" smd circle
			(at 11.058398 -4.44246)
			(size 0.3048 0.3048)
			(layers "F.Cu" "F.Mask" "F.Paste")
			(net "GND")
		)
		(pad "W57" smd circle
			(at 11.820398 -4.44246)
			(size 0.3048 0.3048)
			(layers "F.Cu" "F.Mask" "F.Paste")
			(net "PV_VCCP_NODE1")
		)
		(pad "W59" smd circle
			(at 12.582398 -4.44246)
			(size 0.3048 0.3048)
			(layers "F.Cu" "F.Mask" "F.Paste")
			(net "PV_VCCP_NODE1")
		)
		(pad "W60" smd circle
			(at 13.344398 -4.44246)
			(size 0.3048 0.3048)
			(layers "F.Cu" "F.Mask" "F.Paste")
			(net "GND")
		)
		(pad "W62" smd circle
			(at 14.063218 -4.09575)
			(size 0.3048 0.3048)
			(layers "F.Cu" "F.Mask" "F.Paste")
			(net "GND")
		)
		(pad "Y2" smd circle
			(at -15.805658 -3.63982)
			(size 0.3048 0.3048)
			(layers "F.Cu" "F.Mask" "F.Paste")
			(net "PD_CPU_NODE1_Y2")
		)
		(pad "Y4" smd circle
			(at -14.751558 -3.719576)
			(size 0.3048 0.3048)
			(layers "F.Cu" "F.Mask" "F.Paste")
			(net "GND")
		)
		(pad "Y5" smd circle
			(at -14.063218 -3.888486)
			(size 0.3048 0.3048)
			(layers "F.Cu" "F.Mask" "F.Paste")
			(net "GND")
		)
		(pad "Y7" smd circle
			(at -13.344398 -3.50266)
			(size 0.3048 0.3048)
			(layers "F.Cu" "F.Mask" "F.Paste")
			(net "GND")
		)
		(pad "Y8" smd circle
			(at -12.582398 -3.50266)
			(size 0.3048 0.3048)
			(layers "F.Cu" "F.Mask" "F.Paste")
			(net "Net_370")
		)
		(pad "Y10" smd circle
			(at -11.820398 -3.50266)
			(size 0.3048 0.3048)
			(layers "F.Cu" "F.Mask" "F.Paste")
			(net "GND")
		)
		(pad "Y11" smd circle
			(at -11.058398 -3.50266)
			(size 0.3048 0.3048)
			(layers "F.Cu" "F.Mask" "F.Paste")
			(net "SMB_CPU_NODE1_MEM_ICS_CLK_R")
		)
		(pad "Y13" smd circle
			(at -10.296398 -3.50266)
			(size 0.3048 0.3048)
			(layers "F.Cu" "F.Mask" "F.Paste")
			(net "SMB_CPU_NODE1_BMC_CLK_RR")
		)
		(pad "Y14" smd circle
			(at -9.534398 -3.50266)
			(size 0.3048 0.3048)
			(layers "F.Cu" "F.Mask" "F.Paste")
			(net "GND")
		)
		(pad "Y16" smd circle
			(at -8.772398 -3.50266)
			(size 0.3048 0.3048)
			(layers "F.Cu" "F.Mask" "F.Paste")
			(net "GND")
		)
		(pad "Y17" smd circle
			(at -8.010398 -3.50266)
			(size 0.3048 0.3048)
			(layers "F.Cu" "F.Mask" "F.Paste")
			(net "GND")
		)
		(pad "Y19" smd circle
			(at -7.248398 -3.50266)
			(size 0.3048 0.3048)
			(layers "F.Cu" "F.Mask" "F.Paste")
			(net "GND")
		)
		(pad "Y48" smd circle
			(at 7.248398 -3.742436)
			(size 0.3048 0.3048)
			(layers "F.Cu" "F.Mask" "F.Paste")
			(net "PV_VCCP_NODE1")
		)
		(pad "Y50" smd circle
			(at 8.010398 -3.742436)
			(size 0.3048 0.3048)
			(layers "F.Cu" "F.Mask" "F.Paste")
			(net "PV_VCCP_NODE1")
		)
		(pad "Y51" smd circle
			(at 8.772398 -3.742436)
			(size 0.3048 0.3048)
			(layers "F.Cu" "F.Mask" "F.Paste")
			(net "GND")
		)
		(pad "Y53" smd circle
			(at 9.534398 -3.742436)
			(size 0.3048 0.3048)
			(layers "F.Cu" "F.Mask" "F.Paste")
			(net "PV_VCCP_NODE1")
		)
		(pad "Y54" smd circle
			(at 10.296398 -3.742436)
			(size 0.3048 0.3048)
			(layers "F.Cu" "F.Mask" "F.Paste")
			(net "PV_VCCP_NODE1")
		)
		(pad "Y56" smd circle
			(at 11.058398 -3.742436)
			(size 0.3048 0.3048)
			(layers "F.Cu" "F.Mask" "F.Paste")
			(net "GND")
		)
		(pad "Y57" smd circle
			(at 11.820398 -3.742436)
			(size 0.3048 0.3048)
			(layers "F.Cu" "F.Mask" "F.Paste")
			(net "PV_VCCP_NODE1")
		)
		(pad "Y59" smd circle
			(at 12.582398 -3.742436)
			(size 0.3048 0.3048)
			(layers "F.Cu" "F.Mask" "F.Paste")
			(net "PV_VCCP_NODE1")
		)
		(pad "Y60" smd circle
			(at 13.344398 -3.742436)
			(size 0.3048 0.3048)
			(layers "F.Cu" "F.Mask" "F.Paste")
			(net "GND")
		)
		(pad "Y63" smd circle
			(at 14.794738 -3.938016)
			(size 0.3048 0.3048)
			(layers "F.Cu" "F.Mask" "F.Paste")
			(net "GND")
		)
		(pad "Y65" smd circle
			(at 15.752318 -3.885184)
			(size 0.3048 0.3048)
			(layers "F.Cu" "F.Mask" "F.Paste")
			(net "GND")
		)
	)
	(footprint ""
		(layer "F.Cu")
		(at 66.885566 -99.281234)
		(property "Reference" "R1090"
			(at 26.919174 54.04358 0)
			(unlocked yes)
			(layer "F.SilkS")
			(effects
				(font
					(size 0.7874 0.5842)
					(thickness 0.1524)
				)
				(justify left)
			)
		)
		(property "Value" ""
			(at 0 0 0)
			(layer "F.Fab")
			(effects
				(font
					(size 1.27 1.27)
				)
			)
		)
		(duplicate_pad_numbers_are_jumpers no)
		(fp_line
			(start -0.7874 -0.4064)
			(end 0.7874 -0.4064)
			(stroke
				(width 0.1524)
				(type default)
			)
			(layer "F.SilkS")
		)
		(fp_line
			(start -0.7874 0.4064)
			(end -0.7874 -0.4064)
			(stroke
				(width 0.1524)
				(type default)
			)
			(layer "F.SilkS")
		)
		(fp_line
			(start 0.7874 -0.4064)
			(end 0.7874 0.4064)
			(stroke
				(width 0.1524)
				(type default)
			)
			(layer "F.SilkS")
		)
		(fp_line
			(start 0.7874 0.4064)
			(end -0.7874 0.4064)
			(stroke
				(width 0.1524)
				(type default)
			)
			(layer "F.SilkS")
		)
		(fp_poly
			(pts
				(xy -0.508 0.2794) (xy -0.508 0.2286) (xy -0.635 0.2286) (xy -0.635 -0.254) (xy -0.5334 -0.254)
				(xy -0.5334 -0.2794) (xy 0.5334 -0.2794) (xy 0.5334 -0.254) (xy 0.635 -0.254) (xy 0.635 0.254) (xy 0.5334 0.254)
				(xy 0.5334 0.2794)
			)
			(stroke
				(width 0)
				(type default)
			)
			(fill no)
			(layer "F.CrtYd")
		)
		(pad "1" smd rect
			(at 0.40005 0)
			(size 0.4572 0.508)
			(layers "F.Cu" "F.Mask" "F.Paste")
			(net "P5V_STB_NODE1")
		)
		(pad "2" smd rect
			(at -0.40005 0)
			(size 0.4572 0.508)
			(layers "F.Cu" "F.Mask" "F.Paste")
			(net "FM_CPLD_NODE1_P1V8_SUS_EN_LV")
		)
	)
	(footprint ""
		(layer "F.Cu")
		(at 105.191814 -112.98682 180)
		(property "Reference" "PC120"
			(at 5.811774 -0.736092 0)
			(unlocked yes)
			(layer "F.SilkS")
			(effects
				(font
					(size 0.7874 0.5842)
					(thickness 0.1524)
				)
				(justify left)
			)
		)
		(property "Value" ""
			(at 0 0 180)
			(layer "F.Fab")
			(effects
				(font
					(size 1.27 1.27)
				)
			)
		)
		(duplicate_pad_numbers_are_jumpers no)
		(fp_line
			(start 1.905 0.8636)
			(end -1.905 0.8636)
			(stroke
				(width 0.1524)
				(type default)
			)
			(layer "F.SilkS")
		)
		(fp_line
			(start 1.905 -0.8636)
			(end 1.905 0.8636)
			(stroke
				(width 0.1524)
				(type default)
			)
			(layer "F.SilkS")
		)
		(fp_line
			(start 0 0.8382)
			(end 0 -0.8382)
			(stroke
				(width 0.1524)
				(type default)
			)
			(layer "F.SilkS")
		)
		(fp_line
			(start -1.905 0.8636)
			(end -1.905 -0.8636)
			(stroke
				(width 0.1524)
				(type default)
			)
			(layer "F.SilkS")
		)
		(fp_line
			(start -1.905 -0.8636)
			(end 1.905 -0.8636)
			(stroke
				(width 0.1524)
				(type default)
			)
			(layer "F.SilkS")
		)
		(fp_rect
			(start -1.524 0.7366)
			(end 1.524 -0.7366)
			(stroke
				(width 0)
				(type default)
			)
			(fill no)
			(layer "F.CrtYd")
		)
		(pad "1" smd rect
			(at 0.94996 0 180)
			(size 1.1176 1.3716)
			(layers "F.Cu" "F.Mask" "F.Paste")
			(net "GND")
		)
		(pad "2" smd rect
			(at -0.94996 0 180)
			(size 1.1176 1.3716)
			(layers "F.Cu" "F.Mask" "F.Paste")
			(net "PV_VCCP_NODE1")
		)
	)
	(footprint ""
		(layer "F.Cu")
		(at 175.000158 -182.749952)
		(property "Reference" "H6"
			(at -4.743958 -5.640578 0)
			(unlocked yes)
			(layer "F.SilkS")
			(effects
				(font
					(size 0.7874 0.5842)
					(thickness 0.1524)
				)
				(justify left)
			)
		)
		(property "Value" ""
			(at 0 0 0)
			(layer "F.Fab")
			(effects
				(font
					(size 1.27 1.27)
				)
			)
		)
		(duplicate_pad_numbers_are_jumpers no)
		(fp_poly
			(pts
				(arc
					(start 5.999988 4.99999)
					(mid 0 10.999978)
					(end -5.999988 4.99999)
				)
				(arc
					(start -5.999988 0)
					(mid 0 -5.999988)
					(end 5.999988 0)
				)
			)
			(stroke
				(width 0)
				(type default)
			)
			(fill no)
			(layer "B.CrtYd")
		)
		(fp_poly
			(pts
				(arc
					(start 5.999988 4.99999)
					(mid 0 10.999978)
					(end -5.999988 4.99999)
				)
				(arc
					(start -5.999988 0)
					(mid 0 -5.999988)
					(end 5.999988 0)
				)
			)
			(stroke
				(width 0)
				(type default)
			)
			(fill no)
			(layer "F.CrtYd")
		)
		(pad "" np_thru_hole circle
			(at 0 0)
			(size 3.81 3.81)
			(drill 3.81)
			(layers "*.Cu" "*.Mask")
			(clearance 0.381)
			(thermal_gap 0.381)
		)
	)
	(footprint ""
		(layer "F.Cu")
		(at 79.99476 -172.124624 -90)
		(property "Reference" "U128"
			(at 10.616946 -4.361942 0)
			(unlocked yes)
			(layer "F.SilkS")
			(effects
				(font
					(size 0.7874 0.5842)
					(thickness 0.1524)
				)
				(justify left)
			)
		)
		(property "Value" ""
			(at 0 0 270)
			(layer "F.Fab")
			(effects
				(font
					(size 1.27 1.27)
				)
			)
		)
		(duplicate_pad_numbers_are_jumpers no)
		(fp_line
			(start -4.0386 8.8646)
			(end -4.0386 11.9634)
			(stroke
				(width 0.1524)
				(type default)
			)
			(layer "F.SilkS")
		)
		(fp_line
			(start -1.4986 8.8392)
			(end -1.4986 10.1092)
			(stroke
				(width 0.1524)
				(type default)
			)
			(layer "F.SilkS")
		)
		(fp_line
			(start 1.016 8.7376)
			(end 1.016 11.8364)
			(stroke
				(width 0.1524)
				(type default)
			)
			(layer "F.SilkS")
		)
		(fp_line
			(start 5.9944 8.7376)
			(end 5.9944 11.8364)
			(stroke
				(width 0.1524)
				(type default)
			)
			(layer "F.SilkS")
		)
		(fp_line
			(start -6.2992 6.2992)
			(end -6.2992 -5.969)
			(stroke
				(width 0.1524)
				(type default)
			)
			(layer "F.SilkS")
		)
		(fp_line
			(start 6.2992 6.2992)
			(end -6.2992 6.2992)
			(stroke
				(width 0.1524)
				(type default)
			)
			(layer "F.SilkS")
		)
		(fp_line
			(start 9.9568 3.9878)
			(end 8.6868 3.9878)
			(stroke
				(width 0.1524)
				(type default)
			)
			(layer "F.SilkS")
		)
		(fp_line
			(start 11.4808 1.4986)
			(end 8.7376 1.4986)
			(stroke
				(width 0.1524)
				(type default)
			)
			(layer "F.SilkS")
		)
		(fp_line
			(start -8.763 1.0414)
			(end -10.033 1.0414)
			(stroke
				(width 0.1524)
				(type default)
			)
			(layer "F.SilkS")
		)
		(fp_line
			(start 9.9568 -0.9906)
			(end 8.6868 -0.9906)
			(stroke
				(width 0.1524)
				(type default)
			)
			(layer "F.SilkS")
		)
		(fp_line
			(start -8.7376 -1.4986)
			(end -11.4808 -1.4986)
			(stroke
				(width 0.1524)
				(type default)
			)
			(layer "F.SilkS")
		)
		(fp_line
			(start -8.7122 -4.0132)
			(end -9.9822 -4.0132)
			(stroke
				(width 0.1524)
				(type default)
			)
			(layer "F.SilkS")
		)
		(fp_line
			(start -6.2992 -5.969)
			(end -5.969 -6.2992)
			(stroke
				(width 0.1524)
				(type default)
			)
			(layer "F.SilkS")
		)
		(fp_line
			(start 9.9822 -6.0198)
			(end 8.7122 -6.0198)
			(stroke
				(width 0.1524)
				(type default)
			)
			(layer "F.SilkS")
		)
		(fp_line
			(start -5.969 -6.2992)
			(end 6.2992 -6.2992)
			(stroke
				(width 0.1524)
				(type default)
			)
			(layer "F.SilkS")
		)
		(fp_line
			(start 6.2992 -6.2992)
			(end 6.2992 6.2992)
			(stroke
				(width 0.1524)
				(type default)
			)
			(layer "F.SilkS")
		)
		(fp_line
			(start -3.4798 -9.9568)
			(end -3.4798 -8.6868)
			(stroke
				(width 0.1524)
				(type default)
			)
			(layer "F.SilkS")
		)
		(fp_line
			(start 1.4732 -9.9822)
			(end 1.4732 -8.7122)
			(stroke
				(width 0.1524)
				(type default)
			)
			(layer "F.SilkS")
		)
		(fp_line
			(start -0.9906 -11.7856)
			(end -0.9906 -8.6868)
			(stroke
				(width 0.1524)
				(type default)
			)
			(layer "F.SilkS")
		)
		(fp_line
			(start 3.9878 -11.7856)
			(end 3.9878 -8.6868)
			(stroke
				(width 0.1524)
				(type default)
			)
			(layer "F.SilkS")
		)
		(fp_line
			(start -6.0198 -11.811)
			(end -6.0198 -8.7122)
			(stroke
				(width 0.1524)
				(type default)
			)
			(layer "F.SilkS")
		)
		(fp_poly
			(pts
				(xy -8.751824 -6.07568) (xy -9.513824 -6.22808) (xy -9.513824 -5.94868)
			)
			(stroke
				(width 0)
				(type default)
			)
			(fill yes)
			(layer "F.SilkS")
		)
		(fp_poly
			(pts
				(xy -6.1468 8.509) (xy -6.1468 7.2644) (xy -7.2644 7.2644) (xy -7.2644 6.1468) (xy -8.509 6.1468)
				(xy -8.509 -6.1468) (xy -7.2644 -6.1468) (xy -7.2644 -7.2644) (xy -6.1468 -7.2644) (xy -6.1468 -8.509)
				(xy 6.1468 -8.509) (xy 6.1468 -7.2644) (xy 7.2644 -7.2644) (xy 7.2644 -6.1468) (xy 8.509 -6.1468)
				(xy 8.509 6.1468) (xy 7.2644 6.1468) (xy 7.2644 7.2644) (xy 6.1468 7.2644) (xy 6.1468 8.509)
			)
			(stroke
				(width 0)
				(type default)
			)
			(fill no)
			(layer "F.CrtYd")
		)
		(fp_text user "26"
			(at -6.613144 8.434578 0)
			(unlocked yes)
			(layer "F.SilkS")
			(effects
				(font
					(size 0.635 0.4064)
					(thickness 0.1524)
				)
				(justify left)
			)
		)
		(fp_text user "50"
			(at 6.7437 8.393684 0)
			(unlocked yes)
			(layer "F.SilkS")
			(effects
				(font
					(size 0.635 0.4064)
					(thickness 0.1524)
				)
				(justify left)
			)
		)
		(fp_text user "25"
			(at -7.755382 7.301484 0)
			(unlocked yes)
			(layer "F.SilkS")
			(effects
				(font
					(size 0.635 0.4064)
					(thickness 0.1524)
				)
				(justify left)
			)
		)
		(fp_text user "51"
			(at 8.807196 7.076186 0)
			(unlocked yes)
			(layer "F.SilkS")
			(effects
				(font
					(size 0.635 0.4064)
					(thickness 0.1524)
				)
				(justify left)
			)
		)
		(fp_text user "1"
			(at -9.723882 -5.505958 0)
			(unlocked yes)
			(layer "F.SilkS")
			(effects
				(font
					(size 0.635 0.4064)
					(thickness 0.1524)
				)
				(justify left)
			)
		)
		(fp_text user "75"
			(at 8.082026 -6.324854 0)
			(unlocked yes)
			(layer "F.SilkS")
			(effects
				(font
					(size 0.635 0.4064)
					(thickness 0.1524)
				)
				(justify left)
			)
		)
		(fp_text user "100"
			(at -6.61289 -6.932676 0)
			(unlocked yes)
			(layer "F.SilkS")
			(effects
				(font
					(size 0.635 0.4064)
					(thickness 0.1524)
				)
				(justify left)
			)
		)
		(fp_text user "76"
			(at 6.64464 -8.066024 0)
			(unlocked yes)
			(layer "F.SilkS")
			(effects
				(font
					(size 0.635 0.4064)
					(thickness 0.1524)
				)
				(justify left)
			)
		)
		(pad "1" smd rect
			(at -7.750048 -5.999988)
			(size 0.2794 1.4986)
			(layers "F.Cu" "F.Mask" "F.Paste")
			(net "CPLD_UART_DTR_P4_N")
		)
		(pad "2" smd rect
			(at -7.750048 -5.500116)
			(size 0.2794 1.4986)
			(layers "F.Cu" "F.Mask" "F.Paste")
			(net "UART_SW_S0_N")
		)
		(pad "3" smd rect
			(at -7.750048 -4.99999)
			(size 0.2794 1.4986)
			(layers "F.Cu" "F.Mask" "F.Paste")
			(net "UART_SW_S1_N")
		)
		(pad "4" smd rect
			(at -7.750048 -4.500118)
			(size 0.2794 1.4986)
			(layers "F.Cu" "F.Mask" "F.Paste")
			(net "UART_SW_S2_N")
		)
		(pad "5" smd rect
			(at -7.750048 -3.999992)
			(size 0.2794 1.4986)
			(layers "F.Cu" "F.Mask" "F.Paste")
			(net "UART_SW_S3_N")
		)
		(pad "6" smd rect
			(at -7.750048 -3.50012)
			(size 0.2794 1.4986)
			(layers "F.Cu" "F.Mask" "F.Paste")
			(net "UART_SW_S4_N")
		)
		(pad "7" smd rect
			(at -7.750048 -2.999994)
			(size 0.2794 1.4986)
			(layers "F.Cu" "F.Mask" "F.Paste")
			(net "UART_SW_S5_N")
		)
		(pad "8" smd rect
			(at -7.750048 -2.500122)
			(size 0.2794 1.4986)
			(layers "F.Cu" "F.Mask" "F.Paste")
			(net "SDC_RST_N")
		)
		(pad "9" smd rect
			(at -7.750048 -1.999996)
			(size 0.2794 1.4986)
			(layers "F.Cu" "F.Mask" "F.Paste")
			(net "P3V3_NODE1")
		)
		(pad "10" smd rect
			(at -7.750048 -1.500124)
			(size 0.2794 1.4986)
			(layers "F.Cu" "F.Mask" "F.Paste")
			(net "GND")
		)
		(pad "11" smd rect
			(at -7.750048 -0.999998)
			(size 0.2794 1.4986)
			(layers "F.Cu" "F.Mask" "F.Paste")
			(net "GND")
		)
		(pad "12" smd rect
			(at -7.750048 -0.499872)
			(size 0.2794 1.4986)
			(layers "F.Cu" "F.Mask" "F.Paste")
			(net "CPLD_WDT3")
		)
		(pad "13" smd rect
			(at -7.750048 0)
			(size 0.2794 1.4986)
			(layers "F.Cu" "F.Mask" "F.Paste")
			(net "P3V3_NODE1")
		)
		(pad "14" smd rect
			(at -7.750048 0.499872)
			(size 0.2794 1.4986)
			(layers "F.Cu" "F.Mask" "F.Paste")
			(net "CPU_RSV_1")
		)
		(pad "15" smd rect
			(at -7.750048 0.999998)
			(size 0.2794 1.4986)
			(layers "F.Cu" "F.Mask" "F.Paste")
			(net "UART_TX_P4")
		)
		(pad "16" smd rect
			(at -7.750048 1.500124)
			(size 0.2794 1.4986)
			(layers "F.Cu" "F.Mask" "F.Paste")
			(net "UART_RX_P4")
		)
		(pad "17" smd rect
			(at -7.750048 1.999996)
			(size 0.2794 1.4986)
			(layers "F.Cu" "F.Mask" "F.Paste")
			(net "UART_DTR_P4_N")
		)
		(pad "18" smd rect
			(at -7.750048 2.500122)
			(size 0.2794 1.4986)
			(layers "F.Cu" "F.Mask" "F.Paste")
			(net "UART_RTS_P4_N")
		)
		(pad "19" smd rect
			(at -7.750048 2.999994)
			(size 0.2794 1.4986)
			(layers "F.Cu" "F.Mask" "F.Paste")
			(net "UART_RI_P4_N")
		)
		(pad "20" smd rect
			(at -7.750048 3.50012)
			(size 0.2794 1.4986)
			(layers "F.Cu" "F.Mask" "F.Paste")
			(net "UART_SDC_TX")
		)
		(pad "21" smd rect
			(at -7.750048 3.999992)
			(size 0.2794 1.4986)
			(layers "F.Cu" "F.Mask" "F.Paste")
			(net "UART_SDC_RX")
		)
		(pad "22" smd rect
			(at -7.750048 4.500118)
			(size 0.2794 1.4986)
			(layers "F.Cu" "F.Mask" "F.Paste")
			(net "JTAG_CPLD2_TMS")
		)
		(pad "23" smd rect
			(at -7.750048 4.99999)
			(size 0.2794 1.4986)
			(layers "F.Cu" "F.Mask" "F.Paste")
			(net "JTAG_CPLD2_TDI")
		)
		(pad "24" smd rect
			(at -7.750048 5.500116)
			(size 0.2794 1.4986)
			(layers "F.Cu" "F.Mask" "F.Paste")
			(net "JTAG_CPLD2_TCK")
		)
		(pad "25" smd rect
			(at -7.750048 5.999988)
			(size 0.2794 1.4986)
			(layers "F.Cu" "F.Mask" "F.Paste")
			(net "JTAG_CPLD2_TDO")
		)
		(pad "26" smd rect
			(at -5.999988 7.750048 270)
			(size 0.2794 1.4986)
			(layers "F.Cu" "F.Mask" "F.Paste")
			(net "UART_T1_NODE1_TXD")
		)
		(pad "27" smd rect
			(at -5.500116 7.750048 270)
			(size 0.2794 1.4986)
			(layers "F.Cu" "F.Mask" "F.Paste")
			(net "UART_T1_NODE1_RXD")
		)
		(pad "28" smd rect
			(at -4.99999 7.750048 270)
			(size 0.2794 1.4986)
			(layers "F.Cu" "F.Mask" "F.Paste")
			(net "UART_T1_NODE2_TXD")
		)
		(pad "29" smd rect
			(at -4.500118 7.750048 270)
			(size 0.2794 1.4986)
			(layers "F.Cu" "F.Mask" "F.Paste")
			(net "UART_T1_NODE2_RXD")
		)
		(pad "30" smd rect
			(at -3.999992 7.750048 270)
			(size 0.2794 1.4986)
			(layers "F.Cu" "F.Mask" "F.Paste")
			(net "WDT_LED")
		)
		(pad "31" smd rect
			(at -3.50012 7.750048 270)
			(size 0.2794 1.4986)
			(layers "F.Cu" "F.Mask" "F.Paste")
			(net "P3V3_NODE1")
		)
		(pad "32" smd rect
			(at -2.999994 7.750048 270)
			(size 0.2794 1.4986)
			(layers "F.Cu" "F.Mask" "F.Paste")
			(net "GND")
		)
		(pad "33" smd rect
			(at -2.500122 7.750048 270)
			(size 0.2794 1.4986)
			(layers "F.Cu" "F.Mask" "F.Paste")
			(net "UART_T1_NODE3_TXD")
		)
		(pad "34" smd rect
			(at -1.999996 7.750048 270)
			(size 0.2794 1.4986)
			(layers "F.Cu" "F.Mask" "F.Paste")
			(net "UART_T1_NODE3_RXD")
		)
		(pad "35" smd rect
			(at -1.500124 7.750048 270)
			(size 0.2794 1.4986)
			(layers "F.Cu" "F.Mask" "F.Paste")
			(net "UART_T1_NODE4_TXD")
		)
		(pad "36" smd rect
			(at -0.999998 7.750048 270)
			(size 0.2794 1.4986)
			(layers "F.Cu" "F.Mask" "F.Paste")
			(net "UART_T1_NODE4_RXD")
		)
		(pad "37" smd rect
			(at -0.499872 7.750048 270)
			(size 0.2794 1.4986)
			(layers "F.Cu" "F.Mask" "F.Paste")
			(net "UART_T2_NODE1_TXD")
		)
		(pad "38" smd rect
			(at 0 7.750048 270)
			(size 0.2794 1.4986)
			(layers "F.Cu" "F.Mask" "F.Paste")
			(net "UART_T2_NODE1_RXD")
		)
		(pad "39" smd rect
			(at 0.499872 7.750048 270)
			(size 0.2794 1.4986)
			(layers "F.Cu" "F.Mask" "F.Paste")
			(net "UART_T2_NODE2_TXD")
		)
		(pad "40" smd rect
			(at 0.999998 7.750048 270)
			(size 0.2794 1.4986)
			(layers "F.Cu" "F.Mask" "F.Paste")
			(net "UART_T2_NODE2_RXD")
		)
		(pad "41" smd rect
			(at 1.500124 7.750048 270)
			(size 0.2794 1.4986)
			(layers "F.Cu" "F.Mask" "F.Paste")
			(net "UART_T2_NODE3_TXD")
		)
		(pad "42" smd rect
			(at 1.999996 7.750048 270)
			(size 0.2794 1.4986)
			(layers "F.Cu" "F.Mask" "F.Paste")
			(net "UART_T2_NODE3_RXD")
		)
		(pad "43" smd rect
			(at 2.500122 7.750048 270)
			(size 0.2794 1.4986)
			(layers "F.Cu" "F.Mask" "F.Paste")
			(net "CPLD_WDT1")
		)
		(pad "44" smd rect
			(at 2.999994 7.750048 270)
			(size 0.2794 1.4986)
			(layers "F.Cu" "F.Mask" "F.Paste")
			(net "CPLD_WDT2")
		)
		(pad "45" smd rect
			(at 3.50012 7.750048 270)
			(size 0.2794 1.4986)
			(layers "F.Cu" "F.Mask" "F.Paste")
			(net "P3V3_NODE1")
		)
		(pad "46" smd rect
			(at 3.999992 7.750048 270)
			(size 0.2794 1.4986)
			(layers "F.Cu" "F.Mask" "F.Paste")
			(net "GND")
		)
		(pad "47" smd rect
			(at 4.500118 7.750048 270)
			(size 0.2794 1.4986)
			(layers "F.Cu" "F.Mask" "F.Paste")
			(net "UART_T2_NODE4_TXD")
		)
		(pad "48" smd rect
			(at 4.99999 7.750048 270)
			(size 0.2794 1.4986)
			(layers "F.Cu" "F.Mask" "F.Paste")
			(net "UART_T2_NODE4_RXD")
		)
		(pad "49" smd rect
			(at 5.500116 7.750048 270)
			(size 0.2794 1.4986)
			(layers "F.Cu" "F.Mask" "F.Paste")
			(net "CPLD2_RSV1")
		)
		(pad "50" smd rect
			(at 5.999988 7.750048 270)
			(size 0.2794 1.4986)
			(layers "F.Cu" "F.Mask" "F.Paste")
			(net "CPLD2_RSV2")
		)
		(pad "51" smd rect
			(at 7.750048 5.999988)
			(size 0.2794 1.4986)
			(layers "F.Cu" "F.Mask" "F.Paste")
			(net "CPLD2_RSV3")
		)
		(pad "52" smd rect
			(at 7.750048 5.500116)
			(size 0.2794 1.4986)
			(layers "F.Cu" "F.Mask" "F.Paste")
			(net "UART_T3_NODE1_TXD")
		)
		(pad "53" smd rect
			(at 7.750048 4.99999)
			(size 0.2794 1.4986)
			(layers "F.Cu" "F.Mask" "F.Paste")
			(net "UART_T3_NODE1_RXD")
		)
		(pad "54" smd rect
			(at 7.750048 4.500118)
			(size 0.2794 1.4986)
			(layers "F.Cu" "F.Mask" "F.Paste")
			(net "UART_T3_NODE2_TXD")
		)
		(pad "55" smd rect
			(at 7.750048 3.999992)
			(size 0.2794 1.4986)
			(layers "F.Cu" "F.Mask" "F.Paste")
			(net "UART_T3_NODE2_RXD")
		)
		(pad "56" smd rect
			(at 7.750048 3.50012)
			(size 0.2794 1.4986)
			(layers "F.Cu" "F.Mask" "F.Paste")
			(net "UART_T3_NODE3_TXD")
		)
		(pad "57" smd rect
			(at 7.750048 2.999994)
			(size 0.2794 1.4986)
			(layers "F.Cu" "F.Mask" "F.Paste")
			(net "UART_T3_NODE3_RXD")
		)
		(pad "58" smd rect
			(at 7.750048 2.500122)
			(size 0.2794 1.4986)
			(layers "F.Cu" "F.Mask" "F.Paste")
			(net "TACKOVER_EN_N")
		)
		(pad "59" smd rect
			(at 7.750048 1.999996)
			(size 0.2794 1.4986)
			(layers "F.Cu" "F.Mask" "F.Paste")
			(net "P3V3_NODE1")
		)
		(pad "60" smd rect
			(at 7.750048 1.500124)
			(size 0.2794 1.4986)
			(layers "F.Cu" "F.Mask" "F.Paste")
			(net "GND")
		)
		(pad "61" smd rect
			(at 7.750048 0.999998)
			(size 0.2794 1.4986)
			(layers "F.Cu" "F.Mask" "F.Paste")
			(net "FAN_MAX_CTRL")
		)
		(pad "62" smd rect
			(at 7.750048 0.499872)
			(size 0.2794 1.4986)
			(layers "F.Cu" "F.Mask" "F.Paste")
			(net "CMC_CPLD_RSV1")
		)
		(pad "63" smd rect
			(at 7.750048 0)
			(size 0.2794 1.4986)
			(layers "F.Cu" "F.Mask" "F.Paste")
			(net "P3V3_NODE1")
		)
		(pad "64" smd rect
			(at 7.750048 -0.499872)
			(size 0.2794 1.4986)
			(layers "F.Cu" "F.Mask" "F.Paste")
			(net "CLK_33K_CPLD23")
		)
		(pad "65" smd rect
			(at 7.750048 -0.999998)
			(size 0.2794 1.4986)
			(layers "F.Cu" "F.Mask" "F.Paste")
			(net "GND")
		)
		(pad "66" smd rect
			(at 7.750048 -1.500124)
			(size 0.2794 1.4986)
			(layers "F.Cu" "F.Mask" "F.Paste")
			(net "UART_T3_NODE4_TXD")
		)
		(pad "67" smd rect
			(at 7.750048 -1.999996)
			(size 0.2794 1.4986)
			(layers "F.Cu" "F.Mask" "F.Paste")
			(net "UART_T3_NODE4_RXD")
		)
		(pad "68" smd rect
			(at 7.750048 -2.500122)
			(size 0.2794 1.4986)
			(layers "F.Cu" "F.Mask" "F.Paste")
			(net "UART_T4_NODE1_TXD")
		)
		(pad "69" smd rect
			(at 7.750048 -2.999994)
			(size 0.2794 1.4986)
			(layers "F.Cu" "F.Mask" "F.Paste")
			(net "UART_T4_NODE1_RXD")
		)
		(pad "70" smd rect
			(at 7.750048 -3.50012)
			(size 0.2794 1.4986)
			(layers "F.Cu" "F.Mask" "F.Paste")
			(net "UART_T4_NODE2_TXD")
		)
		(pad "71" smd rect
			(at 7.750048 -3.999992)
			(size 0.2794 1.4986)
			(layers "F.Cu" "F.Mask" "F.Paste")
			(net "UART_T4_NODE2_RXD")
		)
		(pad "72" smd rect
			(at 7.750048 -4.500118)
			(size 0.2794 1.4986)
			(layers "F.Cu" "F.Mask" "F.Paste")
			(net "UART_T4_NODE3_TXD")
		)
		(pad "73" smd rect
			(at 7.750048 -4.99999)
			(size 0.2794 1.4986)
			(layers "F.Cu" "F.Mask" "F.Paste")
			(net "UART_T4_NODE3_RXD")
		)
		(pad "74" smd rect
			(at 7.750048 -5.500116)
			(size 0.2794 1.4986)
			(layers "F.Cu" "F.Mask" "F.Paste")
			(net "UART_T4_NODE4_TXD")
		)
		(pad "75" smd rect
			(at 7.750048 -5.999988)
			(size 0.2794 1.4986)
			(layers "F.Cu" "F.Mask" "F.Paste")
			(net "UART_T4_NODE4_RXD")
		)
		(pad "76" smd rect
			(at 5.999988 -7.750048 270)
			(size 0.2794 1.4986)
			(layers "F.Cu" "F.Mask" "F.Paste")
			(net "UART_T5_NODE1_TXD")
		)
		(pad "77" smd rect
			(at 5.500116 -7.750048 270)
			(size 0.2794 1.4986)
			(layers "F.Cu" "F.Mask" "F.Paste")
			(net "UART_T5_NODE1_RXD")
		)
		(pad "78" smd rect
			(at 4.99999 -7.750048 270)
			(size 0.2794 1.4986)
			(layers "F.Cu" "F.Mask" "F.Paste")
			(net "CPLD_FAN_MAX_CTRL")
		)
		(pad "79" smd rect
			(at 4.500118 -7.750048 270)
			(size 0.2794 1.4986)
			(layers "F.Cu" "F.Mask" "F.Paste")
			(net "GND")
		)
		(pad "80" smd rect
			(at 3.999992 -7.750048 270)
			(size 0.2794 1.4986)
			(layers "F.Cu" "F.Mask" "F.Paste")
			(net "P3V3_NODE1")
		)
		(pad "81" smd rect
			(at 3.50012 -7.750048 270)
			(size 0.2794 1.4986)
			(layers "F.Cu" "F.Mask" "F.Paste")
			(net "UART_T5_NODE2_TXD")
		)
		(pad "82" smd rect
			(at 2.999994 -7.750048 270)
			(size 0.2794 1.4986)
			(layers "F.Cu" "F.Mask" "F.Paste")
			(net "UART_T5_NODE2_RXD")
		)
		(pad "83" smd rect
			(at 2.500122 -7.750048 270)
			(size 0.2794 1.4986)
			(layers "F.Cu" "F.Mask" "F.Paste")
			(net "UART_T5_NODE3_TXD")
		)
		(pad "84" smd rect
			(at 1.999996 -7.750048 270)
			(size 0.2794 1.4986)
			(layers "F.Cu" "F.Mask" "F.Paste")
			(net "UART_T5_NODE3_RXD")
		)
		(pad "85" smd rect
			(at 1.500124 -7.750048 270)
			(size 0.2794 1.4986)
			(layers "F.Cu" "F.Mask" "F.Paste")
			(net "UART_T5_NODE4_TXD")
		)
		(pad "86" smd rect
			(at 0.999998 -7.750048 270)
			(size 0.2794 1.4986)
			(layers "F.Cu" "F.Mask" "F.Paste")
			(net "UART_T5_NODE4_RXD")
		)
		(pad "87" smd rect
			(at 0.499872 -7.750048 270)
			(size 0.2794 1.4986)
			(layers "F.Cu" "F.Mask" "F.Paste")
			(net "UART_T6_NODE1_TXD")
		)
		(pad "88" smd rect
			(at 0 -7.750048 270)
			(size 0.2794 1.4986)
			(layers "F.Cu" "F.Mask" "F.Paste")
			(net "UART_T6_NODE1_RXD")
		)
		(pad "89" smd rect
			(at -0.499872 -7.750048 270)
			(size 0.2794 1.4986)
			(layers "F.Cu" "F.Mask" "F.Paste")
			(net "UART_T6_NODE2_TXD")
		)
		(pad "90" smd rect
			(at -0.999998 -7.750048 270)
			(size 0.2794 1.4986)
			(layers "F.Cu" "F.Mask" "F.Paste")
			(net "UART_T6_NODE2_RXD")
		)
		(pad "91" smd rect
			(at -1.500124 -7.750048 270)
			(size 0.2794 1.4986)
			(layers "F.Cu" "F.Mask" "F.Paste")
			(net "UART_T6_NODE3_TXD")
		)
		(pad "92" smd rect
			(at -1.999996 -7.750048 270)
			(size 0.2794 1.4986)
			(layers "F.Cu" "F.Mask" "F.Paste")
			(net "UART_T6_NODE3_RXD")
		)
		(pad "93" smd rect
			(at -2.500122 -7.750048 270)
			(size 0.2794 1.4986)
			(layers "F.Cu" "F.Mask" "F.Paste")
			(net "GND")
		)
		(pad "94" smd rect
			(at -2.999994 -7.750048 270)
			(size 0.2794 1.4986)
			(layers "F.Cu" "F.Mask" "F.Paste")
			(net "P3V3_NODE1")
		)
		(pad "95" smd rect
			(at -3.50012 -7.750048 270)
			(size 0.2794 1.4986)
			(layers "F.Cu" "F.Mask" "F.Paste")
			(net "UART_T6_NODE4_TXD")
		)
		(pad "96" smd rect
			(at -3.999992 -7.750048 270)
			(size 0.2794 1.4986)
			(layers "F.Cu" "F.Mask" "F.Paste")
			(net "UART_T6_NODE4_RXD")
		)
		(pad "97" smd rect
			(at -4.500118 -7.750048 270)
			(size 0.2794 1.4986)
			(layers "F.Cu" "F.Mask" "F.Paste")
			(net "CPLD_UART_RTS_P4_N")
		)
		(pad "98" smd rect
			(at -4.99999 -7.750048 270)
			(size 0.2794 1.4986)
			(layers "F.Cu" "F.Mask" "F.Paste")
			(net "CPLD_UART_RI_P4_N")
		)
		(pad "99" smd rect
			(at -5.500116 -7.750048 270)
			(size 0.2794 1.4986)
			(layers "F.Cu" "F.Mask" "F.Paste")
			(net "CPLD_UART_RX_P4")
		)
		(pad "100" smd rect
			(at -5.999988 -7.750048 270)
			(size 0.2794 1.4986)
			(layers "F.Cu" "F.Mask" "F.Paste")
			(net "CPLD_UART_TX_P4")
		)
	)
	(footprint ""
		(layer "F.Cu")
		(at 106.170476 -164.769546 180)
		(property "Reference" "R772"
			(at -85.286342 -69.739764 0)
			(unlocked yes)
			(layer "F.SilkS")
			(effects
				(font
					(size 0.7874 0.5842)
					(thickness 0.1524)
				)
				(justify left)
			)
		)
		(property "Value" ""
			(at 0 0 180)
			(layer "F.Fab")
			(effects
				(font
					(size 1.27 1.27)
				)
			)
		)
		(duplicate_pad_numbers_are_jumpers no)
		(fp_line
			(start 0.7874 0.4064)
			(end -0.7874 0.4064)
			(stroke
				(width 0.1524)
				(type default)
			)
			(layer "F.SilkS")
		)
		(fp_line
			(start 0.7874 -0.4064)
			(end 0.7874 0.4064)
			(stroke
				(width 0.1524)
				(type default)
			)
			(layer "F.SilkS")
		)
		(fp_line
			(start -0.7874 0.4064)
			(end -0.7874 -0.4064)
			(stroke
				(width 0.1524)
				(type default)
			)
			(layer "F.SilkS")
		)
		(fp_line
			(start -0.7874 -0.4064)
			(end 0.7874 -0.4064)
			(stroke
				(width 0.1524)
				(type default)
			)
			(layer "F.SilkS")
		)
		(fp_poly
			(pts
				(xy -0.508 0.2794) (xy -0.508 0.2286) (xy -0.635 0.2286) (xy -0.635 -0.254) (xy -0.5334 -0.254)
				(xy -0.5334 -0.2794) (xy 0.5334 -0.2794) (xy 0.5334 -0.254) (xy 0.635 -0.254) (xy 0.635 0.254) (xy 0.5334 0.254)
				(xy 0.5334 0.2794)
			)
			(stroke
				(width 0)
				(type default)
			)
			(fill no)
			(layer "F.CrtYd")
		)
		(pad "1" smd rect
			(at 0.40005 0 180)
			(size 0.4572 0.508)
			(layers "F.Cu" "F.Mask" "F.Paste")
			(net "FNACTRL2_ADD")
		)
		(pad "2" smd rect
			(at -0.40005 0 180)
			(size 0.4572 0.508)
			(layers "F.Cu" "F.Mask" "F.Paste")
			(net "GND")
		)
	)
	(footprint ""
		(layer "F.Cu")
		(at 106.116374 -174.67961 -90)
		(property "Reference" "R765"
			(at -2.00787 1.077468 90)
			(unlocked yes)
			(layer "F.SilkS")
			(effects
				(font
					(size 0.7874 0.5842)
					(thickness 0.1524)
				)
				(justify left)
			)
		)
		(property "Value" ""
			(at 0 0 270)
			(layer "F.Fab")
			(effects
				(font
					(size 1.27 1.27)
				)
			)
		)
		(duplicate_pad_numbers_are_jumpers no)
		(fp_line
			(start -0.7874 0.4064)
			(end -0.7874 -0.4064)
			(stroke
				(width 0.1524)
				(type default)
			)
			(layer "F.SilkS")
		)
		(fp_line
			(start 0.7874 0.4064)
			(end -0.7874 0.4064)
			(stroke
				(width 0.1524)
				(type default)
			)
			(layer "F.SilkS")
		)
		(fp_line
			(start -0.7874 -0.4064)
			(end 0.7874 -0.4064)
			(stroke
				(width 0.1524)
				(type default)
			)
			(layer "F.SilkS")
		)
		(fp_line
			(start 0.7874 -0.4064)
			(end 0.7874 0.4064)
			(stroke
				(width 0.1524)
				(type default)
			)
			(layer "F.SilkS")
		)
		(fp_poly
			(pts
				(xy -0.508 0.2794) (xy -0.508 0.2286) (xy -0.635 0.2286) (xy -0.635 -0.254) (xy -0.5334 -0.254)
				(xy -0.5334 -0.2794) (xy 0.5334 -0.2794) (xy 0.5334 -0.254) (xy 0.635 -0.254) (xy 0.635 0.254) (xy 0.5334 0.254)
				(xy 0.5334 0.2794)
			)
			(stroke
				(width 0)
				(type default)
			)
			(fill no)
			(layer "F.CrtYd")
		)
		(pad "1" smd rect
			(at 0.40005 0 270)
			(size 0.4572 0.508)
			(layers "F.Cu" "F.Mask" "F.Paste")
			(net "I2C_SDA_FANCTRL1_R")
		)
		(pad "2" smd rect
			(at -0.40005 0 270)
			(size 0.4572 0.508)
			(layers "F.Cu" "F.Mask" "F.Paste")
			(net "I2C_COM3_SDA")
		)
	)
	(footprint ""
		(layer "F.Cu")
		(at 30.498288 -122.131582 90)
		(property "Reference" "C828"
			(at -2.965958 -2.225294 90)
			(unlocked yes)
			(layer "F.SilkS")
			(effects
				(font
					(size 0.7874 0.5842)
					(thickness 0.1524)
				)
				(justify left)
			)
		)
		(property "Value" ""
			(at 0 0 90)
			(layer "F.Fab")
			(effects
				(font
					(size 1.27 1.27)
				)
			)
		)
		(duplicate_pad_numbers_are_jumpers no)
		(fp_line
			(start 1.905 -0.8636)
			(end 1.905 0.8636)
			(stroke
				(width 0.1524)
				(type default)
			)
			(layer "F.SilkS")
		)
		(fp_line
			(start -1.905 -0.8636)
			(end 1.905 -0.8636)
			(stroke
				(width 0.1524)
				(type default)
			)
			(layer "F.SilkS")
		)
		(fp_line
			(start 0 0.8382)
			(end 0 -0.8382)
			(stroke
				(width 0.1524)
				(type default)
			)
			(layer "F.SilkS")
		)
		(fp_line
			(start 1.905 0.8636)
			(end -1.905 0.8636)
			(stroke
				(width 0.1524)
				(type default)
			)
			(layer "F.SilkS")
		)
		(fp_line
			(start -1.905 0.8636)
			(end -1.905 -0.8636)
			(stroke
				(width 0.1524)
				(type default)
			)
			(layer "F.SilkS")
		)
		(fp_rect
			(start -1.524 0.7366)
			(end 1.524 -0.7366)
			(stroke
				(width 0)
				(type default)
			)
			(fill no)
			(layer "F.CrtYd")
		)
		(pad "1" smd rect
			(at 0.94996 0 90)
			(size 1.1176 1.3716)
			(layers "F.Cu" "F.Mask" "F.Paste")
			(net "P1V8_NODE1")
		)
		(pad "2" smd rect
			(at -0.94996 0 90)
			(size 1.1176 1.3716)
			(layers "F.Cu" "F.Mask" "F.Paste")
			(net "GND")
		)
	)
	(footprint ""
		(layer "F.Cu")
		(at 15.061946 -134.017512 -90)
		(property "Reference" "PC70"
			(at -0.993648 0.04699 90)
			(unlocked yes)
			(layer "F.SilkS")
			(effects
				(font
					(size 0.7874 0.5842)
					(thickness 0.1524)
				)
				(justify left)
			)
		)
		(property "Value" ""
			(at 0 0 270)
			(layer "F.Fab")
			(effects
				(font
					(size 1.27 1.27)
				)
			)
		)
		(duplicate_pad_numbers_are_jumpers no)
		(fp_line
			(start -0.7874 0.4064)
			(end -0.7874 -0.4064)
			(stroke
				(width 0.1524)
				(type default)
			)
			(layer "F.SilkS")
		)
		(fp_line
			(start 0.7874 0.4064)
			(end -0.7874 0.4064)
			(stroke
				(width 0.1524)
				(type default)
			)
			(layer "F.SilkS")
		)
		(fp_line
			(start 0 0.381)
			(end 0 -0.381)
			(stroke
				(width 0.1524)
				(type default)
			)
			(layer "F.SilkS")
		)
		(fp_line
			(start -0.7874 -0.4064)
			(end 0.7874 -0.4064)
			(stroke
				(width 0.1524)
				(type default)
			)
			(layer "F.SilkS")
		)
		(fp_line
			(start 0.7874 -0.4064)
			(end 0.7874 0.4064)
			(stroke
				(width 0.1524)
				(type default)
			)
			(layer "F.SilkS")
		)
		(fp_poly
			(pts
				(xy -0.5334 0.254) (xy -0.635 0.254) (xy -0.635 0.2286) (xy -0.635 -0.254) (xy -0.5334 -0.254) (xy -0.5334 -0.2794)
				(xy 0.5334 -0.2794) (xy 0.5334 -0.254) (xy 0.635 -0.254) (xy 0.635 0.254) (xy 0.5334 0.254) (xy 0.5334 0.2794)
				(xy -0.508 0.2794) (xy -0.5334 0.2794)
			)
			(stroke
				(width 0)
				(type default)
			)
			(fill no)
			(layer "F.CrtYd")
		)
		(pad "1" smd rect
			(at 0.40005 0 270)
			(size 0.4572 0.508)
			(layers "F.Cu" "F.Mask" "F.Paste")
			(net "P1V05_NODE1_VSNS")
		)
		(pad "2" smd rect
			(at -0.40005 0 270)
			(size 0.4572 0.508)
			(layers "F.Cu" "F.Mask" "F.Paste")
			(net "GND")
		)
	)
	(footprint ""
		(layer "F.Cu")
		(at 94.451932 -165.139624)
		(property "Reference" "R768"
			(at 86.63305 73.147936 0)
			(unlocked yes)
			(layer "F.SilkS")
			(effects
				(font
					(size 0.7874 0.5842)
					(thickness 0.1524)
				)
				(justify left)
			)
		)
		(property "Value" ""
			(at 0 0 0)
			(layer "F.Fab")
			(effects
				(font
					(size 1.27 1.27)
				)
			)
		)
		(duplicate_pad_numbers_are_jumpers no)
		(fp_line
			(start -0.7874 -0.4064)
			(end 0.7874 -0.4064)
			(stroke
				(width 0.1524)
				(type default)
			)
			(layer "F.SilkS")
		)
		(fp_line
			(start -0.7874 0.4064)
			(end -0.7874 -0.4064)
			(stroke
				(width 0.1524)
				(type default)
			)
			(layer "F.SilkS")
		)
		(fp_line
			(start 0.7874 -0.4064)
			(end 0.7874 0.4064)
			(stroke
				(width 0.1524)
				(type default)
			)
			(layer "F.SilkS")
		)
		(fp_line
			(start 0.7874 0.4064)
			(end -0.7874 0.4064)
			(stroke
				(width 0.1524)
				(type default)
			)
			(layer "F.SilkS")
		)
		(fp_poly
			(pts
				(xy -0.508 0.2794) (xy -0.508 0.2286) (xy -0.635 0.2286) (xy -0.635 -0.254) (xy -0.5334 -0.254)
				(xy -0.5334 -0.2794) (xy 0.5334 -0.2794) (xy 0.5334 -0.254) (xy 0.635 -0.254) (xy 0.635 0.254) (xy 0.5334 0.254)
				(xy 0.5334 0.2794)
			)
			(stroke
				(width 0)
				(type default)
			)
			(fill no)
			(layer "F.CrtYd")
		)
		(pad "1" smd rect
			(at 0.40005 0)
			(size 0.4572 0.508)
			(layers "F.Cu" "F.Mask" "F.Paste")
			(net "FAN5_TACH_IN")
		)
		(pad "2" smd rect
			(at -0.40005 0)
			(size 0.4572 0.508)
			(layers "F.Cu" "F.Mask" "F.Paste")
			(net "FAN5_TACH")
		)
	)
	(footprint ""
		(layer "F.Cu")
		(at 35.243008 -186.620404)
		(property "Reference" "C768"
			(at -1.53162 -5.211064 0)
			(unlocked yes)
			(layer "F.SilkS")
			(effects
				(font
					(size 0.7874 0.5842)
					(thickness 0.1524)
				)
				(justify left)
			)
		)
		(property "Value" ""
			(at 0 0 0)
			(layer "F.Fab")
			(effects
				(font
					(size 1.27 1.27)
				)
			)
		)
		(duplicate_pad_numbers_are_jumpers no)
		(fp_line
			(start -0.7874 -0.4064)
			(end 0.7874 -0.4064)
			(stroke
				(width 0.1524)
				(type default)
			)
			(layer "F.SilkS")
		)
		(fp_line
			(start -0.7874 0.4064)
			(end -0.7874 -0.4064)
			(stroke
				(width 0.1524)
				(type default)
			)
			(layer "F.SilkS")
		)
		(fp_line
			(start 0 0.381)
			(end 0 -0.381)
			(stroke
				(width 0.1524)
				(type default)
			)
			(layer "F.SilkS")
		)
		(fp_line
			(start 0.7874 -0.4064)
			(end 0.7874 0.4064)
			(stroke
				(width 0.1524)
				(type default)
			)
			(layer "F.SilkS")
		)
		(fp_line
			(start 0.7874 0.4064)
			(end -0.7874 0.4064)
			(stroke
				(width 0.1524)
				(type default)
			)
			(layer "F.SilkS")
		)
		(fp_poly
			(pts
				(xy -0.5334 0.254) (xy -0.635 0.254) (xy -0.635 0.2286) (xy -0.635 -0.254) (xy -0.5334 -0.254) (xy -0.5334 -0.2794)
				(xy 0.5334 -0.2794) (xy 0.5334 -0.254) (xy 0.635 -0.254) (xy 0.635 0.254) (xy 0.5334 0.254) (xy 0.5334 0.2794)
				(xy -0.508 0.2794) (xy -0.5334 0.2794)
			)
			(stroke
				(width 0)
				(type default)
			)
			(fill no)
			(layer "F.CrtYd")
		)
		(pad "1" smd rect
			(at 0.40005 0)
			(size 0.4572 0.508)
			(layers "F.Cu" "F.Mask" "F.Paste")
			(net "P12V_PDB")
		)
		(pad "2" smd rect
			(at -0.40005 0)
			(size 0.4572 0.508)
			(layers "F.Cu" "F.Mask" "F.Paste")
			(net "GND")
		)
	)
	(footprint ""
		(layer "F.Cu")
		(at 157.58668 -101.105208 180)
		(property "Reference" "C364"
			(at 1.524 -2.075688 0)
			(unlocked yes)
			(layer "F.SilkS")
			(effects
				(font
					(size 0.7874 0.5842)
					(thickness 0.1524)
				)
				(justify left)
			)
		)
		(property "Value" ""
			(at 0 0 180)
			(layer "F.Fab")
			(effects
				(font
					(size 1.27 1.27)
				)
			)
		)
		(duplicate_pad_numbers_are_jumpers no)
		(fp_line
			(start 0.7874 0.4064)
			(end -0.7874 0.4064)
			(stroke
				(width 0.1524)
				(type default)
			)
			(layer "F.SilkS")
		)
		(fp_line
			(start 0.7874 -0.4064)
			(end 0.7874 0.4064)
			(stroke
				(width 0.1524)
				(type default)
			)
			(layer "F.SilkS")
		)
		(fp_line
			(start 0 0.381)
			(end 0 -0.381)
			(stroke
				(width 0.1524)
				(type default)
			)
			(layer "F.SilkS")
		)
		(fp_line
			(start -0.7874 0.4064)
			(end -0.7874 -0.4064)
			(stroke
				(width 0.1524)
				(type default)
			)
			(layer "F.SilkS")
		)
		(fp_line
			(start -0.7874 -0.4064)
			(end 0.7874 -0.4064)
			(stroke
				(width 0.1524)
				(type default)
			)
			(layer "F.SilkS")
		)
		(fp_poly
			(pts
				(xy -0.5334 0.254) (xy -0.635 0.254) (xy -0.635 0.2286) (xy -0.635 -0.254) (xy -0.5334 -0.254) (xy -0.5334 -0.2794)
				(xy 0.5334 -0.2794) (xy 0.5334 -0.254) (xy 0.635 -0.254) (xy 0.635 0.254) (xy 0.5334 0.254) (xy 0.5334 0.2794)
				(xy -0.508 0.2794) (xy -0.5334 0.2794)
			)
			(stroke
				(width 0)
				(type default)
			)
			(fill no)
			(layer "F.CrtYd")
		)
		(pad "1" smd rect
			(at 0.40005 0 180)
			(size 0.4572 0.508)
			(layers "F.Cu" "F.Mask" "F.Paste")
			(net "P2E_CPU_USB_NODE1_RX_DN")
		)
		(pad "2" smd rect
			(at -0.40005 0 180)
			(size 0.4572 0.508)
			(layers "F.Cu" "F.Mask" "F.Paste")
			(net "P2E_CPU_USB_NODE1_RX_C_DN")
		)
	)
	(footprint ""
		(layer "F.Cu")
		(at 147.245578 -57.249822 -90)
		(property "Reference" "R515"
			(at -14.50213 -26.0858 90)
			(unlocked yes)
			(layer "F.SilkS")
			(effects
				(font
					(size 0.7874 0.5842)
					(thickness 0.1524)
				)
				(justify left)
			)
		)
		(property "Value" ""
			(at 0 0 270)
			(layer "F.Fab")
			(effects
				(font
					(size 1.27 1.27)
				)
			)
		)
		(duplicate_pad_numbers_are_jumpers no)
		(fp_line
			(start -0.7874 0.4064)
			(end -0.7874 -0.4064)
			(stroke
				(width 0.1524)
				(type default)
			)
			(layer "F.SilkS")
		)
		(fp_line
			(start 0.7874 0.4064)
			(end -0.7874 0.4064)
			(stroke
				(width 0.1524)
				(type default)
			)
			(layer "F.SilkS")
		)
		(fp_line
			(start -0.7874 -0.4064)
			(end 0.7874 -0.4064)
			(stroke
				(width 0.1524)
				(type default)
			)
			(layer "F.SilkS")
		)
		(fp_line
			(start 0.7874 -0.4064)
			(end 0.7874 0.4064)
			(stroke
				(width 0.1524)
				(type default)
			)
			(layer "F.SilkS")
		)
		(fp_poly
			(pts
				(xy -0.508 0.2794) (xy -0.508 0.2286) (xy -0.635 0.2286) (xy -0.635 -0.254) (xy -0.5334 -0.254)
				(xy -0.5334 -0.2794) (xy 0.5334 -0.2794) (xy 0.5334 -0.254) (xy 0.635 -0.254) (xy 0.635 0.254) (xy 0.5334 0.254)
				(xy 0.5334 0.2794)
			)
			(stroke
				(width 0)
				(type default)
			)
			(fill no)
			(layer "F.CrtYd")
		)
		(pad "1" smd rect
			(at 0.40005 0 270)
			(size 0.4572 0.508)
			(layers "F.Cu" "F.Mask" "F.Paste")
			(net "GND")
		)
		(pad "2" smd rect
			(at -0.40005 0 270)
			(size 0.4572 0.508)
			(layers "F.Cu" "F.Mask" "F.Paste")
			(net "SATA_NODE1_GPIO3")
		)
	)
	(footprint ""
		(layer "F.Cu")
		(at 16.552926 -46.315884 -90)
		(property "Reference" "R639"
			(at 8.57885 0.929386 90)
			(unlocked yes)
			(layer "F.SilkS")
			(effects
				(font
					(size 0.7874 0.5842)
					(thickness 0.1524)
				)
				(justify left)
			)
		)
		(property "Value" ""
			(at 0 0 270)
			(layer "F.Fab")
			(effects
				(font
					(size 1.27 1.27)
				)
			)
		)
		(duplicate_pad_numbers_are_jumpers no)
		(fp_line
			(start -0.7874 0.4064)
			(end -0.7874 -0.4064)
			(stroke
				(width 0.1524)
				(type default)
			)
			(layer "F.SilkS")
		)
		(fp_line
			(start 0.7874 0.4064)
			(end -0.7874 0.4064)
			(stroke
				(width 0.1524)
				(type default)
			)
			(layer "F.SilkS")
		)
		(fp_line
			(start -0.7874 -0.4064)
			(end 0.7874 -0.4064)
			(stroke
				(width 0.1524)
				(type default)
			)
			(layer "F.SilkS")
		)
		(fp_line
			(start 0.7874 -0.4064)
			(end 0.7874 0.4064)
			(stroke
				(width 0.1524)
				(type default)
			)
			(layer "F.SilkS")
		)
		(fp_poly
			(pts
				(xy -0.508 0.2794) (xy -0.508 0.2286) (xy -0.635 0.2286) (xy -0.635 -0.254) (xy -0.5334 -0.254)
				(xy -0.5334 -0.2794) (xy 0.5334 -0.2794) (xy 0.5334 -0.254) (xy 0.635 -0.254) (xy 0.635 0.254) (xy 0.5334 0.254)
				(xy 0.5334 0.2794)
			)
			(stroke
				(width 0)
				(type default)
			)
			(fill no)
			(layer "F.CrtYd")
		)
		(pad "1" smd rect
			(at 0.40005 0 270)
			(size 0.4572 0.508)
			(layers "F.Cu" "F.Mask" "F.Paste")
			(net "I2C_VIDREAR_5V_SDA")
		)
		(pad "2" smd rect
			(at -0.40005 0 270)
			(size 0.4572 0.508)
			(layers "F.Cu" "F.Mask" "F.Paste")
			(net "CRT_DDCDATA")
		)
	)
	(footprint ""
		(layer "F.Cu")
		(at 120.63476 -175.426624 90)
		(property "Reference" "R796"
			(at -57.011316 32.536638 90)
			(unlocked yes)
			(layer "F.SilkS")
			(effects
				(font
					(size 0.7874 0.5842)
					(thickness 0.1524)
				)
				(justify left)
			)
		)
		(property "Value" ""
			(at 0 0 90)
			(layer "F.Fab")
			(effects
				(font
					(size 1.27 1.27)
				)
			)
		)
		(duplicate_pad_numbers_are_jumpers no)
		(fp_line
			(start 0.7874 -0.4064)
			(end 0.7874 0.4064)
			(stroke
				(width 0.1524)
				(type default)
			)
			(layer "F.SilkS")
		)
		(fp_line
			(start -0.7874 -0.4064)
			(end 0.7874 -0.4064)
			(stroke
				(width 0.1524)
				(type default)
			)
			(layer "F.SilkS")
		)
		(fp_line
			(start 0.7874 0.4064)
			(end -0.7874 0.4064)
			(stroke
				(width 0.1524)
				(type default)
			)
			(layer "F.SilkS")
		)
		(fp_line
			(start -0.7874 0.4064)
			(end -0.7874 -0.4064)
			(stroke
				(width 0.1524)
				(type default)
			)
			(layer "F.SilkS")
		)
		(fp_poly
			(pts
				(xy -0.508 0.2794) (xy -0.508 0.2286) (xy -0.635 0.2286) (xy -0.635 -0.254) (xy -0.5334 -0.254)
				(xy -0.5334 -0.2794) (xy 0.5334 -0.2794) (xy 0.5334 -0.254) (xy 0.635 -0.254) (xy 0.635 0.254) (xy 0.5334 0.254)
				(xy 0.5334 0.2794)
			)
			(stroke
				(width 0)
				(type default)
			)
			(fill no)
			(layer "F.CrtYd")
		)
		(pad "1" smd rect
			(at 0.40005 0 90)
			(size 0.4572 0.508)
			(layers "F.Cu" "F.Mask" "F.Paste")
			(net "N31328106")
		)
		(pad "2" smd rect
			(at -0.40005 0 90)
			(size 0.4572 0.508)
			(layers "F.Cu" "F.Mask" "F.Paste")
			(net "GND")
		)
	)
	(footprint ""
		(layer "F.Cu")
		(at 165.464998 -145.83283 -90)
		(property "Reference" "R589"
			(at -1.064768 2.666238 0)
			(unlocked yes)
			(layer "F.SilkS")
			(effects
				(font
					(size 0.635 0.4064)
					(thickness 0.1524)
				)
				(justify left)
			)
		)
		(property "Value" ""
			(at 0 0 270)
			(layer "F.Fab")
			(effects
				(font
					(size 1.27 1.27)
				)
			)
		)
		(duplicate_pad_numbers_are_jumpers no)
		(fp_line
			(start -0.7874 0.4064)
			(end -0.7874 -0.4064)
			(stroke
				(width 0.1524)
				(type default)
			)
			(layer "F.SilkS")
		)
		(fp_line
			(start 0.7874 0.4064)
			(end -0.7874 0.4064)
			(stroke
				(width 0.1524)
				(type default)
			)
			(layer "F.SilkS")
		)
		(fp_line
			(start -0.7874 -0.4064)
			(end 0.7874 -0.4064)
			(stroke
				(width 0.1524)
				(type default)
			)
			(layer "F.SilkS")
		)
		(fp_line
			(start 0.7874 -0.4064)
			(end 0.7874 0.4064)
			(stroke
				(width 0.1524)
				(type default)
			)
			(layer "F.SilkS")
		)
		(fp_poly
			(pts
				(xy -0.508 0.2794) (xy -0.508 0.2286) (xy -0.635 0.2286) (xy -0.635 -0.254) (xy -0.5334 -0.254)
				(xy -0.5334 -0.2794) (xy 0.5334 -0.2794) (xy 0.5334 -0.254) (xy 0.635 -0.254) (xy 0.635 0.254) (xy 0.5334 0.254)
				(xy 0.5334 0.2794)
			)
			(stroke
				(width 0)
				(type default)
			)
			(fill no)
			(layer "F.CrtYd")
		)
		(pad "1" smd rect
			(at 0.40005 0 270)
			(size 0.4572 0.508)
			(layers "F.Cu" "F.Mask" "F.Paste")
			(net "GND")
		)
		(pad "2" smd rect
			(at -0.40005 0 270)
			(size 0.4572 0.508)
			(layers "F.Cu" "F.Mask" "F.Paste")
			(net "LAN2_RST")
		)
	)
	(footprint ""
		(layer "F.Cu")
		(at 126.82728 -114.239294)
		(property "Reference" "R8"
			(at -0.625348 -2.0955 0)
			(unlocked yes)
			(layer "F.SilkS")
			(effects
				(font
					(size 0.7874 0.5842)
					(thickness 0.1524)
				)
				(justify left)
			)
		)
		(property "Value" ""
			(at 0 0 0)
			(layer "F.Fab")
			(effects
				(font
					(size 1.27 1.27)
				)
			)
		)
		(duplicate_pad_numbers_are_jumpers no)
		(fp_line
			(start -0.7874 -0.4064)
			(end 0.7874 -0.4064)
			(stroke
				(width 0.1524)
				(type default)
			)
			(layer "F.SilkS")
		)
		(fp_line
			(start -0.7874 0.4064)
			(end -0.7874 -0.4064)
			(stroke
				(width 0.1524)
				(type default)
			)
			(layer "F.SilkS")
		)
		(fp_line
			(start 0.7874 -0.4064)
			(end 0.7874 0.4064)
			(stroke
				(width 0.1524)
				(type default)
			)
			(layer "F.SilkS")
		)
		(fp_line
			(start 0.7874 0.4064)
			(end -0.7874 0.4064)
			(stroke
				(width 0.1524)
				(type default)
			)
			(layer "F.SilkS")
		)
		(fp_poly
			(pts
				(xy -0.508 0.2794) (xy -0.508 0.2286) (xy -0.635 0.2286) (xy -0.635 -0.254) (xy -0.5334 -0.254)
				(xy -0.5334 -0.2794) (xy 0.5334 -0.2794) (xy 0.5334 -0.254) (xy 0.635 -0.254) (xy 0.635 0.254) (xy 0.5334 0.254)
				(xy 0.5334 0.2794)
			)
			(stroke
				(width 0)
				(type default)
			)
			(fill no)
			(layer "F.CrtYd")
		)
		(pad "1" smd rect
			(at 0.40005 0)
			(size 0.4572 0.508)
			(layers "F.Cu" "F.Mask" "F.Paste")
			(net "FM_CPLD_CLK_R_PG_NODE1_R")
		)
		(pad "2" smd rect
			(at -0.40005 0)
			(size 0.4572 0.508)
			(layers "F.Cu" "F.Mask" "F.Paste")
			(net "P3V3_CLK_NODE1")
		)
	)
	(footprint ""
		(layer "F.Cu")
		(at 153.572972 -26.601928 180)
		(property "Reference" "C533"
			(at -5.442712 -0.855218 90)
			(unlocked yes)
			(layer "F.SilkS")
			(effects
				(font
					(size 0.7874 0.5842)
					(thickness 0.1524)
				)
				(justify left)
			)
		)
		(property "Value" ""
			(at 0 0 180)
			(layer "F.Fab")
			(effects
				(font
					(size 1.27 1.27)
				)
			)
		)
		(duplicate_pad_numbers_are_jumpers no)
		(fp_line
			(start 0.7874 0.4064)
			(end -0.7874 0.4064)
			(stroke
				(width 0.1524)
				(type default)
			)
			(layer "F.SilkS")
		)
		(fp_line
			(start 0.7874 -0.4064)
			(end 0.7874 0.4064)
			(stroke
				(width 0.1524)
				(type default)
			)
			(layer "F.SilkS")
		)
		(fp_line
			(start 0 0.381)
			(end 0 -0.381)
			(stroke
				(width 0.1524)
				(type default)
			)
			(layer "F.SilkS")
		)
		(fp_line
			(start -0.7874 0.4064)
			(end -0.7874 -0.4064)
			(stroke
				(width 0.1524)
				(type default)
			)
			(layer "F.SilkS")
		)
		(fp_line
			(start -0.7874 -0.4064)
			(end 0.7874 -0.4064)
			(stroke
				(width 0.1524)
				(type default)
			)
			(layer "F.SilkS")
		)
		(fp_poly
			(pts
				(xy -0.5334 0.254) (xy -0.635 0.254) (xy -0.635 0.2286) (xy -0.635 -0.254) (xy -0.5334 -0.254) (xy -0.5334 -0.2794)
				(xy 0.5334 -0.2794) (xy 0.5334 -0.254) (xy 0.635 -0.254) (xy 0.635 0.254) (xy 0.5334 0.254) (xy 0.5334 0.2794)
				(xy -0.508 0.2794) (xy -0.5334 0.2794)
			)
			(stroke
				(width 0)
				(type default)
			)
			(fill no)
			(layer "F.CrtYd")
		)
		(pad "1" smd rect
			(at 0.40005 0 180)
			(size 0.4572 0.508)
			(layers "F.Cu" "F.Mask" "F.Paste")
			(net "N21624848")
		)
		(pad "2" smd rect
			(at -0.40005 0 180)
			(size 0.4572 0.508)
			(layers "F.Cu" "F.Mask" "F.Paste")
			(net "N21624850")
		)
	)
	(footprint ""
		(layer "F.Cu")
		(at 176.58842 -48.354742 90)
		(property "Reference" "FS4"
			(at -0.050292 1.750568 90)
			(unlocked yes)
			(layer "F.SilkS")
			(effects
				(font
					(size 0.7874 0.5842)
					(thickness 0.1524)
				)
				(justify left)
			)
		)
		(property "Value" ""
			(at 0 0 90)
			(layer "F.Fab")
			(effects
				(font
					(size 1.27 1.27)
				)
			)
		)
		(duplicate_pad_numbers_are_jumpers no)
		(fp_line
			(start 3.550412 -1.050036)
			(end 3.550412 1.050036)
			(stroke
				(width 0.1524)
				(type default)
			)
			(layer "F.SilkS")
		)
		(fp_line
			(start -0.650494 -1.050036)
			(end 3.550412 -1.050036)
			(stroke
				(width 0.1524)
				(type default)
			)
			(layer "F.SilkS")
		)
		(fp_line
			(start 3.550412 1.050036)
			(end -0.650494 1.050036)
			(stroke
				(width 0.1524)
				(type default)
			)
			(layer "F.SilkS")
		)
		(fp_line
			(start -0.650494 1.050036)
			(end -0.650494 -1.050036)
			(stroke
				(width 0.1524)
				(type default)
			)
			(layer "F.SilkS")
		)
		(fp_poly
			(pts
				(xy 3.228086 -0.9652) (xy 3.228086 -1.100074) (xy -0.327914 -1.100074) (xy -0.327914 -0.9652) (xy -0.556514 -0.9652)
				(xy -0.556514 0.9652) (xy -0.327914 0.9652) (xy -0.327914 1.100074) (xy 3.228086 1.100074) (xy 3.228086 0.9652)
				(xy 3.456686 0.9652) (xy 3.456686 -0.9652)
			)
			(stroke
				(width 0)
				(type default)
			)
			(fill no)
			(layer "F.CrtYd")
		)
		(fp_text user "1"
			(at -1.18491 -1.651 0)
			(unlocked yes)
			(layer "F.SilkS")
			(effects
				(font
					(size 0.635 0.4064)
					(thickness 0.1524)
				)
				(justify left)
			)
		)
		(fp_text user "2"
			(at 3.151632 1.41351 0)
			(unlocked yes)
			(layer "F.SilkS")
			(effects
				(font
					(size 0.635 0.4064)
					(thickness 0.1524)
				)
				(justify left)
			)
		)
		(pad "1" smd rect
			(at 0 0 90)
			(size 1.016 1.8034)
			(layers "F.Cu" "F.Mask" "F.Paste")
			(net "P5V_NODE1")
		)
		(pad "2" smd rect
			(at 2.899918 0 90)
			(size 1.016 1.8034)
			(layers "F.Cu" "F.Mask" "F.Paste")
			(net "USBPWR_P1")
		)
	)
	(footprint ""
		(layer "F.Cu")
		(at 74.353166 -96.709992 -90)
		(property "Reference" "R105"
			(at 54.98719 -28.313888 90)
			(unlocked yes)
			(layer "F.SilkS")
			(effects
				(font
					(size 0.7874 0.5842)
					(thickness 0.1524)
				)
				(justify left)
			)
		)
		(property "Value" ""
			(at 0 0 270)
			(layer "F.Fab")
			(effects
				(font
					(size 1.27 1.27)
				)
			)
		)
		(duplicate_pad_numbers_are_jumpers no)
		(fp_line
			(start -0.7874 0.4064)
			(end -0.7874 -0.4064)
			(stroke
				(width 0.1524)
				(type default)
			)
			(layer "F.SilkS")
		)
		(fp_line
			(start 0.7874 0.4064)
			(end -0.7874 0.4064)
			(stroke
				(width 0.1524)
				(type default)
			)
			(layer "F.SilkS")
		)
		(fp_line
			(start -0.7874 -0.4064)
			(end 0.7874 -0.4064)
			(stroke
				(width 0.1524)
				(type default)
			)
			(layer "F.SilkS")
		)
		(fp_line
			(start 0.7874 -0.4064)
			(end 0.7874 0.4064)
			(stroke
				(width 0.1524)
				(type default)
			)
			(layer "F.SilkS")
		)
		(fp_poly
			(pts
				(xy -0.508 0.2794) (xy -0.508 0.2286) (xy -0.635 0.2286) (xy -0.635 -0.254) (xy -0.5334 -0.254)
				(xy -0.5334 -0.2794) (xy 0.5334 -0.2794) (xy 0.5334 -0.254) (xy 0.635 -0.254) (xy 0.635 0.254) (xy 0.5334 0.254)
				(xy 0.5334 0.2794)
			)
			(stroke
				(width 0)
				(type default)
			)
			(fill no)
			(layer "F.CrtYd")
		)
		(pad "1" smd rect
			(at 0.40005 0 270)
			(size 0.4572 0.508)
			(layers "F.Cu" "F.Mask" "F.Paste")
			(net "H_CPU_NODE1_ERR2_R")
		)
		(pad "2" smd rect
			(at -0.40005 0 270)
			(size 0.4572 0.508)
			(layers "F.Cu" "F.Mask" "F.Paste")
			(net "P3V3_NODE1")
		)
	)
	(footprint ""
		(layer "F.Cu")
		(at 21.928582 -56.828436 90)
		(property "Reference" "U44"
			(at -2.449068 13.606018 0)
			(unlocked yes)
			(layer "F.SilkS")
			(effects
				(font
					(size 0.7874 0.5842)
					(thickness 0.1524)
				)
			)
		)
		(property "Value" ""
			(at 0 0 90)
			(layer "F.Fab")
			(effects
				(font
					(size 1.27 1.27)
				)
			)
		)
		(duplicate_pad_numbers_are_jumpers no)
		(fp_line
			(start 1.651 -1.905)
			(end 1.651 1.905)
			(stroke
				(width 0.1524)
				(type default)
			)
			(layer "F.SilkS")
		)
		(fp_line
			(start -1.651 -1.905)
			(end 1.651 -1.905)
			(stroke
				(width 0.1524)
				(type default)
			)
			(layer "F.SilkS")
		)
		(fp_line
			(start 1.651 1.905)
			(end -1.651 1.905)
			(stroke
				(width 0.1524)
				(type default)
			)
			(layer "F.SilkS")
		)
		(fp_line
			(start -1.651 1.905)
			(end -1.651 -1.905)
			(stroke
				(width 0.1524)
				(type default)
			)
			(layer "F.SilkS")
		)
		(fp_poly
			(pts
				(xy -1.524 0.7112) (xy -1.524 1.7526) (xy -0.508 1.7526) (xy -0.508 0.6985) (xy 0.508 0.6985) (xy 0.508 1.7526)
				(xy 1.524 1.7526) (xy 1.524 0.6985) (xy 1.524 -0.6985) (xy 0.508 -0.6985) (xy 0.508 -1.7526) (xy -0.508 -1.7526)
				(xy -0.508 -0.6985) (xy -1.524 -0.6985) (xy -1.524 0.6985)
			)
			(stroke
				(width 0)
				(type default)
			)
			(fill no)
			(layer "F.CrtYd")
		)
		(fp_text user "3"
			(at -0.429514 -2.62509 0)
			(unlocked yes)
			(layer "F.SilkS")
			(effects
				(font
					(size 0.635 0.4064)
					(thickness 0.1524)
				)
			)
		)
		(fp_text user "2"
			(at 2.237486 1.81991 0)
			(unlocked yes)
			(layer "F.SilkS")
			(effects
				(font
					(size 0.635 0.4064)
					(thickness 0.1524)
				)
			)
		)
		(fp_text user "1"
			(at -0.683514 2.07391 0)
			(unlocked yes)
			(layer "F.SilkS")
			(effects
				(font
					(size 0.635 0.4064)
					(thickness 0.1524)
				)
			)
		)
		(pad "1" smd rect
			(at -1.016 1.1176 90)
			(size 1.016 1.27)
			(layers "F.Cu" "F.Mask" "F.Paste")
			(net "GND")
		)
		(pad "2" smd rect
			(at 1.016 1.1176 90)
			(size 1.016 1.27)
			(layers "F.Cu" "F.Mask" "F.Paste")
			(net "P5V_CRT")
		)
		(pad "3" smd rect
			(at 0 -1.1176 90)
			(size 1.016 1.27)
			(layers "F.Cu" "F.Mask" "F.Paste")
			(net "CRT_B")
		)
	)
	(footprint ""
		(layer "F.Cu")
		(at 182.45709 -149.212554 -90)
		(property "Reference" "R595"
			(at 1.75641 2.137918 90)
			(unlocked yes)
			(layer "F.SilkS")
			(effects
				(font
					(size 0.7874 0.5842)
					(thickness 0.1524)
				)
				(justify left)
			)
		)
		(property "Value" ""
			(at 0 0 270)
			(layer "F.Fab")
			(effects
				(font
					(size 1.27 1.27)
				)
			)
		)
		(duplicate_pad_numbers_are_jumpers no)
		(fp_line
			(start -2.2098 0.9398)
			(end -2.2098 -0.9398)
			(stroke
				(width 0.1524)
				(type default)
			)
			(layer "F.SilkS")
		)
		(fp_line
			(start 2.2098 0.9398)
			(end -2.2098 0.9398)
			(stroke
				(width 0.1524)
				(type default)
			)
			(layer "F.SilkS")
		)
		(fp_line
			(start -2.2098 -0.9398)
			(end 2.2098 -0.9398)
			(stroke
				(width 0.1524)
				(type default)
			)
			(layer "F.SilkS")
		)
		(fp_line
			(start 2.2098 -0.9398)
			(end 2.2098 0.9398)
			(stroke
				(width 0.1524)
				(type default)
			)
			(layer "F.SilkS")
		)
		(fp_poly
			(pts
				(xy 2.0574 0.8382) (xy 2.0574 -0.8382) (xy 2.0574 -0.9398) (xy -2.0574 -0.9398) (xy -2.0574 -0.8382)
				(xy -2.0574 0.8382) (xy -2.0574 0.9398) (xy 2.0574 0.9398)
			)
			(stroke
				(width 0)
				(type default)
			)
			(fill no)
			(layer "F.CrtYd")
		)
		(pad "1" smd rect
			(at 1.4732 0 270)
			(size 1.1684 1.5748)
			(layers "F.Cu" "F.Mask" "F.Paste")
			(net "LAN2_CTRL_P1V9")
		)
		(pad "2" smd rect
			(at -1.4732 0 270)
			(size 1.1684 1.5748)
			(layers "F.Cu" "F.Mask" "F.Paste")
			(net "LAN2_CTRL_P1V9_R")
		)
	)
	(footprint ""
		(layer "F.Cu")
		(at 162.035998 -142.04823 180)
		(property "Reference" "Y5"
			(at -0.320294 -2.38252 0)
			(unlocked yes)
			(layer "F.SilkS")
			(effects
				(font
					(size 0.7874 0.5842)
					(thickness 0.1524)
				)
				(justify left)
			)
		)
		(property "Value" ""
			(at 0 0 180)
			(layer "F.Fab")
			(effects
				(font
					(size 1.27 1.27)
				)
			)
		)
		(duplicate_pad_numbers_are_jumpers no)
		(fp_line
			(start 3.3528 1.700022)
			(end -3.3528 1.700022)
			(stroke
				(width 0.1524)
				(type default)
			)
			(layer "F.SilkS")
		)
		(fp_line
			(start 3.3528 -1.700022)
			(end 3.3528 1.700022)
			(stroke
				(width 0.1524)
				(type default)
			)
			(layer "F.SilkS")
		)
		(fp_line
			(start -3.3528 1.700022)
			(end -3.3528 -1.700022)
			(stroke
				(width 0.1524)
				(type default)
			)
			(layer "F.SilkS")
		)
		(fp_line
			(start -3.3528 -1.700022)
			(end 3.3528 -1.700022)
			(stroke
				(width 0.1524)
				(type default)
			)
			(layer "F.SilkS")
		)
		(fp_poly
			(pts
				(xy -2.599944 1.700022) (xy 2.599944 1.700022) (xy 2.599944 1.1176) (xy 3.2258 1.1176) (xy 3.2258 -1.1176)
				(xy 2.599944 -1.1176) (xy 2.599944 -1.700022) (xy -2.599944 -1.700022) (xy -2.599944 -1.1176) (xy -3.2258 -1.1176)
				(xy -3.2258 1.1176) (xy -2.599944 1.1176)
			)
			(stroke
				(width 0)
				(type default)
			)
			(fill no)
			(layer "F.CrtYd")
		)
		(fp_line
			(start 2.599944 1.700022)
			(end -2.599944 1.700022)
			(stroke
				(width 0.1)
				(type default)
			)
			(layer "F.Fab")
		)
		(fp_line
			(start 2.599944 -1.700022)
			(end 2.599944 1.700022)
			(stroke
				(width 0.1)
				(type default)
			)
			(layer "F.Fab")
		)
		(fp_line
			(start -2.599944 1.700022)
			(end -2.599944 -1.700022)
			(stroke
				(width 0.1)
				(type default)
			)
			(layer "F.Fab")
		)
		(fp_line
			(start -2.599944 -1.700022)
			(end 2.599944 -1.700022)
			(stroke
				(width 0.1)
				(type default)
			)
			(layer "F.Fab")
		)
		(pad "1" smd rect
			(at -2.100072 0 180)
			(size 2.2098 2.2098)
			(layers "F.Cu" "F.Mask" "F.Paste")
			(net "LAN2_XTAL_IN")
		)
		(pad "2" smd rect
			(at 2.100072 0 180)
			(size 2.2098 2.2098)
			(layers "F.Cu" "F.Mask" "F.Paste")
			(net "LAN2_XTAL_OUT")
		)
	)
	(footprint ""
		(layer "F.Cu")
		(at 127.568452 -153.67635 90)
		(property "Reference" "R296"
			(at -111.020352 -58.8264 90)
			(unlocked yes)
			(layer "F.SilkS")
			(effects
				(font
					(size 0.7874 0.5842)
					(thickness 0.1524)
				)
				(justify left)
			)
		)
		(property "Value" ""
			(at 0 0 90)
			(layer "F.Fab")
			(effects
				(font
					(size 1.27 1.27)
				)
			)
		)
		(duplicate_pad_numbers_are_jumpers no)
		(fp_line
			(start 0.7874 -0.4064)
			(end 0.7874 0.4064)
			(stroke
				(width 0.1524)
				(type default)
			)
			(layer "F.SilkS")
		)
		(fp_line
			(start -0.7874 -0.4064)
			(end 0.7874 -0.4064)
			(stroke
				(width 0.1524)
				(type default)
			)
			(layer "F.SilkS")
		)
		(fp_line
			(start 0.7874 0.4064)
			(end -0.7874 0.4064)
			(stroke
				(width 0.1524)
				(type default)
			)
			(layer "F.SilkS")
		)
		(fp_line
			(start -0.7874 0.4064)
			(end -0.7874 -0.4064)
			(stroke
				(width 0.1524)
				(type default)
			)
			(layer "F.SilkS")
		)
		(fp_poly
			(pts
				(xy -0.508 0.2794) (xy -0.508 0.2286) (xy -0.635 0.2286) (xy -0.635 -0.254) (xy -0.5334 -0.254)
				(xy -0.5334 -0.2794) (xy 0.5334 -0.2794) (xy 0.5334 -0.254) (xy 0.635 -0.254) (xy 0.635 0.254) (xy 0.5334 0.254)
				(xy 0.5334 0.2794)
			)
			(stroke
				(width 0)
				(type default)
			)
			(fill no)
			(layer "F.CrtYd")
		)
		(pad "1" smd rect
			(at 0.40005 0 90)
			(size 0.4572 0.508)
			(layers "F.Cu" "F.Mask" "F.Paste")
			(net "GND")
		)
		(pad "2" smd rect
			(at -0.40005 0 90)
			(size 0.4572 0.508)
			(layers "F.Cu" "F.Mask" "F.Paste")
			(net "PCIE_SW_TMS")
		)
	)
	(footprint ""
		(layer "F.Cu")
		(at 111.699548 -131.998974 90)
		(property "Reference" "PR42"
			(at -0.694944 5.295646 90)
			(unlocked yes)
			(layer "F.SilkS")
			(effects
				(font
					(size 0.7874 0.5842)
					(thickness 0.1524)
				)
				(justify left)
			)
		)
		(property "Value" ""
			(at 0 0 90)
			(layer "F.Fab")
			(effects
				(font
					(size 1.27 1.27)
				)
			)
		)
		(duplicate_pad_numbers_are_jumpers no)
		(fp_line
			(start 0.7874 -0.4064)
			(end 0.7874 0.4064)
			(stroke
				(width 0.1524)
				(type default)
			)
			(layer "F.SilkS")
		)
		(fp_line
			(start -0.7874 -0.4064)
			(end 0.7874 -0.4064)
			(stroke
				(width 0.1524)
				(type default)
			)
			(layer "F.SilkS")
		)
		(fp_line
			(start 0.7874 0.4064)
			(end -0.7874 0.4064)
			(stroke
				(width 0.1524)
				(type default)
			)
			(layer "F.SilkS")
		)
		(fp_line
			(start -0.7874 0.4064)
			(end -0.7874 -0.4064)
			(stroke
				(width 0.1524)
				(type default)
			)
			(layer "F.SilkS")
		)
		(fp_poly
			(pts
				(xy -0.508 0.2794) (xy -0.508 0.2286) (xy -0.635 0.2286) (xy -0.635 -0.254) (xy -0.5334 -0.254)
				(xy -0.5334 -0.2794) (xy 0.5334 -0.2794) (xy 0.5334 -0.254) (xy 0.635 -0.254) (xy 0.635 0.254) (xy 0.5334 0.254)
				(xy 0.5334 0.2794)
			)
			(stroke
				(width 0)
				(type default)
			)
			(fill no)
			(layer "F.CrtYd")
		)
		(pad "1" smd rect
			(at 0.40005 0 90)
			(size 0.4572 0.508)
			(layers "F.Cu" "F.Mask" "F.Paste")
			(net "VR_PVCCP_NODE1_TONSET")
		)
		(pad "2" smd rect
			(at -0.40005 0 90)
			(size 0.4572 0.508)
			(layers "F.Cu" "F.Mask" "F.Paste")
			(net "VR_PVCCP_NODE1_TONSET_R")
		)
	)
	(footprint ""
		(layer "F.Cu")
		(at 148.937726 -150.264368 90)
		(property "Reference" "R1227"
			(at -2.863596 1.071118 90)
			(unlocked yes)
			(layer "F.SilkS")
			(effects
				(font
					(size 0.7874 0.5842)
					(thickness 0.1524)
				)
				(justify left)
			)
		)
		(property "Value" ""
			(at 0 0 90)
			(layer "F.Fab")
			(effects
				(font
					(size 1.27 1.27)
				)
			)
		)
		(duplicate_pad_numbers_are_jumpers no)
		(fp_line
			(start 0.7874 -0.4064)
			(end 0.7874 0.4064)
			(stroke
				(width 0.1524)
				(type default)
			)
			(layer "F.SilkS")
		)
		(fp_line
			(start -0.7874 -0.4064)
			(end 0.7874 -0.4064)
			(stroke
				(width 0.1524)
				(type default)
			)
			(layer "F.SilkS")
		)
		(fp_line
			(start 0.7874 0.4064)
			(end -0.7874 0.4064)
			(stroke
				(width 0.1524)
				(type default)
			)
			(layer "F.SilkS")
		)
		(fp_line
			(start -0.7874 0.4064)
			(end -0.7874 -0.4064)
			(stroke
				(width 0.1524)
				(type default)
			)
			(layer "F.SilkS")
		)
		(fp_poly
			(pts
				(xy -0.508 0.2794) (xy -0.508 0.2286) (xy -0.635 0.2286) (xy -0.635 -0.254) (xy -0.5334 -0.254)
				(xy -0.5334 -0.2794) (xy 0.5334 -0.2794) (xy 0.5334 -0.254) (xy 0.635 -0.254) (xy 0.635 0.254) (xy 0.5334 0.254)
				(xy 0.5334 0.2794)
			)
			(stroke
				(width 0)
				(type default)
			)
			(fill no)
			(layer "F.CrtYd")
		)
		(pad "1" smd rect
			(at 0.40005 0 90)
			(size 0.4572 0.508)
			(layers "F.Cu" "F.Mask" "F.Paste")
			(net "PCIE_SW_WP_N")
		)
		(pad "2" smd rect
			(at -0.40005 0 90)
			(size 0.4572 0.508)
			(layers "F.Cu" "F.Mask" "F.Paste")
			(net "GND")
		)
	)
	(footprint ""
		(layer "F.Cu")
		(at 128.77927 -110.92815)
		(property "Reference" "C13"
			(at -5.883656 -0.032512 0)
			(unlocked yes)
			(layer "F.SilkS")
			(effects
				(font
					(size 0.7874 0.5842)
					(thickness 0.1524)
				)
				(justify left)
			)
		)
		(property "Value" ""
			(at 0 0 0)
			(layer "F.Fab")
			(effects
				(font
					(size 1.27 1.27)
				)
			)
		)
		(duplicate_pad_numbers_are_jumpers no)
		(fp_line
			(start -0.7874 -0.4064)
			(end 0.7874 -0.4064)
			(stroke
				(width 0.1524)
				(type default)
			)
			(layer "F.SilkS")
		)
		(fp_line
			(start -0.7874 0.4064)
			(end -0.7874 -0.4064)
			(stroke
				(width 0.1524)
				(type default)
			)
			(layer "F.SilkS")
		)
		(fp_line
			(start 0 0.381)
			(end 0 -0.381)
			(stroke
				(width 0.1524)
				(type default)
			)
			(layer "F.SilkS")
		)
		(fp_line
			(start 0.7874 -0.4064)
			(end 0.7874 0.4064)
			(stroke
				(width 0.1524)
				(type default)
			)
			(layer "F.SilkS")
		)
		(fp_line
			(start 0.7874 0.4064)
			(end -0.7874 0.4064)
			(stroke
				(width 0.1524)
				(type default)
			)
			(layer "F.SilkS")
		)
		(fp_poly
			(pts
				(xy -0.5334 0.254) (xy -0.635 0.254) (xy -0.635 0.2286) (xy -0.635 -0.254) (xy -0.5334 -0.254) (xy -0.5334 -0.2794)
				(xy 0.5334 -0.2794) (xy 0.5334 -0.254) (xy 0.635 -0.254) (xy 0.635 0.254) (xy 0.5334 0.254) (xy 0.5334 0.2794)
				(xy -0.508 0.2794) (xy -0.5334 0.2794)
			)
			(stroke
				(width 0)
				(type default)
			)
			(fill no)
			(layer "F.CrtYd")
		)
		(pad "1" smd rect
			(at 0.40005 0)
			(size 0.4572 0.508)
			(layers "F.Cu" "F.Mask" "F.Paste")
			(net "XTAL_CLK_NODE1_X2")
		)
		(pad "2" smd rect
			(at -0.40005 0)
			(size 0.4572 0.508)
			(layers "F.Cu" "F.Mask" "F.Paste")
			(net "GND")
		)
	)
	(footprint ""
		(layer "F.Cu")
		(at 115.478052 -42.45356 -90)
		(property "Reference" "OSC4"
			(at 4.26339 0.976884 0)
			(unlocked yes)
			(layer "F.SilkS")
			(effects
				(font
					(size 0.7874 0.5842)
					(thickness 0.1524)
				)
				(justify left)
			)
		)
		(property "Value" ""
			(at 0 0 270)
			(layer "F.Fab")
			(effects
				(font
					(size 1.27 1.27)
				)
			)
		)
		(duplicate_pad_numbers_are_jumpers no)
		(fp_line
			(start -3.599942 2.599944)
			(end -3.599942 -2.599944)
			(stroke
				(width 0.1524)
				(type default)
			)
			(layer "F.SilkS")
		)
		(fp_line
			(start 3.599942 2.599944)
			(end -3.599942 2.599944)
			(stroke
				(width 0.1524)
				(type default)
			)
			(layer "F.SilkS")
		)
		(fp_line
			(start -3.599942 -2.599944)
			(end 3.599942 -2.599944)
			(stroke
				(width 0.1524)
				(type default)
			)
			(layer "F.SilkS")
		)
		(fp_line
			(start 3.599942 -2.599944)
			(end 3.599942 2.599944)
			(stroke
				(width 0.1524)
				(type default)
			)
			(layer "F.SilkS")
		)
		(fp_poly
			(pts
				(xy -2.54 2.667) (xy -3.302 4.191) (xy -1.778 4.191)
			)
			(stroke
				(width 0)
				(type default)
			)
			(fill yes)
			(layer "F.SilkS")
		)
		(fp_rect
			(start -3.599942 2.599944)
			(end 3.599942 -2.599944)
			(stroke
				(width 0)
				(type default)
			)
			(fill no)
			(layer "F.CrtYd")
		)
		(fp_line
			(start -3.599942 2.599944)
			(end -3.599942 -2.599944)
			(stroke
				(width 0.1)
				(type default)
			)
			(layer "F.Fab")
		)
		(fp_line
			(start 3.599942 2.599944)
			(end -3.599942 2.599944)
			(stroke
				(width 0.1)
				(type default)
			)
			(layer "F.Fab")
		)
		(fp_line
			(start -3.599942 -2.599944)
			(end 3.599942 -2.599944)
			(stroke
				(width 0.1)
				(type default)
			)
			(layer "F.Fab")
		)
		(fp_line
			(start 3.599942 -2.599944)
			(end 3.599942 2.599944)
			(stroke
				(width 0.1)
				(type default)
			)
			(layer "F.Fab")
		)
		(fp_poly
			(pts
				(xy -2.54 2.667) (xy -3.302 4.191) (xy -1.778 4.191)
			)
			(stroke
				(width 0)
				(type default)
			)
			(fill yes)
			(layer "F.Fab")
		)
		(fp_text user "2"
			(at 2.692146 3.206496 0)
			(unlocked yes)
			(layer "F.SilkS")
			(effects
				(font
					(size 0.635 0.4064)
					(thickness 0.1524)
				)
				(justify left)
			)
		)
		(fp_text user "1"
			(at -1.845056 3.151378 0)
			(unlocked yes)
			(layer "F.SilkS")
			(effects
				(font
					(size 0.635 0.4064)
					(thickness 0.1524)
				)
				(justify left)
			)
		)
		(fp_text user "3"
			(at -0.430276 -2.766568 0)
			(unlocked yes)
			(layer "F.SilkS")
			(effects
				(font
					(size 0.635 0.4064)
					(thickness 0.1524)
				)
				(justify left)
			)
		)
		(fp_text user "4"
			(at -2.545334 -2.769108 0)
			(unlocked yes)
			(layer "F.SilkS")
			(effects
				(font
					(size 0.7874 0.5842)
					(thickness 0.1524)
				)
				(justify left)
			)
		)
		(fp_text user "1"
			(at -3.5941 3.337052 270)
			(unlocked yes)
			(layer "F.Fab")
			(effects
				(font
					(size 0.7874 0.5842)
					(thickness 0.000001)
				)
				(justify left)
			)
		)
		(fp_text user "2"
			(at 2.2479 3.337052 270)
			(unlocked yes)
			(layer "F.Fab")
			(effects
				(font
					(size 0.7874 0.5842)
					(thickness 0.000001)
				)
				(justify left)
			)
		)
		(fp_text user "4"
			(at -2.8321 -3.139948 270)
			(unlocked yes)
			(layer "F.Fab")
			(effects
				(font
					(size 0.7874 0.5842)
					(thickness 0.000001)
				)
				(justify left)
			)
		)
		(fp_text user "3"
			(at 2.2479 -3.139948 270)
			(unlocked yes)
			(layer "F.Fab")
			(effects
				(font
					(size 0.7874 0.5842)
					(thickness 0.000001)
				)
				(justify left)
			)
		)
		(pad "1" smd rect
			(at -2.54 1.849882)
			(size 1.1176 1.4224)
			(layers "F.Cu" "F.Mask" "F.Paste")
			(net "N21550241")
		)
		(pad "2" smd rect
			(at 2.54 1.849882)
			(size 1.1176 1.4224)
			(layers "F.Cu" "F.Mask" "F.Paste")
			(net "GND")
		)
		(pad "3" smd rect
			(at 2.54 -1.849882)
			(size 1.1176 1.4224)
			(layers "F.Cu" "F.Mask" "F.Paste")
			(net "OSC1_48MHZ")
		)
		(pad "4" smd rect
			(at -2.54 -1.849882)
			(size 1.1176 1.4224)
			(layers "F.Cu" "F.Mask" "F.Paste")
			(net "N46114787")
		)
	)
	(footprint ""
		(layer "F.Cu")
		(at 111.21771 -140.547598)
		(property "Reference" "PR60"
			(at 2.96545 -4.32435 0)
			(unlocked yes)
			(layer "F.SilkS")
			(effects
				(font
					(size 0.635 0.4064)
					(thickness 0.1524)
				)
				(justify left)
			)
		)
		(property "Value" ""
			(at 0 0 0)
			(layer "F.Fab")
			(effects
				(font
					(size 1.27 1.27)
				)
			)
		)
		(duplicate_pad_numbers_are_jumpers no)
		(fp_line
			(start -0.7874 -0.4064)
			(end 0.7874 -0.4064)
			(stroke
				(width 0.1524)
				(type default)
			)
			(layer "F.SilkS")
		)
		(fp_line
			(start -0.7874 0.4064)
			(end -0.7874 -0.4064)
			(stroke
				(width 0.1524)
				(type default)
			)
			(layer "F.SilkS")
		)
		(fp_line
			(start 0.7874 -0.4064)
			(end 0.7874 0.4064)
			(stroke
				(width 0.1524)
				(type default)
			)
			(layer "F.SilkS")
		)
		(fp_line
			(start 0.7874 0.4064)
			(end -0.7874 0.4064)
			(stroke
				(width 0.1524)
				(type default)
			)
			(layer "F.SilkS")
		)
		(fp_poly
			(pts
				(xy -0.508 0.2794) (xy -0.508 0.2286) (xy -0.635 0.2286) (xy -0.635 -0.254) (xy -0.5334 -0.254)
				(xy -0.5334 -0.2794) (xy 0.5334 -0.2794) (xy 0.5334 -0.254) (xy 0.635 -0.254) (xy 0.635 0.254) (xy 0.5334 0.254)
				(xy 0.5334 0.2794)
			)
			(stroke
				(width 0)
				(type default)
			)
			(fill no)
			(layer "F.CrtYd")
		)
		(pad "1" smd rect
			(at 0.40005 0)
			(size 0.4572 0.508)
			(layers "F.Cu" "F.Mask" "F.Paste")
			(net "AGND_PVCCP_NODE1")
		)
		(pad "2" smd rect
			(at -0.40005 0)
			(size 0.4572 0.508)
			(layers "F.Cu" "F.Mask" "F.Paste")
			(net "VR_PVCCP_NODE1_SETINI")
		)
	)
	(footprint ""
		(layer "F.Cu")
		(at 99.455986 -154.3177 -90)
		(property "Reference" "PC36"
			(at -0.964692 -0.001016 90)
			(unlocked yes)
			(layer "F.SilkS")
			(effects
				(font
					(size 0.7874 0.5842)
					(thickness 0.1524)
				)
				(justify left)
			)
		)
		(property "Value" ""
			(at 0 0 270)
			(layer "F.Fab")
			(effects
				(font
					(size 1.27 1.27)
				)
			)
		)
		(duplicate_pad_numbers_are_jumpers no)
		(fp_line
			(start -0.7874 0.4064)
			(end -0.7874 -0.4064)
			(stroke
				(width 0.1524)
				(type default)
			)
			(layer "F.SilkS")
		)
		(fp_line
			(start 0.7874 0.4064)
			(end -0.7874 0.4064)
			(stroke
				(width 0.1524)
				(type default)
			)
			(layer "F.SilkS")
		)
		(fp_line
			(start 0 0.381)
			(end 0 -0.381)
			(stroke
				(width 0.1524)
				(type default)
			)
			(layer "F.SilkS")
		)
		(fp_line
			(start -0.7874 -0.4064)
			(end 0.7874 -0.4064)
			(stroke
				(width 0.1524)
				(type default)
			)
			(layer "F.SilkS")
		)
		(fp_line
			(start 0.7874 -0.4064)
			(end 0.7874 0.4064)
			(stroke
				(width 0.1524)
				(type default)
			)
			(layer "F.SilkS")
		)
		(fp_poly
			(pts
				(xy -0.5334 0.254) (xy -0.635 0.254) (xy -0.635 0.2286) (xy -0.635 -0.254) (xy -0.5334 -0.254) (xy -0.5334 -0.2794)
				(xy 0.5334 -0.2794) (xy 0.5334 -0.254) (xy 0.635 -0.254) (xy 0.635 0.254) (xy 0.5334 0.254) (xy 0.5334 0.2794)
				(xy -0.508 0.2794) (xy -0.5334 0.2794)
			)
			(stroke
				(width 0)
				(type default)
			)
			(fill no)
			(layer "F.CrtYd")
		)
		(pad "1" smd rect
			(at 0.40005 0 270)
			(size 0.4572 0.508)
			(layers "F.Cu" "F.Mask" "F.Paste")
			(net "SW_P1V8_STB_NODE1_BT")
		)
		(pad "2" smd rect
			(at -0.40005 0 270)
			(size 0.4572 0.508)
			(layers "F.Cu" "F.Mask" "F.Paste")
			(net "SW_P1V8_STB_NODE1_PH")
		)
	)
	(footprint ""
		(layer "F.Cu")
		(at 64.24676 -188.126624 -90)
		(property "Reference" "R931"
			(at -4.548886 0.146558 90)
			(unlocked yes)
			(layer "F.SilkS")
			(effects
				(font
					(size 0.7874 0.5842)
					(thickness 0.1524)
				)
				(justify left)
			)
		)
		(property "Value" ""
			(at 0 0 270)
			(layer "F.Fab")
			(effects
				(font
					(size 1.27 1.27)
				)
			)
		)
		(duplicate_pad_numbers_are_jumpers no)
		(fp_line
			(start -0.7874 0.406146)
			(end -0.7874 -0.406146)
			(stroke
				(width 0.1524)
				(type default)
			)
			(layer "F.SilkS")
		)
		(fp_line
			(start 0.7874 0.406146)
			(end -0.7874 0.406146)
			(stroke
				(width 0.1524)
				(type default)
			)
			(layer "F.SilkS")
		)
		(fp_line
			(start -0.7874 -0.406146)
			(end 0.7874 -0.406146)
			(stroke
				(width 0.1524)
				(type default)
			)
			(layer "F.SilkS")
		)
		(fp_line
			(start 0.7874 -0.406146)
			(end 0.7874 0.406146)
			(stroke
				(width 0.1524)
				(type default)
			)
			(layer "F.SilkS")
		)
		(fp_poly
			(pts
				(xy -0.508 0.2794) (xy -0.508 0.2286) (xy -0.635 0.2286) (xy -0.635 -0.254) (xy -0.5334 -0.254)
				(xy -0.5334 -0.2794) (xy 0.5334 -0.2794) (xy 0.5334 -0.254) (xy 0.635 -0.254) (xy 0.635 0.254) (xy 0.5334 0.254)
				(xy 0.5334 0.2794)
			)
			(stroke
				(width 0)
				(type default)
			)
			(fill no)
			(layer "F.CrtYd")
		)
		(pad "1" smd rect
			(at 0.40005 0 270)
			(size 0.4572 0.508)
			(layers "F.Cu" "F.Mask" "F.Paste")
			(net "UART_T2_NODE1_RXD")
		)
		(pad "2" smd rect
			(at -0.40005 0 270)
			(size 0.4572 0.508)
			(layers "F.Cu" "F.Mask" "F.Paste")
			(net "UART_T2_NODE1_RXD_R")
		)
	)
	(footprint ""
		(layer "F.Cu")
		(at 43.498516 -4.177538 90)
		(property "Reference" "PC75"
			(at -3.59791 -13.713968 90)
			(unlocked yes)
			(layer "F.SilkS")
			(effects
				(font
					(size 0.7874 0.5842)
					(thickness 0.1524)
				)
				(justify left)
			)
		)
		(property "Value" ""
			(at 0 0 90)
			(layer "F.Fab")
			(effects
				(font
					(size 1.27 1.27)
				)
			)
		)
		(duplicate_pad_numbers_are_jumpers no)
		(fp_line
			(start 0.7874 -0.4064)
			(end 0.7874 0.4064)
			(stroke
				(width 0.1524)
				(type default)
			)
			(layer "F.SilkS")
		)
		(fp_line
			(start -0.7874 -0.4064)
			(end 0.7874 -0.4064)
			(stroke
				(width 0.1524)
				(type default)
			)
			(layer "F.SilkS")
		)
		(fp_line
			(start 0 0.381)
			(end 0 -0.381)
			(stroke
				(width 0.1524)
				(type default)
			)
			(layer "F.SilkS")
		)
		(fp_line
			(start 0.7874 0.4064)
			(end -0.7874 0.4064)
			(stroke
				(width 0.1524)
				(type default)
			)
			(layer "F.SilkS")
		)
		(fp_line
			(start -0.7874 0.4064)
			(end -0.7874 -0.4064)
			(stroke
				(width 0.1524)
				(type default)
			)
			(layer "F.SilkS")
		)
		(fp_poly
			(pts
				(xy -0.5334 0.254) (xy -0.635 0.254) (xy -0.635 0.2286) (xy -0.635 -0.254) (xy -0.5334 -0.254) (xy -0.5334 -0.2794)
				(xy 0.5334 -0.2794) (xy 0.5334 -0.254) (xy 0.635 -0.254) (xy 0.635 0.254) (xy 0.5334 0.254) (xy 0.5334 0.2794)
				(xy -0.508 0.2794) (xy -0.5334 0.2794)
			)
			(stroke
				(width 0)
				(type default)
			)
			(fill no)
			(layer "F.CrtYd")
		)
		(pad "1" smd rect
			(at 0.40005 0 90)
			(size 0.4572 0.508)
			(layers "F.Cu" "F.Mask" "F.Paste")
			(net "SW_PV_VDDR_NODE1_VIN_FLT")
		)
		(pad "2" smd rect
			(at -0.40005 0 90)
			(size 0.4572 0.508)
			(layers "F.Cu" "F.Mask" "F.Paste")
			(net "GND")
		)
	)
	(footprint ""
		(layer "F.Cu")
		(at 114.473228 -18.60931 90)
		(property "Reference" "C198"
			(at -1.661668 5.643118 90)
			(unlocked yes)
			(layer "F.SilkS")
			(effects
				(font
					(size 0.7874 0.5842)
					(thickness 0.1524)
				)
				(justify left)
			)
		)
		(property "Value" ""
			(at 0 0 90)
			(layer "F.Fab")
			(effects
				(font
					(size 1.27 1.27)
				)
			)
		)
		(duplicate_pad_numbers_are_jumpers no)
		(fp_line
			(start 0.7874 -0.4064)
			(end 0.7874 0.4064)
			(stroke
				(width 0.1524)
				(type default)
			)
			(layer "F.SilkS")
		)
		(fp_line
			(start -0.7874 -0.4064)
			(end 0.7874 -0.4064)
			(stroke
				(width 0.1524)
				(type default)
			)
			(layer "F.SilkS")
		)
		(fp_line
			(start 0 0.381)
			(end 0 -0.381)
			(stroke
				(width 0.1524)
				(type default)
			)
			(layer "F.SilkS")
		)
		(fp_line
			(start 0.7874 0.4064)
			(end -0.7874 0.4064)
			(stroke
				(width 0.1524)
				(type default)
			)
			(layer "F.SilkS")
		)
		(fp_line
			(start -0.7874 0.4064)
			(end -0.7874 -0.4064)
			(stroke
				(width 0.1524)
				(type default)
			)
			(layer "F.SilkS")
		)
		(fp_poly
			(pts
				(xy -0.5334 0.254) (xy -0.635 0.254) (xy -0.635 0.2286) (xy -0.635 -0.254) (xy -0.5334 -0.254) (xy -0.5334 -0.2794)
				(xy 0.5334 -0.2794) (xy 0.5334 -0.254) (xy 0.635 -0.254) (xy 0.635 0.254) (xy 0.5334 0.254) (xy 0.5334 0.2794)
				(xy -0.508 0.2794) (xy -0.5334 0.2794)
			)
			(stroke
				(width 0)
				(type default)
			)
			(fill no)
			(layer "F.CrtYd")
		)
		(pad "1" smd rect
			(at 0.40005 0 90)
			(size 0.4572 0.508)
			(layers "F.Cu" "F.Mask" "F.Paste")
			(net "FM_CPLD_NODE1_PVTT_DDR_EN")
		)
		(pad "2" smd rect
			(at -0.40005 0 90)
			(size 0.4572 0.508)
			(layers "F.Cu" "F.Mask" "F.Paste")
			(net "GND")
		)
	)
	(footprint ""
		(layer "F.Cu")
		(at 13.039598 -133.21919 -90)
		(property "Reference" "PR29"
			(at 0.50546 2.120138 90)
			(unlocked yes)
			(layer "F.SilkS")
			(effects
				(font
					(size 0.7874 0.5842)
					(thickness 0.1524)
				)
				(justify left)
			)
		)
		(property "Value" ""
			(at 0 0 270)
			(layer "F.Fab")
			(effects
				(font
					(size 1.27 1.27)
				)
			)
		)
		(duplicate_pad_numbers_are_jumpers no)
		(fp_line
			(start -0.7874 0.4064)
			(end -0.7874 -0.4064)
			(stroke
				(width 0.1524)
				(type default)
			)
			(layer "F.SilkS")
		)
		(fp_line
			(start 0.7874 0.4064)
			(end -0.7874 0.4064)
			(stroke
				(width 0.1524)
				(type default)
			)
			(layer "F.SilkS")
		)
		(fp_line
			(start -0.7874 -0.4064)
			(end 0.7874 -0.4064)
			(stroke
				(width 0.1524)
				(type default)
			)
			(layer "F.SilkS")
		)
		(fp_line
			(start 0.7874 -0.4064)
			(end 0.7874 0.4064)
			(stroke
				(width 0.1524)
				(type default)
			)
			(layer "F.SilkS")
		)
		(fp_poly
			(pts
				(xy -0.508 0.2794) (xy -0.508 0.2286) (xy -0.635 0.2286) (xy -0.635 -0.254) (xy -0.5334 -0.254)
				(xy -0.5334 -0.2794) (xy 0.5334 -0.2794) (xy 0.5334 -0.254) (xy 0.635 -0.254) (xy 0.635 0.254) (xy 0.5334 0.254)
				(xy 0.5334 0.2794)
			)
			(stroke
				(width 0)
				(type default)
			)
			(fill no)
			(layer "F.CrtYd")
		)
		(pad "1" smd rect
			(at 0.40005 0 270)
			(size 0.4572 0.508)
			(layers "F.Cu" "F.Mask" "F.Paste")
			(net "VSENSE_P1V05_NODE1_P")
		)
		(pad "2" smd rect
			(at -0.40005 0 270)
			(size 0.4572 0.508)
			(layers "F.Cu" "F.Mask" "F.Paste")
			(net "P1V05_NODE1_VSNS")
		)
	)
	(footprint ""
		(layer "F.Cu")
		(at 98.373946 -4.449826)
		(property "Reference" "C334"
			(at -0.563626 1.177544 0)
			(unlocked yes)
			(layer "F.SilkS")
			(effects
				(font
					(size 0.7874 0.5842)
					(thickness 0.1524)
				)
				(justify left)
			)
		)
		(property "Value" ""
			(at 0 0 0)
			(layer "F.Fab")
			(effects
				(font
					(size 1.27 1.27)
				)
			)
		)
		(duplicate_pad_numbers_are_jumpers no)
		(fp_line
			(start -0.7874 -0.4064)
			(end 0.7874 -0.4064)
			(stroke
				(width 0.1524)
				(type default)
			)
			(layer "F.SilkS")
		)
		(fp_line
			(start -0.7874 0.4064)
			(end -0.7874 -0.4064)
			(stroke
				(width 0.1524)
				(type default)
			)
			(layer "F.SilkS")
		)
		(fp_line
			(start 0 0.381)
			(end 0 -0.381)
			(stroke
				(width 0.1524)
				(type default)
			)
			(layer "F.SilkS")
		)
		(fp_line
			(start 0.7874 -0.4064)
			(end 0.7874 0.4064)
			(stroke
				(width 0.1524)
				(type default)
			)
			(layer "F.SilkS")
		)
		(fp_line
			(start 0.7874 0.4064)
			(end -0.7874 0.4064)
			(stroke
				(width 0.1524)
				(type default)
			)
			(layer "F.SilkS")
		)
		(fp_poly
			(pts
				(xy -0.5334 0.254) (xy -0.635 0.254) (xy -0.635 0.2286) (xy -0.635 -0.254) (xy -0.5334 -0.254) (xy -0.5334 -0.2794)
				(xy 0.5334 -0.2794) (xy 0.5334 -0.254) (xy 0.635 -0.254) (xy 0.635 0.254) (xy 0.5334 0.254) (xy 0.5334 0.2794)
				(xy -0.508 0.2794) (xy -0.5334 0.2794)
			)
			(stroke
				(width 0)
				(type default)
			)
			(fill no)
			(layer "F.CrtYd")
		)
		(pad "1" smd rect
			(at 0.40005 0)
			(size 0.4572 0.508)
			(layers "F.Cu" "F.Mask" "F.Paste")
			(net "P3V3_NODE1")
		)
		(pad "2" smd rect
			(at -0.40005 0)
			(size 0.4572 0.508)
			(layers "F.Cu" "F.Mask" "F.Paste")
			(net "GND")
		)
	)
	(footprint ""
		(layer "F.Cu")
		(at 169.649394 -36.938712)
		(property "Reference" "R265"
			(at -1.495806 2.202942 0)
			(unlocked yes)
			(layer "F.SilkS")
			(effects
				(font
					(size 0.7874 0.5842)
					(thickness 0.1524)
				)
				(justify left)
			)
		)
		(property "Value" ""
			(at 0 0 0)
			(layer "F.Fab")
			(effects
				(font
					(size 1.27 1.27)
				)
			)
		)
		(duplicate_pad_numbers_are_jumpers no)
		(fp_line
			(start -0.7874 -0.4064)
			(end 0.7874 -0.4064)
			(stroke
				(width 0.1524)
				(type default)
			)
			(layer "F.SilkS")
		)
		(fp_line
			(start -0.7874 0.4064)
			(end -0.7874 -0.4064)
			(stroke
				(width 0.1524)
				(type default)
			)
			(layer "F.SilkS")
		)
		(fp_line
			(start 0.7874 -0.4064)
			(end 0.7874 0.4064)
			(stroke
				(width 0.1524)
				(type default)
			)
			(layer "F.SilkS")
		)
		(fp_line
			(start 0.7874 0.4064)
			(end -0.7874 0.4064)
			(stroke
				(width 0.1524)
				(type default)
			)
			(layer "F.SilkS")
		)
		(fp_poly
			(pts
				(xy -0.508 0.2794) (xy -0.508 0.2286) (xy -0.635 0.2286) (xy -0.635 -0.254) (xy -0.5334 -0.254)
				(xy -0.5334 -0.2794) (xy 0.5334 -0.2794) (xy 0.5334 -0.254) (xy 0.635 -0.254) (xy 0.635 0.254) (xy 0.5334 0.254)
				(xy 0.5334 0.2794)
			)
			(stroke
				(width 0)
				(type default)
			)
			(fill no)
			(layer "F.CrtYd")
		)
		(pad "1" smd rect
			(at 0.40005 0)
			(size 0.4572 0.508)
			(layers "F.Cu" "F.Mask" "F.Paste")
			(net "USB0_L_DN")
		)
		(pad "2" smd rect
			(at -0.40005 0)
			(size 0.4572 0.508)
			(layers "F.Cu" "F.Mask" "F.Paste")
			(net "USB0_DN")
		)
	)
	(footprint ""
		(layer "F.Cu")
		(at 56.084216 -170.630088)
		(property "Reference" "C620"
			(at -9.010142 131.070096 0)
			(unlocked yes)
			(layer "F.SilkS")
			(effects
				(font
					(size 0.7874 0.5842)
					(thickness 0.1524)
				)
				(justify left)
			)
		)
		(property "Value" ""
			(at 0 0 0)
			(layer "F.Fab")
			(effects
				(font
					(size 1.27 1.27)
				)
			)
		)
		(duplicate_pad_numbers_are_jumpers no)
		(fp_line
			(start -0.7874 -0.4064)
			(end 0.7874 -0.4064)
			(stroke
				(width 0.1524)
				(type default)
			)
			(layer "F.SilkS")
		)
		(fp_line
			(start -0.7874 0.4064)
			(end -0.7874 -0.4064)
			(stroke
				(width 0.1524)
				(type default)
			)
			(layer "F.SilkS")
		)
		(fp_line
			(start 0 0.381)
			(end 0 -0.381)
			(stroke
				(width 0.1524)
				(type default)
			)
			(layer "F.SilkS")
		)
		(fp_line
			(start 0.7874 -0.4064)
			(end 0.7874 0.4064)
			(stroke
				(width 0.1524)
				(type default)
			)
			(layer "F.SilkS")
		)
		(fp_line
			(start 0.7874 0.4064)
			(end -0.7874 0.4064)
			(stroke
				(width 0.1524)
				(type default)
			)
			(layer "F.SilkS")
		)
		(fp_poly
			(pts
				(xy -0.5334 0.254) (xy -0.635 0.254) (xy -0.635 0.2286) (xy -0.635 -0.254) (xy -0.5334 -0.254) (xy -0.5334 -0.2794)
				(xy 0.5334 -0.2794) (xy 0.5334 -0.254) (xy 0.635 -0.254) (xy 0.635 0.254) (xy 0.5334 0.254) (xy 0.5334 0.2794)
				(xy -0.508 0.2794) (xy -0.5334 0.2794)
			)
			(stroke
				(width 0)
				(type default)
			)
			(fill no)
			(layer "F.CrtYd")
		)
		(pad "1" smd rect
			(at 0.40005 0)
			(size 0.4572 0.508)
			(layers "F.Cu" "F.Mask" "F.Paste")
			(net "P3V3_NODE1")
		)
		(pad "2" smd rect
			(at -0.40005 0)
			(size 0.4572 0.508)
			(layers "F.Cu" "F.Mask" "F.Paste")
			(net "GND")
		)
	)
	(footprint ""
		(layer "F.Cu")
		(at 15.920466 -74.465434 -90)
		(property "Reference" "CD1"
			(at -1.393698 1.763776 0)
			(unlocked yes)
			(layer "F.SilkS")
			(effects
				(font
					(size 0.7874 0.5842)
					(thickness 0.1524)
				)
				(justify left)
			)
		)
		(property "Value" ""
			(at 0 0 270)
			(layer "F.Fab")
			(effects
				(font
					(size 1.27 1.27)
				)
			)
		)
		(duplicate_pad_numbers_are_jumpers no)
		(fp_line
			(start -0.674878 2.203196)
			(end 0.674878 2.203196)
			(stroke
				(width 0.1524)
				(type default)
			)
			(layer "F.SilkS")
		)
		(fp_line
			(start 0.674878 2.203196)
			(end 0.674878 -1.623822)
			(stroke
				(width 0.1524)
				(type default)
			)
			(layer "F.SilkS")
		)
		(fp_line
			(start -0.40005 0.299974)
			(end 0.40005 0.299974)
			(stroke
				(width 0.1524)
				(type default)
			)
			(layer "F.SilkS")
		)
		(fp_line
			(start 0 0.299974)
			(end 0 0.49911)
			(stroke
				(width 0.1524)
				(type default)
			)
			(layer "F.SilkS")
		)
		(fp_line
			(start 0 0.299974)
			(end -0.40005 -0.299974)
			(stroke
				(width 0.1524)
				(type default)
			)
			(layer "F.SilkS")
		)
		(fp_line
			(start -0.40005 -0.299974)
			(end 0.40005 -0.299974)
			(stroke
				(width 0.1524)
				(type default)
			)
			(layer "F.SilkS")
		)
		(fp_line
			(start 0.40005 -0.299974)
			(end 0 0.299974)
			(stroke
				(width 0.1524)
				(type default)
			)
			(layer "F.SilkS")
		)
		(fp_line
			(start 0 -0.49911)
			(end 0 -0.299974)
			(stroke
				(width 0.1524)
				(type default)
			)
			(layer "F.SilkS")
		)
		(fp_line
			(start -0.674878 -1.623822)
			(end -0.674878 2.203196)
			(stroke
				(width 0.1524)
				(type default)
			)
			(layer "F.SilkS")
		)
		(fp_line
			(start 0.674878 -1.623822)
			(end -0.674878 -1.623822)
			(stroke
				(width 0.1524)
				(type default)
			)
			(layer "F.SilkS")
		)
		(fp_poly
			(pts
				(xy 0.674878 1.549146) (xy 0.674878 2.203196) (xy -0.674878 2.203196) (xy -0.674878 1.549146)
			)
			(stroke
				(width 0)
				(type default)
			)
			(fill yes)
			(layer "F.SilkS")
		)
		(fp_poly
			(pts
				(xy -0.508 1.527302) (xy -0.508 0.975106) (xy -0.674878 0.975106) (xy -0.674878 -0.975106) (xy -0.508 -0.975106)
				(xy -0.508 -1.527302) (xy 0.508 -1.527302) (xy 0.508 -0.975106) (xy 0.674878 -0.975106) (xy 0.674878 0.975106)
				(xy 0.508 0.975106) (xy 0.508 1.527302)
			)
			(stroke
				(width 0)
				(type default)
			)
			(fill no)
			(layer "F.CrtYd")
		)
		(fp_line
			(start -0.674878 0.975106)
			(end 0.674878 0.975106)
			(stroke
				(width 0.1)
				(type default)
			)
			(layer "F.Fab")
		)
		(fp_line
			(start 0.674878 0.975106)
			(end 0.674878 -0.975106)
			(stroke
				(width 0.1)
				(type default)
			)
			(layer "F.Fab")
		)
		(fp_line
			(start -0.40005 0.299974)
			(end 0.40005 0.299974)
			(stroke
				(width 0.1)
				(type default)
			)
			(layer "F.Fab")
		)
		(fp_line
			(start 0 0.299974)
			(end 0 0.49911)
			(stroke
				(width 0.1)
				(type default)
			)
			(layer "F.Fab")
		)
		(fp_line
			(start 0 0.299974)
			(end -0.40005 -0.299974)
			(stroke
				(width 0.1)
				(type default)
			)
			(layer "F.Fab")
		)
		(fp_line
			(start -0.40005 -0.299974)
			(end 0.40005 -0.299974)
			(stroke
				(width 0.1)
				(type default)
			)
			(layer "F.Fab")
		)
		(fp_line
			(start 0.40005 -0.299974)
			(end 0 0.299974)
			(stroke
				(width 0.1)
				(type default)
			)
			(layer "F.Fab")
		)
		(fp_line
			(start 0 -0.49911)
			(end 0 -0.299974)
			(stroke
				(width 0.1)
				(type default)
			)
			(layer "F.Fab")
		)
		(fp_line
			(start -0.674878 -0.975106)
			(end -0.674878 0.975106)
			(stroke
				(width 0.1)
				(type default)
			)
			(layer "F.Fab")
		)
		(fp_line
			(start 0.674878 -0.975106)
			(end -0.674878 -0.975106)
			(stroke
				(width 0.1)
				(type default)
			)
			(layer "F.Fab")
		)
		(fp_text user "-"
			(at -0.260096 3.367024 0)
			(unlocked yes)
			(layer "F.SilkS")
			(effects
				(font
					(size 1.6002 1.1938)
					(thickness 0.1524)
				)
				(justify left)
			)
		)
		(fp_text user "+"
			(at -2.348738 -0.525018 0)
			(unlocked yes)
			(layer "F.SilkS")
			(effects
				(font
					(size 1.6002 1.1938)
					(thickness 0.1524)
				)
				(justify left)
			)
		)
		(fp_text user "-"
			(at -0.5969 2.313178 270)
			(unlocked yes)
			(layer "F.Fab")
			(effects
				(font
					(size 1.6002 1.1938)
					(thickness 0.000001)
				)
				(justify left)
			)
		)
		(pad "1" smd rect
			(at 0 -1.070102)
			(size 0.8128 0.9144)
			(layers "F.Cu" "F.Mask" "F.Paste")
			(net "VCC5_CRTXX")
		)
		(pad "2" smd rect
			(at 0 1.070102)
			(size 0.8128 0.9144)
			(layers "F.Cu" "F.Mask" "F.Paste")
			(net "N21581564")
		)
	)
	(footprint ""
		(layer "F.Cu")
		(at 76.802996 -182.171848)
		(property "Reference" "R1075"
			(at -4.798314 0.98933 0)
			(unlocked yes)
			(layer "F.SilkS")
			(effects
				(font
					(size 0.7874 0.5842)
					(thickness 0.1524)
				)
				(justify left)
			)
		)
		(property "Value" ""
			(at 0 0 0)
			(layer "F.Fab")
			(effects
				(font
					(size 1.27 1.27)
				)
			)
		)
		(duplicate_pad_numbers_are_jumpers no)
		(fp_line
			(start -0.7874 -0.4064)
			(end 0.7874 -0.4064)
			(stroke
				(width 0.1524)
				(type default)
			)
			(layer "F.SilkS")
		)
		(fp_line
			(start -0.7874 0.4064)
			(end -0.7874 -0.4064)
			(stroke
				(width 0.1524)
				(type default)
			)
			(layer "F.SilkS")
		)
		(fp_line
			(start 0.7874 -0.4064)
			(end 0.7874 0.4064)
			(stroke
				(width 0.1524)
				(type default)
			)
			(layer "F.SilkS")
		)
		(fp_line
			(start 0.7874 0.4064)
			(end -0.7874 0.4064)
			(stroke
				(width 0.1524)
				(type default)
			)
			(layer "F.SilkS")
		)
		(fp_poly
			(pts
				(xy -0.508 0.2794) (xy -0.508 0.2286) (xy -0.635 0.2286) (xy -0.635 -0.254) (xy -0.5334 -0.254)
				(xy -0.5334 -0.2794) (xy 0.5334 -0.2794) (xy 0.5334 -0.254) (xy 0.635 -0.254) (xy 0.635 0.254) (xy 0.5334 0.254)
				(xy 0.5334 0.2794)
			)
			(stroke
				(width 0)
				(type default)
			)
			(fill no)
			(layer "F.CrtYd")
		)
		(pad "1" smd rect
			(at 0.40005 0)
			(size 0.4572 0.508)
			(layers "F.Cu" "F.Mask" "F.Paste")
			(net "P3V3_NODE1")
		)
		(pad "2" smd rect
			(at -0.40005 0)
			(size 0.4572 0.508)
			(layers "F.Cu" "F.Mask" "F.Paste")
			(net "JTAG_CPLD2_TMS")
		)
	)
	(footprint ""
		(layer "F.Cu")
		(at 57.195466 -161.928556 -90)
		(property "Reference" "R553"
			(at -1.475232 0.055626 90)
			(unlocked yes)
			(layer "F.SilkS")
			(effects
				(font
					(size 0.7874 0.5842)
					(thickness 0.1524)
				)
				(justify left)
			)
		)
		(property "Value" ""
			(at 0 0 270)
			(layer "F.Fab")
			(effects
				(font
					(size 1.27 1.27)
				)
			)
		)
		(duplicate_pad_numbers_are_jumpers no)
		(fp_line
			(start -0.7874 0.4064)
			(end -0.7874 -0.4064)
			(stroke
				(width 0.1524)
				(type default)
			)
			(layer "F.SilkS")
		)
		(fp_line
			(start 0.7874 0.4064)
			(end -0.7874 0.4064)
			(stroke
				(width 0.1524)
				(type default)
			)
			(layer "F.SilkS")
		)
		(fp_line
			(start -0.7874 -0.4064)
			(end 0.7874 -0.4064)
			(stroke
				(width 0.1524)
				(type default)
			)
			(layer "F.SilkS")
		)
		(fp_line
			(start 0.7874 -0.4064)
			(end 0.7874 0.4064)
			(stroke
				(width 0.1524)
				(type default)
			)
			(layer "F.SilkS")
		)
		(fp_poly
			(pts
				(xy -0.508 0.2794) (xy -0.508 0.2286) (xy -0.635 0.2286) (xy -0.635 -0.254) (xy -0.5334 -0.254)
				(xy -0.5334 -0.2794) (xy 0.5334 -0.2794) (xy 0.5334 -0.254) (xy 0.635 -0.254) (xy 0.635 0.254) (xy 0.5334 0.254)
				(xy 0.5334 0.2794)
			)
			(stroke
				(width 0)
				(type default)
			)
			(fill no)
			(layer "F.CrtYd")
		)
		(pad "1" smd rect
			(at 0.40005 0 270)
			(size 0.4572 0.508)
			(layers "F.Cu" "F.Mask" "F.Paste")
			(net "LAN1_NVM_HOLD_N")
		)
		(pad "2" smd rect
			(at -0.40005 0 270)
			(size 0.4572 0.508)
			(layers "F.Cu" "F.Mask" "F.Paste")
			(net "P3V3_NODE1")
		)
	)
	(footprint ""
		(layer "F.Cu")
		(at 101.387656 -161.76625)
		(property "Reference" "Q44"
			(at 87.97925 70.97649 90)
			(unlocked yes)
			(layer "F.SilkS")
			(effects
				(font
					(size 0.7874 0.5842)
					(thickness 0.1524)
				)
			)
		)
		(property "Value" ""
			(at 0 0 0)
			(layer "F.Fab")
			(effects
				(font
					(size 1.27 1.27)
				)
			)
		)
		(duplicate_pad_numbers_are_jumpers no)
		(fp_line
			(start -1.488186 -1.500124)
			(end 1.488186 -1.500124)
			(stroke
				(width 0.1524)
				(type default)
			)
			(layer "F.SilkS")
		)
		(fp_line
			(start -1.488186 1.500124)
			(end -1.488186 -1.500124)
			(stroke
				(width 0.1524)
				(type default)
			)
			(layer "F.SilkS")
		)
		(fp_line
			(start 1.488186 -1.500124)
			(end 1.488186 1.500124)
			(stroke
				(width 0.1524)
				(type default)
			)
			(layer "F.SilkS")
		)
		(fp_line
			(start 1.488186 1.500124)
			(end -1.488186 1.500124)
			(stroke
				(width 0.1524)
				(type default)
			)
			(layer "F.SilkS")
		)
		(fp_poly
			(pts
				(xy -0.700024 1.500124) (xy 0.700024 1.500124) (xy 0.700024 0.3556) (xy 1.4224 0.3556) (xy 1.4224 -0.3556)
				(xy 0.700024 -0.3556) (xy 0.700024 -1.500124) (xy -0.700024 -1.500124) (xy -0.700024 -1.3208) (xy -1.4224 -1.3208)
				(xy -1.4224 -0.5842) (xy -0.700024 -0.5842) (xy -0.700024 0.5842) (xy -1.4224 0.5842) (xy -1.4224 1.3208)
				(xy -0.700024 1.3208)
			)
			(stroke
				(width 0)
				(type default)
			)
			(fill no)
			(layer "F.CrtYd")
		)
		(fp_line
			(start -0.700024 -1.500124)
			(end 0.700024 -1.500124)
			(stroke
				(width 0.1)
				(type default)
			)
			(layer "F.Fab")
		)
		(fp_line
			(start -0.700024 1.500124)
			(end -0.700024 -1.500124)
			(stroke
				(width 0.1)
				(type default)
			)
			(layer "F.Fab")
		)
		(fp_line
			(start 0.700024 -1.500124)
			(end 0.700024 1.500124)
			(stroke
				(width 0.1)
				(type default)
			)
			(layer "F.Fab")
		)
		(fp_line
			(start 0.700024 1.500124)
			(end -0.700024 1.500124)
			(stroke
				(width 0.1)
				(type default)
			)
			(layer "F.Fab")
		)
		(fp_text user "2"
			(at -1.830832 1.08839 0)
			(unlocked yes)
			(layer "F.SilkS")
			(effects
				(font
					(size 0.635 0.4064)
					(thickness 0.1524)
				)
			)
		)
		(fp_text user "1"
			(at -1.662684 -1.338834 0)
			(unlocked yes)
			(layer "F.SilkS")
			(effects
				(font
					(size 0.635 0.4064)
					(thickness 0.1524)
				)
			)
		)
		(fp_text user "3"
			(at 0.932942 0.999998 0)
			(unlocked yes)
			(layer "F.SilkS")
			(effects
				(font
					(size 0.635 0.4064)
					(thickness 0.1524)
				)
			)
		)
		(fp_text user "1"
			(at -0.90805 -1.8034 270)
			(unlocked yes)
			(layer "F.Fab")
			(effects
				(font
					(size 0.7874 0.5842)
					(thickness 0.000001)
				)
			)
		)
		(fp_text user "2"
			(at -0.90805 1.8542 270)
			(unlocked yes)
			(layer "F.Fab")
			(effects
				(font
					(size 0.7874 0.5842)
					(thickness 0.000001)
				)
			)
		)
		(fp_text user "3"
			(at 2.15773 0 270)
			(unlocked yes)
			(layer "F.Fab")
			(effects
				(font
					(size 0.7874 0.5842)
					(thickness 0.000001)
				)
			)
		)
		(pad "1" smd rect
			(at -0.999998 -0.94996 270)
			(size 0.6096 0.7112)
			(layers "F.Cu" "F.Mask" "F.Paste")
			(net "N52411069")
		)
		(pad "2" smd rect
			(at -0.999998 0.94996 270)
			(size 0.6096 0.7112)
			(layers "F.Cu" "F.Mask" "F.Paste")
			(net "N52411102")
		)
		(pad "3" smd rect
			(at 0.999998 0 270)
			(size 0.6096 0.7112)
			(layers "F.Cu" "F.Mask" "F.Paste")
			(net "POWER_SW1_PWR_CTR_12V")
		)
	)
	(footprint ""
		(layer "F.Cu")
		(at 141.208252 -25.812242 90)
		(property "Reference" "C482"
			(at -10.732008 4.18719 90)
			(unlocked yes)
			(layer "F.SilkS")
			(effects
				(font
					(size 0.7874 0.5842)
					(thickness 0.1524)
				)
				(justify left)
			)
		)
		(property "Value" ""
			(at 0 0 90)
			(layer "F.Fab")
			(effects
				(font
					(size 1.27 1.27)
				)
			)
		)
		(duplicate_pad_numbers_are_jumpers no)
		(fp_line
			(start 0.7874 -0.4064)
			(end 0.7874 0.4064)
			(stroke
				(width 0.1524)
				(type default)
			)
			(layer "F.SilkS")
		)
		(fp_line
			(start -0.7874 -0.4064)
			(end 0.7874 -0.4064)
			(stroke
				(width 0.1524)
				(type default)
			)
			(layer "F.SilkS")
		)
		(fp_line
			(start 0 0.381)
			(end 0 -0.381)
			(stroke
				(width 0.1524)
				(type default)
			)
			(layer "F.SilkS")
		)
		(fp_line
			(start 0.7874 0.4064)
			(end -0.7874 0.4064)
			(stroke
				(width 0.1524)
				(type default)
			)
			(layer "F.SilkS")
		)
		(fp_line
			(start -0.7874 0.4064)
			(end -0.7874 -0.4064)
			(stroke
				(width 0.1524)
				(type default)
			)
			(layer "F.SilkS")
		)
		(fp_poly
			(pts
				(xy -0.5334 0.254) (xy -0.635 0.254) (xy -0.635 0.2286) (xy -0.635 -0.254) (xy -0.5334 -0.254) (xy -0.5334 -0.2794)
				(xy 0.5334 -0.2794) (xy 0.5334 -0.254) (xy 0.635 -0.254) (xy 0.635 0.254) (xy 0.5334 0.254) (xy 0.5334 0.2794)
				(xy -0.508 0.2794) (xy -0.5334 0.2794)
			)
			(stroke
				(width 0)
				(type default)
			)
			(fill no)
			(layer "F.CrtYd")
		)
		(pad "1" smd rect
			(at 0.40005 0 90)
			(size 0.4572 0.508)
			(layers "F.Cu" "F.Mask" "F.Paste")
			(net "SIO_AVCC")
		)
		(pad "2" smd rect
			(at -0.40005 0 90)
			(size 0.4572 0.508)
			(layers "F.Cu" "F.Mask" "F.Paste")
			(net "GNDA")
		)
	)
	(footprint ""
		(layer "F.Cu")
		(at 90.063066 -100.479606 180)
		(property "Reference" "U5"
			(at -5.448046 4.63804 0)
			(unlocked yes)
			(layer "F.SilkS")
			(effects
				(font
					(size 0.7874 0.5842)
					(thickness 0.1524)
				)
				(justify left)
			)
		)
		(property "Value" ""
			(at 0 0 180)
			(layer "F.Fab")
			(effects
				(font
					(size 1.27 1.27)
				)
			)
		)
		(duplicate_pad_numbers_are_jumpers no)
		(fp_line
			(start 4.76504 5.350002)
			(end -4.76504 5.350002)
			(stroke
				(width 0.1524)
				(type default)
			)
			(layer "F.SilkS")
		)
		(fp_line
			(start 4.76504 -5.350002)
			(end 4.76504 5.350002)
			(stroke
				(width 0.1524)
				(type default)
			)
			(layer "F.SilkS")
		)
		(fp_line
			(start -4.76504 5.350002)
			(end -4.76504 1.999996)
			(stroke
				(width 0.1524)
				(type default)
			)
			(layer "F.SilkS")
		)
		(fp_line
			(start -4.76504 1.999996)
			(end -8.465058 1.999996)
			(stroke
				(width 0.1524)
				(type default)
			)
			(layer "F.SilkS")
		)
		(fp_line
			(start -4.76504 -1.999996)
			(end -4.76504 -5.350002)
			(stroke
				(width 0.1524)
				(type default)
			)
			(layer "F.SilkS")
		)
		(fp_line
			(start -4.76504 -5.350002)
			(end 4.76504 -5.350002)
			(stroke
				(width 0.1524)
				(type default)
			)
			(layer "F.SilkS")
		)
		(fp_line
			(start -8.465058 1.999996)
			(end -8.465058 -1.999996)
			(stroke
				(width 0.1524)
				(type default)
			)
			(layer "F.SilkS")
		)
		(fp_line
			(start -8.465058 -1.999996)
			(end -4.76504 -1.999996)
			(stroke
				(width 0.1524)
				(type default)
			)
			(layer "F.SilkS")
		)
		(fp_poly
			(pts
				(xy 4.908296 -2.242058) (xy 5.924296 -2.750058) (xy 5.924296 -1.734058)
			)
			(stroke
				(width 0)
				(type default)
			)
			(fill yes)
			(layer "F.SilkS")
		)
		(fp_poly
			(pts
				(xy -4.76504 -5.350002) (xy 4.76504 -5.350002) (xy 4.76504 5.350002) (xy -4.76504 5.350002) (xy -4.76504 1.999996)
				(xy -8.465058 1.999996) (xy -8.465058 -1.999996) (xy -4.76504 -1.999996)
			)
			(stroke
				(width 0)
				(type default)
			)
			(fill no)
			(layer "F.CrtYd")
		)
		(fp_line
			(start 4.76504 5.350002)
			(end -4.76504 5.350002)
			(stroke
				(width 0.1)
				(type default)
			)
			(layer "F.Fab")
		)
		(fp_line
			(start 4.76504 -5.350002)
			(end 4.76504 5.350002)
			(stroke
				(width 0.1)
				(type default)
			)
			(layer "F.Fab")
		)
		(fp_line
			(start -4.76504 5.350002)
			(end -4.76504 1.999996)
			(stroke
				(width 0.1)
				(type default)
			)
			(layer "F.Fab")
		)
		(fp_line
			(start -4.76504 1.999996)
			(end -8.465058 1.999996)
			(stroke
				(width 0.1)
				(type default)
			)
			(layer "F.Fab")
		)
		(fp_line
			(start -4.76504 -1.999996)
			(end -4.76504 -5.350002)
			(stroke
				(width 0.1)
				(type default)
			)
			(layer "F.Fab")
		)
		(fp_line
			(start -4.76504 -5.350002)
			(end 4.76504 -5.350002)
			(stroke
				(width 0.1)
				(type default)
			)
			(layer "F.Fab")
		)
		(fp_line
			(start -8.465058 1.999996)
			(end -8.465058 -1.999996)
			(stroke
				(width 0.1)
				(type default)
			)
			(layer "F.Fab")
		)
		(fp_line
			(start -8.465058 -1.999996)
			(end -4.76504 -1.999996)
			(stroke
				(width 0.1)
				(type default)
			)
			(layer "F.Fab")
		)
		(fp_text user "8"
			(at 5.639054 5.441188 0)
			(unlocked yes)
			(layer "F.SilkS")
			(effects
				(font
					(size 0.635 0.4064)
					(thickness 0.1524)
				)
				(justify left)
			)
		)
		(fp_text user "1"
			(at 5.26669 -5.071364 0)
			(unlocked yes)
			(layer "F.SilkS")
			(effects
				(font
					(size 0.635 0.4064)
					(thickness 0.1524)
				)
				(justify left)
			)
		)
		(fp_text user "5"
			(at -3.871214 6.049518 0)
			(unlocked yes)
			(layer "F.SilkS")
			(effects
				(font
					(size 0.7874 0.5842)
					(thickness 0.1524)
				)
				(justify left)
			)
		)
		(fp_text user "4"
			(at -5.077968 -4.186936 0)
			(unlocked yes)
			(layer "F.SilkS")
			(effects
				(font
					(size 0.635 0.4064)
					(thickness 0.1524)
				)
				(justify left)
			)
		)
		(pad "1" smd rect
			(at 1.905 -3.379978 180)
			(size 0.6604 1.9304)
			(layers "F.Cu" "F.Mask" "F.Paste")
			(net "SPI_CPU_NODE1_CS0_L")
		)
		(pad "2" smd rect
			(at 0.635 -3.379978 180)
			(size 0.6604 1.9304)
			(layers "F.Cu" "F.Mask" "F.Paste")
			(net "SPI_CPU_NODE1_MISO_R")
		)
		(pad "3" smd rect
			(at -0.635 -3.379978 180)
			(size 0.6604 1.9304)
			(layers "F.Cu" "F.Mask" "F.Paste")
			(net "SPI_CPU_NODE1_WP_L")
		)
		(pad "4" smd rect
			(at -1.905 -3.379978 180)
			(size 0.6604 1.9304)
			(layers "F.Cu" "F.Mask" "F.Paste")
			(net "GND")
		)
		(pad "5" smd rect
			(at -1.905 3.379978 180)
			(size 0.6604 1.9304)
			(layers "F.Cu" "F.Mask" "F.Paste")
			(net "SPI_CPU_NODE1_MOSI")
		)
		(pad "6" smd rect
			(at -0.635 3.379978 180)
			(size 0.6604 1.9304)
			(layers "F.Cu" "F.Mask" "F.Paste")
			(net "SPI_CPU_NODE1_SCLK")
		)
		(pad "7" smd rect
			(at 0.635 3.379978 180)
			(size 0.6604 1.9304)
			(layers "F.Cu" "F.Mask" "F.Paste")
			(net "SPI_CPU_NODE1_HOLD_L")
		)
		(pad "8" smd rect
			(at 1.905 3.379978 180)
			(size 0.6604 1.9304)
			(layers "F.Cu" "F.Mask" "F.Paste")
			(net "P3V3_NODE1")
		)
	)
	(footprint ""
		(layer "F.Cu")
		(at 165.34638 -161.37001 90)
		(property "Reference" "R587"
			(at -8.06577 17.513554 90)
			(unlocked yes)
			(layer "F.SilkS")
			(effects
				(font
					(size 0.7874 0.5842)
					(thickness 0.1524)
				)
				(justify left)
			)
		)
		(property "Value" ""
			(at 0 0 90)
			(layer "F.Fab")
			(effects
				(font
					(size 1.27 1.27)
				)
			)
		)
		(duplicate_pad_numbers_are_jumpers no)
		(fp_line
			(start 0.7874 -0.4064)
			(end 0.7874 0.4064)
			(stroke
				(width 0.1524)
				(type default)
			)
			(layer "F.SilkS")
		)
		(fp_line
			(start -0.7874 -0.4064)
			(end 0.7874 -0.4064)
			(stroke
				(width 0.1524)
				(type default)
			)
			(layer "F.SilkS")
		)
		(fp_line
			(start 0.7874 0.4064)
			(end -0.7874 0.4064)
			(stroke
				(width 0.1524)
				(type default)
			)
			(layer "F.SilkS")
		)
		(fp_line
			(start -0.7874 0.4064)
			(end -0.7874 -0.4064)
			(stroke
				(width 0.1524)
				(type default)
			)
			(layer "F.SilkS")
		)
		(fp_poly
			(pts
				(xy -0.508 0.2794) (xy -0.508 0.2286) (xy -0.635 0.2286) (xy -0.635 -0.254) (xy -0.5334 -0.254)
				(xy -0.5334 -0.2794) (xy 0.5334 -0.2794) (xy 0.5334 -0.254) (xy 0.635 -0.254) (xy 0.635 0.254) (xy 0.5334 0.254)
				(xy 0.5334 0.2794)
			)
			(stroke
				(width 0)
				(type default)
			)
			(fill no)
			(layer "F.CrtYd")
		)
		(pad "1" smd rect
			(at 0.40005 0 90)
			(size 0.4572 0.508)
			(layers "F.Cu" "F.Mask" "F.Paste")
			(net "GND")
		)
		(pad "2" smd rect
			(at -0.40005 0 90)
			(size 0.4572 0.508)
			(layers "F.Cu" "F.Mask" "F.Paste")
			(net "LAN2_NC_SI_CRS_DV")
		)
	)
	(footprint ""
		(layer "F.Cu")
		(at 52.223162 -147.546822)
		(property "Reference" "R542"
			(at -2.1336 5.291582 0)
			(unlocked yes)
			(layer "F.SilkS")
			(effects
				(font
					(size 0.7874 0.5842)
					(thickness 0.1524)
				)
				(justify left)
			)
		)
		(property "Value" ""
			(at 0 0 0)
			(layer "F.Fab")
			(effects
				(font
					(size 1.27 1.27)
				)
			)
		)
		(duplicate_pad_numbers_are_jumpers no)
		(fp_line
			(start -0.7874 -0.406146)
			(end 0.7874 -0.406146)
			(stroke
				(width 0.1524)
				(type default)
			)
			(layer "F.SilkS")
		)
		(fp_line
			(start -0.7874 0.406146)
			(end -0.7874 -0.406146)
			(stroke
				(width 0.1524)
				(type default)
			)
			(layer "F.SilkS")
		)
		(fp_line
			(start 0.7874 -0.406146)
			(end 0.7874 0.406146)
			(stroke
				(width 0.1524)
				(type default)
			)
			(layer "F.SilkS")
		)
		(fp_line
			(start 0.7874 0.406146)
			(end -0.7874 0.406146)
			(stroke
				(width 0.1524)
				(type default)
			)
			(layer "F.SilkS")
		)
		(fp_poly
			(pts
				(xy -0.508 0.2794) (xy -0.508 0.2286) (xy -0.635 0.2286) (xy -0.635 -0.254) (xy -0.5334 -0.254)
				(xy -0.5334 -0.2794) (xy 0.5334 -0.2794) (xy 0.5334 -0.254) (xy 0.635 -0.254) (xy 0.635 0.254) (xy 0.5334 0.254)
				(xy 0.5334 0.2794)
			)
			(stroke
				(width 0)
				(type default)
			)
			(fill no)
			(layer "F.CrtYd")
		)
		(pad "1" smd rect
			(at 0.40005 0)
			(size 0.4572 0.508)
			(layers "F.Cu" "F.Mask" "F.Paste")
			(net "P3V3_NODE1")
		)
		(pad "2" smd rect
			(at -0.40005 0)
			(size 0.4572 0.508)
			(layers "F.Cu" "F.Mask" "F.Paste")
			(net "SPI_LAN1_NVM_CS_N")
		)
	)
	(footprint ""
		(layer "F.Cu")
		(at 157.530292 -26.594816 180)
		(property "Reference" "C532"
			(at -3.56108 -0.848106 90)
			(unlocked yes)
			(layer "F.SilkS")
			(effects
				(font
					(size 0.7874 0.5842)
					(thickness 0.1524)
				)
				(justify left)
			)
		)
		(property "Value" ""
			(at 0 0 180)
			(layer "F.Fab")
			(effects
				(font
					(size 1.27 1.27)
				)
			)
		)
		(duplicate_pad_numbers_are_jumpers no)
		(fp_line
			(start 0.7874 0.4064)
			(end -0.7874 0.4064)
			(stroke
				(width 0.1524)
				(type default)
			)
			(layer "F.SilkS")
		)
		(fp_line
			(start 0.7874 -0.4064)
			(end 0.7874 0.4064)
			(stroke
				(width 0.1524)
				(type default)
			)
			(layer "F.SilkS")
		)
		(fp_line
			(start 0 0.381)
			(end 0 -0.381)
			(stroke
				(width 0.1524)
				(type default)
			)
			(layer "F.SilkS")
		)
		(fp_line
			(start -0.7874 0.4064)
			(end -0.7874 -0.4064)
			(stroke
				(width 0.1524)
				(type default)
			)
			(layer "F.SilkS")
		)
		(fp_line
			(start -0.7874 -0.4064)
			(end 0.7874 -0.4064)
			(stroke
				(width 0.1524)
				(type default)
			)
			(layer "F.SilkS")
		)
		(fp_poly
			(pts
				(xy -0.5334 0.254) (xy -0.635 0.254) (xy -0.635 0.2286) (xy -0.635 -0.254) (xy -0.5334 -0.254) (xy -0.5334 -0.2794)
				(xy 0.5334 -0.2794) (xy 0.5334 -0.254) (xy 0.635 -0.254) (xy 0.635 0.254) (xy 0.5334 0.254) (xy 0.5334 0.2794)
				(xy -0.508 0.2794) (xy -0.5334 0.2794)
			)
			(stroke
				(width 0)
				(type default)
			)
			(fill no)
			(layer "F.CrtYd")
		)
		(pad "1" smd rect
			(at 0.40005 0 180)
			(size 0.4572 0.508)
			(layers "F.Cu" "F.Mask" "F.Paste")
			(net "GND")
		)
		(pad "2" smd rect
			(at -0.40005 0 180)
			(size 0.4572 0.508)
			(layers "F.Cu" "F.Mask" "F.Paste")
			(net "N21624894")
		)
	)
	(footprint ""
		(layer "F.Cu")
		(at 15.21206 -107.34802 -90)
		(property "Reference" "PC64"
			(at -7.638288 4.15798 0)
			(unlocked yes)
			(layer "F.SilkS")
			(effects
				(font
					(size 0.7874 0.5842)
					(thickness 0.1524)
				)
				(justify left)
			)
		)
		(property "Value" ""
			(at 0 0 270)
			(layer "F.Fab")
			(effects
				(font
					(size 1.27 1.27)
				)
			)
		)
		(duplicate_pad_numbers_are_jumpers no)
		(fp_line
			(start -2.249932 4.533392)
			(end -2.249932 -4.533392)
			(stroke
				(width 0.1524)
				(type default)
			)
			(layer "F.SilkS")
		)
		(fp_line
			(start 2.249932 4.533392)
			(end -2.249932 4.533392)
			(stroke
				(width 0.1524)
				(type default)
			)
			(layer "F.SilkS")
		)
		(fp_line
			(start -2.249932 -4.533392)
			(end 2.249932 -4.533392)
			(stroke
				(width 0.1524)
				(type default)
			)
			(layer "F.SilkS")
		)
		(fp_line
			(start 2.249932 -4.533392)
			(end 2.249932 4.533392)
			(stroke
				(width 0.1524)
				(type default)
			)
			(layer "F.SilkS")
		)
		(fp_poly
			(pts
				(xy 2.326132 -4.533392) (xy 2.326132 -5.39242) (xy -2.326132 -5.39242) (xy -2.326132 -4.533392)
			)
			(stroke
				(width 0)
				(type default)
			)
			(fill yes)
			(layer "F.SilkS")
		)
		(fp_poly
			(pts
				(xy -1.4605 4.457192) (xy -1.4605 3.750056) (xy -2.249932 3.750056) (xy -2.249932 -3.750056) (xy -1.4605 -3.750056)
				(xy -1.4605 -4.457192) (xy 1.4605 -4.457192) (xy 1.4605 -3.750056) (xy 2.249932 -3.750056) (xy 2.249932 3.750056)
				(xy 1.4605 3.750056) (xy 1.4605 4.457192)
			)
			(stroke
				(width 0)
				(type default)
			)
			(fill no)
			(layer "F.CrtYd")
		)
		(fp_line
			(start -2.249932 3.750056)
			(end -2.249932 -3.750056)
			(stroke
				(width 0.1)
				(type default)
			)
			(layer "F.Fab")
		)
		(fp_line
			(start 2.249932 3.750056)
			(end -2.249932 3.750056)
			(stroke
				(width 0.1)
				(type default)
			)
			(layer "F.Fab")
		)
		(fp_line
			(start -2.249932 -3.750056)
			(end 2.249932 -3.750056)
			(stroke
				(width 0.1)
				(type default)
			)
			(layer "F.Fab")
		)
		(fp_line
			(start 2.249932 -3.750056)
			(end 2.249932 3.750056)
			(stroke
				(width 0.1)
				(type default)
			)
			(layer "F.Fab")
		)
		(fp_text user "+"
			(at -6.83514 -6.076442 270)
			(unlocked yes)
			(layer "F.SilkS")
			(effects
				(font
					(size 1.27 0.9652)
					(thickness 0.1524)
				)
				(justify left)
			)
		)
		(fp_text user "+"
			(at -0.786384 -6.322314 270)
			(unlocked yes)
			(layer "F.Fab")
			(effects
				(font
					(size 1.905 1.4224)
					(thickness 0.000001)
				)
				(justify left)
			)
		)
		(pad "1" smd rect
			(at 0 -3.199892 180)
			(size 2.413 2.8194)
			(layers "F.Cu" "F.Mask" "F.Paste")
			(net "P1V05_NODE1")
		)
		(pad "2" smd rect
			(at 0 3.199892 180)
			(size 2.413 2.8194)
			(layers "F.Cu" "F.Mask" "F.Paste")
			(net "GND")
		)
	)
	(footprint ""
		(layer "F.Cu")
		(at 11.933174 -16.260572 -90)
		(property "Reference" "R652"
			(at 1.500124 6.319774 90)
			(unlocked yes)
			(layer "F.SilkS")
			(effects
				(font
					(size 0.7874 0.5842)
					(thickness 0.1524)
				)
				(justify left)
			)
		)
		(property "Value" ""
			(at 0 0 270)
			(layer "F.Fab")
			(effects
				(font
					(size 1.27 1.27)
				)
			)
		)
		(duplicate_pad_numbers_are_jumpers no)
		(fp_line
			(start -0.7874 0.4064)
			(end -0.7874 -0.4064)
			(stroke
				(width 0.1524)
				(type default)
			)
			(layer "F.SilkS")
		)
		(fp_line
			(start 0.7874 0.4064)
			(end -0.7874 0.4064)
			(stroke
				(width 0.1524)
				(type default)
			)
			(layer "F.SilkS")
		)
		(fp_line
			(start -0.7874 -0.4064)
			(end 0.7874 -0.4064)
			(stroke
				(width 0.1524)
				(type default)
			)
			(layer "F.SilkS")
		)
		(fp_line
			(start 0.7874 -0.4064)
			(end 0.7874 0.4064)
			(stroke
				(width 0.1524)
				(type default)
			)
			(layer "F.SilkS")
		)
		(fp_poly
			(pts
				(xy -0.508 0.2794) (xy -0.508 0.2286) (xy -0.635 0.2286) (xy -0.635 -0.254) (xy -0.5334 -0.254)
				(xy -0.5334 -0.2794) (xy 0.5334 -0.2794) (xy 0.5334 -0.254) (xy 0.635 -0.254) (xy 0.635 0.254) (xy 0.5334 0.254)
				(xy 0.5334 0.2794)
			)
			(stroke
				(width 0)
				(type default)
			)
			(fill no)
			(layer "F.CrtYd")
		)
		(pad "1" smd rect
			(at 0.40005 0 270)
			(size 0.4572 0.508)
			(layers "F.Cu" "F.Mask" "F.Paste")
			(net "P3V3_NODE1")
		)
		(pad "2" smd rect
			(at -0.40005 0 270)
			(size 0.4572 0.508)
			(layers "F.Cu" "F.Mask" "F.Paste")
			(net "N54251489")
		)
	)
	(footprint ""
		(layer "F.Cu")
		(at 100.496624 -131.539488 -90)
		(property "Reference" "PR45"
			(at 3.448812 2.178304 90)
			(unlocked yes)
			(layer "F.SilkS")
			(effects
				(font
					(size 0.7874 0.5842)
					(thickness 0.1524)
				)
				(justify left)
			)
		)
		(property "Value" ""
			(at 0 0 270)
			(layer "F.Fab")
			(effects
				(font
					(size 1.27 1.27)
				)
			)
		)
		(duplicate_pad_numbers_are_jumpers no)
		(fp_line
			(start -0.7874 0.4064)
			(end -0.7874 -0.4064)
			(stroke
				(width 0.1524)
				(type default)
			)
			(layer "F.SilkS")
		)
		(fp_line
			(start 0.7874 0.4064)
			(end -0.7874 0.4064)
			(stroke
				(width 0.1524)
				(type default)
			)
			(layer "F.SilkS")
		)
		(fp_line
			(start -0.7874 -0.4064)
			(end 0.7874 -0.4064)
			(stroke
				(width 0.1524)
				(type default)
			)
			(layer "F.SilkS")
		)
		(fp_line
			(start 0.7874 -0.4064)
			(end 0.7874 0.4064)
			(stroke
				(width 0.1524)
				(type default)
			)
			(layer "F.SilkS")
		)
		(fp_poly
			(pts
				(xy -0.508 0.2794) (xy -0.508 0.2286) (xy -0.635 0.2286) (xy -0.635 -0.254) (xy -0.5334 -0.254)
				(xy -0.5334 -0.2794) (xy 0.5334 -0.2794) (xy 0.5334 -0.254) (xy 0.635 -0.254) (xy 0.635 0.254) (xy 0.5334 0.254)
				(xy 0.5334 0.2794)
			)
			(stroke
				(width 0)
				(type default)
			)
			(fill no)
			(layer "F.CrtYd")
		)
		(pad "1" smd rect
			(at 0.40005 0 270)
			(size 0.4572 0.508)
			(layers "F.Cu" "F.Mask" "F.Paste")
			(net "P1V05_NODE1")
		)
		(pad "2" smd rect
			(at -0.40005 0 270)
			(size 0.4572 0.508)
			(layers "F.Cu" "F.Mask" "F.Paste")
			(net "SVID_CPU_NODE1_PVCCP_DAT")
		)
	)
	(footprint ""
		(layer "F.Cu")
		(at 184.7342 -174.4218 180)
		(property "Reference" "R1315"
			(at -10.0076 -17.45107 0)
			(unlocked yes)
			(layer "F.SilkS")
			(effects
				(font
					(size 0.7874 0.5842)
					(thickness 0.1524)
				)
				(justify left)
			)
		)
		(property "Value" ""
			(at 0 0 180)
			(layer "F.Fab")
			(effects
				(font
					(size 1.27 1.27)
				)
			)
		)
		(duplicate_pad_numbers_are_jumpers no)
		(fp_line
			(start 0.7874 0.4064)
			(end -0.7874 0.4064)
			(stroke
				(width 0.1524)
				(type default)
			)
			(layer "F.SilkS")
		)
		(fp_line
			(start 0.7874 -0.4064)
			(end 0.7874 0.4064)
			(stroke
				(width 0.1524)
				(type default)
			)
			(layer "F.SilkS")
		)
		(fp_line
			(start -0.7874 0.4064)
			(end -0.7874 -0.4064)
			(stroke
				(width 0.1524)
				(type default)
			)
			(layer "F.SilkS")
		)
		(fp_line
			(start -0.7874 -0.4064)
			(end 0.7874 -0.4064)
			(stroke
				(width 0.1524)
				(type default)
			)
			(layer "F.SilkS")
		)
		(fp_poly
			(pts
				(xy -0.508 0.2794) (xy -0.508 0.2286) (xy -0.635 0.2286) (xy -0.635 -0.254) (xy -0.5334 -0.254)
				(xy -0.5334 -0.2794) (xy 0.5334 -0.2794) (xy 0.5334 -0.254) (xy 0.635 -0.254) (xy 0.635 0.254) (xy 0.5334 0.254)
				(xy 0.5334 0.2794)
			)
			(stroke
				(width 0)
				(type default)
			)
			(fill no)
			(layer "F.CrtYd")
		)
		(pad "1" smd rect
			(at 0.40005 0 180)
			(size 0.4572 0.508)
			(layers "F.Cu" "F.Mask" "F.Paste")
			(net "POWER_SW2_PWR_CTR_12V")
		)
		(pad "2" smd rect
			(at -0.40005 0 180)
			(size 0.4572 0.508)
			(layers "F.Cu" "F.Mask" "F.Paste")
			(net "POWER_SW2_PWR_CTR_12V_R")
		)
	)
	(footprint ""
		(layer "F.Cu")
		(at 69.755004 -166.748714 180)
		(property "Reference" "R662"
			(at 4.49072 0.046228 0)
			(unlocked yes)
			(layer "F.SilkS")
			(effects
				(font
					(size 0.7874 0.5842)
					(thickness 0.1524)
				)
				(justify left)
			)
		)
		(property "Value" ""
			(at 0 0 180)
			(layer "F.Fab")
			(effects
				(font
					(size 1.27 1.27)
				)
			)
		)
		(duplicate_pad_numbers_are_jumpers no)
		(fp_line
			(start 0.7874 0.4064)
			(end -0.7874 0.4064)
			(stroke
				(width 0.1524)
				(type default)
			)
			(layer "F.SilkS")
		)
		(fp_line
			(start 0.7874 -0.4064)
			(end 0.7874 0.4064)
			(stroke
				(width 0.1524)
				(type default)
			)
			(layer "F.SilkS")
		)
		(fp_line
			(start -0.7874 0.4064)
			(end -0.7874 -0.4064)
			(stroke
				(width 0.1524)
				(type default)
			)
			(layer "F.SilkS")
		)
		(fp_line
			(start -0.7874 -0.4064)
			(end 0.7874 -0.4064)
			(stroke
				(width 0.1524)
				(type default)
			)
			(layer "F.SilkS")
		)
		(fp_poly
			(pts
				(xy -0.508 0.2794) (xy -0.508 0.2286) (xy -0.635 0.2286) (xy -0.635 -0.254) (xy -0.5334 -0.254)
				(xy -0.5334 -0.2794) (xy 0.5334 -0.2794) (xy 0.5334 -0.254) (xy 0.635 -0.254) (xy 0.635 0.254) (xy 0.5334 0.254)
				(xy 0.5334 0.2794)
			)
			(stroke
				(width 0)
				(type default)
			)
			(fill no)
			(layer "F.CrtYd")
		)
		(pad "1" smd rect
			(at 0.40005 0 180)
			(size 0.4572 0.508)
			(layers "F.Cu" "F.Mask" "F.Paste")
			(net "CPLD123_RSV1")
		)
		(pad "2" smd rect
			(at -0.40005 0 180)
			(size 0.4572 0.508)
			(layers "F.Cu" "F.Mask" "F.Paste")
			(net "CPLD2_RSV1")
		)
	)
	(footprint ""
		(layer "B.Cu")
		(at 79.702406 -29.777436 -90)
		(property "Reference" "C157"
			(at 0.716534 1.106932 270)
			(unlocked yes)
			(layer "B.SilkS")
			(effects
				(font
					(size 0.7874 0.5842)
					(thickness 0.1524)
				)
				(justify left mirror)
			)
		)
		(property "Value" ""
			(at 0 0 90)
			(layer "B.Fab")
			(effects
				(font
					(size 1.27 1.27)
				)
				(justify mirror)
			)
		)
		(duplicate_pad_numbers_are_jumpers no)
		(fp_line
			(start -0.7874 0.4064)
			(end 0.7874 0.4064)
			(stroke
				(width 0.1524)
				(type default)
			)
			(layer "B.SilkS")
		)
		(fp_line
			(start 0.7874 0.4064)
			(end 0.7874 -0.4064)
			(stroke
				(width 0.1524)
				(type default)
			)
			(layer "B.SilkS")
		)
		(fp_line
			(start 0 0.381)
			(end 0 -0.381)
			(stroke
				(width 0.1524)
				(type default)
			)
			(layer "B.SilkS")
		)
		(fp_line
			(start -0.7874 -0.4064)
			(end -0.7874 0.4064)
			(stroke
				(width 0.1524)
				(type default)
			)
			(layer "B.SilkS")
		)
		(fp_line
			(start 0.7874 -0.4064)
			(end -0.7874 -0.4064)
			(stroke
				(width 0.1524)
				(type default)
			)
			(layer "B.SilkS")
		)
		(fp_poly
			(pts
				(xy 0.5334 0.254) (xy 0.635 0.254) (xy 0.635 0.2286) (xy 0.635 -0.254) (xy 0.5334 -0.254) (xy 0.5334 -0.2794)
				(xy -0.5334 -0.2794) (xy -0.5334 -0.254) (xy -0.635 -0.254) (xy -0.635 0.254) (xy -0.5334 0.254)
				(xy -0.5334 0.2794) (xy 0.508 0.2794) (xy 0.5334 0.2794)
			)
			(stroke
				(width 0)
				(type default)
			)
			(fill no)
			(layer "B.CrtYd")
		)
		(pad "1" smd rect
			(at -0.40005 0 90)
			(size 0.4572 0.508)
			(layers "B.Cu" "B.Mask" "B.Paste")
			(net "PV_VDDR_NODE1")
		)
		(pad "2" smd rect
			(at 0.40005 0 90)
			(size 0.4572 0.508)
			(layers "B.Cu" "B.Mask" "B.Paste")
			(net "GND")
		)
	)
	(footprint ""
		(layer "B.Cu")
		(at 65.048638 -73.928478 90)
		(property "Reference" "C106"
			(at -32.233362 -14.384528 270)
			(unlocked yes)
			(layer "B.SilkS")
			(effects
				(font
					(size 0.7874 0.5842)
					(thickness 0.1524)
				)
				(justify left mirror)
			)
		)
		(property "Value" ""
			(at 0 0 90)
			(layer "B.Fab")
			(effects
				(font
					(size 1.27 1.27)
				)
				(justify mirror)
			)
		)
		(duplicate_pad_numbers_are_jumpers no)
		(fp_line
			(start 0.7874 -0.4064)
			(end -0.7874 -0.4064)
			(stroke
				(width 0.1524)
				(type default)
			)
			(layer "B.SilkS")
		)
		(fp_line
			(start -0.7874 -0.4064)
			(end -0.7874 0.4064)
			(stroke
				(width 0.1524)
				(type default)
			)
			(layer "B.SilkS")
		)
		(fp_line
			(start 0 0.381)
			(end 0 -0.381)
			(stroke
				(width 0.1524)
				(type default)
			)
			(layer "B.SilkS")
		)
		(fp_line
			(start 0.7874 0.4064)
			(end 0.7874 -0.4064)
			(stroke
				(width 0.1524)
				(type default)
			)
			(layer "B.SilkS")
		)
		(fp_line
			(start -0.7874 0.4064)
			(end 0.7874 0.4064)
			(stroke
				(width 0.1524)
				(type default)
			)
			(layer "B.SilkS")
		)
		(fp_poly
			(pts
				(xy 0.5334 0.254) (xy 0.635 0.254) (xy 0.635 0.2286) (xy 0.635 -0.254) (xy 0.5334 -0.254) (xy 0.5334 -0.2794)
				(xy -0.5334 -0.2794) (xy -0.5334 -0.254) (xy -0.635 -0.254) (xy -0.635 0.254) (xy -0.5334 0.254)
				(xy -0.5334 0.2794) (xy 0.508 0.2794) (xy 0.5334 0.2794)
			)
			(stroke
				(width 0)
				(type default)
			)
			(fill no)
			(layer "B.CrtYd")
		)
		(pad "1" smd rect
			(at -0.40005 0 270)
			(size 0.4572 0.508)
			(layers "B.Cu" "B.Mask" "B.Paste")
			(net "P1V05_NODE1")
		)
		(pad "2" smd rect
			(at 0.40005 0 270)
			(size 0.4572 0.508)
			(layers "B.Cu" "B.Mask" "B.Paste")
			(net "GND")
		)
	)
	(footprint ""
		(layer "B.Cu")
		(at 88.77935 -71.145654)
		(property "Reference" "R174"
			(at -1.91516 9.466834 0)
			(unlocked yes)
			(layer "B.SilkS")
			(effects
				(font
					(size 0.7874 0.5842)
					(thickness 0.1524)
				)
				(justify left mirror)
			)
		)
		(property "Value" ""
			(at 0 0 0)
			(layer "B.Fab")
			(effects
				(font
					(size 1.27 1.27)
				)
				(justify mirror)
			)
		)
		(duplicate_pad_numbers_are_jumpers no)
		(fp_line
			(start -0.7874 -0.4064)
			(end -0.7874 0.4064)
			(stroke
				(width 0.1524)
				(type default)
			)
			(layer "B.SilkS")
		)
		(fp_line
			(start -0.7874 0.4064)
			(end 0.7874 0.4064)
			(stroke
				(width 0.1524)
				(type default)
			)
			(layer "B.SilkS")
		)
		(fp_line
			(start 0.7874 -0.4064)
			(end -0.7874 -0.4064)
			(stroke
				(width 0.1524)
				(type default)
			)
			(layer "B.SilkS")
		)
		(fp_line
			(start 0.7874 0.4064)
			(end 0.7874 -0.4064)
			(stroke
				(width 0.1524)
				(type default)
			)
			(layer "B.SilkS")
		)
		(fp_poly
			(pts
				(xy 0.508 0.2794) (xy 0.508 0.2286) (xy 0.635 0.2286) (xy 0.635 -0.254) (xy 0.5334 -0.254) (xy 0.5334 -0.2794)
				(xy -0.5334 -0.2794) (xy -0.5334 -0.254) (xy -0.635 -0.254) (xy -0.635 0.254) (xy -0.5334 0.254)
				(xy -0.5334 0.2794)
			)
			(stroke
				(width 0)
				(type default)
			)
			(fill no)
			(layer "B.CrtYd")
		)
		(pad "1" smd rect
			(at -0.40005 0 180)
			(size 0.4572 0.508)
			(layers "B.Cu" "B.Mask" "B.Paste")
			(net "GND")
		)
		(pad "2" smd rect
			(at 0.40005 0 180)
			(size 0.4572 0.508)
			(layers "B.Cu" "B.Mask" "B.Paste")
			(net "PD_CPU_NODE1_PUNIT_ST_ADDR1")
		)
	)
	(footprint ""
		(layer "B.Cu")
		(at 163.128452 -102.002082)
		(property "Reference" "C385"
			(at 4.541012 0.032766 0)
			(unlocked yes)
			(layer "B.SilkS")
			(effects
				(font
					(size 0.7874 0.5842)
					(thickness 0.1524)
				)
				(justify left mirror)
			)
		)
		(property "Value" ""
			(at 0 0 0)
			(layer "B.Fab")
			(effects
				(font
					(size 1.27 1.27)
				)
				(justify mirror)
			)
		)
		(duplicate_pad_numbers_are_jumpers no)
		(fp_line
			(start -0.7874 -0.4064)
			(end -0.7874 0.4064)
			(stroke
				(width 0.1524)
				(type default)
			)
			(layer "B.SilkS")
		)
		(fp_line
			(start -0.7874 0.4064)
			(end 0.7874 0.4064)
			(stroke
				(width 0.1524)
				(type default)
			)
			(layer "B.SilkS")
		)
		(fp_line
			(start 0 0.381)
			(end 0 -0.381)
			(stroke
				(width 0.1524)
				(type default)
			)
			(layer "B.SilkS")
		)
		(fp_line
			(start 0.7874 -0.4064)
			(end -0.7874 -0.4064)
			(stroke
				(width 0.1524)
				(type default)
			)
			(layer "B.SilkS")
		)
		(fp_line
			(start 0.7874 0.4064)
			(end 0.7874 -0.4064)
			(stroke
				(width 0.1524)
				(type default)
			)
			(layer "B.SilkS")
		)
		(fp_poly
			(pts
				(xy 0.5334 0.254) (xy 0.635 0.254) (xy 0.635 0.2286) (xy 0.635 -0.254) (xy 0.5334 -0.254) (xy 0.5334 -0.2794)
				(xy -0.5334 -0.2794) (xy -0.5334 -0.254) (xy -0.635 -0.254) (xy -0.635 0.254) (xy -0.5334 0.254)
				(xy -0.5334 0.2794) (xy 0.508 0.2794) (xy 0.5334 0.2794)
			)
			(stroke
				(width 0)
				(type default)
			)
			(fill no)
			(layer "B.CrtYd")
		)
		(pad "1" smd rect
			(at -0.40005 0 180)
			(size 0.4572 0.508)
			(layers "B.Cu" "B.Mask" "B.Paste")
			(net "P3V3_USB_NODE1")
		)
		(pad "2" smd rect
			(at 0.40005 0 180)
			(size 0.4572 0.508)
			(layers "B.Cu" "B.Mask" "B.Paste")
			(net "GND")
		)
	)
	(footprint ""
		(layer "B.Cu")
		(at 78.978506 -21.14296 90)
		(property "Reference" "C146"
			(at -5.852668 -0.770128 270)
			(unlocked yes)
			(layer "B.SilkS")
			(effects
				(font
					(size 0.7874 0.5842)
					(thickness 0.1524)
				)
				(justify left mirror)
			)
		)
		(property "Value" ""
			(at 0 0 90)
			(layer "B.Fab")
			(effects
				(font
					(size 1.27 1.27)
				)
				(justify mirror)
			)
		)
		(duplicate_pad_numbers_are_jumpers no)
		(fp_line
			(start 0.7874 -0.4064)
			(end -0.7874 -0.4064)
			(stroke
				(width 0.1524)
				(type default)
			)
			(layer "B.SilkS")
		)
		(fp_line
			(start -0.7874 -0.4064)
			(end -0.7874 0.4064)
			(stroke
				(width 0.1524)
				(type default)
			)
			(layer "B.SilkS")
		)
		(fp_line
			(start 0 0.381)
			(end 0 -0.381)
			(stroke
				(width 0.1524)
				(type default)
			)
			(layer "B.SilkS")
		)
		(fp_line
			(start 0.7874 0.4064)
			(end 0.7874 -0.4064)
			(stroke
				(width 0.1524)
				(type default)
			)
			(layer "B.SilkS")
		)
		(fp_line
			(start -0.7874 0.4064)
			(end 0.7874 0.4064)
			(stroke
				(width 0.1524)
				(type default)
			)
			(layer "B.SilkS")
		)
		(fp_poly
			(pts
				(xy 0.5334 0.254) (xy 0.635 0.254) (xy 0.635 0.2286) (xy 0.635 -0.254) (xy 0.5334 -0.254) (xy 0.5334 -0.2794)
				(xy -0.5334 -0.2794) (xy -0.5334 -0.254) (xy -0.635 -0.254) (xy -0.635 0.254) (xy -0.5334 0.254)
				(xy -0.5334 0.2794) (xy 0.508 0.2794) (xy 0.5334 0.2794)
			)
			(stroke
				(width 0)
				(type default)
			)
			(fill no)
			(layer "B.CrtYd")
		)
		(pad "1" smd rect
			(at -0.40005 0 270)
			(size 0.4572 0.508)
			(layers "B.Cu" "B.Mask" "B.Paste")
			(net "PV_VDDR_NODE1")
		)
		(pad "2" smd rect
			(at 0.40005 0 270)
			(size 0.4572 0.508)
			(layers "B.Cu" "B.Mask" "B.Paste")
			(net "GND")
		)
	)
	(footprint ""
		(layer "B.Cu")
		(at 176.1236 -192.582292 -90)
		(property "Reference" ""
			(at 0 0 90)
			(layer "B.SilkS")
			(hide yes)
			(effects
				(font
					(size 1.27 1.27)
				)
				(justify mirror)
			)
		)
		(property "Value" ""
			(at 0 0 90)
			(layer "B.Fab")
			(effects
				(font
					(size 1.27 1.27)
				)
				(justify mirror)
			)
		)
		(duplicate_pad_numbers_are_jumpers no)
		(fp_poly
			(pts
				(arc
					(start 0 -1.4986)
					(mid 0 1.4986)
					(end 0 -1.4986)
				)
			)
			(stroke
				(width 0)
				(type default)
			)
			(fill no)
			(layer "B.CrtYd")
		)
		(pad "1" smd circle
			(at 0 0 90)
			(size 0.9906 0.9906)
			(layers "B.Cu" "B.Mask" "B.Paste")
			(net "Net_38")
		)
		(zone
			(layer "B.Cu")
			(hatch none 0.5)
			(connect_pads
				(clearance 0)
			)
			(min_thickness 0.25)
			(keepout
				(tracks not_allowed)
				(vias allowed)
				(pads allowed)
				(copperpour not_allowed)
				(footprints allowed)
			)
			(placement
				(enabled no)
				(sheetname "")
			)
			(fill
				(thermal_gap 0.5)
				(thermal_bridge_width 0.5)
				(island_removal_mode 0)
			)
			(polygon
				(pts
					(arc
						(start 177.7492 -192.582292)
						(mid 174.498 -192.582292)
						(end 177.7492 -192.582292)
					)
				)
			)
		)
	)
	(footprint ""
		(layer "B.Cu")
		(at 69.96176 -185.205624 90)
		(property "Reference" "R923"
			(at 4.15163 -0.00635 270)
			(unlocked yes)
			(layer "B.SilkS")
			(effects
				(font
					(size 0.7874 0.5842)
					(thickness 0.1524)
				)
				(justify left mirror)
			)
		)
		(property "Value" ""
			(at 0 0 90)
			(layer "B.Fab")
			(effects
				(font
					(size 1.27 1.27)
				)
				(justify mirror)
			)
		)
		(duplicate_pad_numbers_are_jumpers no)
		(fp_line
			(start 0.7874 -0.4064)
			(end -0.7874 -0.4064)
			(stroke
				(width 0.1524)
				(type default)
			)
			(layer "B.SilkS")
		)
		(fp_line
			(start -0.7874 -0.4064)
			(end -0.7874 0.4064)
			(stroke
				(width 0.1524)
				(type default)
			)
			(layer "B.SilkS")
		)
		(fp_line
			(start 0.7874 0.4064)
			(end 0.7874 -0.4064)
			(stroke
				(width 0.1524)
				(type default)
			)
			(layer "B.SilkS")
		)
		(fp_line
			(start -0.7874 0.4064)
			(end 0.7874 0.4064)
			(stroke
				(width 0.1524)
				(type default)
			)
			(layer "B.SilkS")
		)
		(fp_poly
			(pts
				(xy 0.508 0.2794) (xy 0.508 0.2286) (xy 0.635 0.2286) (xy 0.635 -0.254) (xy 0.5334 -0.254) (xy 0.5334 -0.2794)
				(xy -0.5334 -0.2794) (xy -0.5334 -0.254) (xy -0.635 -0.254) (xy -0.635 0.254) (xy -0.5334 0.254)
				(xy -0.5334 0.2794)
			)
			(stroke
				(width 0)
				(type default)
			)
			(fill no)
			(layer "B.CrtYd")
		)
		(pad "1" smd rect
			(at -0.40005 0 270)
			(size 0.4572 0.508)
			(layers "B.Cu" "B.Mask" "B.Paste")
			(net "UART_T3_NODE3_TXD")
		)
		(pad "2" smd rect
			(at 0.40005 0 270)
			(size 0.4572 0.508)
			(layers "B.Cu" "B.Mask" "B.Paste")
			(net "UART_T3_NODE3_TXD_R")
		)
	)
	(footprint ""
		(layer "B.Cu")
		(at 68.246498 -96.696784 90)
		(property "Reference" "R110"
			(at -2.631694 -0.989584 270)
			(unlocked yes)
			(layer "B.SilkS")
			(effects
				(font
					(size 0.7874 0.5842)
					(thickness 0.1524)
				)
				(justify left mirror)
			)
		)
		(property "Value" ""
			(at 0 0 90)
			(layer "B.Fab")
			(effects
				(font
					(size 1.27 1.27)
				)
				(justify mirror)
			)
		)
		(duplicate_pad_numbers_are_jumpers no)
		(fp_line
			(start 0.7874 -0.4064)
			(end -0.7874 -0.4064)
			(stroke
				(width 0.1524)
				(type default)
			)
			(layer "B.SilkS")
		)
		(fp_line
			(start -0.7874 -0.4064)
			(end -0.7874 0.4064)
			(stroke
				(width 0.1524)
				(type default)
			)
			(layer "B.SilkS")
		)
		(fp_line
			(start 0.7874 0.4064)
			(end 0.7874 -0.4064)
			(stroke
				(width 0.1524)
				(type default)
			)
			(layer "B.SilkS")
		)
		(fp_line
			(start -0.7874 0.4064)
			(end 0.7874 0.4064)
			(stroke
				(width 0.1524)
				(type default)
			)
			(layer "B.SilkS")
		)
		(fp_poly
			(pts
				(xy 0.508 0.2794) (xy 0.508 0.2286) (xy 0.635 0.2286) (xy 0.635 -0.254) (xy 0.5334 -0.254) (xy 0.5334 -0.2794)
				(xy -0.5334 -0.2794) (xy -0.5334 -0.254) (xy -0.635 -0.254) (xy -0.635 0.254) (xy -0.5334 0.254)
				(xy -0.5334 0.2794)
			)
			(stroke
				(width 0)
				(type default)
			)
			(fill no)
			(layer "B.CrtYd")
		)
		(pad "1" smd rect
			(at -0.40005 0 270)
			(size 0.4572 0.508)
			(layers "B.Cu" "B.Mask" "B.Paste")
			(net "CPU_RSV_1_R")
		)
		(pad "2" smd rect
			(at 0.40005 0 270)
			(size 0.4572 0.508)
			(layers "B.Cu" "B.Mask" "B.Paste")
			(net "CPU_RSV_1")
		)
	)
	(footprint ""
		(layer "B.Cu")
		(at 155.661614 -64.971422 90)
		(property "Reference" "L30"
			(at -2.04343 6.068568 270)
			(unlocked yes)
			(layer "B.SilkS")
			(effects
				(font
					(size 0.7874 0.5842)
					(thickness 0.1524)
				)
				(justify left mirror)
			)
		)
		(property "Value" ""
			(at 0 0 90)
			(layer "B.Fab")
			(effects
				(font
					(size 1.27 1.27)
				)
				(justify mirror)
			)
		)
		(duplicate_pad_numbers_are_jumpers no)
		(fp_line
			(start 0.7874 -0.4064)
			(end -0.7874 -0.4064)
			(stroke
				(width 0.1524)
				(type default)
			)
			(layer "B.SilkS")
		)
		(fp_line
			(start -0.7874 -0.4064)
			(end -0.7874 0.4064)
			(stroke
				(width 0.1524)
				(type default)
			)
			(layer "B.SilkS")
		)
		(fp_line
			(start 0.7874 0.4064)
			(end 0.7874 -0.4064)
			(stroke
				(width 0.1524)
				(type default)
			)
			(layer "B.SilkS")
		)
		(fp_line
			(start 0.0889 0.4064)
			(end 0.0889 -0.4064)
			(stroke
				(width 0.1524)
				(type default)
			)
			(layer "B.SilkS")
		)
		(fp_line
			(start -0.0889 0.4064)
			(end -0.0889 -0.4064)
			(stroke
				(width 0.1524)
				(type default)
			)
			(layer "B.SilkS")
		)
		(fp_line
			(start -0.7874 0.4064)
			(end 0.7874 0.4064)
			(stroke
				(width 0.1524)
				(type default)
			)
			(layer "B.SilkS")
		)
		(fp_poly
			(pts
				(xy 0.5334 0.254) (xy 0.635 0.254) (xy 0.635 0.2286) (xy 0.635 -0.254) (xy 0.5334 -0.254) (xy 0.5334 -0.2794)
				(xy -0.5334 -0.2794) (xy -0.5334 -0.254) (xy -0.635 -0.254) (xy -0.635 0.254) (xy -0.5334 0.254)
				(xy -0.5334 0.2794) (xy 0.508 0.2794) (xy 0.5334 0.2794)
			)
			(stroke
				(width 0)
				(type default)
			)
			(fill no)
			(layer "B.CrtYd")
		)
		(pad "1" smd rect
			(at -0.40005 0 270)
			(size 0.4572 0.508)
			(layers "B.Cu" "B.Mask" "B.Paste")
			(net "P1V8_NODE1")
		)
		(pad "2" smd rect
			(at 0.40005 0 270)
			(size 0.4572 0.508)
			(layers "B.Cu" "B.Mask" "B.Paste")
			(net "P1V8_SATA_VAA2_0_NODE1")
		)
	)
	(footprint ""
		(layer "B.Cu")
		(at 75.148948 -21.12264 90)
		(property "Reference" "C154"
			(at -5.832348 -0.078486 270)
			(unlocked yes)
			(layer "B.SilkS")
			(effects
				(font
					(size 0.7874 0.5842)
					(thickness 0.1524)
				)
				(justify left mirror)
			)
		)
		(property "Value" ""
			(at 0 0 90)
			(layer "B.Fab")
			(effects
				(font
					(size 1.27 1.27)
				)
				(justify mirror)
			)
		)
		(duplicate_pad_numbers_are_jumpers no)
		(fp_line
			(start 0.7874 -0.4064)
			(end -0.7874 -0.4064)
			(stroke
				(width 0.1524)
				(type default)
			)
			(layer "B.SilkS")
		)
		(fp_line
			(start -0.7874 -0.4064)
			(end -0.7874 0.4064)
			(stroke
				(width 0.1524)
				(type default)
			)
			(layer "B.SilkS")
		)
		(fp_line
			(start 0 0.381)
			(end 0 -0.381)
			(stroke
				(width 0.1524)
				(type default)
			)
			(layer "B.SilkS")
		)
		(fp_line
			(start 0.7874 0.4064)
			(end 0.7874 -0.4064)
			(stroke
				(width 0.1524)
				(type default)
			)
			(layer "B.SilkS")
		)
		(fp_line
			(start -0.7874 0.4064)
			(end 0.7874 0.4064)
			(stroke
				(width 0.1524)
				(type default)
			)
			(layer "B.SilkS")
		)
		(fp_poly
			(pts
				(xy 0.5334 0.254) (xy 0.635 0.254) (xy 0.635 0.2286) (xy 0.635 -0.254) (xy 0.5334 -0.254) (xy 0.5334 -0.2794)
				(xy -0.5334 -0.2794) (xy -0.5334 -0.254) (xy -0.635 -0.254) (xy -0.635 0.254) (xy -0.5334 0.254)
				(xy -0.5334 0.2794) (xy 0.508 0.2794) (xy 0.5334 0.2794)
			)
			(stroke
				(width 0)
				(type default)
			)
			(fill no)
			(layer "B.CrtYd")
		)
		(pad "1" smd rect
			(at -0.40005 0 270)
			(size 0.4572 0.508)
			(layers "B.Cu" "B.Mask" "B.Paste")
			(net "PV_VDDR_NODE1")
		)
		(pad "2" smd rect
			(at 0.40005 0 270)
			(size 0.4572 0.508)
			(layers "B.Cu" "B.Mask" "B.Paste")
			(net "GND")
		)
	)
	(footprint ""
		(layer "B.Cu")
		(at 50.53076 -188.126624 -90)
		(property "Reference" "R855"
			(at -4.318254 0.671576 270)
			(unlocked yes)
			(layer "B.SilkS")
			(effects
				(font
					(size 0.7874 0.5842)
					(thickness 0.1524)
				)
				(justify left mirror)
			)
		)
		(property "Value" ""
			(at 0 0 90)
			(layer "B.Fab")
			(effects
				(font
					(size 1.27 1.27)
				)
				(justify mirror)
			)
		)
		(duplicate_pad_numbers_are_jumpers no)
		(fp_line
			(start -0.7874 0.4064)
			(end 0.7874 0.4064)
			(stroke
				(width 0.1524)
				(type default)
			)
			(layer "B.SilkS")
		)
		(fp_line
			(start 0.7874 0.4064)
			(end 0.7874 -0.4064)
			(stroke
				(width 0.1524)
				(type default)
			)
			(layer "B.SilkS")
		)
		(fp_line
			(start -0.7874 -0.4064)
			(end -0.7874 0.4064)
			(stroke
				(width 0.1524)
				(type default)
			)
			(layer "B.SilkS")
		)
		(fp_line
			(start 0.7874 -0.4064)
			(end -0.7874 -0.4064)
			(stroke
				(width 0.1524)
				(type default)
			)
			(layer "B.SilkS")
		)
		(fp_poly
			(pts
				(xy 0.508 0.2794) (xy 0.508 0.2286) (xy 0.635 0.2286) (xy 0.635 -0.254) (xy 0.5334 -0.254) (xy 0.5334 -0.2794)
				(xy -0.5334 -0.2794) (xy -0.5334 -0.254) (xy -0.635 -0.254) (xy -0.635 0.254) (xy -0.5334 0.254)
				(xy -0.5334 0.2794)
			)
			(stroke
				(width 0)
				(type default)
			)
			(fill no)
			(layer "B.CrtYd")
		)
		(pad "1" smd rect
			(at -0.40005 0 90)
			(size 0.4572 0.508)
			(layers "B.Cu" "B.Mask" "B.Paste")
			(net "PSU3_DC_OK_R")
		)
		(pad "2" smd rect
			(at 0.40005 0 90)
			(size 0.4572 0.508)
			(layers "B.Cu" "B.Mask" "B.Paste")
			(net "GND")
		)
	)
	(footprint ""
		(layer "B.Cu")
		(at 27.969972 -115.223544)
		(property "Reference" "C97"
			(at -2.203958 -0.129794 0)
			(unlocked yes)
			(layer "B.SilkS")
			(effects
				(font
					(size 0.7874 0.5842)
					(thickness 0.1524)
				)
				(justify left mirror)
			)
		)
		(property "Value" ""
			(at 0 0 0)
			(layer "B.Fab")
			(effects
				(font
					(size 1.27 1.27)
				)
				(justify mirror)
			)
		)
		(duplicate_pad_numbers_are_jumpers no)
		(fp_line
			(start -1.905 -0.8636)
			(end -1.905 0.8636)
			(stroke
				(width 0.1524)
				(type default)
			)
			(layer "B.SilkS")
		)
		(fp_line
			(start -1.905 0.8636)
			(end 1.905 0.8636)
			(stroke
				(width 0.1524)
				(type default)
			)
			(layer "B.SilkS")
		)
		(fp_line
			(start 0 0.8382)
			(end 0 -0.8382)
			(stroke
				(width 0.1524)
				(type default)
			)
			(layer "B.SilkS")
		)
		(fp_line
			(start 1.905 -0.8636)
			(end -1.905 -0.8636)
			(stroke
				(width 0.1524)
				(type default)
			)
			(layer "B.SilkS")
		)
		(fp_line
			(start 1.905 0.8636)
			(end 1.905 -0.8636)
			(stroke
				(width 0.1524)
				(type default)
			)
			(layer "B.SilkS")
		)
		(fp_rect
			(start 1.524 0.7366)
			(end -1.524 -0.7366)
			(stroke
				(width 0)
				(type default)
			)
			(fill no)
			(layer "B.CrtYd")
		)
		(pad "1" smd rect
			(at -0.94996 0 180)
			(size 1.1176 1.3716)
			(layers "B.Cu" "B.Mask" "B.Paste")
			(net "P1V05_NODE1")
		)
		(pad "2" smd rect
			(at 0.94996 0 180)
			(size 1.1176 1.3716)
			(layers "B.Cu" "B.Mask" "B.Paste")
			(net "GND")
		)
	)
	(footprint ""
		(layer "B.Cu")
		(at 125.545596 -32.681164 180)
		(property "Reference" "R628"
			(at -2.291334 1.07188 0)
			(unlocked yes)
			(layer "B.SilkS")
			(effects
				(font
					(size 0.7874 0.5842)
					(thickness 0.1524)
				)
				(justify left mirror)
			)
		)
		(property "Value" ""
			(at 0 0 0)
			(layer "B.Fab")
			(effects
				(font
					(size 1.27 1.27)
				)
				(justify mirror)
			)
		)
		(duplicate_pad_numbers_are_jumpers no)
		(fp_line
			(start 0.7874 0.4064)
			(end 0.7874 -0.4064)
			(stroke
				(width 0.1524)
				(type default)
			)
			(layer "B.SilkS")
		)
		(fp_line
			(start 0.7874 -0.4064)
			(end -0.7874 -0.4064)
			(stroke
				(width 0.1524)
				(type default)
			)
			(layer "B.SilkS")
		)
		(fp_line
			(start -0.7874 0.4064)
			(end 0.7874 0.4064)
			(stroke
				(width 0.1524)
				(type default)
			)
			(layer "B.SilkS")
		)
		(fp_line
			(start -0.7874 -0.4064)
			(end -0.7874 0.4064)
			(stroke
				(width 0.1524)
				(type default)
			)
			(layer "B.SilkS")
		)
		(fp_poly
			(pts
				(xy 0.508 0.2794) (xy 0.508 0.2286) (xy 0.635 0.2286) (xy 0.635 -0.254) (xy 0.5334 -0.254) (xy 0.5334 -0.2794)
				(xy -0.5334 -0.2794) (xy -0.5334 -0.254) (xy -0.635 -0.254) (xy -0.635 0.254) (xy -0.5334 0.254)
				(xy -0.5334 0.2794)
			)
			(stroke
				(width 0)
				(type default)
			)
			(fill no)
			(layer "B.CrtYd")
		)
		(pad "1" smd rect
			(at -0.40005 0)
			(size 0.4572 0.508)
			(layers "B.Cu" "B.Mask" "B.Paste")
			(net "P5V_STB_NODE1")
		)
		(pad "2" smd rect
			(at 0.40005 0)
			(size 0.4572 0.508)
			(layers "B.Cu" "B.Mask" "B.Paste")
			(net "SIO_VCCH")
		)
	)
	(footprint ""
		(layer "B.Cu")
		(at 60.118498 -96.696784 -90)
		(property "Reference" "R62"
			(at -6.3627 5.414264 270)
			(unlocked yes)
			(layer "B.SilkS")
			(effects
				(font
					(size 0.7874 0.5842)
					(thickness 0.1524)
				)
				(justify left mirror)
			)
		)
		(property "Value" ""
			(at 0 0 90)
			(layer "B.Fab")
			(effects
				(font
					(size 1.27 1.27)
				)
				(justify mirror)
			)
		)
		(duplicate_pad_numbers_are_jumpers no)
		(fp_line
			(start -0.7874 0.4064)
			(end 0.7874 0.4064)
			(stroke
				(width 0.1524)
				(type default)
			)
			(layer "B.SilkS")
		)
		(fp_line
			(start 0.7874 0.4064)
			(end 0.7874 -0.4064)
			(stroke
				(width 0.1524)
				(type default)
			)
			(layer "B.SilkS")
		)
		(fp_line
			(start -0.7874 -0.4064)
			(end -0.7874 0.4064)
			(stroke
				(width 0.1524)
				(type default)
			)
			(layer "B.SilkS")
		)
		(fp_line
			(start 0.7874 -0.4064)
			(end -0.7874 -0.4064)
			(stroke
				(width 0.1524)
				(type default)
			)
			(layer "B.SilkS")
		)
		(fp_poly
			(pts
				(xy 0.508 0.2794) (xy 0.508 0.2286) (xy 0.635 0.2286) (xy 0.635 -0.254) (xy 0.5334 -0.254) (xy 0.5334 -0.2794)
				(xy -0.5334 -0.2794) (xy -0.5334 -0.254) (xy -0.635 -0.254) (xy -0.635 0.254) (xy -0.5334 0.254)
				(xy -0.5334 0.2794)
			)
			(stroke
				(width 0)
				(type default)
			)
			(fill no)
			(layer "B.CrtYd")
		)
		(pad "1" smd rect
			(at -0.40005 0 90)
			(size 0.4572 0.508)
			(layers "B.Cu" "B.Mask" "B.Paste")
			(net "LPC_CPU_NODE1_LAD1")
		)
		(pad "2" smd rect
			(at 0.40005 0 90)
			(size 0.4572 0.508)
			(layers "B.Cu" "B.Mask" "B.Paste")
			(net "LPC_CPU_NODE1_LAD1_R")
		)
	)
	(footprint ""
		(layer "B.Cu")
		(at 26.432256 -156.570172)
		(property "Reference" "C512"
			(at -2.96926 -0.13335 0)
			(unlocked yes)
			(layer "B.SilkS")
			(effects
				(font
					(size 0.7874 0.5842)
					(thickness 0.1524)
				)
				(justify left mirror)
			)
		)
		(property "Value" ""
			(at 0 0 0)
			(layer "B.Fab")
			(effects
				(font
					(size 1.27 1.27)
				)
				(justify mirror)
			)
		)
		(duplicate_pad_numbers_are_jumpers no)
		(fp_line
			(start -0.7874 -0.4064)
			(end -0.7874 0.4064)
			(stroke
				(width 0.1524)
				(type default)
			)
			(layer "B.SilkS")
		)
		(fp_line
			(start -0.7874 0.4064)
			(end 0.7874 0.4064)
			(stroke
				(width 0.1524)
				(type default)
			)
			(layer "B.SilkS")
		)
		(fp_line
			(start 0 0.381)
			(end 0 -0.381)
			(stroke
				(width 0.1524)
				(type default)
			)
			(layer "B.SilkS")
		)
		(fp_line
			(start 0.7874 -0.4064)
			(end -0.7874 -0.4064)
			(stroke
				(width 0.1524)
				(type default)
			)
			(layer "B.SilkS")
		)
		(fp_line
			(start 0.7874 0.4064)
			(end 0.7874 -0.4064)
			(stroke
				(width 0.1524)
				(type default)
			)
			(layer "B.SilkS")
		)
		(fp_poly
			(pts
				(xy 0.5334 0.254) (xy 0.635 0.254) (xy 0.635 0.2286) (xy 0.635 -0.254) (xy 0.5334 -0.254) (xy 0.5334 -0.2794)
				(xy -0.5334 -0.2794) (xy -0.5334 -0.254) (xy -0.635 -0.254) (xy -0.635 0.254) (xy -0.5334 0.254)
				(xy -0.5334 0.2794) (xy 0.508 0.2794) (xy 0.5334 0.2794)
			)
			(stroke
				(width 0)
				(type default)
			)
			(fill no)
			(layer "B.CrtYd")
		)
		(pad "1" smd rect
			(at -0.40005 0 180)
			(size 0.4572 0.508)
			(layers "B.Cu" "B.Mask" "B.Paste")
			(net "P1V9_LAN1")
		)
		(pad "2" smd rect
			(at 0.40005 0 180)
			(size 0.4572 0.508)
			(layers "B.Cu" "B.Mask" "B.Paste")
			(net "GND")
		)
	)
	(footprint ""
		(layer "B.Cu")
		(at 189.37732 -15.96898 -90)
		(property "Reference" ""
			(at 0 0 90)
			(layer "B.SilkS")
			(hide yes)
			(effects
				(font
					(size 1.27 1.27)
				)
				(justify mirror)
			)
		)
		(property "Value" ""
			(at 0 0 90)
			(layer "B.Fab")
			(effects
				(font
					(size 1.27 1.27)
				)
				(justify mirror)
			)
		)
		(duplicate_pad_numbers_are_jumpers no)
		(fp_poly
			(pts
				(arc
					(start 0 -1.4986)
					(mid 0 1.4986)
					(end 0 -1.4986)
				)
			)
			(stroke
				(width 0)
				(type default)
			)
			(fill no)
			(layer "B.CrtYd")
		)
		(pad "1" smd circle
			(at 0 0 90)
			(size 0.9906 0.9906)
			(layers "B.Cu" "B.Mask" "B.Paste")
			(net "Net_40")
		)
		(zone
			(layer "B.Cu")
			(hatch none 0.5)
			(connect_pads
				(clearance 0)
			)
			(min_thickness 0.25)
			(keepout
				(tracks not_allowed)
				(vias allowed)
				(pads allowed)
				(copperpour not_allowed)
				(footprints allowed)
			)
			(placement
				(enabled no)
				(sheetname "")
			)
			(fill
				(thermal_gap 0.5)
				(thermal_bridge_width 0.5)
				(island_removal_mode 0)
			)
			(polygon
				(pts
					(arc
						(start 191.00292 -15.96898)
						(mid 187.75172 -15.96898)
						(end 191.00292 -15.96898)
					)
				)
			)
		)
	)
	(footprint ""
		(layer "B.Cu")
		(at 63.812674 -82.151728 -90)
		(property "Reference" "C77"
			(at 32.255206 14.433804 270)
			(unlocked yes)
			(layer "B.SilkS")
			(effects
				(font
					(size 0.7874 0.5842)
					(thickness 0.1524)
				)
				(justify left mirror)
			)
		)
		(property "Value" ""
			(at 0 0 90)
			(layer "B.Fab")
			(effects
				(font
					(size 1.27 1.27)
				)
				(justify mirror)
			)
		)
		(duplicate_pad_numbers_are_jumpers no)
		(fp_line
			(start -0.7874 0.4064)
			(end 0.7874 0.4064)
			(stroke
				(width 0.1524)
				(type default)
			)
			(layer "B.SilkS")
		)
		(fp_line
			(start 0.7874 0.4064)
			(end 0.7874 -0.4064)
			(stroke
				(width 0.1524)
				(type default)
			)
			(layer "B.SilkS")
		)
		(fp_line
			(start 0 0.381)
			(end 0 -0.381)
			(stroke
				(width 0.1524)
				(type default)
			)
			(layer "B.SilkS")
		)
		(fp_line
			(start -0.7874 -0.4064)
			(end -0.7874 0.4064)
			(stroke
				(width 0.1524)
				(type default)
			)
			(layer "B.SilkS")
		)
		(fp_line
			(start 0.7874 -0.4064)
			(end -0.7874 -0.4064)
			(stroke
				(width 0.1524)
				(type default)
			)
			(layer "B.SilkS")
		)
		(fp_poly
			(pts
				(xy 0.5334 0.254) (xy 0.635 0.254) (xy 0.635 0.2286) (xy 0.635 -0.254) (xy 0.5334 -0.254) (xy 0.5334 -0.2794)
				(xy -0.5334 -0.2794) (xy -0.5334 -0.254) (xy -0.635 -0.254) (xy -0.635 0.254) (xy -0.5334 0.254)
				(xy -0.5334 0.2794) (xy 0.508 0.2794) (xy 0.5334 0.2794)
			)
			(stroke
				(width 0)
				(type default)
			)
			(fill no)
			(layer "B.CrtYd")
		)
		(pad "1" smd rect
			(at -0.40005 0 90)
			(size 0.4572 0.508)
			(layers "B.Cu" "B.Mask" "B.Paste")
			(net "P1V8_SUS_NODE1")
		)
		(pad "2" smd rect
			(at 0.40005 0 90)
			(size 0.4572 0.508)
			(layers "B.Cu" "B.Mask" "B.Paste")
			(net "GND")
		)
	)
	(footprint ""
		(layer "B.Cu")
		(at 48.42002 -79.147162)
		(property "Reference" "C56"
			(at -14.7574 31.544006 0)
			(unlocked yes)
			(layer "B.SilkS")
			(effects
				(font
					(size 0.7874 0.5842)
					(thickness 0.1524)
				)
				(justify left mirror)
			)
		)
		(property "Value" ""
			(at 0 0 0)
			(layer "B.Fab")
			(effects
				(font
					(size 1.27 1.27)
				)
				(justify mirror)
			)
		)
		(duplicate_pad_numbers_are_jumpers no)
		(fp_line
			(start -0.7874 -0.4064)
			(end -0.7874 0.4064)
			(stroke
				(width 0.1524)
				(type default)
			)
			(layer "B.SilkS")
		)
		(fp_line
			(start -0.7874 0.4064)
			(end 0.7874 0.4064)
			(stroke
				(width 0.1524)
				(type default)
			)
			(layer "B.SilkS")
		)
		(fp_line
			(start 0 0.381)
			(end 0 -0.381)
			(stroke
				(width 0.1524)
				(type default)
			)
			(layer "B.SilkS")
		)
		(fp_line
			(start 0.7874 -0.4064)
			(end -0.7874 -0.4064)
			(stroke
				(width 0.1524)
				(type default)
			)
			(layer "B.SilkS")
		)
		(fp_line
			(start 0.7874 0.4064)
			(end 0.7874 -0.4064)
			(stroke
				(width 0.1524)
				(type default)
			)
			(layer "B.SilkS")
		)
		(fp_poly
			(pts
				(xy 0.5334 0.254) (xy 0.635 0.254) (xy 0.635 0.2286) (xy 0.635 -0.254) (xy 0.5334 -0.254) (xy 0.5334 -0.2794)
				(xy -0.5334 -0.2794) (xy -0.5334 -0.254) (xy -0.635 -0.254) (xy -0.635 0.254) (xy -0.5334 0.254)
				(xy -0.5334 0.2794) (xy 0.508 0.2794) (xy 0.5334 0.2794)
			)
			(stroke
				(width 0)
				(type default)
			)
			(fill no)
			(layer "B.CrtYd")
		)
		(pad "1" smd rect
			(at -0.40005 0 180)
			(size 0.4572 0.508)
			(layers "B.Cu" "B.Mask" "B.Paste")
			(net "P1V05_NODE1")
		)
		(pad "2" smd rect
			(at 0.40005 0 180)
			(size 0.4572 0.508)
			(layers "B.Cu" "B.Mask" "B.Paste")
			(net "GND")
		)
	)
	(footprint ""
		(layer "B.Cu")
		(at 165.210998 -150.30323 180)
		(property "Reference" "C455"
			(at 1.156462 0.177292 0)
			(unlocked yes)
			(layer "B.SilkS")
			(effects
				(font
					(size 0.7874 0.5842)
					(thickness 0.1524)
				)
				(justify left mirror)
			)
		)
		(property "Value" ""
			(at 0 0 0)
			(layer "B.Fab")
			(effects
				(font
					(size 1.27 1.27)
				)
				(justify mirror)
			)
		)
		(duplicate_pad_numbers_are_jumpers no)
		(fp_line
			(start 0.7874 0.4064)
			(end 0.7874 -0.4064)
			(stroke
				(width 0.1524)
				(type default)
			)
			(layer "B.SilkS")
		)
		(fp_line
			(start 0.7874 -0.4064)
			(end -0.7874 -0.4064)
			(stroke
				(width 0.1524)
				(type default)
			)
			(layer "B.SilkS")
		)
		(fp_line
			(start 0 0.381)
			(end 0 -0.381)
			(stroke
				(width 0.1524)
				(type default)
			)
			(layer "B.SilkS")
		)
		(fp_line
			(start -0.7874 0.4064)
			(end 0.7874 0.4064)
			(stroke
				(width 0.1524)
				(type default)
			)
			(layer "B.SilkS")
		)
		(fp_line
			(start -0.7874 -0.4064)
			(end -0.7874 0.4064)
			(stroke
				(width 0.1524)
				(type default)
			)
			(layer "B.SilkS")
		)
		(fp_poly
			(pts
				(xy 0.5334 0.254) (xy 0.635 0.254) (xy 0.635 0.2286) (xy 0.635 -0.254) (xy 0.5334 -0.254) (xy 0.5334 -0.2794)
				(xy -0.5334 -0.2794) (xy -0.5334 -0.254) (xy -0.635 -0.254) (xy -0.635 0.254) (xy -0.5334 0.254)
				(xy -0.5334 0.2794) (xy 0.508 0.2794) (xy 0.5334 0.2794)
			)
			(stroke
				(width 0)
				(type default)
			)
			(fill no)
			(layer "B.CrtYd")
		)
		(pad "1" smd rect
			(at -0.40005 0)
			(size 0.4572 0.508)
			(layers "B.Cu" "B.Mask" "B.Paste")
			(net "P1V9_LAN2")
		)
		(pad "2" smd rect
			(at 0.40005 0)
			(size 0.4572 0.508)
			(layers "B.Cu" "B.Mask" "B.Paste")
			(net "GND")
		)
	)
	(footprint ""
		(layer "B.Cu")
		(at 133.969252 -151.31415 90)
		(property "Reference" "C869"
			(at 1.2446 1.166876 270)
			(unlocked yes)
			(layer "B.SilkS")
			(effects
				(font
					(size 0.7874 0.5842)
					(thickness 0.1524)
				)
				(justify left mirror)
			)
		)
		(property "Value" ""
			(at 0 0 90)
			(layer "B.Fab")
			(effects
				(font
					(size 1.27 1.27)
				)
				(justify mirror)
			)
		)
		(duplicate_pad_numbers_are_jumpers no)
		(fp_line
			(start 0.7874 -0.4064)
			(end -0.7874 -0.4064)
			(stroke
				(width 0.1524)
				(type default)
			)
			(layer "B.SilkS")
		)
		(fp_line
			(start -0.7874 -0.4064)
			(end -0.7874 0.4064)
			(stroke
				(width 0.1524)
				(type default)
			)
			(layer "B.SilkS")
		)
		(fp_line
			(start 0 0.381)
			(end 0 -0.381)
			(stroke
				(width 0.1524)
				(type default)
			)
			(layer "B.SilkS")
		)
		(fp_line
			(start 0.7874 0.4064)
			(end 0.7874 -0.4064)
			(stroke
				(width 0.1524)
				(type default)
			)
			(layer "B.SilkS")
		)
		(fp_line
			(start -0.7874 0.4064)
			(end 0.7874 0.4064)
			(stroke
				(width 0.1524)
				(type default)
			)
			(layer "B.SilkS")
		)
		(fp_poly
			(pts
				(xy 0.5334 0.254) (xy 0.635 0.254) (xy 0.635 0.2286) (xy 0.635 -0.254) (xy 0.5334 -0.254) (xy 0.5334 -0.2794)
				(xy -0.5334 -0.2794) (xy -0.5334 -0.254) (xy -0.635 -0.254) (xy -0.635 0.254) (xy -0.5334 0.254)
				(xy -0.5334 0.2794) (xy 0.508 0.2794) (xy 0.5334 0.2794)
			)
			(stroke
				(width 0)
				(type default)
			)
			(fill no)
			(layer "B.CrtYd")
		)
		(pad "1" smd rect
			(at -0.40005 0 270)
			(size 0.4572 0.508)
			(layers "B.Cu" "B.Mask" "B.Paste")
			(net "P3V3_NODE1")
		)
		(pad "2" smd rect
			(at 0.40005 0 270)
			(size 0.4572 0.508)
			(layers "B.Cu" "B.Mask" "B.Paste")
			(net "GND")
		)
	)
	(footprint ""
		(layer "B.Cu")
		(at 39.650416 -97.068132 -90)
		(property "Reference" "R131"
			(at -0.973328 -0.017272 270)
			(unlocked yes)
			(layer "B.SilkS")
			(effects
				(font
					(size 0.7874 0.5842)
					(thickness 0.1524)
				)
				(justify left mirror)
			)
		)
		(property "Value" ""
			(at 0 0 90)
			(layer "B.Fab")
			(effects
				(font
					(size 1.27 1.27)
				)
				(justify mirror)
			)
		)
		(duplicate_pad_numbers_are_jumpers no)
		(fp_line
			(start -0.7874 0.4064)
			(end 0.7874 0.4064)
			(stroke
				(width 0.1524)
				(type default)
			)
			(layer "B.SilkS")
		)
		(fp_line
			(start 0.7874 0.4064)
			(end 0.7874 -0.4064)
			(stroke
				(width 0.1524)
				(type default)
			)
			(layer "B.SilkS")
		)
		(fp_line
			(start -0.7874 -0.4064)
			(end -0.7874 0.4064)
			(stroke
				(width 0.1524)
				(type default)
			)
			(layer "B.SilkS")
		)
		(fp_line
			(start 0.7874 -0.4064)
			(end -0.7874 -0.4064)
			(stroke
				(width 0.1524)
				(type default)
			)
			(layer "B.SilkS")
		)
		(fp_poly
			(pts
				(xy 0.508 0.2794) (xy 0.508 0.2286) (xy 0.635 0.2286) (xy 0.635 -0.254) (xy 0.5334 -0.254) (xy 0.5334 -0.2794)
				(xy -0.5334 -0.2794) (xy -0.5334 -0.254) (xy -0.635 -0.254) (xy -0.635 0.254) (xy -0.5334 0.254)
				(xy -0.5334 0.2794)
			)
			(stroke
				(width 0)
				(type default)
			)
			(fill no)
			(layer "B.CrtYd")
		)
		(pad "1" smd rect
			(at -0.40005 0 90)
			(size 0.4572 0.508)
			(layers "B.Cu" "B.Mask" "B.Paste")
			(net "P3V3_NODE1")
		)
		(pad "2" smd rect
			(at 0.40005 0 90)
			(size 0.4572 0.508)
			(layers "B.Cu" "B.Mask" "B.Paste")
			(net "SMB_CPU_NODE1_BMC_CLK")
		)
	)
	(footprint ""
		(layer "B.Cu")
		(at -11.397488 -59.063382 -90)
		(property "Reference" "J29"
			(at -6.14426 -2.971038 0)
			(unlocked yes)
			(layer "B.SilkS")
			(effects
				(font
					(size 0.7874 0.5842)
					(thickness 0.1524)
				)
				(justify left mirror)
			)
		)
		(property "Value" ""
			(at 0 0 90)
			(layer "B.Fab")
			(effects
				(font
					(size 1.27 1.27)
				)
				(justify mirror)
			)
		)
		(duplicate_pad_numbers_are_jumpers no)
		(fp_circle
			(center -4.064 0)
			(end -4.064 -0.635)
			(stroke
				(width 0.05)
				(type default)
			)
			(fill no)
			(layer "Edge.Cuts")
		)
		(fp_circle
			(center 0 0)
			(end 0 -0.635)
			(stroke
				(width 0.05)
				(type default)
			)
			(fill no)
			(layer "Edge.Cuts")
		)
		(fp_circle
			(center -4.064 -4.572)
			(end -4.064 -5.207)
			(stroke
				(width 0.05)
				(type default)
			)
			(fill no)
			(layer "Edge.Cuts")
		)
		(fp_circle
			(center 0 -4.572)
			(end 0 -5.207)
			(stroke
				(width 0.05)
				(type default)
			)
			(fill no)
			(layer "Edge.Cuts")
		)
		(fp_rect
			(start 1.27 1.27)
			(end -5.334 -5.842)
			(stroke
				(width 0)
				(type default)
			)
			(fill no)
			(layer "B.CrtYd")
		)
		(pad "" np_thru_hole circle
			(at -4.064 -4.572 90)
			(size 0.254 0.254)
			(drill 1.27)
			(layers "*.Cu" "*.Mask")
			(clearance 0.889)
			(thermal_gap 0.889)
		)
		(pad "" np_thru_hole circle
			(at -4.064 0 90)
			(size 0.254 0.254)
			(drill 1.27)
			(layers "*.Cu" "*.Mask")
			(clearance 0.889)
			(thermal_gap 0.889)
		)
		(pad "" np_thru_hole circle
			(at 0 -4.572 90)
			(size 0.254 0.254)
			(drill 1.27)
			(layers "*.Cu" "*.Mask")
			(clearance 0.889)
			(thermal_gap 0.889)
		)
		(pad "" np_thru_hole circle
			(at 0 0 90)
			(size 0.254 0.254)
			(drill 1.27)
			(layers "*.Cu" "*.Mask")
			(clearance 0.889)
			(thermal_gap 0.889)
		)
		(pad "1" thru_hole custom
			(at -1.397 -2.286)
			(size 0.139735 0.139735)
			(drill 0.254)
			(layers "*.Cu" "*.Mask")
			(remove_unused_layers no)
			(net "GND")
			(options
				(clearance outline)
				(anchor circle)
			)
			(primitives
				(gr_poly
					(pts
						(arc
							(start 0.26035 -0.1016)
							(mid 0 -0.279472)
							(end -0.26035 -0.1016)
						)
						(arc
							(start -0.50165 -0.1016)
							(mid -1.041472 0)
							(end -0.50165 0.1016)
						)
						(arc
							(start -0.26035 0.1016)
							(mid 0 0.279472)
							(end 0.26035 0.1016)
						)
						(arc
							(start 0.50165 0.1016)
							(mid 1.041472 0)
							(end 0.50165 -0.1016)
						)
					)
					(width 0)
					(fill yes)
				)
			)
			(padstack
				(mode front_inner_back)
				(layer "Inner"
					(shape custom)
					(size 0.139735 0.139735)
					(options
						(anchor circle)
					)
					(primitives
						(gr_poly
							(pts
								(arc
									(start 0.26035 -0.1016)
									(mid 0 -0.279472)
									(end -0.26035 -0.1016)
								)
								(arc
									(start -0.50165 -0.1016)
									(mid -1.041472 0)
									(end -0.50165 0.1016)
								)
								(arc
									(start -0.26035 0.1016)
									(mid 0 0.279472)
									(end 0.26035 0.1016)
								)
								(arc
									(start 0.50165 0.1016)
									(mid 1.041472 0)
									(end 0.50165 -0.1016)
								)
							)
							(width 0)
							(fill yes)
						)
					)
				)
				(layer "B.Cu"
					(shape custom)
					(size 0.266741 0.266741)
					(options
						(anchor circle)
					)
					(primitives
						(gr_poly
							(pts
								(xy -0.979932 -0.5334)
								(arc
									(start -0.979932 0.078994)
									(mid -0.925932 0.48038)
									(end -0.527812 0.4064)
								)
								(arc
									(start -0.234188 0.4064)
									(mid 0 0.53341)
									(end 0.234188 0.4064)
								)
								(arc
									(start 0.527812 0.4064)
									(mid 0.925878 0.480305)
									(end 0.979932 0.078994)
								)
								(xy 0.979932 -0.5334) (xy 0.548132 -0.5334) (xy 0.548132 -0.1016) (xy -0.548132 -0.1016) (xy -0.548132 -0.5334)
							)
							(width 0)
							(fill yes)
						)
					)
				)
			)
		)
		(pad "2" smd rect
			(at -2.032 -2.060956 90)
			(size 0.3048 0.2032)
			(layers "B.Cu" "B.Mask" "B.Paste")
			(net "BOT_85OHM")
		)
		(pad "3" smd rect
			(at -2.032 -2.511044 90)
			(size 0.3048 0.2032)
			(layers "B.Cu" "B.Mask" "B.Paste")
			(net "BOT_85OHM")
		)
		(zone
			(layers "F.Cu" "B.Cu" "In1.Cu" "In2.Cu" "In3.Cu" "In4.Cu" "In5.Cu" "In6.Cu"
				"In7.Cu" "In8.Cu"
			)
			(hatch none 0.5)
			(connect_pads
				(clearance 0)
			)
			(min_thickness 0.25)
			(keepout
				(tracks not_allowed)
				(vias allowed)
				(pads allowed)
				(copperpour not_allowed)
				(footprints allowed)
			)
			(placement
				(enabled no)
				(sheetname "")
			)
			(fill
				(thermal_gap 0.5)
				(thermal_bridge_width 0.5)
				(island_removal_mode 0)
			)
			(polygon
				(pts
					(arc
						(start -11.397488 -64.016382)
						(mid -11.397488 -62.238382)
						(end -11.397488 -64.016382)
					)
				)
			)
		)
		(zone
			(layers "F.Cu" "B.Cu" "In1.Cu" "In2.Cu" "In3.Cu" "In4.Cu" "In5.Cu" "In6.Cu"
				"In7.Cu" "In8.Cu"
			)
			(hatch none 0.5)
			(connect_pads
				(clearance 0)
			)
			(min_thickness 0.25)
			(keepout
				(tracks not_allowed)
				(vias allowed)
				(pads allowed)
				(copperpour not_allowed)
				(footprints allowed)
			)
			(placement
				(enabled no)
				(sheetname "")
			)
			(fill
				(thermal_gap 0.5)
				(thermal_bridge_width 0.5)
				(island_removal_mode 0)
			)
			(polygon
				(pts
					(arc
						(start -11.397488 -59.952382)
						(mid -11.397488 -58.174382)
						(end -11.397488 -59.952382)
					)
				)
			)
		)
		(zone
			(layers "F.Cu" "B.Cu" "In1.Cu" "In2.Cu" "In3.Cu" "In4.Cu" "In5.Cu" "In6.Cu"
				"In7.Cu" "In8.Cu"
			)
			(hatch none 0.5)
			(connect_pads
				(clearance 0)
			)
			(min_thickness 0.25)
			(keepout
				(tracks not_allowed)
				(vias allowed)
				(pads allowed)
				(copperpour not_allowed)
				(footprints allowed)
			)
			(placement
				(enabled no)
				(sheetname "")
			)
			(fill
				(thermal_gap 0.5)
				(thermal_bridge_width 0.5)
				(island_removal_mode 0)
			)
			(polygon
				(pts
					(arc
						(start -6.825488 -64.016382)
						(mid -6.825488 -62.238382)
						(end -6.825488 -64.016382)
					)
				)
			)
		)
		(zone
			(layers "F.Cu" "B.Cu" "In1.Cu" "In2.Cu" "In3.Cu" "In4.Cu" "In5.Cu" "In6.Cu"
				"In7.Cu" "In8.Cu"
			)
			(hatch none 0.5)
			(connect_pads
				(clearance 0)
			)
			(min_thickness 0.25)
			(keepout
				(tracks not_allowed)
				(vias allowed)
				(pads allowed)
				(copperpour not_allowed)
				(footprints allowed)
			)
			(placement
				(enabled no)
				(sheetname "")
			)
			(fill
				(thermal_gap 0.5)
				(thermal_bridge_width 0.5)
				(island_removal_mode 0)
			)
			(polygon
				(pts
					(arc
						(start -6.825488 -59.952382)
						(mid -6.825488 -58.174382)
						(end -6.825488 -59.952382)
					)
				)
			)
		)
	)
	(footprint ""
		(layer "B.Cu")
		(at 137.970006 -34.39541)
		(property "Reference" "R1186"
			(at -4.172458 18.515838 0)
			(unlocked yes)
			(layer "B.SilkS")
			(effects
				(font
					(size 0.7874 0.5842)
					(thickness 0.1524)
				)
				(justify left mirror)
			)
		)
		(property "Value" ""
			(at 0 0 0)
			(layer "B.Fab")
			(effects
				(font
					(size 1.27 1.27)
				)
				(justify mirror)
			)
		)
		(duplicate_pad_numbers_are_jumpers no)
		(fp_line
			(start -0.7874 -0.4064)
			(end -0.7874 0.4064)
			(stroke
				(width 0.1524)
				(type default)
			)
			(layer "B.SilkS")
		)
		(fp_line
			(start -0.7874 0.4064)
			(end 0.7874 0.4064)
			(stroke
				(width 0.1524)
				(type default)
			)
			(layer "B.SilkS")
		)
		(fp_line
			(start 0.7874 -0.4064)
			(end -0.7874 -0.4064)
			(stroke
				(width 0.1524)
				(type default)
			)
			(layer "B.SilkS")
		)
		(fp_line
			(start 0.7874 0.4064)
			(end 0.7874 -0.4064)
			(stroke
				(width 0.1524)
				(type default)
			)
			(layer "B.SilkS")
		)
		(fp_poly
			(pts
				(xy 0.508 0.2794) (xy 0.508 0.2286) (xy 0.635 0.2286) (xy 0.635 -0.254) (xy 0.5334 -0.254) (xy 0.5334 -0.2794)
				(xy -0.5334 -0.2794) (xy -0.5334 -0.254) (xy -0.635 -0.254) (xy -0.635 0.254) (xy -0.5334 0.254)
				(xy -0.5334 0.2794)
			)
			(stroke
				(width 0)
				(type default)
			)
			(fill no)
			(layer "B.CrtYd")
		)
		(pad "1" smd rect
			(at -0.40005 0 180)
			(size 0.4572 0.508)
			(layers "B.Cu" "B.Mask" "B.Paste")
			(net "SIO_CPLD_RSV3_R")
		)
		(pad "2" smd rect
			(at 0.40005 0 180)
			(size 0.4572 0.508)
			(layers "B.Cu" "B.Mask" "B.Paste")
			(net "GND")
		)
	)
	(footprint ""
		(layer "B.Cu")
		(at 40.36822 -153.70429)
		(property "Reference" "C417"
			(at -6.35127 -10.195814 0)
			(unlocked yes)
			(layer "B.SilkS")
			(effects
				(font
					(size 0.7874 0.5842)
					(thickness 0.1524)
				)
				(justify left mirror)
			)
		)
		(property "Value" ""
			(at 0 0 0)
			(layer "B.Fab")
			(effects
				(font
					(size 1.27 1.27)
				)
				(justify mirror)
			)
		)
		(duplicate_pad_numbers_are_jumpers no)
		(fp_line
			(start -0.7874 -0.4064)
			(end -0.7874 0.4064)
			(stroke
				(width 0.1524)
				(type default)
			)
			(layer "B.SilkS")
		)
		(fp_line
			(start -0.7874 0.4064)
			(end 0.7874 0.4064)
			(stroke
				(width 0.1524)
				(type default)
			)
			(layer "B.SilkS")
		)
		(fp_line
			(start 0 0.381)
			(end 0 -0.381)
			(stroke
				(width 0.1524)
				(type default)
			)
			(layer "B.SilkS")
		)
		(fp_line
			(start 0.7874 -0.4064)
			(end -0.7874 -0.4064)
			(stroke
				(width 0.1524)
				(type default)
			)
			(layer "B.SilkS")
		)
		(fp_line
			(start 0.7874 0.4064)
			(end 0.7874 -0.4064)
			(stroke
				(width 0.1524)
				(type default)
			)
			(layer "B.SilkS")
		)
		(fp_poly
			(pts
				(xy 0.5334 0.254) (xy 0.635 0.254) (xy 0.635 0.2286) (xy 0.635 -0.254) (xy 0.5334 -0.254) (xy 0.5334 -0.2794)
				(xy -0.5334 -0.2794) (xy -0.5334 -0.254) (xy -0.635 -0.254) (xy -0.635 0.254) (xy -0.5334 0.254)
				(xy -0.5334 0.2794) (xy 0.508 0.2794) (xy 0.5334 0.2794)
			)
			(stroke
				(width 0)
				(type default)
			)
			(fill no)
			(layer "B.CrtYd")
		)
		(pad "1" smd rect
			(at -0.40005 0 180)
			(size 0.4572 0.508)
			(layers "B.Cu" "B.Mask" "B.Paste")
			(net "P1V05_LAN1")
		)
		(pad "2" smd rect
			(at 0.40005 0 180)
			(size 0.4572 0.508)
			(layers "B.Cu" "B.Mask" "B.Paste")
			(net "GND")
		)
	)
	(footprint ""
		(layer "B.Cu")
		(at 68.633086 -131.280662 90)
		(property "Reference" "C256"
			(at -55.831486 -38.570662 270)
			(unlocked yes)
			(layer "B.SilkS")
			(effects
				(font
					(size 0.7874 0.5842)
					(thickness 0.1524)
				)
				(justify left mirror)
			)
		)
		(property "Value" ""
			(at 0 0 90)
			(layer "B.Fab")
			(effects
				(font
					(size 1.27 1.27)
				)
				(justify mirror)
			)
		)
		(duplicate_pad_numbers_are_jumpers no)
		(fp_line
			(start 0.7874 -0.4064)
			(end -0.7874 -0.4064)
			(stroke
				(width 0.1524)
				(type default)
			)
			(layer "B.SilkS")
		)
		(fp_line
			(start -0.7874 -0.4064)
			(end -0.7874 0.4064)
			(stroke
				(width 0.1524)
				(type default)
			)
			(layer "B.SilkS")
		)
		(fp_line
			(start 0 0.381)
			(end 0 -0.381)
			(stroke
				(width 0.1524)
				(type default)
			)
			(layer "B.SilkS")
		)
		(fp_line
			(start 0.7874 0.4064)
			(end 0.7874 -0.4064)
			(stroke
				(width 0.1524)
				(type default)
			)
			(layer "B.SilkS")
		)
		(fp_line
			(start -0.7874 0.4064)
			(end 0.7874 0.4064)
			(stroke
				(width 0.1524)
				(type default)
			)
			(layer "B.SilkS")
		)
		(fp_poly
			(pts
				(xy 0.5334 0.254) (xy 0.635 0.254) (xy 0.635 0.2286) (xy 0.635 -0.254) (xy 0.5334 -0.254) (xy 0.5334 -0.2794)
				(xy -0.5334 -0.2794) (xy -0.5334 -0.254) (xy -0.635 -0.254) (xy -0.635 0.254) (xy -0.5334 0.254)
				(xy -0.5334 0.2794) (xy 0.508 0.2794) (xy 0.5334 0.2794)
			)
			(stroke
				(width 0)
				(type default)
			)
			(fill no)
			(layer "B.CrtYd")
		)
		(pad "1" smd rect
			(at -0.40005 0 270)
			(size 0.4572 0.508)
			(layers "B.Cu" "B.Mask" "B.Paste")
			(net "P3V3_NODE1")
		)
		(pad "2" smd rect
			(at 0.40005 0 270)
			(size 0.4572 0.508)
			(layers "B.Cu" "B.Mask" "B.Paste")
			(net "GND")
		)
	)
	(footprint ""
		(layer "B.Cu")
		(at 58.53176 -185.205624 90)
		(property "Reference" "R922"
			(at 4.15163 0.268224 270)
			(unlocked yes)
			(layer "B.SilkS")
			(effects
				(font
					(size 0.7874 0.5842)
					(thickness 0.1524)
				)
				(justify left mirror)
			)
		)
		(property "Value" ""
			(at 0 0 90)
			(layer "B.Fab")
			(effects
				(font
					(size 1.27 1.27)
				)
				(justify mirror)
			)
		)
		(duplicate_pad_numbers_are_jumpers no)
		(fp_line
			(start 0.7874 -0.4064)
			(end -0.7874 -0.4064)
			(stroke
				(width 0.1524)
				(type default)
			)
			(layer "B.SilkS")
		)
		(fp_line
			(start -0.7874 -0.4064)
			(end -0.7874 0.4064)
			(stroke
				(width 0.1524)
				(type default)
			)
			(layer "B.SilkS")
		)
		(fp_line
			(start 0.7874 0.4064)
			(end 0.7874 -0.4064)
			(stroke
				(width 0.1524)
				(type default)
			)
			(layer "B.SilkS")
		)
		(fp_line
			(start -0.7874 0.4064)
			(end 0.7874 0.4064)
			(stroke
				(width 0.1524)
				(type default)
			)
			(layer "B.SilkS")
		)
		(fp_poly
			(pts
				(xy 0.508 0.2794) (xy 0.508 0.2286) (xy 0.635 0.2286) (xy 0.635 -0.254) (xy 0.5334 -0.254) (xy 0.5334 -0.2794)
				(xy -0.5334 -0.2794) (xy -0.5334 -0.254) (xy -0.635 -0.254) (xy -0.635 0.254) (xy -0.5334 0.254)
				(xy -0.5334 0.2794)
			)
			(stroke
				(width 0)
				(type default)
			)
			(fill no)
			(layer "B.CrtYd")
		)
		(pad "1" smd rect
			(at -0.40005 0 270)
			(size 0.4572 0.508)
			(layers "B.Cu" "B.Mask" "B.Paste")
			(net "UART_T1_NODE3_TXD")
		)
		(pad "2" smd rect
			(at 0.40005 0 270)
			(size 0.4572 0.508)
			(layers "B.Cu" "B.Mask" "B.Paste")
			(net "UART_T1_NODE3_TXD_R")
		)
	)
	(footprint ""
		(layer "B.Cu")
		(at 64.736472 -138.915648 180)
		(property "Reference" "C250"
			(at 38.965886 -54.703218 0)
			(unlocked yes)
			(layer "B.SilkS")
			(effects
				(font
					(size 0.7874 0.5842)
					(thickness 0.1524)
				)
				(justify left mirror)
			)
		)
		(property "Value" ""
			(at 0 0 0)
			(layer "B.Fab")
			(effects
				(font
					(size 1.27 1.27)
				)
				(justify mirror)
			)
		)
		(duplicate_pad_numbers_are_jumpers no)
		(fp_line
			(start 0.7874 0.4064)
			(end 0.7874 -0.4064)
			(stroke
				(width 0.1524)
				(type default)
			)
			(layer "B.SilkS")
		)
		(fp_line
			(start 0.7874 -0.4064)
			(end -0.7874 -0.4064)
			(stroke
				(width 0.1524)
				(type default)
			)
			(layer "B.SilkS")
		)
		(fp_line
			(start 0 0.381)
			(end 0 -0.381)
			(stroke
				(width 0.1524)
				(type default)
			)
			(layer "B.SilkS")
		)
		(fp_line
			(start -0.7874 0.4064)
			(end 0.7874 0.4064)
			(stroke
				(width 0.1524)
				(type default)
			)
			(layer "B.SilkS")
		)
		(fp_line
			(start -0.7874 -0.4064)
			(end -0.7874 0.4064)
			(stroke
				(width 0.1524)
				(type default)
			)
			(layer "B.SilkS")
		)
		(fp_poly
			(pts
				(xy 0.5334 0.254) (xy 0.635 0.254) (xy 0.635 0.2286) (xy 0.635 -0.254) (xy 0.5334 -0.254) (xy 0.5334 -0.2794)
				(xy -0.5334 -0.2794) (xy -0.5334 -0.254) (xy -0.635 -0.254) (xy -0.635 0.254) (xy -0.5334 0.254)
				(xy -0.5334 0.2794) (xy 0.508 0.2794) (xy 0.5334 0.2794)
			)
			(stroke
				(width 0)
				(type default)
			)
			(fill no)
			(layer "B.CrtYd")
		)
		(pad "1" smd rect
			(at -0.40005 0)
			(size 0.4572 0.508)
			(layers "B.Cu" "B.Mask" "B.Paste")
			(net "P3V3_NODE1")
		)
		(pad "2" smd rect
			(at 0.40005 0)
			(size 0.4572 0.508)
			(layers "B.Cu" "B.Mask" "B.Paste")
			(net "GND")
		)
	)
	(footprint ""
		(layer "B.Cu")
		(at 132.978652 -137.92835 180)
		(property "Reference" "C895"
			(at -4.032504 0.06477 0)
			(unlocked yes)
			(layer "B.SilkS")
			(effects
				(font
					(size 0.7874 0.5842)
					(thickness 0.1524)
				)
				(justify left mirror)
			)
		)
		(property "Value" ""
			(at 0 0 0)
			(layer "B.Fab")
			(effects
				(font
					(size 1.27 1.27)
				)
				(justify mirror)
			)
		)
		(duplicate_pad_numbers_are_jumpers no)
		(fp_line
			(start 0.7874 0.4064)
			(end 0.7874 -0.4064)
			(stroke
				(width 0.1524)
				(type default)
			)
			(layer "B.SilkS")
		)
		(fp_line
			(start 0.7874 -0.4064)
			(end -0.7874 -0.4064)
			(stroke
				(width 0.1524)
				(type default)
			)
			(layer "B.SilkS")
		)
		(fp_line
			(start 0 0.381)
			(end 0 -0.381)
			(stroke
				(width 0.1524)
				(type default)
			)
			(layer "B.SilkS")
		)
		(fp_line
			(start -0.7874 0.4064)
			(end 0.7874 0.4064)
			(stroke
				(width 0.1524)
				(type default)
			)
			(layer "B.SilkS")
		)
		(fp_line
			(start -0.7874 -0.4064)
			(end -0.7874 0.4064)
			(stroke
				(width 0.1524)
				(type default)
			)
			(layer "B.SilkS")
		)
		(fp_poly
			(pts
				(xy 0.5334 0.254) (xy 0.635 0.254) (xy 0.635 0.2286) (xy 0.635 -0.254) (xy 0.5334 -0.254) (xy 0.5334 -0.2794)
				(xy -0.5334 -0.2794) (xy -0.5334 -0.254) (xy -0.635 -0.254) (xy -0.635 0.254) (xy -0.5334 0.254)
				(xy -0.5334 0.2794) (xy 0.508 0.2794) (xy 0.5334 0.2794)
			)
			(stroke
				(width 0)
				(type default)
			)
			(fill no)
			(layer "B.CrtYd")
		)
		(pad "1" smd rect
			(at -0.40005 0)
			(size 0.4572 0.508)
			(layers "B.Cu" "B.Mask" "B.Paste")
			(net "P1V0_PCI_SW_A")
		)
		(pad "2" smd rect
			(at 0.40005 0)
			(size 0.4572 0.508)
			(layers "B.Cu" "B.Mask" "B.Paste")
			(net "GND")
		)
	)
	(footprint ""
		(layer "B.Cu")
		(at 105.191814 -108.92282)
		(property "Reference" "PC105"
			(at -3.119374 -0.235712 0)
			(unlocked yes)
			(layer "B.SilkS")
			(effects
				(font
					(size 0.7874 0.5842)
					(thickness 0.1524)
				)
				(justify left mirror)
			)
		)
		(property "Value" ""
			(at 0 0 0)
			(layer "B.Fab")
			(effects
				(font
					(size 1.27 1.27)
				)
				(justify mirror)
			)
		)
		(duplicate_pad_numbers_are_jumpers no)
		(fp_line
			(start -1.905 -0.8636)
			(end -1.905 0.8636)
			(stroke
				(width 0.1524)
				(type default)
			)
			(layer "B.SilkS")
		)
		(fp_line
			(start -1.905 0.8636)
			(end 1.905 0.8636)
			(stroke
				(width 0.1524)
				(type default)
			)
			(layer "B.SilkS")
		)
		(fp_line
			(start 0 0.8382)
			(end 0 -0.8382)
			(stroke
				(width 0.1524)
				(type default)
			)
			(layer "B.SilkS")
		)
		(fp_line
			(start 1.905 -0.8636)
			(end -1.905 -0.8636)
			(stroke
				(width 0.1524)
				(type default)
			)
			(layer "B.SilkS")
		)
		(fp_line
			(start 1.905 0.8636)
			(end 1.905 -0.8636)
			(stroke
				(width 0.1524)
				(type default)
			)
			(layer "B.SilkS")
		)
		(fp_rect
			(start 1.524 0.7366)
			(end -1.524 -0.7366)
			(stroke
				(width 0)
				(type default)
			)
			(fill no)
			(layer "B.CrtYd")
		)
		(pad "1" smd rect
			(at -0.94996 0 180)
			(size 1.1176 1.3716)
			(layers "B.Cu" "B.Mask" "B.Paste")
			(net "GND")
		)
		(pad "2" smd rect
			(at 0.94996 0 180)
			(size 1.1176 1.3716)
			(layers "B.Cu" "B.Mask" "B.Paste")
			(net "PV_VCCP_NODE1")
		)
	)
	(footprint ""
		(layer "B.Cu")
		(at 169.554652 -104.84739 90)
		(property "Reference" "C375"
			(at 1.423416 6.014212 270)
			(unlocked yes)
			(layer "B.SilkS")
			(effects
				(font
					(size 0.7874 0.5842)
					(thickness 0.1524)
				)
				(justify left mirror)
			)
		)
		(property "Value" ""
			(at 0 0 90)
			(layer "B.Fab")
			(effects
				(font
					(size 1.27 1.27)
				)
				(justify mirror)
			)
		)
		(duplicate_pad_numbers_are_jumpers no)
		(fp_line
			(start 0.7874 -0.4064)
			(end -0.7874 -0.4064)
			(stroke
				(width 0.1524)
				(type default)
			)
			(layer "B.SilkS")
		)
		(fp_line
			(start -0.7874 -0.4064)
			(end -0.7874 0.4064)
			(stroke
				(width 0.1524)
				(type default)
			)
			(layer "B.SilkS")
		)
		(fp_line
			(start 0 0.381)
			(end 0 -0.381)
			(stroke
				(width 0.1524)
				(type default)
			)
			(layer "B.SilkS")
		)
		(fp_line
			(start 0.7874 0.4064)
			(end 0.7874 -0.4064)
			(stroke
				(width 0.1524)
				(type default)
			)
			(layer "B.SilkS")
		)
		(fp_line
			(start -0.7874 0.4064)
			(end 0.7874 0.4064)
			(stroke
				(width 0.1524)
				(type default)
			)
			(layer "B.SilkS")
		)
		(fp_poly
			(pts
				(xy 0.5334 0.254) (xy 0.635 0.254) (xy 0.635 0.2286) (xy 0.635 -0.254) (xy 0.5334 -0.254) (xy 0.5334 -0.2794)
				(xy -0.5334 -0.2794) (xy -0.5334 -0.254) (xy -0.635 -0.254) (xy -0.635 0.254) (xy -0.5334 0.254)
				(xy -0.5334 0.2794) (xy 0.508 0.2794) (xy 0.5334 0.2794)
			)
			(stroke
				(width 0)
				(type default)
			)
			(fill no)
			(layer "B.CrtYd")
		)
		(pad "1" smd rect
			(at -0.40005 0 270)
			(size 0.4572 0.508)
			(layers "B.Cu" "B.Mask" "B.Paste")
			(net "GND")
		)
		(pad "2" smd rect
			(at 0.40005 0 270)
			(size 0.4572 0.508)
			(layers "B.Cu" "B.Mask" "B.Paste")
			(net "P1V05_NODE1")
		)
	)
	(footprint ""
		(layer "B.Cu")
		(at 154.06116 -173.521624)
		(property "Reference" "R748"
			(at -1.545844 12.970002 0)
			(unlocked yes)
			(layer "B.SilkS")
			(effects
				(font
					(size 0.7874 0.5842)
					(thickness 0.1524)
				)
				(justify left mirror)
			)
		)
		(property "Value" ""
			(at 0 0 0)
			(layer "B.Fab")
			(effects
				(font
					(size 1.27 1.27)
				)
				(justify mirror)
			)
		)
		(duplicate_pad_numbers_are_jumpers no)
		(fp_line
			(start -0.7874 -0.4064)
			(end -0.7874 0.4064)
			(stroke
				(width 0.1524)
				(type default)
			)
			(layer "B.SilkS")
		)
		(fp_line
			(start -0.7874 0.4064)
			(end 0.7874 0.4064)
			(stroke
				(width 0.1524)
				(type default)
			)
			(layer "B.SilkS")
		)
		(fp_line
			(start 0.7874 -0.4064)
			(end -0.7874 -0.4064)
			(stroke
				(width 0.1524)
				(type default)
			)
			(layer "B.SilkS")
		)
		(fp_line
			(start 0.7874 0.4064)
			(end 0.7874 -0.4064)
			(stroke
				(width 0.1524)
				(type default)
			)
			(layer "B.SilkS")
		)
		(fp_poly
			(pts
				(xy 0.508 0.2794) (xy 0.508 0.2286) (xy 0.635 0.2286) (xy 0.635 -0.254) (xy 0.5334 -0.254) (xy 0.5334 -0.2794)
				(xy -0.5334 -0.2794) (xy -0.5334 -0.254) (xy -0.635 -0.254) (xy -0.635 0.254) (xy -0.5334 0.254)
				(xy -0.5334 0.2794)
			)
			(stroke
				(width 0)
				(type default)
			)
			(fill no)
			(layer "B.CrtYd")
		)
		(pad "1" smd rect
			(at -0.40005 0 180)
			(size 0.4572 0.508)
			(layers "B.Cu" "B.Mask" "B.Paste")
			(net "T12_NODE3_EN")
		)
		(pad "2" smd rect
			(at 0.40005 0 180)
			(size 0.4572 0.508)
			(layers "B.Cu" "B.Mask" "B.Paste")
			(net "P5V_NODE1")
		)
	)
	(footprint ""
		(layer "B.Cu")
		(at 121.14784 -45.817282)
		(property "Reference" "R95"
			(at -1.094486 -0.749808 0)
			(unlocked yes)
			(layer "B.SilkS")
			(effects
				(font
					(size 0.7874 0.5842)
					(thickness 0.1524)
				)
				(justify left mirror)
			)
		)
		(property "Value" ""
			(at 0 0 0)
			(layer "B.Fab")
			(effects
				(font
					(size 1.27 1.27)
				)
				(justify mirror)
			)
		)
		(duplicate_pad_numbers_are_jumpers no)
		(fp_line
			(start -0.7874 -0.4064)
			(end -0.7874 0.4064)
			(stroke
				(width 0.1524)
				(type default)
			)
			(layer "B.SilkS")
		)
		(fp_line
			(start -0.7874 0.4064)
			(end 0.7874 0.4064)
			(stroke
				(width 0.1524)
				(type default)
			)
			(layer "B.SilkS")
		)
		(fp_line
			(start 0.7874 -0.4064)
			(end -0.7874 -0.4064)
			(stroke
				(width 0.1524)
				(type default)
			)
			(layer "B.SilkS")
		)
		(fp_line
			(start 0.7874 0.4064)
			(end 0.7874 -0.4064)
			(stroke
				(width 0.1524)
				(type default)
			)
			(layer "B.SilkS")
		)
		(fp_poly
			(pts
				(xy 0.508 0.2794) (xy 0.508 0.2286) (xy 0.635 0.2286) (xy 0.635 -0.254) (xy 0.5334 -0.254) (xy 0.5334 -0.2794)
				(xy -0.5334 -0.2794) (xy -0.5334 -0.254) (xy -0.635 -0.254) (xy -0.635 0.254) (xy -0.5334 0.254)
				(xy -0.5334 0.2794)
			)
			(stroke
				(width 0)
				(type default)
			)
			(fill no)
			(layer "B.CrtYd")
		)
		(pad "1" smd rect
			(at -0.40005 0 180)
			(size 0.4572 0.508)
			(layers "B.Cu" "B.Mask" "B.Paste")
			(net "IRQ_CPU_NODE1_SERIAL")
		)
		(pad "2" smd rect
			(at 0.40005 0 180)
			(size 0.4572 0.508)
			(layers "B.Cu" "B.Mask" "B.Paste")
			(net "IRQ_CPU_NODE1_SERIAL_SIO")
		)
	)
	(footprint ""
		(layer "B.Cu")
		(at 26.432256 -157.713172)
		(property "Reference" "C513"
			(at -2.96926 -0.13335 0)
			(unlocked yes)
			(layer "B.SilkS")
			(effects
				(font
					(size 0.7874 0.5842)
					(thickness 0.1524)
				)
				(justify left mirror)
			)
		)
		(property "Value" ""
			(at 0 0 0)
			(layer "B.Fab")
			(effects
				(font
					(size 1.27 1.27)
				)
				(justify mirror)
			)
		)
		(duplicate_pad_numbers_are_jumpers no)
		(fp_line
			(start -0.7874 -0.4064)
			(end -0.7874 0.4064)
			(stroke
				(width 0.1524)
				(type default)
			)
			(layer "B.SilkS")
		)
		(fp_line
			(start -0.7874 0.4064)
			(end 0.7874 0.4064)
			(stroke
				(width 0.1524)
				(type default)
			)
			(layer "B.SilkS")
		)
		(fp_line
			(start 0 0.381)
			(end 0 -0.381)
			(stroke
				(width 0.1524)
				(type default)
			)
			(layer "B.SilkS")
		)
		(fp_line
			(start 0.7874 -0.4064)
			(end -0.7874 -0.4064)
			(stroke
				(width 0.1524)
				(type default)
			)
			(layer "B.SilkS")
		)
		(fp_line
			(start 0.7874 0.4064)
			(end 0.7874 -0.4064)
			(stroke
				(width 0.1524)
				(type default)
			)
			(layer "B.SilkS")
		)
		(fp_poly
			(pts
				(xy 0.5334 0.254) (xy 0.635 0.254) (xy 0.635 0.2286) (xy 0.635 -0.254) (xy 0.5334 -0.254) (xy 0.5334 -0.2794)
				(xy -0.5334 -0.2794) (xy -0.5334 -0.254) (xy -0.635 -0.254) (xy -0.635 0.254) (xy -0.5334 0.254)
				(xy -0.5334 0.2794) (xy 0.508 0.2794) (xy 0.5334 0.2794)
			)
			(stroke
				(width 0)
				(type default)
			)
			(fill no)
			(layer "B.CrtYd")
		)
		(pad "1" smd rect
			(at -0.40005 0 180)
			(size 0.4572 0.508)
			(layers "B.Cu" "B.Mask" "B.Paste")
			(net "P1V9_LAN1")
		)
		(pad "2" smd rect
			(at 0.40005 0 180)
			(size 0.4572 0.508)
			(layers "B.Cu" "B.Mask" "B.Paste")
			(net "GND")
		)
	)
	(footprint ""
		(layer "B.Cu")
		(at 84.827872 -165.979348 90)
		(property "Reference" "U73"
			(at -18.702274 27.113738 0)
			(unlocked yes)
			(layer "B.SilkS")
			(effects
				(font
					(size 0.7874 0.5842)
					(thickness 0.1524)
				)
				(justify left mirror)
			)
		)
		(property "Value" ""
			(at 0 0 90)
			(layer "B.Fab")
			(effects
				(font
					(size 1.27 1.27)
				)
				(justify mirror)
			)
		)
		(duplicate_pad_numbers_are_jumpers no)
		(fp_line
			(start 2.5654 -2.0066)
			(end -2.5654 -2.0066)
			(stroke
				(width 0.1524)
				(type default)
			)
			(layer "B.SilkS")
		)
		(fp_line
			(start -2.5654 -2.0066)
			(end -2.5654 2.0066)
			(stroke
				(width 0.1524)
				(type default)
			)
			(layer "B.SilkS")
		)
		(fp_line
			(start 2.5654 -0.5842)
			(end 2.5654 -2.0066)
			(stroke
				(width 0.1524)
				(type default)
			)
			(layer "B.SilkS")
		)
		(fp_line
			(start 1.9812 0)
			(end 2.5654 -0.5842)
			(stroke
				(width 0.1524)
				(type default)
			)
			(layer "B.SilkS")
		)
		(fp_line
			(start 2.5654 0.5842)
			(end 1.9812 0)
			(stroke
				(width 0.1524)
				(type default)
			)
			(layer "B.SilkS")
		)
		(fp_line
			(start 2.5654 2.0066)
			(end 2.5654 0.5842)
			(stroke
				(width 0.1524)
				(type default)
			)
			(layer "B.SilkS")
		)
		(fp_line
			(start -2.5654 2.0066)
			(end 2.5654 2.0066)
			(stroke
				(width 0.1524)
				(type default)
			)
			(layer "B.SilkS")
		)
		(fp_circle
			(center 2.032 1.524)
			(end 2.032 1.778)
			(stroke
				(width 0.1524)
				(type default)
			)
			(fill no)
			(layer "B.SilkS")
		)
		(fp_rect
			(start 2.5654 3.6703)
			(end -2.5654 -3.6703)
			(stroke
				(width 0)
				(type default)
			)
			(fill no)
			(layer "B.CrtYd")
		)
		(pad "1" smd rect
			(at 2.275078 2.921 270)
			(size 0.3556 1.4986)
			(layers "B.Cu" "B.Mask" "B.Paste")
			(net "UART_SW_S0_N")
		)
		(pad "2" smd rect
			(at 1.625092 2.921 270)
			(size 0.3556 1.4986)
			(layers "B.Cu" "B.Mask" "B.Paste")
			(net "UART_SW_S1_N")
		)
		(pad "3" smd rect
			(at 0.975106 2.921 270)
			(size 0.3556 1.4986)
			(layers "B.Cu" "B.Mask" "B.Paste")
			(net "SDC_RST_N")
		)
		(pad "4" smd rect
			(at 0.32512 2.921 270)
			(size 0.3556 1.4986)
			(layers "B.Cu" "B.Mask" "B.Paste")
			(net "GND")
		)
		(pad "5" smd rect
			(at -0.32512 2.921 270)
			(size 0.3556 1.4986)
			(layers "B.Cu" "B.Mask" "B.Paste")
			(net "UART_SW_S2_N")
		)
		(pad "6" smd rect
			(at -0.975106 2.921 270)
			(size 0.3556 1.4986)
			(layers "B.Cu" "B.Mask" "B.Paste")
			(net "UART_SW_S3_N")
		)
		(pad "7" smd rect
			(at -1.625092 2.921 270)
			(size 0.3556 1.4986)
			(layers "B.Cu" "B.Mask" "B.Paste")
			(net "I2C_SDC_SDA")
		)
		(pad "8" smd rect
			(at -2.275078 2.921 270)
			(size 0.3556 1.4986)
			(layers "B.Cu" "B.Mask" "B.Paste")
			(net "I2C_SDC_SCL")
		)
		(pad "9" smd rect
			(at -2.275078 -2.921 270)
			(size 0.3556 1.4986)
			(layers "B.Cu" "B.Mask" "B.Paste")
			(net "UART_SDC_TX")
		)
		(pad "10" smd rect
			(at -1.625092 -2.921 270)
			(size 0.3556 1.4986)
			(layers "B.Cu" "B.Mask" "B.Paste")
			(net "UART_SDC_RX")
		)
		(pad "11" smd rect
			(at -0.975106 -2.921 270)
			(size 0.3556 1.4986)
			(layers "B.Cu" "B.Mask" "B.Paste")
			(net "CPLD_WDT2_R")
		)
		(pad "12" smd rect
			(at -0.32512 -2.921 270)
			(size 0.3556 1.4986)
			(layers "B.Cu" "B.Mask" "B.Paste")
			(net "P3V3_NODE1")
		)
		(pad "13" smd rect
			(at 0.32512 -2.921 270)
			(size 0.3556 1.4986)
			(layers "B.Cu" "B.Mask" "B.Paste")
			(net "SDC_WAKEUP")
		)
		(pad "14" smd rect
			(at 0.975106 -2.921 270)
			(size 0.3556 1.4986)
			(layers "B.Cu" "B.Mask" "B.Paste")
			(net "UART_SW_S5_N")
		)
		(pad "15" smd rect
			(at 1.625092 -2.921 270)
			(size 0.3556 1.4986)
			(layers "B.Cu" "B.Mask" "B.Paste")
			(net "UART_SW_S4_N")
		)
		(pad "16" smd rect
			(at 2.275078 -2.921 270)
			(size 0.3556 1.4986)
			(layers "B.Cu" "B.Mask" "B.Paste")
			(net "CM_CABLE_DET_N")
		)
	)
	(footprint ""
		(layer "B.Cu")
		(at 127.508 -59.436 90)
		(property "Reference" "R1328"
			(at 1.143 -0.02667 270)
			(unlocked yes)
			(layer "B.SilkS")
			(effects
				(font
					(size 0.7874 0.5842)
					(thickness 0.1524)
				)
				(justify left mirror)
			)
		)
		(property "Value" ""
			(at 0 0 90)
			(layer "B.Fab")
			(effects
				(font
					(size 1.27 1.27)
				)
				(justify mirror)
			)
		)
		(duplicate_pad_numbers_are_jumpers no)
		(fp_line
			(start 0.7874 -0.4064)
			(end -0.7874 -0.4064)
			(stroke
				(width 0.1524)
				(type default)
			)
			(layer "B.SilkS")
		)
		(fp_line
			(start -0.7874 -0.4064)
			(end -0.7874 0.4064)
			(stroke
				(width 0.1524)
				(type default)
			)
			(layer "B.SilkS")
		)
		(fp_line
			(start 0.7874 0.4064)
			(end 0.7874 -0.4064)
			(stroke
				(width 0.1524)
				(type default)
			)
			(layer "B.SilkS")
		)
		(fp_line
			(start -0.7874 0.4064)
			(end 0.7874 0.4064)
			(stroke
				(width 0.1524)
				(type default)
			)
			(layer "B.SilkS")
		)
		(fp_poly
			(pts
				(xy 0.508 0.2794) (xy 0.508 0.2286) (xy 0.635 0.2286) (xy 0.635 -0.254) (xy 0.5334 -0.254) (xy 0.5334 -0.2794)
				(xy -0.5334 -0.2794) (xy -0.5334 -0.254) (xy -0.635 -0.254) (xy -0.635 0.254) (xy -0.5334 0.254)
				(xy -0.5334 0.2794)
			)
			(stroke
				(width 0)
				(type default)
			)
			(fill no)
			(layer "B.CrtYd")
		)
		(pad "1" smd rect
			(at -0.40005 0 270)
			(size 0.4572 0.508)
			(layers "B.Cu" "B.Mask" "B.Paste")
			(net "UART_RI_P3_N")
		)
		(pad "2" smd rect
			(at 0.40005 0 270)
			(size 0.4572 0.508)
			(layers "B.Cu" "B.Mask" "B.Paste")
			(net "GND")
		)
	)
	(footprint ""
		(layer "B.Cu")
		(at 74.38136 -185.698638 -90)
		(property "Reference" "C671"
			(at -3.673094 -0.83312 270)
			(unlocked yes)
			(layer "B.SilkS")
			(effects
				(font
					(size 0.7874 0.5842)
					(thickness 0.1524)
				)
				(justify left mirror)
			)
		)
		(property "Value" ""
			(at 0 0 90)
			(layer "B.Fab")
			(effects
				(font
					(size 1.27 1.27)
				)
				(justify mirror)
			)
		)
		(duplicate_pad_numbers_are_jumpers no)
		(fp_line
			(start -0.7874 0.4064)
			(end 0.7874 0.4064)
			(stroke
				(width 0.1524)
				(type default)
			)
			(layer "B.SilkS")
		)
		(fp_line
			(start 0.7874 0.4064)
			(end 0.7874 -0.4064)
			(stroke
				(width 0.1524)
				(type default)
			)
			(layer "B.SilkS")
		)
		(fp_line
			(start 0 0.381)
			(end 0 -0.381)
			(stroke
				(width 0.1524)
				(type default)
			)
			(layer "B.SilkS")
		)
		(fp_line
			(start -0.7874 -0.4064)
			(end -0.7874 0.4064)
			(stroke
				(width 0.1524)
				(type default)
			)
			(layer "B.SilkS")
		)
		(fp_line
			(start 0.7874 -0.4064)
			(end -0.7874 -0.4064)
			(stroke
				(width 0.1524)
				(type default)
			)
			(layer "B.SilkS")
		)
		(fp_poly
			(pts
				(xy 0.5334 0.254) (xy 0.635 0.254) (xy 0.635 0.2286) (xy 0.635 -0.254) (xy 0.5334 -0.254) (xy 0.5334 -0.2794)
				(xy -0.5334 -0.2794) (xy -0.5334 -0.254) (xy -0.635 -0.254) (xy -0.635 0.254) (xy -0.5334 0.254)
				(xy -0.5334 0.2794) (xy 0.508 0.2794) (xy 0.5334 0.2794)
			)
			(stroke
				(width 0)
				(type default)
			)
			(fill no)
			(layer "B.CrtYd")
		)
		(pad "1" smd rect
			(at -0.40005 0 90)
			(size 0.4572 0.508)
			(layers "B.Cu" "B.Mask" "B.Paste")
			(net "UART_T3_NODE1_RXD")
		)
		(pad "2" smd rect
			(at 0.40005 0 90)
			(size 0.4572 0.508)
			(layers "B.Cu" "B.Mask" "B.Paste")
			(net "GND")
		)
	)
	(footprint ""
		(layer "B.Cu")
		(at 166.79164 -188.19749 -90)
		(property "Reference" "C610"
			(at -0.98171 -0.03429 270)
			(unlocked yes)
			(layer "B.SilkS")
			(effects
				(font
					(size 0.7874 0.5842)
					(thickness 0.1524)
				)
				(justify left mirror)
			)
		)
		(property "Value" ""
			(at 0 0 90)
			(layer "B.Fab")
			(effects
				(font
					(size 1.27 1.27)
				)
				(justify mirror)
			)
		)
		(duplicate_pad_numbers_are_jumpers no)
		(fp_line
			(start -0.7874 0.4064)
			(end 0.7874 0.4064)
			(stroke
				(width 0.1524)
				(type default)
			)
			(layer "B.SilkS")
		)
		(fp_line
			(start 0.7874 0.4064)
			(end 0.7874 -0.4064)
			(stroke
				(width 0.1524)
				(type default)
			)
			(layer "B.SilkS")
		)
		(fp_line
			(start 0 0.381)
			(end 0 -0.381)
			(stroke
				(width 0.1524)
				(type default)
			)
			(layer "B.SilkS")
		)
		(fp_line
			(start -0.7874 -0.4064)
			(end -0.7874 0.4064)
			(stroke
				(width 0.1524)
				(type default)
			)
			(layer "B.SilkS")
		)
		(fp_line
			(start 0.7874 -0.4064)
			(end -0.7874 -0.4064)
			(stroke
				(width 0.1524)
				(type default)
			)
			(layer "B.SilkS")
		)
		(fp_poly
			(pts
				(xy 0.5334 0.254) (xy 0.635 0.254) (xy 0.635 0.2286) (xy 0.635 -0.254) (xy 0.5334 -0.254) (xy 0.5334 -0.2794)
				(xy -0.5334 -0.2794) (xy -0.5334 -0.254) (xy -0.635 -0.254) (xy -0.635 0.254) (xy -0.5334 0.254)
				(xy -0.5334 0.2794) (xy 0.508 0.2794) (xy 0.5334 0.2794)
			)
			(stroke
				(width 0)
				(type default)
			)
			(fill no)
			(layer "B.CrtYd")
		)
		(pad "1" smd rect
			(at -0.40005 0 90)
			(size 0.4572 0.508)
			(layers "B.Cu" "B.Mask" "B.Paste")
			(net "I2C_PDB_R_SCL")
		)
		(pad "2" smd rect
			(at 0.40005 0 90)
			(size 0.4572 0.508)
			(layers "B.Cu" "B.Mask" "B.Paste")
			(net "GND")
		)
	)
	(footprint ""
		(layer "B.Cu")
		(at 26.432256 -155.427172)
		(property "Reference" "C514"
			(at -2.96926 -0.13335 0)
			(unlocked yes)
			(layer "B.SilkS")
			(effects
				(font
					(size 0.7874 0.5842)
					(thickness 0.1524)
				)
				(justify left mirror)
			)
		)
		(property "Value" ""
			(at 0 0 0)
			(layer "B.Fab")
			(effects
				(font
					(size 1.27 1.27)
				)
				(justify mirror)
			)
		)
		(duplicate_pad_numbers_are_jumpers no)
		(fp_line
			(start -0.7874 -0.4064)
			(end -0.7874 0.4064)
			(stroke
				(width 0.1524)
				(type default)
			)
			(layer "B.SilkS")
		)
		(fp_line
			(start -0.7874 0.4064)
			(end 0.7874 0.4064)
			(stroke
				(width 0.1524)
				(type default)
			)
			(layer "B.SilkS")
		)
		(fp_line
			(start 0 0.381)
			(end 0 -0.381)
			(stroke
				(width 0.1524)
				(type default)
			)
			(layer "B.SilkS")
		)
		(fp_line
			(start 0.7874 -0.4064)
			(end -0.7874 -0.4064)
			(stroke
				(width 0.1524)
				(type default)
			)
			(layer "B.SilkS")
		)
		(fp_line
			(start 0.7874 0.4064)
			(end 0.7874 -0.4064)
			(stroke
				(width 0.1524)
				(type default)
			)
			(layer "B.SilkS")
		)
		(fp_poly
			(pts
				(xy 0.5334 0.254) (xy 0.635 0.254) (xy 0.635 0.2286) (xy 0.635 -0.254) (xy 0.5334 -0.254) (xy 0.5334 -0.2794)
				(xy -0.5334 -0.2794) (xy -0.5334 -0.254) (xy -0.635 -0.254) (xy -0.635 0.254) (xy -0.5334 0.254)
				(xy -0.5334 0.2794) (xy 0.508 0.2794) (xy 0.5334 0.2794)
			)
			(stroke
				(width 0)
				(type default)
			)
			(fill no)
			(layer "B.CrtYd")
		)
		(pad "1" smd rect
			(at -0.40005 0 180)
			(size 0.4572 0.508)
			(layers "B.Cu" "B.Mask" "B.Paste")
			(net "P1V9_LAN1")
		)
		(pad "2" smd rect
			(at 0.40005 0 180)
			(size 0.4572 0.508)
			(layers "B.Cu" "B.Mask" "B.Paste")
			(net "GND")
		)
	)
	(footprint ""
		(layer "B.Cu")
		(at 158.48076 -187.872624 -90)
		(property "Reference" "R1224"
			(at -4.565396 4.021074 270)
			(unlocked yes)
			(layer "B.SilkS")
			(effects
				(font
					(size 0.7874 0.5842)
					(thickness 0.1524)
				)
				(justify left mirror)
			)
		)
		(property "Value" ""
			(at 0 0 90)
			(layer "B.Fab")
			(effects
				(font
					(size 1.27 1.27)
				)
				(justify mirror)
			)
		)
		(duplicate_pad_numbers_are_jumpers no)
		(fp_line
			(start -0.7874 0.4064)
			(end 0.7874 0.4064)
			(stroke
				(width 0.1524)
				(type default)
			)
			(layer "B.SilkS")
		)
		(fp_line
			(start 0.7874 0.4064)
			(end 0.7874 -0.4064)
			(stroke
				(width 0.1524)
				(type default)
			)
			(layer "B.SilkS")
		)
		(fp_line
			(start -0.7874 -0.4064)
			(end -0.7874 0.4064)
			(stroke
				(width 0.1524)
				(type default)
			)
			(layer "B.SilkS")
		)
		(fp_line
			(start 0.7874 -0.4064)
			(end -0.7874 -0.4064)
			(stroke
				(width 0.1524)
				(type default)
			)
			(layer "B.SilkS")
		)
		(fp_poly
			(pts
				(xy 0.508 0.2794) (xy 0.508 0.2286) (xy 0.635 0.2286) (xy 0.635 -0.254) (xy 0.5334 -0.254) (xy 0.5334 -0.2794)
				(xy -0.5334 -0.2794) (xy -0.5334 -0.254) (xy -0.635 -0.254) (xy -0.635 0.254) (xy -0.5334 0.254)
				(xy -0.5334 0.2794)
			)
			(stroke
				(width 0)
				(type default)
			)
			(fill no)
			(layer "B.CrtYd")
		)
		(pad "1" smd rect
			(at -0.40005 0 90)
			(size 0.4572 0.508)
			(layers "B.Cu" "B.Mask" "B.Paste")
			(net "FAN6_TACH_R")
		)
		(pad "2" smd rect
			(at 0.40005 0 90)
			(size 0.4572 0.508)
			(layers "B.Cu" "B.Mask" "B.Paste")
			(net "GND")
		)
	)
	(footprint ""
		(layer "B.Cu")
		(at 35.847274 -66.433192 180)
		(property "Reference" "C18"
			(at 2.047494 0.057404 0)
			(unlocked yes)
			(layer "B.SilkS")
			(effects
				(font
					(size 0.7874 0.5842)
					(thickness 0.1524)
				)
				(justify left mirror)
			)
		)
		(property "Value" ""
			(at 0 0 0)
			(layer "B.Fab")
			(effects
				(font
					(size 1.27 1.27)
				)
				(justify mirror)
			)
		)
		(duplicate_pad_numbers_are_jumpers no)
		(fp_line
			(start 0.7874 0.4064)
			(end 0.7874 -0.4064)
			(stroke
				(width 0.1524)
				(type default)
			)
			(layer "B.SilkS")
		)
		(fp_line
			(start 0.7874 -0.4064)
			(end -0.7874 -0.4064)
			(stroke
				(width 0.1524)
				(type default)
			)
			(layer "B.SilkS")
		)
		(fp_line
			(start 0 0.381)
			(end 0 -0.381)
			(stroke
				(width 0.1524)
				(type default)
			)
			(layer "B.SilkS")
		)
		(fp_line
			(start -0.7874 0.4064)
			(end 0.7874 0.4064)
			(stroke
				(width 0.1524)
				(type default)
			)
			(layer "B.SilkS")
		)
		(fp_line
			(start -0.7874 -0.4064)
			(end -0.7874 0.4064)
			(stroke
				(width 0.1524)
				(type default)
			)
			(layer "B.SilkS")
		)
		(fp_poly
			(pts
				(xy 0.5334 0.254) (xy 0.635 0.254) (xy 0.635 0.2286) (xy 0.635 -0.254) (xy 0.5334 -0.254) (xy 0.5334 -0.2794)
				(xy -0.5334 -0.2794) (xy -0.5334 -0.254) (xy -0.635 -0.254) (xy -0.635 0.254) (xy -0.5334 0.254)
				(xy -0.5334 0.2794) (xy 0.508 0.2794) (xy 0.5334 0.2794)
			)
			(stroke
				(width 0)
				(type default)
			)
			(fill no)
			(layer "B.CrtYd")
		)
		(pad "1" smd rect
			(at -0.40005 0)
			(size 0.4572 0.508)
			(layers "B.Cu" "B.Mask" "B.Paste")
			(net "P2E_CPU_NIC2_NODE1_TX_C_DN")
		)
		(pad "2" smd rect
			(at 0.40005 0)
			(size 0.4572 0.508)
			(layers "B.Cu" "B.Mask" "B.Paste")
			(net "P2E_CPU_NIC2_NODE1_TX_DN")
		)
	)
	(footprint ""
		(layer "B.Cu")
		(at 104.408224 -65.148206)
		(property "Reference" "R220"
			(at -4.645914 0.87884 0)
			(unlocked yes)
			(layer "B.SilkS")
			(effects
				(font
					(size 0.7874 0.5842)
					(thickness 0.1524)
				)
				(justify left mirror)
			)
		)
		(property "Value" ""
			(at 0 0 0)
			(layer "B.Fab")
			(effects
				(font
					(size 1.27 1.27)
				)
				(justify mirror)
			)
		)
		(duplicate_pad_numbers_are_jumpers no)
		(fp_line
			(start -0.7874 -0.4064)
			(end -0.7874 0.4064)
			(stroke
				(width 0.1524)
				(type default)
			)
			(layer "B.SilkS")
		)
		(fp_line
			(start -0.7874 0.4064)
			(end 0.7874 0.4064)
			(stroke
				(width 0.1524)
				(type default)
			)
			(layer "B.SilkS")
		)
		(fp_line
			(start 0.7874 -0.4064)
			(end -0.7874 -0.4064)
			(stroke
				(width 0.1524)
				(type default)
			)
			(layer "B.SilkS")
		)
		(fp_line
			(start 0.7874 0.4064)
			(end 0.7874 -0.4064)
			(stroke
				(width 0.1524)
				(type default)
			)
			(layer "B.SilkS")
		)
		(fp_poly
			(pts
				(xy 0.508 0.2794) (xy 0.508 0.2286) (xy 0.635 0.2286) (xy 0.635 -0.254) (xy 0.5334 -0.254) (xy 0.5334 -0.2794)
				(xy -0.5334 -0.2794) (xy -0.5334 -0.254) (xy -0.635 -0.254) (xy -0.635 0.254) (xy -0.5334 0.254)
				(xy -0.5334 0.2794)
			)
			(stroke
				(width 0)
				(type default)
			)
			(fill no)
			(layer "B.CrtYd")
		)
		(pad "1" smd rect
			(at -0.40005 0 180)
			(size 0.4572 0.508)
			(layers "B.Cu" "B.Mask" "B.Paste")
			(net "P3V3_STB_NODE1")
		)
		(pad "2" smd rect
			(at 0.40005 0 180)
			(size 0.4572 0.508)
			(layers "B.Cu" "B.Mask" "B.Paste")
			(net "XDP_CPU_NODE1_PG_RST_R")
		)
	)
	(footprint ""
		(layer "B.Cu")
		(at 150.47976 -187.872624 90)
		(property "Reference" "R957"
			(at 4.565396 -3.28676 270)
			(unlocked yes)
			(layer "B.SilkS")
			(effects
				(font
					(size 0.7874 0.5842)
					(thickness 0.1524)
				)
				(justify left mirror)
			)
		)
		(property "Value" ""
			(at 0 0 90)
			(layer "B.Fab")
			(effects
				(font
					(size 1.27 1.27)
				)
				(justify mirror)
			)
		)
		(duplicate_pad_numbers_are_jumpers no)
		(fp_line
			(start 0.7874 -0.4064)
			(end -0.7874 -0.4064)
			(stroke
				(width 0.1524)
				(type default)
			)
			(layer "B.SilkS")
		)
		(fp_line
			(start -0.7874 -0.4064)
			(end -0.7874 0.4064)
			(stroke
				(width 0.1524)
				(type default)
			)
			(layer "B.SilkS")
		)
		(fp_line
			(start 0.7874 0.4064)
			(end 0.7874 -0.4064)
			(stroke
				(width 0.1524)
				(type default)
			)
			(layer "B.SilkS")
		)
		(fp_line
			(start -0.7874 0.4064)
			(end 0.7874 0.4064)
			(stroke
				(width 0.1524)
				(type default)
			)
			(layer "B.SilkS")
		)
		(fp_poly
			(pts
				(xy 0.508 0.2794) (xy 0.508 0.2286) (xy 0.635 0.2286) (xy 0.635 -0.254) (xy 0.5334 -0.254) (xy 0.5334 -0.2794)
				(xy -0.5334 -0.2794) (xy -0.5334 -0.254) (xy -0.635 -0.254) (xy -0.635 0.254) (xy -0.5334 0.254)
				(xy -0.5334 0.2794)
			)
			(stroke
				(width 0)
				(type default)
			)
			(fill no)
			(layer "B.CrtYd")
		)
		(pad "1" smd rect
			(at -0.40005 0 270)
			(size 0.4572 0.508)
			(layers "B.Cu" "B.Mask" "B.Paste")
			(net "UART_T11_NODE1_RXD")
		)
		(pad "2" smd rect
			(at 0.40005 0 270)
			(size 0.4572 0.508)
			(layers "B.Cu" "B.Mask" "B.Paste")
			(net "UART_T11_NODE1_RXD_R")
		)
	)
	(footprint ""
		(layer "B.Cu")
		(at 148.247354 -178.784504 90)
		(property "Reference" "R742"
			(at 0.380492 2.223008 270)
			(unlocked yes)
			(layer "B.SilkS")
			(effects
				(font
					(size 0.7874 0.5842)
					(thickness 0.1524)
				)
				(justify left mirror)
			)
		)
		(property "Value" ""
			(at 0 0 90)
			(layer "B.Fab")
			(effects
				(font
					(size 1.27 1.27)
				)
				(justify mirror)
			)
		)
		(duplicate_pad_numbers_are_jumpers no)
		(fp_line
			(start 0.7874 -0.4064)
			(end -0.7874 -0.4064)
			(stroke
				(width 0.1524)
				(type default)
			)
			(layer "B.SilkS")
		)
		(fp_line
			(start -0.7874 -0.4064)
			(end -0.7874 0.4064)
			(stroke
				(width 0.1524)
				(type default)
			)
			(layer "B.SilkS")
		)
		(fp_line
			(start 0.7874 0.4064)
			(end 0.7874 -0.4064)
			(stroke
				(width 0.1524)
				(type default)
			)
			(layer "B.SilkS")
		)
		(fp_line
			(start -0.7874 0.4064)
			(end 0.7874 0.4064)
			(stroke
				(width 0.1524)
				(type default)
			)
			(layer "B.SilkS")
		)
		(fp_poly
			(pts
				(xy 0.508 0.2794) (xy 0.508 0.2286) (xy 0.635 0.2286) (xy 0.635 -0.254) (xy 0.5334 -0.254) (xy 0.5334 -0.2794)
				(xy -0.5334 -0.2794) (xy -0.5334 -0.254) (xy -0.635 -0.254) (xy -0.635 0.254) (xy -0.5334 0.254)
				(xy -0.5334 0.2794)
			)
			(stroke
				(width 0)
				(type default)
			)
			(fill no)
			(layer "B.CrtYd")
		)
		(pad "1" smd rect
			(at -0.40005 0 270)
			(size 0.4572 0.508)
			(layers "B.Cu" "B.Mask" "B.Paste")
			(net "T11_NODE2_EN")
		)
		(pad "2" smd rect
			(at 0.40005 0 270)
			(size 0.4572 0.508)
			(layers "B.Cu" "B.Mask" "B.Paste")
			(net "P5V_NODE1")
		)
	)
	(footprint ""
		(layer "B.Cu")
		(at 134.197852 -120.884442 -90)
		(property "Reference" "C11"
			(at 0.541274 1.403604 270)
			(unlocked yes)
			(layer "B.SilkS")
			(effects
				(font
					(size 0.7874 0.5842)
					(thickness 0.1524)
				)
				(justify left mirror)
			)
		)
		(property "Value" ""
			(at 0 0 90)
			(layer "B.Fab")
			(effects
				(font
					(size 1.27 1.27)
				)
				(justify mirror)
			)
		)
		(duplicate_pad_numbers_are_jumpers no)
		(fp_line
			(start -0.7874 0.4064)
			(end 0.7874 0.4064)
			(stroke
				(width 0.1524)
				(type default)
			)
			(layer "B.SilkS")
		)
		(fp_line
			(start 0.7874 0.4064)
			(end 0.7874 -0.4064)
			(stroke
				(width 0.1524)
				(type default)
			)
			(layer "B.SilkS")
		)
		(fp_line
			(start 0 0.381)
			(end 0 -0.381)
			(stroke
				(width 0.1524)
				(type default)
			)
			(layer "B.SilkS")
		)
		(fp_line
			(start -0.7874 -0.4064)
			(end -0.7874 0.4064)
			(stroke
				(width 0.1524)
				(type default)
			)
			(layer "B.SilkS")
		)
		(fp_line
			(start 0.7874 -0.4064)
			(end -0.7874 -0.4064)
			(stroke
				(width 0.1524)
				(type default)
			)
			(layer "B.SilkS")
		)
		(fp_poly
			(pts
				(xy 0.5334 0.254) (xy 0.635 0.254) (xy 0.635 0.2286) (xy 0.635 -0.254) (xy 0.5334 -0.254) (xy 0.5334 -0.2794)
				(xy -0.5334 -0.2794) (xy -0.5334 -0.254) (xy -0.635 -0.254) (xy -0.635 0.254) (xy -0.5334 0.254)
				(xy -0.5334 0.2794) (xy 0.508 0.2794) (xy 0.5334 0.2794)
			)
			(stroke
				(width 0)
				(type default)
			)
			(fill no)
			(layer "B.CrtYd")
		)
		(pad "1" smd rect
			(at -0.40005 0 90)
			(size 0.4572 0.508)
			(layers "B.Cu" "B.Mask" "B.Paste")
			(net "P1V05_CLK_NODE1")
		)
		(pad "2" smd rect
			(at 0.40005 0 90)
			(size 0.4572 0.508)
			(layers "B.Cu" "B.Mask" "B.Paste")
			(net "GND")
		)
	)
	(footprint ""
		(layer "B.Cu")
		(at 129.743708 -115.82146)
		(property "Reference" "C1"
			(at -1.518412 1.218946 0)
			(unlocked yes)
			(layer "B.SilkS")
			(effects
				(font
					(size 0.7874 0.5842)
					(thickness 0.1524)
				)
				(justify mirror)
			)
		)
		(property "Value" ""
			(at 0 0 0)
			(layer "B.Fab")
			(effects
				(font
					(size 1.27 1.27)
				)
				(justify mirror)
			)
		)
		(duplicate_pad_numbers_are_jumpers no)
		(fp_line
			(start -1.2954 -0.5842)
			(end -1.2954 0.5842)
			(stroke
				(width 0.1524)
				(type default)
			)
			(layer "B.SilkS")
		)
		(fp_line
			(start -1.2954 0.5842)
			(end 1.2954 0.5842)
			(stroke
				(width 0.1524)
				(type default)
			)
			(layer "B.SilkS")
		)
		(fp_line
			(start 0 -0.5842)
			(end 0 0.5842)
			(stroke
				(width 0.1524)
				(type default)
			)
			(layer "B.SilkS")
		)
		(fp_line
			(start 1.2954 -0.5842)
			(end -1.2954 -0.5842)
			(stroke
				(width 0.1524)
				(type default)
			)
			(layer "B.SilkS")
		)
		(fp_line
			(start 1.2954 0.5842)
			(end 1.2954 -0.5842)
			(stroke
				(width 0.1524)
				(type default)
			)
			(layer "B.SilkS")
		)
		(fp_poly
			(pts
				(xy -0.8636 -0.4572) (xy -0.8636 -0.3556) (xy -1.143 -0.3556) (xy -1.143 0.3556) (xy -0.8636 0.3556)
				(xy -0.8636 0.4572) (xy 0.8636 0.4572) (xy 0.8636 0.3556) (xy 1.143 0.3556) (xy 1.143 -0.3556) (xy 0.8636 -0.3556)
				(xy 0.8636 -0.4572)
			)
			(stroke
				(width 0)
				(type default)
			)
			(fill no)
			(layer "B.CrtYd")
		)
		(fp_line
			(start -0.884936 -0.504952)
			(end -0.884936 0.504952)
			(stroke
				(width 0.1)
				(type default)
			)
			(layer "B.Fab")
		)
		(fp_line
			(start -0.884936 0.504952)
			(end 0.884936 0.504952)
			(stroke
				(width 0.1)
				(type default)
			)
			(layer "B.Fab")
		)
		(fp_line
			(start 0.884936 -0.504952)
			(end -0.884936 -0.504952)
			(stroke
				(width 0.1)
				(type default)
			)
			(layer "B.Fab")
		)
		(fp_line
			(start 0.884936 0.504952)
			(end 0.884936 -0.504952)
			(stroke
				(width 0.1)
				(type default)
			)
			(layer "B.Fab")
		)
		(pad "1" smd rect
			(at -0.7366 0 90)
			(size 0.7112 0.8128)
			(layers "B.Cu" "B.Mask" "B.Paste")
			(net "P3V3_CLK_NODE1")
		)
		(pad "2" smd rect
			(at 0.7366 0 90)
			(size 0.7112 0.8128)
			(layers "B.Cu" "B.Mask" "B.Paste")
			(net "GND")
		)
	)
	(footprint ""
		(layer "B.Cu")
		(at 58.10123 -67.092322 90)
		(property "Reference" "R1044"
			(at -34.333688 -13.67282 270)
			(unlocked yes)
			(layer "B.SilkS")
			(effects
				(font
					(size 0.7874 0.5842)
					(thickness 0.1524)
				)
				(justify left mirror)
			)
		)
		(property "Value" ""
			(at 0 0 90)
			(layer "B.Fab")
			(effects
				(font
					(size 1.27 1.27)
				)
				(justify mirror)
			)
		)
		(duplicate_pad_numbers_are_jumpers no)
		(fp_line
			(start 0.7874 -0.4064)
			(end -0.7874 -0.4064)
			(stroke
				(width 0.1524)
				(type default)
			)
			(layer "B.SilkS")
		)
		(fp_line
			(start -0.7874 -0.4064)
			(end -0.7874 0.4064)
			(stroke
				(width 0.1524)
				(type default)
			)
			(layer "B.SilkS")
		)
		(fp_line
			(start 0.7874 0.4064)
			(end 0.7874 -0.4064)
			(stroke
				(width 0.1524)
				(type default)
			)
			(layer "B.SilkS")
		)
		(fp_line
			(start -0.7874 0.4064)
			(end 0.7874 0.4064)
			(stroke
				(width 0.1524)
				(type default)
			)
			(layer "B.SilkS")
		)
		(fp_poly
			(pts
				(xy 0.508 0.2794) (xy 0.508 0.2286) (xy 0.635 0.2286) (xy 0.635 -0.254) (xy 0.5334 -0.254) (xy 0.5334 -0.2794)
				(xy -0.5334 -0.2794) (xy -0.5334 -0.254) (xy -0.635 -0.254) (xy -0.635 0.254) (xy -0.5334 0.254)
				(xy -0.5334 0.2794)
			)
			(stroke
				(width 0)
				(type default)
			)
			(fill no)
			(layer "B.CrtYd")
		)
		(pad "1" smd rect
			(at -0.40005 0 270)
			(size 0.4572 0.508)
			(layers "B.Cu" "B.Mask" "B.Paste")
			(net "PWRGD_NODE1_DDR3_SYSPWRGD")
		)
		(pad "2" smd rect
			(at 0.40005 0 270)
			(size 0.4572 0.508)
			(layers "B.Cu" "B.Mask" "B.Paste")
			(net "PV_VDDR_NODE1")
		)
	)
	(footprint ""
		(layer "B.Cu")
		(at 54.469538 -79.531718)
		(property "Reference" "C49"
			(at -12.404598 30.92069 0)
			(unlocked yes)
			(layer "B.SilkS")
			(effects
				(font
					(size 0.7874 0.5842)
					(thickness 0.1524)
				)
				(justify left mirror)
			)
		)
		(property "Value" ""
			(at 0 0 0)
			(layer "B.Fab")
			(effects
				(font
					(size 1.27 1.27)
				)
				(justify mirror)
			)
		)
		(duplicate_pad_numbers_are_jumpers no)
		(fp_line
			(start -0.7874 -0.4064)
			(end -0.7874 0.4064)
			(stroke
				(width 0.1524)
				(type default)
			)
			(layer "B.SilkS")
		)
		(fp_line
			(start -0.7874 0.4064)
			(end 0.7874 0.4064)
			(stroke
				(width 0.1524)
				(type default)
			)
			(layer "B.SilkS")
		)
		(fp_line
			(start 0 0.381)
			(end 0 -0.381)
			(stroke
				(width 0.1524)
				(type default)
			)
			(layer "B.SilkS")
		)
		(fp_line
			(start 0.7874 -0.4064)
			(end -0.7874 -0.4064)
			(stroke
				(width 0.1524)
				(type default)
			)
			(layer "B.SilkS")
		)
		(fp_line
			(start 0.7874 0.4064)
			(end 0.7874 -0.4064)
			(stroke
				(width 0.1524)
				(type default)
			)
			(layer "B.SilkS")
		)
		(fp_poly
			(pts
				(xy 0.5334 0.254) (xy 0.635 0.254) (xy 0.635 0.2286) (xy 0.635 -0.254) (xy 0.5334 -0.254) (xy 0.5334 -0.2794)
				(xy -0.5334 -0.2794) (xy -0.5334 -0.254) (xy -0.635 -0.254) (xy -0.635 0.254) (xy -0.5334 0.254)
				(xy -0.5334 0.2794) (xy 0.508 0.2794) (xy 0.5334 0.2794)
			)
			(stroke
				(width 0)
				(type default)
			)
			(fill no)
			(layer "B.CrtYd")
		)
		(pad "1" smd rect
			(at -0.40005 0 180)
			(size 0.4572 0.508)
			(layers "B.Cu" "B.Mask" "B.Paste")
			(net "P1V05_NODE1")
		)
		(pad "2" smd rect
			(at 0.40005 0 180)
			(size 0.4572 0.508)
			(layers "B.Cu" "B.Mask" "B.Paste")
			(net "GND")
		)
	)
	(footprint ""
		(layer "B.Cu")
		(at 45.625258 -60.445396 -90)
		(property "Reference" "C21"
			(at 2.31775 2.249424 270)
			(unlocked yes)
			(layer "B.SilkS")
			(effects
				(font
					(size 0.7874 0.5842)
					(thickness 0.1524)
				)
				(justify left mirror)
			)
		)
		(property "Value" ""
			(at 0 0 90)
			(layer "B.Fab")
			(effects
				(font
					(size 1.27 1.27)
				)
				(justify mirror)
			)
		)
		(duplicate_pad_numbers_are_jumpers no)
		(fp_line
			(start -0.7874 0.4064)
			(end 0.7874 0.4064)
			(stroke
				(width 0.1524)
				(type default)
			)
			(layer "B.SilkS")
		)
		(fp_line
			(start 0.7874 0.4064)
			(end 0.7874 -0.4064)
			(stroke
				(width 0.1524)
				(type default)
			)
			(layer "B.SilkS")
		)
		(fp_line
			(start 0 0.381)
			(end 0 -0.381)
			(stroke
				(width 0.1524)
				(type default)
			)
			(layer "B.SilkS")
		)
		(fp_line
			(start -0.7874 -0.4064)
			(end -0.7874 0.4064)
			(stroke
				(width 0.1524)
				(type default)
			)
			(layer "B.SilkS")
		)
		(fp_line
			(start 0.7874 -0.4064)
			(end -0.7874 -0.4064)
			(stroke
				(width 0.1524)
				(type default)
			)
			(layer "B.SilkS")
		)
		(fp_poly
			(pts
				(xy 0.5334 0.254) (xy 0.635 0.254) (xy 0.635 0.2286) (xy 0.635 -0.254) (xy 0.5334 -0.254) (xy 0.5334 -0.2794)
				(xy -0.5334 -0.2794) (xy -0.5334 -0.254) (xy -0.635 -0.254) (xy -0.635 0.254) (xy -0.5334 0.254)
				(xy -0.5334 0.2794) (xy 0.508 0.2794) (xy 0.5334 0.2794)
			)
			(stroke
				(width 0)
				(type default)
			)
			(fill no)
			(layer "B.CrtYd")
		)
		(pad "1" smd rect
			(at -0.40005 0 90)
			(size 0.4572 0.508)
			(layers "B.Cu" "B.Mask" "B.Paste")
			(net "P2E_CPU_SATA_NODE1_TX_C_DP")
		)
		(pad "2" smd rect
			(at 0.40005 0 90)
			(size 0.4572 0.508)
			(layers "B.Cu" "B.Mask" "B.Paste")
			(net "P2E_CPU_SATA_NODE1_TX_DP")
		)
	)
	(footprint ""
		(layer "B.Cu")
		(at 134.435088 -46.960536 90)
		(property "Reference" "R1136"
			(at 3.102864 11.385042 270)
			(unlocked yes)
			(layer "B.SilkS")
			(effects
				(font
					(size 0.7874 0.5842)
					(thickness 0.1524)
				)
				(justify left mirror)
			)
		)
		(property "Value" ""
			(at 0 0 90)
			(layer "B.Fab")
			(effects
				(font
					(size 1.27 1.27)
				)
				(justify mirror)
			)
		)
		(duplicate_pad_numbers_are_jumpers no)
		(fp_line
			(start 0.7874 -0.4064)
			(end -0.7874 -0.4064)
			(stroke
				(width 0.1524)
				(type default)
			)
			(layer "B.SilkS")
		)
		(fp_line
			(start -0.7874 -0.4064)
			(end -0.7874 0.4064)
			(stroke
				(width 0.1524)
				(type default)
			)
			(layer "B.SilkS")
		)
		(fp_line
			(start 0.7874 0.4064)
			(end 0.7874 -0.4064)
			(stroke
				(width 0.1524)
				(type default)
			)
			(layer "B.SilkS")
		)
		(fp_line
			(start -0.7874 0.4064)
			(end 0.7874 0.4064)
			(stroke
				(width 0.1524)
				(type default)
			)
			(layer "B.SilkS")
		)
		(fp_poly
			(pts
				(xy 0.508 0.2794) (xy 0.508 0.2286) (xy 0.635 0.2286) (xy 0.635 -0.254) (xy 0.5334 -0.254) (xy 0.5334 -0.2794)
				(xy -0.5334 -0.2794) (xy -0.5334 -0.254) (xy -0.635 -0.254) (xy -0.635 0.254) (xy -0.5334 0.254)
				(xy -0.5334 0.2794)
			)
			(stroke
				(width 0)
				(type default)
			)
			(fill no)
			(layer "B.CrtYd")
		)
		(pad "1" smd rect
			(at -0.40005 0 270)
			(size 0.4572 0.508)
			(layers "B.Cu" "B.Mask" "B.Paste")
			(net "P5V_NODE1")
		)
		(pad "2" smd rect
			(at 0.40005 0 270)
			(size 0.4572 0.508)
			(layers "B.Cu" "B.Mask" "B.Paste")
			(net "UART_RTS_P3_R_N")
		)
	)
	(footprint ""
		(layer "B.Cu")
		(at 121.72061 -38.446456 180)
		(property "Reference" "R1204"
			(at 3.310636 -0.941578 0)
			(unlocked yes)
			(layer "B.SilkS")
			(effects
				(font
					(size 0.7874 0.5842)
					(thickness 0.1524)
				)
				(justify left mirror)
			)
		)
		(property "Value" ""
			(at 0 0 0)
			(layer "B.Fab")
			(effects
				(font
					(size 1.27 1.27)
				)
				(justify mirror)
			)
		)
		(duplicate_pad_numbers_are_jumpers no)
		(fp_line
			(start 0.7874 0.4064)
			(end 0.7874 -0.4064)
			(stroke
				(width 0.1524)
				(type default)
			)
			(layer "B.SilkS")
		)
		(fp_line
			(start 0.7874 -0.4064)
			(end -0.7874 -0.4064)
			(stroke
				(width 0.1524)
				(type default)
			)
			(layer "B.SilkS")
		)
		(fp_line
			(start -0.7874 0.4064)
			(end 0.7874 0.4064)
			(stroke
				(width 0.1524)
				(type default)
			)
			(layer "B.SilkS")
		)
		(fp_line
			(start -0.7874 -0.4064)
			(end -0.7874 0.4064)
			(stroke
				(width 0.1524)
				(type default)
			)
			(layer "B.SilkS")
		)
		(fp_poly
			(pts
				(xy 0.508 0.2794) (xy 0.508 0.2286) (xy 0.635 0.2286) (xy 0.635 -0.254) (xy 0.5334 -0.254) (xy 0.5334 -0.2794)
				(xy -0.5334 -0.2794) (xy -0.5334 -0.254) (xy -0.635 -0.254) (xy -0.635 0.254) (xy -0.5334 0.254)
				(xy -0.5334 0.2794)
			)
			(stroke
				(width 0)
				(type default)
			)
			(fill no)
			(layer "B.CrtYd")
		)
		(pad "1" smd rect
			(at -0.40005 0)
			(size 0.4572 0.508)
			(layers "B.Cu" "B.Mask" "B.Paste")
			(net "SIO_JTAG_CPLD3_TCK_R")
		)
		(pad "2" smd rect
			(at 0.40005 0)
			(size 0.4572 0.508)
			(layers "B.Cu" "B.Mask" "B.Paste")
			(net "P3V3_NODE1")
		)
	)
	(footprint ""
		(layer "B.Cu")
		(at 114.28476 -185.205624 90)
		(property "Reference" "R958"
			(at 3.957828 0.471424 270)
			(unlocked yes)
			(layer "B.SilkS")
			(effects
				(font
					(size 0.7874 0.5842)
					(thickness 0.1524)
				)
				(justify left mirror)
			)
		)
		(property "Value" ""
			(at 0 0 90)
			(layer "B.Fab")
			(effects
				(font
					(size 1.27 1.27)
				)
				(justify mirror)
			)
		)
		(duplicate_pad_numbers_are_jumpers no)
		(fp_line
			(start 0.7874 -0.4064)
			(end -0.7874 -0.4064)
			(stroke
				(width 0.1524)
				(type default)
			)
			(layer "B.SilkS")
		)
		(fp_line
			(start -0.7874 -0.4064)
			(end -0.7874 0.4064)
			(stroke
				(width 0.1524)
				(type default)
			)
			(layer "B.SilkS")
		)
		(fp_line
			(start 0.7874 0.4064)
			(end 0.7874 -0.4064)
			(stroke
				(width 0.1524)
				(type default)
			)
			(layer "B.SilkS")
		)
		(fp_line
			(start -0.7874 0.4064)
			(end 0.7874 0.4064)
			(stroke
				(width 0.1524)
				(type default)
			)
			(layer "B.SilkS")
		)
		(fp_poly
			(pts
				(xy 0.508 0.2794) (xy 0.508 0.2286) (xy 0.635 0.2286) (xy 0.635 -0.254) (xy 0.5334 -0.254) (xy 0.5334 -0.2794)
				(xy -0.5334 -0.2794) (xy -0.5334 -0.254) (xy -0.635 -0.254) (xy -0.635 0.254) (xy -0.5334 0.254)
				(xy -0.5334 0.2794)
			)
			(stroke
				(width 0)
				(type default)
			)
			(fill no)
			(layer "B.CrtYd")
		)
		(pad "1" smd rect
			(at -0.40005 0 270)
			(size 0.4572 0.508)
			(layers "B.Cu" "B.Mask" "B.Paste")
			(net "UART_T7_NODE1_TXD")
		)
		(pad "2" smd rect
			(at 0.40005 0 270)
			(size 0.4572 0.508)
			(layers "B.Cu" "B.Mask" "B.Paste")
			(net "UART_T7_NODE1_TXD_R")
		)
	)
	(footprint ""
		(layer "B.Cu")
		(at 136.50976 -187.872624 -90)
		(property "Reference" "C633"
			(at -4.565396 1.38938 270)
			(unlocked yes)
			(layer "B.SilkS")
			(effects
				(font
					(size 0.7874 0.5842)
					(thickness 0.1524)
				)
				(justify left mirror)
			)
		)
		(property "Value" ""
			(at 0 0 90)
			(layer "B.Fab")
			(effects
				(font
					(size 1.27 1.27)
				)
				(justify mirror)
			)
		)
		(duplicate_pad_numbers_are_jumpers no)
		(fp_line
			(start -0.7874 0.4064)
			(end 0.7874 0.4064)
			(stroke
				(width 0.1524)
				(type default)
			)
			(layer "B.SilkS")
		)
		(fp_line
			(start 0.7874 0.4064)
			(end 0.7874 -0.4064)
			(stroke
				(width 0.1524)
				(type default)
			)
			(layer "B.SilkS")
		)
		(fp_line
			(start 0 0.381)
			(end 0 -0.381)
			(stroke
				(width 0.1524)
				(type default)
			)
			(layer "B.SilkS")
		)
		(fp_line
			(start -0.7874 -0.4064)
			(end -0.7874 0.4064)
			(stroke
				(width 0.1524)
				(type default)
			)
			(layer "B.SilkS")
		)
		(fp_line
			(start 0.7874 -0.4064)
			(end -0.7874 -0.4064)
			(stroke
				(width 0.1524)
				(type default)
			)
			(layer "B.SilkS")
		)
		(fp_poly
			(pts
				(xy 0.5334 0.254) (xy 0.635 0.254) (xy 0.635 0.2286) (xy 0.635 -0.254) (xy 0.5334 -0.254) (xy 0.5334 -0.2794)
				(xy -0.5334 -0.2794) (xy -0.5334 -0.254) (xy -0.635 -0.254) (xy -0.635 0.254) (xy -0.5334 0.254)
				(xy -0.5334 0.2794) (xy 0.508 0.2794) (xy 0.5334 0.2794)
			)
			(stroke
				(width 0)
				(type default)
			)
			(fill no)
			(layer "B.CrtYd")
		)
		(pad "1" smd rect
			(at -0.40005 0 90)
			(size 0.4572 0.508)
			(layers "B.Cu" "B.Mask" "B.Paste")
			(net "T9_NODE4_EN_R")
		)
		(pad "2" smd rect
			(at 0.40005 0 90)
			(size 0.4572 0.508)
			(layers "B.Cu" "B.Mask" "B.Paste")
			(net "GND")
		)
	)
	(footprint ""
		(layer "B.Cu")
		(at 43.671236 -97.104708 -90)
		(property "Reference" "R129"
			(at -1.440688 -0.033274 270)
			(unlocked yes)
			(layer "B.SilkS")
			(effects
				(font
					(size 0.7874 0.5842)
					(thickness 0.1524)
				)
				(justify left mirror)
			)
		)
		(property "Value" ""
			(at 0 0 90)
			(layer "B.Fab")
			(effects
				(font
					(size 1.27 1.27)
				)
				(justify mirror)
			)
		)
		(duplicate_pad_numbers_are_jumpers no)
		(fp_line
			(start -0.7874 0.4064)
			(end 0.7874 0.4064)
			(stroke
				(width 0.1524)
				(type default)
			)
			(layer "B.SilkS")
		)
		(fp_line
			(start 0.7874 0.4064)
			(end 0.7874 -0.4064)
			(stroke
				(width 0.1524)
				(type default)
			)
			(layer "B.SilkS")
		)
		(fp_line
			(start -0.7874 -0.4064)
			(end -0.7874 0.4064)
			(stroke
				(width 0.1524)
				(type default)
			)
			(layer "B.SilkS")
		)
		(fp_line
			(start 0.7874 -0.4064)
			(end -0.7874 -0.4064)
			(stroke
				(width 0.1524)
				(type default)
			)
			(layer "B.SilkS")
		)
		(fp_poly
			(pts
				(xy 0.508 0.2794) (xy 0.508 0.2286) (xy 0.635 0.2286) (xy 0.635 -0.254) (xy 0.5334 -0.254) (xy 0.5334 -0.2794)
				(xy -0.5334 -0.2794) (xy -0.5334 -0.254) (xy -0.635 -0.254) (xy -0.635 0.254) (xy -0.5334 0.254)
				(xy -0.5334 0.2794)
			)
			(stroke
				(width 0)
				(type default)
			)
			(fill no)
			(layer "B.CrtYd")
		)
		(pad "1" smd rect
			(at -0.40005 0 90)
			(size 0.4572 0.508)
			(layers "B.Cu" "B.Mask" "B.Paste")
			(net "P3V3_NODE1")
		)
		(pad "2" smd rect
			(at 0.40005 0 90)
			(size 0.4572 0.508)
			(layers "B.Cu" "B.Mask" "B.Paste")
			(net "SMB_MUX_CPU_ICS_NODE1_DAT")
		)
	)
	(footprint ""
		(layer "B.Cu")
		(at 133.08076 -184.951624 -90)
		(property "Reference" "C725"
			(at -4.357624 1.543812 270)
			(unlocked yes)
			(layer "B.SilkS")
			(effects
				(font
					(size 0.7874 0.5842)
					(thickness 0.1524)
				)
				(justify left mirror)
			)
		)
		(property "Value" ""
			(at 0 0 90)
			(layer "B.Fab")
			(effects
				(font
					(size 1.27 1.27)
				)
				(justify mirror)
			)
		)
		(duplicate_pad_numbers_are_jumpers no)
		(fp_line
			(start -0.7874 0.4064)
			(end 0.7874 0.4064)
			(stroke
				(width 0.1524)
				(type default)
			)
			(layer "B.SilkS")
		)
		(fp_line
			(start 0.7874 0.4064)
			(end 0.7874 -0.4064)
			(stroke
				(width 0.1524)
				(type default)
			)
			(layer "B.SilkS")
		)
		(fp_line
			(start 0 0.381)
			(end 0 -0.381)
			(stroke
				(width 0.1524)
				(type default)
			)
			(layer "B.SilkS")
		)
		(fp_line
			(start -0.7874 -0.4064)
			(end -0.7874 0.4064)
			(stroke
				(width 0.1524)
				(type default)
			)
			(layer "B.SilkS")
		)
		(fp_line
			(start 0.7874 -0.4064)
			(end -0.7874 -0.4064)
			(stroke
				(width 0.1524)
				(type default)
			)
			(layer "B.SilkS")
		)
		(fp_poly
			(pts
				(xy 0.5334 0.254) (xy 0.635 0.254) (xy 0.635 0.2286) (xy 0.635 -0.254) (xy 0.5334 -0.254) (xy 0.5334 -0.2794)
				(xy -0.5334 -0.2794) (xy -0.5334 -0.254) (xy -0.635 -0.254) (xy -0.635 0.254) (xy -0.5334 0.254)
				(xy -0.5334 0.2794) (xy 0.508 0.2794) (xy 0.5334 0.2794)
			)
			(stroke
				(width 0)
				(type default)
			)
			(fill no)
			(layer "B.CrtYd")
		)
		(pad "1" smd rect
			(at -0.40005 0 90)
			(size 0.4572 0.508)
			(layers "B.Cu" "B.Mask" "B.Paste")
			(net "UART_T9_NODE2_RXD")
		)
		(pad "2" smd rect
			(at 0.40005 0 90)
			(size 0.4572 0.508)
			(layers "B.Cu" "B.Mask" "B.Paste")
			(net "GND")
		)
	)
	(footprint ""
		(layer "B.Cu")
		(at 63.553086 -131.661662 90)
		(property "Reference" "C293"
			(at -54.974236 -41.15181 270)
			(unlocked yes)
			(layer "B.SilkS")
			(effects
				(font
					(size 0.7874 0.5842)
					(thickness 0.1524)
				)
				(justify left mirror)
			)
		)
		(property "Value" ""
			(at 0 0 90)
			(layer "B.Fab")
			(effects
				(font
					(size 1.27 1.27)
				)
				(justify mirror)
			)
		)
		(duplicate_pad_numbers_are_jumpers no)
		(fp_line
			(start 0.7874 -0.4064)
			(end -0.7874 -0.4064)
			(stroke
				(width 0.1524)
				(type default)
			)
			(layer "B.SilkS")
		)
		(fp_line
			(start -0.7874 -0.4064)
			(end -0.7874 0.4064)
			(stroke
				(width 0.1524)
				(type default)
			)
			(layer "B.SilkS")
		)
		(fp_line
			(start 0 0.381)
			(end 0 -0.381)
			(stroke
				(width 0.1524)
				(type default)
			)
			(layer "B.SilkS")
		)
		(fp_line
			(start 0.7874 0.4064)
			(end 0.7874 -0.4064)
			(stroke
				(width 0.1524)
				(type default)
			)
			(layer "B.SilkS")
		)
		(fp_line
			(start -0.7874 0.4064)
			(end 0.7874 0.4064)
			(stroke
				(width 0.1524)
				(type default)
			)
			(layer "B.SilkS")
		)
		(fp_poly
			(pts
				(xy 0.5334 0.254) (xy 0.635 0.254) (xy 0.635 0.2286) (xy 0.635 -0.254) (xy 0.5334 -0.254) (xy 0.5334 -0.2794)
				(xy -0.5334 -0.2794) (xy -0.5334 -0.254) (xy -0.635 -0.254) (xy -0.635 0.254) (xy -0.5334 0.254)
				(xy -0.5334 0.2794) (xy 0.508 0.2794) (xy 0.5334 0.2794)
			)
			(stroke
				(width 0)
				(type default)
			)
			(fill no)
			(layer "B.CrtYd")
		)
		(pad "1" smd rect
			(at -0.40005 0 270)
			(size 0.4572 0.508)
			(layers "B.Cu" "B.Mask" "B.Paste")
			(net "P1V26_BMC_NODE1")
		)
		(pad "2" smd rect
			(at 0.40005 0 270)
			(size 0.4572 0.508)
			(layers "B.Cu" "B.Mask" "B.Paste")
			(net "GND")
		)
	)
	(footprint ""
		(layer "B.Cu")
		(at 137.970006 -36.42741)
		(property "Reference" "R1182"
			(at -3.527806 18.57248 0)
			(unlocked yes)
			(layer "B.SilkS")
			(effects
				(font
					(size 0.7874 0.5842)
					(thickness 0.1524)
				)
				(justify left mirror)
			)
		)
		(property "Value" ""
			(at 0 0 0)
			(layer "B.Fab")
			(effects
				(font
					(size 1.27 1.27)
				)
				(justify mirror)
			)
		)
		(duplicate_pad_numbers_are_jumpers no)
		(fp_line
			(start -0.7874 -0.4064)
			(end -0.7874 0.4064)
			(stroke
				(width 0.1524)
				(type default)
			)
			(layer "B.SilkS")
		)
		(fp_line
			(start -0.7874 0.4064)
			(end 0.7874 0.4064)
			(stroke
				(width 0.1524)
				(type default)
			)
			(layer "B.SilkS")
		)
		(fp_line
			(start 0.7874 -0.4064)
			(end -0.7874 -0.4064)
			(stroke
				(width 0.1524)
				(type default)
			)
			(layer "B.SilkS")
		)
		(fp_line
			(start 0.7874 0.4064)
			(end 0.7874 -0.4064)
			(stroke
				(width 0.1524)
				(type default)
			)
			(layer "B.SilkS")
		)
		(fp_poly
			(pts
				(xy 0.508 0.2794) (xy 0.508 0.2286) (xy 0.635 0.2286) (xy 0.635 -0.254) (xy 0.5334 -0.254) (xy 0.5334 -0.2794)
				(xy -0.5334 -0.2794) (xy -0.5334 -0.254) (xy -0.635 -0.254) (xy -0.635 0.254) (xy -0.5334 0.254)
				(xy -0.5334 0.2794)
			)
			(stroke
				(width 0)
				(type default)
			)
			(fill no)
			(layer "B.CrtYd")
		)
		(pad "1" smd rect
			(at -0.40005 0 180)
			(size 0.4572 0.508)
			(layers "B.Cu" "B.Mask" "B.Paste")
			(net "SIO_CPLD_RSV1_R")
		)
		(pad "2" smd rect
			(at 0.40005 0 180)
			(size 0.4572 0.508)
			(layers "B.Cu" "B.Mask" "B.Paste")
			(net "GND")
		)
	)
	(footprint ""
		(layer "B.Cu")
		(at 75.04176 -188.126624 90)
		(property "Reference" "R908"
			(at 4.318254 -0.374396 270)
			(unlocked yes)
			(layer "B.SilkS")
			(effects
				(font
					(size 0.7874 0.5842)
					(thickness 0.1524)
				)
				(justify left mirror)
			)
		)
		(property "Value" ""
			(at 0 0 90)
			(layer "B.Fab")
			(effects
				(font
					(size 1.27 1.27)
				)
				(justify mirror)
			)
		)
		(duplicate_pad_numbers_are_jumpers no)
		(fp_line
			(start 0.7874 -0.4064)
			(end -0.7874 -0.4064)
			(stroke
				(width 0.1524)
				(type default)
			)
			(layer "B.SilkS")
		)
		(fp_line
			(start -0.7874 -0.4064)
			(end -0.7874 0.4064)
			(stroke
				(width 0.1524)
				(type default)
			)
			(layer "B.SilkS")
		)
		(fp_line
			(start 0.7874 0.4064)
			(end 0.7874 -0.4064)
			(stroke
				(width 0.1524)
				(type default)
			)
			(layer "B.SilkS")
		)
		(fp_line
			(start -0.7874 0.4064)
			(end 0.7874 0.4064)
			(stroke
				(width 0.1524)
				(type default)
			)
			(layer "B.SilkS")
		)
		(fp_poly
			(pts
				(xy 0.508 0.2794) (xy 0.508 0.2286) (xy 0.635 0.2286) (xy 0.635 -0.254) (xy 0.5334 -0.254) (xy 0.5334 -0.2794)
				(xy -0.5334 -0.2794) (xy -0.5334 -0.254) (xy -0.635 -0.254) (xy -0.635 0.254) (xy -0.5334 0.254)
				(xy -0.5334 0.2794)
			)
			(stroke
				(width 0)
				(type default)
			)
			(fill no)
			(layer "B.CrtYd")
		)
		(pad "1" smd rect
			(at -0.40005 0 270)
			(size 0.4572 0.508)
			(layers "B.Cu" "B.Mask" "B.Paste")
			(net "UART_T3_NODE1_RXD")
		)
		(pad "2" smd rect
			(at 0.40005 0 270)
			(size 0.4572 0.508)
			(layers "B.Cu" "B.Mask" "B.Paste")
			(net "UART_T3_NODE1_RXD_R")
		)
	)
	(footprint ""
		(layer "B.Cu")
		(at 163.128452 -98.37039 180)
		(property "Reference" "C382"
			(at -4.541012 0.480314 0)
			(unlocked yes)
			(layer "B.SilkS")
			(effects
				(font
					(size 0.7874 0.5842)
					(thickness 0.1524)
				)
				(justify left mirror)
			)
		)
		(property "Value" ""
			(at 0 0 0)
			(layer "B.Fab")
			(effects
				(font
					(size 1.27 1.27)
				)
				(justify mirror)
			)
		)
		(duplicate_pad_numbers_are_jumpers no)
		(fp_line
			(start 0.7874 0.4064)
			(end 0.7874 -0.4064)
			(stroke
				(width 0.1524)
				(type default)
			)
			(layer "B.SilkS")
		)
		(fp_line
			(start 0.7874 -0.4064)
			(end -0.7874 -0.4064)
			(stroke
				(width 0.1524)
				(type default)
			)
			(layer "B.SilkS")
		)
		(fp_line
			(start 0 0.381)
			(end 0 -0.381)
			(stroke
				(width 0.1524)
				(type default)
			)
			(layer "B.SilkS")
		)
		(fp_line
			(start -0.7874 0.4064)
			(end 0.7874 0.4064)
			(stroke
				(width 0.1524)
				(type default)
			)
			(layer "B.SilkS")
		)
		(fp_line
			(start -0.7874 -0.4064)
			(end -0.7874 0.4064)
			(stroke
				(width 0.1524)
				(type default)
			)
			(layer "B.SilkS")
		)
		(fp_poly
			(pts
				(xy 0.5334 0.254) (xy 0.635 0.254) (xy 0.635 0.2286) (xy 0.635 -0.254) (xy 0.5334 -0.254) (xy 0.5334 -0.2794)
				(xy -0.5334 -0.2794) (xy -0.5334 -0.254) (xy -0.635 -0.254) (xy -0.635 0.254) (xy -0.5334 0.254)
				(xy -0.5334 0.2794) (xy 0.508 0.2794) (xy 0.5334 0.2794)
			)
			(stroke
				(width 0)
				(type default)
			)
			(fill no)
			(layer "B.CrtYd")
		)
		(pad "1" smd rect
			(at -0.40005 0)
			(size 0.4572 0.508)
			(layers "B.Cu" "B.Mask" "B.Paste")
			(net "GND")
		)
		(pad "2" smd rect
			(at 0.40005 0)
			(size 0.4572 0.508)
			(layers "B.Cu" "B.Mask" "B.Paste")
			(net "P3V3_NODE1")
		)
	)
	(footprint ""
		(layer "B.Cu")
		(at 136.483852 -116.871242 180)
		(property "Reference" "C3"
			(at -0.739902 0.926592 0)
			(unlocked yes)
			(layer "B.SilkS")
			(effects
				(font
					(size 0.7874 0.5842)
					(thickness 0.1524)
				)
				(justify left mirror)
			)
		)
		(property "Value" ""
			(at 0 0 0)
			(layer "B.Fab")
			(effects
				(font
					(size 1.27 1.27)
				)
				(justify mirror)
			)
		)
		(duplicate_pad_numbers_are_jumpers no)
		(fp_line
			(start 0.7874 0.4064)
			(end 0.7874 -0.4064)
			(stroke
				(width 0.1524)
				(type default)
			)
			(layer "B.SilkS")
		)
		(fp_line
			(start 0.7874 -0.4064)
			(end -0.7874 -0.4064)
			(stroke
				(width 0.1524)
				(type default)
			)
			(layer "B.SilkS")
		)
		(fp_line
			(start 0 0.381)
			(end 0 -0.381)
			(stroke
				(width 0.1524)
				(type default)
			)
			(layer "B.SilkS")
		)
		(fp_line
			(start -0.7874 0.4064)
			(end 0.7874 0.4064)
			(stroke
				(width 0.1524)
				(type default)
			)
			(layer "B.SilkS")
		)
		(fp_line
			(start -0.7874 -0.4064)
			(end -0.7874 0.4064)
			(stroke
				(width 0.1524)
				(type default)
			)
			(layer "B.SilkS")
		)
		(fp_poly
			(pts
				(xy 0.5334 0.254) (xy 0.635 0.254) (xy 0.635 0.2286) (xy 0.635 -0.254) (xy 0.5334 -0.254) (xy 0.5334 -0.2794)
				(xy -0.5334 -0.2794) (xy -0.5334 -0.254) (xy -0.635 -0.254) (xy -0.635 0.254) (xy -0.5334 0.254)
				(xy -0.5334 0.2794) (xy 0.508 0.2794) (xy 0.5334 0.2794)
			)
			(stroke
				(width 0)
				(type default)
			)
			(fill no)
			(layer "B.CrtYd")
		)
		(pad "1" smd rect
			(at -0.40005 0)
			(size 0.4572 0.508)
			(layers "B.Cu" "B.Mask" "B.Paste")
			(net "P3V3_CLK_NODE1")
		)
		(pad "2" smd rect
			(at 0.40005 0)
			(size 0.4572 0.508)
			(layers "B.Cu" "B.Mask" "B.Paste")
			(net "GND")
		)
	)
	(footprint ""
		(layer "B.Cu")
		(at 113.14176 -185.205624 -90)
		(property "Reference" "C724"
			(at -3.957828 -0.52832 270)
			(unlocked yes)
			(layer "B.SilkS")
			(effects
				(font
					(size 0.7874 0.5842)
					(thickness 0.1524)
				)
				(justify left mirror)
			)
		)
		(property "Value" ""
			(at 0 0 90)
			(layer "B.Fab")
			(effects
				(font
					(size 1.27 1.27)
				)
				(justify mirror)
			)
		)
		(duplicate_pad_numbers_are_jumpers no)
		(fp_line
			(start -0.7874 0.4064)
			(end 0.7874 0.4064)
			(stroke
				(width 0.1524)
				(type default)
			)
			(layer "B.SilkS")
		)
		(fp_line
			(start 0.7874 0.4064)
			(end 0.7874 -0.4064)
			(stroke
				(width 0.1524)
				(type default)
			)
			(layer "B.SilkS")
		)
		(fp_line
			(start 0 0.381)
			(end 0 -0.381)
			(stroke
				(width 0.1524)
				(type default)
			)
			(layer "B.SilkS")
		)
		(fp_line
			(start -0.7874 -0.4064)
			(end -0.7874 0.4064)
			(stroke
				(width 0.1524)
				(type default)
			)
			(layer "B.SilkS")
		)
		(fp_line
			(start 0.7874 -0.4064)
			(end -0.7874 -0.4064)
			(stroke
				(width 0.1524)
				(type default)
			)
			(layer "B.SilkS")
		)
		(fp_poly
			(pts
				(xy 0.5334 0.254) (xy 0.635 0.254) (xy 0.635 0.2286) (xy 0.635 -0.254) (xy 0.5334 -0.254) (xy 0.5334 -0.2794)
				(xy -0.5334 -0.2794) (xy -0.5334 -0.254) (xy -0.635 -0.254) (xy -0.635 0.254) (xy -0.5334 0.254)
				(xy -0.5334 0.2794) (xy 0.508 0.2794) (xy 0.5334 0.2794)
			)
			(stroke
				(width 0)
				(type default)
			)
			(fill no)
			(layer "B.CrtYd")
		)
		(pad "1" smd rect
			(at -0.40005 0 90)
			(size 0.4572 0.508)
			(layers "B.Cu" "B.Mask" "B.Paste")
			(net "UART_T7_NODE2_RXD")
		)
		(pad "2" smd rect
			(at 0.40005 0 90)
			(size 0.4572 0.508)
			(layers "B.Cu" "B.Mask" "B.Paste")
			(net "GND")
		)
	)
	(footprint ""
		(layer "B.Cu")
		(at 91.47302 -75.772518)
		(property "Reference" "R164"
			(at 4.07797 0.606044 0)
			(unlocked yes)
			(layer "B.SilkS")
			(effects
				(font
					(size 0.7874 0.5842)
					(thickness 0.1524)
				)
				(justify left mirror)
			)
		)
		(property "Value" ""
			(at 0 0 0)
			(layer "B.Fab")
			(effects
				(font
					(size 1.27 1.27)
				)
				(justify mirror)
			)
		)
		(duplicate_pad_numbers_are_jumpers no)
		(fp_line
			(start -0.7874 -0.4064)
			(end -0.7874 0.4064)
			(stroke
				(width 0.1524)
				(type default)
			)
			(layer "B.SilkS")
		)
		(fp_line
			(start -0.7874 0.4064)
			(end 0.7874 0.4064)
			(stroke
				(width 0.1524)
				(type default)
			)
			(layer "B.SilkS")
		)
		(fp_line
			(start 0.7874 -0.4064)
			(end -0.7874 -0.4064)
			(stroke
				(width 0.1524)
				(type default)
			)
			(layer "B.SilkS")
		)
		(fp_line
			(start 0.7874 0.4064)
			(end 0.7874 -0.4064)
			(stroke
				(width 0.1524)
				(type default)
			)
			(layer "B.SilkS")
		)
		(fp_poly
			(pts
				(xy 0.508 0.2794) (xy 0.508 0.2286) (xy 0.635 0.2286) (xy 0.635 -0.254) (xy 0.5334 -0.254) (xy 0.5334 -0.2794)
				(xy -0.5334 -0.2794) (xy -0.5334 -0.254) (xy -0.635 -0.254) (xy -0.635 0.254) (xy -0.5334 0.254)
				(xy -0.5334 0.2794)
			)
			(stroke
				(width 0)
				(type default)
			)
			(fill no)
			(layer "B.CrtYd")
		)
		(pad "1" smd rect
			(at -0.40005 0 180)
			(size 0.4572 0.508)
			(layers "B.Cu" "B.Mask" "B.Paste")
			(net "PD_CPU_NODE1_MEM_SPEED1")
		)
		(pad "2" smd rect
			(at 0.40005 0 180)
			(size 0.4572 0.508)
			(layers "B.Cu" "B.Mask" "B.Paste")
			(net "P1V05_SUS_NODE1")
		)
	)
	(footprint ""
		(layer "B.Cu")
		(at 50.53076 -185.205624 -90)
		(property "Reference" "R837"
			(at -4.15163 -0.163068 270)
			(unlocked yes)
			(layer "B.SilkS")
			(effects
				(font
					(size 0.7874 0.5842)
					(thickness 0.1524)
				)
				(justify left mirror)
			)
		)
		(property "Value" ""
			(at 0 0 90)
			(layer "B.Fab")
			(effects
				(font
					(size 1.27 1.27)
				)
				(justify mirror)
			)
		)
		(duplicate_pad_numbers_are_jumpers no)
		(fp_line
			(start -0.7874 0.4064)
			(end 0.7874 0.4064)
			(stroke
				(width 0.1524)
				(type default)
			)
			(layer "B.SilkS")
		)
		(fp_line
			(start 0.7874 0.4064)
			(end 0.7874 -0.4064)
			(stroke
				(width 0.1524)
				(type default)
			)
			(layer "B.SilkS")
		)
		(fp_line
			(start -0.7874 -0.4064)
			(end -0.7874 0.4064)
			(stroke
				(width 0.1524)
				(type default)
			)
			(layer "B.SilkS")
		)
		(fp_line
			(start 0.7874 -0.4064)
			(end -0.7874 -0.4064)
			(stroke
				(width 0.1524)
				(type default)
			)
			(layer "B.SilkS")
		)
		(fp_poly
			(pts
				(xy 0.508 0.2794) (xy 0.508 0.2286) (xy 0.635 0.2286) (xy 0.635 -0.254) (xy 0.5334 -0.254) (xy 0.5334 -0.2794)
				(xy -0.5334 -0.2794) (xy -0.5334 -0.254) (xy -0.635 -0.254) (xy -0.635 0.254) (xy -0.5334 0.254)
				(xy -0.5334 0.2794)
			)
			(stroke
				(width 0)
				(type default)
			)
			(fill no)
			(layer "B.CrtYd")
		)
		(pad "1" smd rect
			(at -0.40005 0 90)
			(size 0.4572 0.508)
			(layers "B.Cu" "B.Mask" "B.Paste")
			(net "PSU3_DC_OK_R")
		)
		(pad "2" smd rect
			(at 0.40005 0 90)
			(size 0.4572 0.508)
			(layers "B.Cu" "B.Mask" "B.Paste")
			(net "PSU3_DC_OK_R_BUF")
		)
	)
	(footprint ""
		(layer "B.Cu")
		(at 165.19398 -151.369522 180)
		(property "Reference" "C456"
			(at 1.058164 0.191008 0)
			(unlocked yes)
			(layer "B.SilkS")
			(effects
				(font
					(size 0.7874 0.5842)
					(thickness 0.1524)
				)
				(justify left mirror)
			)
		)
		(property "Value" ""
			(at 0 0 0)
			(layer "B.Fab")
			(effects
				(font
					(size 1.27 1.27)
				)
				(justify mirror)
			)
		)
		(duplicate_pad_numbers_are_jumpers no)
		(fp_line
			(start 0.7874 0.4064)
			(end 0.7874 -0.4064)
			(stroke
				(width 0.1524)
				(type default)
			)
			(layer "B.SilkS")
		)
		(fp_line
			(start 0.7874 -0.4064)
			(end -0.7874 -0.4064)
			(stroke
				(width 0.1524)
				(type default)
			)
			(layer "B.SilkS")
		)
		(fp_line
			(start 0 0.381)
			(end 0 -0.381)
			(stroke
				(width 0.1524)
				(type default)
			)
			(layer "B.SilkS")
		)
		(fp_line
			(start -0.7874 0.4064)
			(end 0.7874 0.4064)
			(stroke
				(width 0.1524)
				(type default)
			)
			(layer "B.SilkS")
		)
		(fp_line
			(start -0.7874 -0.4064)
			(end -0.7874 0.4064)
			(stroke
				(width 0.1524)
				(type default)
			)
			(layer "B.SilkS")
		)
		(fp_poly
			(pts
				(xy 0.5334 0.254) (xy 0.635 0.254) (xy 0.635 0.2286) (xy 0.635 -0.254) (xy 0.5334 -0.254) (xy 0.5334 -0.2794)
				(xy -0.5334 -0.2794) (xy -0.5334 -0.254) (xy -0.635 -0.254) (xy -0.635 0.254) (xy -0.5334 0.254)
				(xy -0.5334 0.2794) (xy 0.508 0.2794) (xy 0.5334 0.2794)
			)
			(stroke
				(width 0)
				(type default)
			)
			(fill no)
			(layer "B.CrtYd")
		)
		(pad "1" smd rect
			(at -0.40005 0)
			(size 0.4572 0.508)
			(layers "B.Cu" "B.Mask" "B.Paste")
			(net "P1V9_LAN2")
		)
		(pad "2" smd rect
			(at 0.40005 0)
			(size 0.4572 0.508)
			(layers "B.Cu" "B.Mask" "B.Paste")
			(net "GND")
		)
	)
	(footprint ""
		(layer "B.Cu")
		(at 61.320172 -129.91211)
		(property "Reference" "C270"
			(at -40.546782 53.033676 0)
			(unlocked yes)
			(layer "B.SilkS")
			(effects
				(font
					(size 0.7874 0.5842)
					(thickness 0.1524)
				)
				(justify left mirror)
			)
		)
		(property "Value" ""
			(at 0 0 0)
			(layer "B.Fab")
			(effects
				(font
					(size 1.27 1.27)
				)
				(justify mirror)
			)
		)
		(duplicate_pad_numbers_are_jumpers no)
		(fp_line
			(start -0.7874 -0.4064)
			(end -0.7874 0.4064)
			(stroke
				(width 0.1524)
				(type default)
			)
			(layer "B.SilkS")
		)
		(fp_line
			(start -0.7874 0.4064)
			(end 0.7874 0.4064)
			(stroke
				(width 0.1524)
				(type default)
			)
			(layer "B.SilkS")
		)
		(fp_line
			(start 0 0.381)
			(end 0 -0.381)
			(stroke
				(width 0.1524)
				(type default)
			)
			(layer "B.SilkS")
		)
		(fp_line
			(start 0.7874 -0.4064)
			(end -0.7874 -0.4064)
			(stroke
				(width 0.1524)
				(type default)
			)
			(layer "B.SilkS")
		)
		(fp_line
			(start 0.7874 0.4064)
			(end 0.7874 -0.4064)
			(stroke
				(width 0.1524)
				(type default)
			)
			(layer "B.SilkS")
		)
		(fp_poly
			(pts
				(xy 0.5334 0.254) (xy 0.635 0.254) (xy 0.635 0.2286) (xy 0.635 -0.254) (xy 0.5334 -0.254) (xy 0.5334 -0.2794)
				(xy -0.5334 -0.2794) (xy -0.5334 -0.254) (xy -0.635 -0.254) (xy -0.635 0.254) (xy -0.5334 0.254)
				(xy -0.5334 0.2794) (xy 0.508 0.2794) (xy 0.5334 0.2794)
			)
			(stroke
				(width 0)
				(type default)
			)
			(fill no)
			(layer "B.CrtYd")
		)
		(pad "1" smd rect
			(at -0.40005 0 180)
			(size 0.4572 0.508)
			(layers "B.Cu" "B.Mask" "B.Paste")
			(net "BMC_NODE1_HPLLAV33")
		)
		(pad "2" smd rect
			(at 0.40005 0 180)
			(size 0.4572 0.508)
			(layers "B.Cu" "B.Mask" "B.Paste")
			(net "GND")
		)
	)
	(footprint ""
		(layer "B.Cu")
		(at 51.675538 -77.804518 -90)
		(property "Reference" "C59"
			(at 32.241744 15.405608 270)
			(unlocked yes)
			(layer "B.SilkS")
			(effects
				(font
					(size 0.7874 0.5842)
					(thickness 0.1524)
				)
				(justify left mirror)
			)
		)
		(property "Value" ""
			(at 0 0 90)
			(layer "B.Fab")
			(effects
				(font
					(size 1.27 1.27)
				)
				(justify mirror)
			)
		)
		(duplicate_pad_numbers_are_jumpers no)
		(fp_line
			(start -0.7874 0.4064)
			(end 0.7874 0.4064)
			(stroke
				(width 0.1524)
				(type default)
			)
			(layer "B.SilkS")
		)
		(fp_line
			(start 0.7874 0.4064)
			(end 0.7874 -0.4064)
			(stroke
				(width 0.1524)
				(type default)
			)
			(layer "B.SilkS")
		)
		(fp_line
			(start 0 0.381)
			(end 0 -0.381)
			(stroke
				(width 0.1524)
				(type default)
			)
			(layer "B.SilkS")
		)
		(fp_line
			(start -0.7874 -0.4064)
			(end -0.7874 0.4064)
			(stroke
				(width 0.1524)
				(type default)
			)
			(layer "B.SilkS")
		)
		(fp_line
			(start 0.7874 -0.4064)
			(end -0.7874 -0.4064)
			(stroke
				(width 0.1524)
				(type default)
			)
			(layer "B.SilkS")
		)
		(fp_poly
			(pts
				(xy 0.5334 0.254) (xy 0.635 0.254) (xy 0.635 0.2286) (xy 0.635 -0.254) (xy 0.5334 -0.254) (xy 0.5334 -0.2794)
				(xy -0.5334 -0.2794) (xy -0.5334 -0.254) (xy -0.635 -0.254) (xy -0.635 0.254) (xy -0.5334 0.254)
				(xy -0.5334 0.2794) (xy 0.508 0.2794) (xy 0.5334 0.2794)
			)
			(stroke
				(width 0)
				(type default)
			)
			(fill no)
			(layer "B.CrtYd")
		)
		(pad "1" smd rect
			(at -0.40005 0 90)
			(size 0.4572 0.508)
			(layers "B.Cu" "B.Mask" "B.Paste")
			(net "P1V05_NODE1")
		)
		(pad "2" smd rect
			(at 0.40005 0 90)
			(size 0.4572 0.508)
			(layers "B.Cu" "B.Mask" "B.Paste")
			(net "GND")
		)
	)
	(footprint ""
		(layer "B.Cu")
		(at 135.196834 -37.375084 180)
		(property "Reference" "R1188"
			(at 5.415788 -18.226532 0)
			(unlocked yes)
			(layer "B.SilkS")
			(effects
				(font
					(size 0.7874 0.5842)
					(thickness 0.1524)
				)
				(justify left mirror)
			)
		)
		(property "Value" ""
			(at 0 0 0)
			(layer "B.Fab")
			(effects
				(font
					(size 1.27 1.27)
				)
				(justify mirror)
			)
		)
		(duplicate_pad_numbers_are_jumpers no)
		(fp_line
			(start 0.7874 0.4064)
			(end 0.7874 -0.4064)
			(stroke
				(width 0.1524)
				(type default)
			)
			(layer "B.SilkS")
		)
		(fp_line
			(start 0.7874 -0.4064)
			(end -0.7874 -0.4064)
			(stroke
				(width 0.1524)
				(type default)
			)
			(layer "B.SilkS")
		)
		(fp_line
			(start -0.7874 0.4064)
			(end 0.7874 0.4064)
			(stroke
				(width 0.1524)
				(type default)
			)
			(layer "B.SilkS")
		)
		(fp_line
			(start -0.7874 -0.4064)
			(end -0.7874 0.4064)
			(stroke
				(width 0.1524)
				(type default)
			)
			(layer "B.SilkS")
		)
		(fp_poly
			(pts
				(xy 0.508 0.2794) (xy 0.508 0.2286) (xy 0.635 0.2286) (xy 0.635 -0.254) (xy 0.5334 -0.254) (xy 0.5334 -0.2794)
				(xy -0.5334 -0.2794) (xy -0.5334 -0.254) (xy -0.635 -0.254) (xy -0.635 0.254) (xy -0.5334 0.254)
				(xy -0.5334 0.2794)
			)
			(stroke
				(width 0)
				(type default)
			)
			(fill no)
			(layer "B.CrtYd")
		)
		(pad "1" smd rect
			(at -0.40005 0)
			(size 0.4572 0.508)
			(layers "B.Cu" "B.Mask" "B.Paste")
			(net "SIO_JTAG_CPLD2_TDI")
		)
		(pad "2" smd rect
			(at 0.40005 0)
			(size 0.4572 0.508)
			(layers "B.Cu" "B.Mask" "B.Paste")
			(net "GND")
		)
	)
	(footprint ""
		(layer "B.Cu")
		(at 169.134028 -154.804872 180)
		(property "Reference" "R581"
			(at -4.380992 -0.115316 0)
			(unlocked yes)
			(layer "B.SilkS")
			(effects
				(font
					(size 0.7874 0.5842)
					(thickness 0.1524)
				)
				(justify left mirror)
			)
		)
		(property "Value" ""
			(at 0 0 0)
			(layer "B.Fab")
			(effects
				(font
					(size 1.27 1.27)
				)
				(justify mirror)
			)
		)
		(duplicate_pad_numbers_are_jumpers no)
		(fp_line
			(start 0.7874 0.4064)
			(end 0.7874 -0.4064)
			(stroke
				(width 0.1524)
				(type default)
			)
			(layer "B.SilkS")
		)
		(fp_line
			(start 0.7874 -0.4064)
			(end -0.7874 -0.4064)
			(stroke
				(width 0.1524)
				(type default)
			)
			(layer "B.SilkS")
		)
		(fp_line
			(start -0.7874 0.4064)
			(end 0.7874 0.4064)
			(stroke
				(width 0.1524)
				(type default)
			)
			(layer "B.SilkS")
		)
		(fp_line
			(start -0.7874 -0.4064)
			(end -0.7874 0.4064)
			(stroke
				(width 0.1524)
				(type default)
			)
			(layer "B.SilkS")
		)
		(fp_poly
			(pts
				(xy 0.508 0.2794) (xy 0.508 0.2286) (xy 0.635 0.2286) (xy 0.635 -0.254) (xy 0.5334 -0.254) (xy 0.5334 -0.2794)
				(xy -0.5334 -0.2794) (xy -0.5334 -0.254) (xy -0.635 -0.254) (xy -0.635 0.254) (xy -0.5334 0.254)
				(xy -0.5334 0.2794)
			)
			(stroke
				(width 0)
				(type default)
			)
			(fill no)
			(layer "B.CrtYd")
		)
		(pad "1" smd rect
			(at -0.40005 0)
			(size 0.4572 0.508)
			(layers "B.Cu" "B.Mask" "B.Paste")
			(net "P3V3_NODE1")
		)
		(pad "2" smd rect
			(at 0.40005 0)
			(size 0.4572 0.508)
			(layers "B.Cu" "B.Mask" "B.Paste")
			(net "LAN2_DIS_REG10")
		)
	)
	(footprint ""
		(layer "B.Cu")
		(at 46.56582 -150.27529 90)
		(property "Reference" "C422"
			(at 7.935214 -13.231622 270)
			(unlocked yes)
			(layer "B.SilkS")
			(effects
				(font
					(size 0.7874 0.5842)
					(thickness 0.1524)
				)
				(justify left mirror)
			)
		)
		(property "Value" ""
			(at 0 0 90)
			(layer "B.Fab")
			(effects
				(font
					(size 1.27 1.27)
				)
				(justify mirror)
			)
		)
		(duplicate_pad_numbers_are_jumpers no)
		(fp_line
			(start 0.7874 -0.4064)
			(end -0.7874 -0.4064)
			(stroke
				(width 0.1524)
				(type default)
			)
			(layer "B.SilkS")
		)
		(fp_line
			(start -0.7874 -0.4064)
			(end -0.7874 0.4064)
			(stroke
				(width 0.1524)
				(type default)
			)
			(layer "B.SilkS")
		)
		(fp_line
			(start 0 0.381)
			(end 0 -0.381)
			(stroke
				(width 0.1524)
				(type default)
			)
			(layer "B.SilkS")
		)
		(fp_line
			(start 0.7874 0.4064)
			(end 0.7874 -0.4064)
			(stroke
				(width 0.1524)
				(type default)
			)
			(layer "B.SilkS")
		)
		(fp_line
			(start -0.7874 0.4064)
			(end 0.7874 0.4064)
			(stroke
				(width 0.1524)
				(type default)
			)
			(layer "B.SilkS")
		)
		(fp_poly
			(pts
				(xy 0.5334 0.254) (xy 0.635 0.254) (xy 0.635 0.2286) (xy 0.635 -0.254) (xy 0.5334 -0.254) (xy 0.5334 -0.2794)
				(xy -0.5334 -0.2794) (xy -0.5334 -0.254) (xy -0.635 -0.254) (xy -0.635 0.254) (xy -0.5334 0.254)
				(xy -0.5334 0.2794) (xy 0.508 0.2794) (xy 0.5334 0.2794)
			)
			(stroke
				(width 0)
				(type default)
			)
			(fill no)
			(layer "B.CrtYd")
		)
		(pad "1" smd rect
			(at -0.40005 0 270)
			(size 0.4572 0.508)
			(layers "B.Cu" "B.Mask" "B.Paste")
			(net "P1V05_LAN1")
		)
		(pad "2" smd rect
			(at 0.40005 0 270)
			(size 0.4572 0.508)
			(layers "B.Cu" "B.Mask" "B.Paste")
			(net "GND")
		)
	)
	(footprint ""
		(layer "B.Cu")
		(at 69.649086 -124.930662 -90)
		(property "Reference" "C278"
			(at 3.666744 -8.660384 270)
			(unlocked yes)
			(layer "B.SilkS")
			(effects
				(font
					(size 0.7874 0.5842)
					(thickness 0.1524)
				)
				(justify left mirror)
			)
		)
		(property "Value" ""
			(at 0 0 90)
			(layer "B.Fab")
			(effects
				(font
					(size 1.27 1.27)
				)
				(justify mirror)
			)
		)
		(duplicate_pad_numbers_are_jumpers no)
		(fp_line
			(start -0.7874 0.4064)
			(end 0.7874 0.4064)
			(stroke
				(width 0.1524)
				(type default)
			)
			(layer "B.SilkS")
		)
		(fp_line
			(start 0.7874 0.4064)
			(end 0.7874 -0.4064)
			(stroke
				(width 0.1524)
				(type default)
			)
			(layer "B.SilkS")
		)
		(fp_line
			(start 0 0.381)
			(end 0 -0.381)
			(stroke
				(width 0.1524)
				(type default)
			)
			(layer "B.SilkS")
		)
		(fp_line
			(start -0.7874 -0.4064)
			(end -0.7874 0.4064)
			(stroke
				(width 0.1524)
				(type default)
			)
			(layer "B.SilkS")
		)
		(fp_line
			(start 0.7874 -0.4064)
			(end -0.7874 -0.4064)
			(stroke
				(width 0.1524)
				(type default)
			)
			(layer "B.SilkS")
		)
		(fp_poly
			(pts
				(xy 0.5334 0.254) (xy 0.635 0.254) (xy 0.635 0.2286) (xy 0.635 -0.254) (xy 0.5334 -0.254) (xy 0.5334 -0.2794)
				(xy -0.5334 -0.2794) (xy -0.5334 -0.254) (xy -0.635 -0.254) (xy -0.635 0.254) (xy -0.5334 0.254)
				(xy -0.5334 0.2794) (xy 0.508 0.2794) (xy 0.5334 0.2794)
			)
			(stroke
				(width 0)
				(type default)
			)
			(fill no)
			(layer "B.CrtYd")
		)
		(pad "1" smd rect
			(at -0.40005 0 90)
			(size 0.4572 0.508)
			(layers "B.Cu" "B.Mask" "B.Paste")
			(net "BMC_NODE1_VCC_1V8_PCIE")
		)
		(pad "2" smd rect
			(at 0.40005 0 90)
			(size 0.4572 0.508)
			(layers "B.Cu" "B.Mask" "B.Paste")
			(net "GND")
		)
	)
	(footprint ""
		(layer "B.Cu")
		(at 66.52133 -138.966448 180)
		(property "Reference" "C291"
			(at 37.32784 -54.78907 0)
			(unlocked yes)
			(layer "B.SilkS")
			(effects
				(font
					(size 0.7874 0.5842)
					(thickness 0.1524)
				)
				(justify left mirror)
			)
		)
		(property "Value" ""
			(at 0 0 0)
			(layer "B.Fab")
			(effects
				(font
					(size 1.27 1.27)
				)
				(justify mirror)
			)
		)
		(duplicate_pad_numbers_are_jumpers no)
		(fp_line
			(start 0.7874 0.4064)
			(end 0.7874 -0.4064)
			(stroke
				(width 0.1524)
				(type default)
			)
			(layer "B.SilkS")
		)
		(fp_line
			(start 0.7874 -0.4064)
			(end -0.7874 -0.4064)
			(stroke
				(width 0.1524)
				(type default)
			)
			(layer "B.SilkS")
		)
		(fp_line
			(start 0 0.381)
			(end 0 -0.381)
			(stroke
				(width 0.1524)
				(type default)
			)
			(layer "B.SilkS")
		)
		(fp_line
			(start -0.7874 0.4064)
			(end 0.7874 0.4064)
			(stroke
				(width 0.1524)
				(type default)
			)
			(layer "B.SilkS")
		)
		(fp_line
			(start -0.7874 -0.4064)
			(end -0.7874 0.4064)
			(stroke
				(width 0.1524)
				(type default)
			)
			(layer "B.SilkS")
		)
		(fp_poly
			(pts
				(xy 0.5334 0.254) (xy 0.635 0.254) (xy 0.635 0.2286) (xy 0.635 -0.254) (xy 0.5334 -0.254) (xy 0.5334 -0.2794)
				(xy -0.5334 -0.2794) (xy -0.5334 -0.254) (xy -0.635 -0.254) (xy -0.635 0.254) (xy -0.5334 0.254)
				(xy -0.5334 0.2794) (xy 0.508 0.2794) (xy 0.5334 0.2794)
			)
			(stroke
				(width 0)
				(type default)
			)
			(fill no)
			(layer "B.CrtYd")
		)
		(pad "1" smd rect
			(at -0.40005 0)
			(size 0.4572 0.508)
			(layers "B.Cu" "B.Mask" "B.Paste")
			(net "P1V26_BMC_NODE1")
		)
		(pad "2" smd rect
			(at 0.40005 0)
			(size 0.4572 0.508)
			(layers "B.Cu" "B.Mask" "B.Paste")
			(net "GND")
		)
	)
	(footprint ""
		(layer "B.Cu")
		(at 128.701546 -38.274244)
		(property "Reference" "R1207"
			(at 0.419354 7.550912 0)
			(unlocked yes)
			(layer "B.SilkS")
			(effects
				(font
					(size 0.7874 0.5842)
					(thickness 0.1524)
				)
				(justify left mirror)
			)
		)
		(property "Value" ""
			(at 0 0 0)
			(layer "B.Fab")
			(effects
				(font
					(size 1.27 1.27)
				)
				(justify mirror)
			)
		)
		(duplicate_pad_numbers_are_jumpers no)
		(fp_line
			(start -0.7874 -0.4064)
			(end -0.7874 0.4064)
			(stroke
				(width 0.1524)
				(type default)
			)
			(layer "B.SilkS")
		)
		(fp_line
			(start -0.7874 0.4064)
			(end 0.7874 0.4064)
			(stroke
				(width 0.1524)
				(type default)
			)
			(layer "B.SilkS")
		)
		(fp_line
			(start 0.7874 -0.4064)
			(end -0.7874 -0.4064)
			(stroke
				(width 0.1524)
				(type default)
			)
			(layer "B.SilkS")
		)
		(fp_line
			(start 0.7874 0.4064)
			(end 0.7874 -0.4064)
			(stroke
				(width 0.1524)
				(type default)
			)
			(layer "B.SilkS")
		)
		(fp_poly
			(pts
				(xy 0.508 0.2794) (xy 0.508 0.2286) (xy 0.635 0.2286) (xy 0.635 -0.254) (xy 0.5334 -0.254) (xy 0.5334 -0.2794)
				(xy -0.5334 -0.2794) (xy -0.5334 -0.254) (xy -0.635 -0.254) (xy -0.635 0.254) (xy -0.5334 0.254)
				(xy -0.5334 0.2794)
			)
			(stroke
				(width 0)
				(type default)
			)
			(fill no)
			(layer "B.CrtYd")
		)
		(pad "1" smd rect
			(at -0.40005 0 180)
			(size 0.4572 0.508)
			(layers "B.Cu" "B.Mask" "B.Paste")
			(net "SIO_JTAG_CPLD3_TCK_R")
		)
		(pad "2" smd rect
			(at 0.40005 0 180)
			(size 0.4572 0.508)
			(layers "B.Cu" "B.Mask" "B.Paste")
			(net "SIO_JTAG_CPLD3_TCK")
		)
	)
	(footprint ""
		(layer "B.Cu")
		(at 143.36776 -184.951624 90)
		(property "Reference" "R972"
			(at 4.392676 -2.31775 270)
			(unlocked yes)
			(layer "B.SilkS")
			(effects
				(font
					(size 0.7874 0.5842)
					(thickness 0.1524)
				)
				(justify left mirror)
			)
		)
		(property "Value" ""
			(at 0 0 90)
			(layer "B.Fab")
			(effects
				(font
					(size 1.27 1.27)
				)
				(justify mirror)
			)
		)
		(duplicate_pad_numbers_are_jumpers no)
		(fp_line
			(start 0.7874 -0.4064)
			(end -0.7874 -0.4064)
			(stroke
				(width 0.1524)
				(type default)
			)
			(layer "B.SilkS")
		)
		(fp_line
			(start -0.7874 -0.4064)
			(end -0.7874 0.4064)
			(stroke
				(width 0.1524)
				(type default)
			)
			(layer "B.SilkS")
		)
		(fp_line
			(start 0.7874 0.4064)
			(end 0.7874 -0.4064)
			(stroke
				(width 0.1524)
				(type default)
			)
			(layer "B.SilkS")
		)
		(fp_line
			(start -0.7874 0.4064)
			(end 0.7874 0.4064)
			(stroke
				(width 0.1524)
				(type default)
			)
			(layer "B.SilkS")
		)
		(fp_poly
			(pts
				(xy 0.508 0.2794) (xy 0.508 0.2286) (xy 0.635 0.2286) (xy 0.635 -0.254) (xy 0.5334 -0.254) (xy 0.5334 -0.2794)
				(xy -0.5334 -0.2794) (xy -0.5334 -0.254) (xy -0.635 -0.254) (xy -0.635 0.254) (xy -0.5334 0.254)
				(xy -0.5334 0.2794)
			)
			(stroke
				(width 0)
				(type default)
			)
			(fill no)
			(layer "B.CrtYd")
		)
		(pad "1" smd rect
			(at -0.40005 0 270)
			(size 0.4572 0.508)
			(layers "B.Cu" "B.Mask" "B.Paste")
			(net "UART_T11_NODE3_TXD")
		)
		(pad "2" smd rect
			(at 0.40005 0 270)
			(size 0.4572 0.508)
			(layers "B.Cu" "B.Mask" "B.Paste")
			(net "UART_T11_NODE3_TXD_R")
		)
	)
	(footprint ""
		(layer "B.Cu")
		(at 59.694572 -79.912718 90)
		(property "Reference" "C98"
			(at -32.491426 -14.379702 270)
			(unlocked yes)
			(layer "B.SilkS")
			(effects
				(font
					(size 0.7874 0.5842)
					(thickness 0.1524)
				)
				(justify left mirror)
			)
		)
		(property "Value" ""
			(at 0 0 90)
			(layer "B.Fab")
			(effects
				(font
					(size 1.27 1.27)
				)
				(justify mirror)
			)
		)
		(duplicate_pad_numbers_are_jumpers no)
		(fp_line
			(start 0.7874 -0.4064)
			(end -0.7874 -0.4064)
			(stroke
				(width 0.1524)
				(type default)
			)
			(layer "B.SilkS")
		)
		(fp_line
			(start -0.7874 -0.4064)
			(end -0.7874 0.4064)
			(stroke
				(width 0.1524)
				(type default)
			)
			(layer "B.SilkS")
		)
		(fp_line
			(start 0 0.381)
			(end 0 -0.381)
			(stroke
				(width 0.1524)
				(type default)
			)
			(layer "B.SilkS")
		)
		(fp_line
			(start 0.7874 0.4064)
			(end 0.7874 -0.4064)
			(stroke
				(width 0.1524)
				(type default)
			)
			(layer "B.SilkS")
		)
		(fp_line
			(start -0.7874 0.4064)
			(end 0.7874 0.4064)
			(stroke
				(width 0.1524)
				(type default)
			)
			(layer "B.SilkS")
		)
		(fp_poly
			(pts
				(xy 0.5334 0.254) (xy 0.635 0.254) (xy 0.635 0.2286) (xy 0.635 -0.254) (xy 0.5334 -0.254) (xy 0.5334 -0.2794)
				(xy -0.5334 -0.2794) (xy -0.5334 -0.254) (xy -0.635 -0.254) (xy -0.635 0.254) (xy -0.5334 0.254)
				(xy -0.5334 0.2794) (xy 0.508 0.2794) (xy 0.5334 0.2794)
			)
			(stroke
				(width 0)
				(type default)
			)
			(fill no)
			(layer "B.CrtYd")
		)
		(pad "1" smd rect
			(at -0.40005 0 270)
			(size 0.4572 0.508)
			(layers "B.Cu" "B.Mask" "B.Paste")
			(net "P1V05_NODE1")
		)
		(pad "2" smd rect
			(at 0.40005 0 270)
			(size 0.4572 0.508)
			(layers "B.Cu" "B.Mask" "B.Paste")
			(net "GND")
		)
	)
	(footprint ""
		(layer "B.Cu")
		(at 110.44936 -173.521624 180)
		(property "Reference" "R718"
			(at 21.356828 -32.269176 0)
			(unlocked yes)
			(layer "B.SilkS")
			(effects
				(font
					(size 0.7874 0.5842)
					(thickness 0.1524)
				)
				(justify left mirror)
			)
		)
		(property "Value" ""
			(at 0 0 0)
			(layer "B.Fab")
			(effects
				(font
					(size 1.27 1.27)
				)
				(justify mirror)
			)
		)
		(duplicate_pad_numbers_are_jumpers no)
		(fp_line
			(start 0.7874 0.4064)
			(end 0.7874 -0.4064)
			(stroke
				(width 0.1524)
				(type default)
			)
			(layer "B.SilkS")
		)
		(fp_line
			(start 0.7874 -0.4064)
			(end -0.7874 -0.4064)
			(stroke
				(width 0.1524)
				(type default)
			)
			(layer "B.SilkS")
		)
		(fp_line
			(start -0.7874 0.4064)
			(end 0.7874 0.4064)
			(stroke
				(width 0.1524)
				(type default)
			)
			(layer "B.SilkS")
		)
		(fp_line
			(start -0.7874 -0.4064)
			(end -0.7874 0.4064)
			(stroke
				(width 0.1524)
				(type default)
			)
			(layer "B.SilkS")
		)
		(fp_poly
			(pts
				(xy 0.508 0.2794) (xy 0.508 0.2286) (xy 0.635 0.2286) (xy 0.635 -0.254) (xy 0.5334 -0.254) (xy 0.5334 -0.2794)
				(xy -0.5334 -0.2794) (xy -0.5334 -0.254) (xy -0.635 -0.254) (xy -0.635 0.254) (xy -0.5334 0.254)
				(xy -0.5334 0.2794)
			)
			(stroke
				(width 0)
				(type default)
			)
			(fill no)
			(layer "B.CrtYd")
		)
		(pad "1" smd rect
			(at -0.40005 0)
			(size 0.4572 0.508)
			(layers "B.Cu" "B.Mask" "B.Paste")
			(net "N21699716")
		)
		(pad "2" smd rect
			(at 0.40005 0)
			(size 0.4572 0.508)
			(layers "B.Cu" "B.Mask" "B.Paste")
			(net "GND")
		)
	)
	(footprint ""
		(layer "B.Cu")
		(at 79.60614 -185.598054 90)
		(property "Reference" "R883"
			(at 3.446272 -0.247142 270)
			(unlocked yes)
			(layer "B.SilkS")
			(effects
				(font
					(size 0.7874 0.5842)
					(thickness 0.1524)
				)
				(justify left mirror)
			)
		)
		(property "Value" ""
			(at 0 0 90)
			(layer "B.Fab")
			(effects
				(font
					(size 1.27 1.27)
				)
				(justify mirror)
			)
		)
		(duplicate_pad_numbers_are_jumpers no)
		(fp_line
			(start 0.7874 -0.4064)
			(end -0.7874 -0.4064)
			(stroke
				(width 0.1524)
				(type default)
			)
			(layer "B.SilkS")
		)
		(fp_line
			(start -0.7874 -0.4064)
			(end -0.7874 0.4064)
			(stroke
				(width 0.1524)
				(type default)
			)
			(layer "B.SilkS")
		)
		(fp_line
			(start 0.7874 0.4064)
			(end 0.7874 -0.4064)
			(stroke
				(width 0.1524)
				(type default)
			)
			(layer "B.SilkS")
		)
		(fp_line
			(start -0.7874 0.4064)
			(end 0.7874 0.4064)
			(stroke
				(width 0.1524)
				(type default)
			)
			(layer "B.SilkS")
		)
		(fp_poly
			(pts
				(xy 0.508 0.2794) (xy 0.508 0.2286) (xy 0.635 0.2286) (xy 0.635 -0.254) (xy 0.5334 -0.254) (xy 0.5334 -0.2794)
				(xy -0.5334 -0.2794) (xy -0.5334 -0.254) (xy -0.635 -0.254) (xy -0.635 0.254) (xy -0.5334 0.254)
				(xy -0.5334 0.2794)
			)
			(stroke
				(width 0)
				(type default)
			)
			(fill no)
			(layer "B.CrtYd")
		)
		(pad "1" smd rect
			(at -0.40005 0 270)
			(size 0.4572 0.508)
			(layers "B.Cu" "B.Mask" "B.Paste")
			(net "T3_NODE1_EN")
		)
		(pad "2" smd rect
			(at 0.40005 0 270)
			(size 0.4572 0.508)
			(layers "B.Cu" "B.Mask" "B.Paste")
			(net "T3_NODE1_EN_R")
		)
	)
	(footprint ""
		(layer "B.Cu")
		(at 128.905 -55.245)
		(property "Reference" "U146"
			(at -1.70307 0.0254 270)
			(unlocked yes)
			(layer "B.SilkS")
			(effects
				(font
					(size 0.7874 0.5842)
					(thickness 0.1524)
				)
				(justify mirror)
			)
		)
		(property "Value" ""
			(at 0 0 0)
			(layer "B.Fab")
			(effects
				(font
					(size 1.27 1.27)
				)
				(justify mirror)
			)
		)
		(duplicate_pad_numbers_are_jumpers no)
		(fp_line
			(start -1.1176 -1.7018)
			(end -1.1176 1.7018)
			(stroke
				(width 0.1524)
				(type default)
			)
			(layer "B.SilkS")
		)
		(fp_line
			(start -1.1176 1.7018)
			(end 1.1176 1.7018)
			(stroke
				(width 0.1524)
				(type default)
			)
			(layer "B.SilkS")
		)
		(fp_line
			(start 0.7112 0)
			(end 1.1176 0.254)
			(stroke
				(width 0.1524)
				(type default)
			)
			(layer "B.SilkS")
		)
		(fp_line
			(start 1.1176 -1.7018)
			(end -1.1176 -1.7018)
			(stroke
				(width 0.1524)
				(type default)
			)
			(layer "B.SilkS")
		)
		(fp_line
			(start 1.1176 -1.7018)
			(end 1.1176 -0.254)
			(stroke
				(width 0.1524)
				(type default)
			)
			(layer "B.SilkS")
		)
		(fp_line
			(start 1.1176 -0.254)
			(end 0.7112 0)
			(stroke
				(width 0.1524)
				(type default)
			)
			(layer "B.SilkS")
		)
		(fp_line
			(start 1.1176 0.254)
			(end 1.1176 1.7018)
			(stroke
				(width 0.1524)
				(type default)
			)
			(layer "B.SilkS")
		)
		(fp_poly
			(pts
				(xy 0.675386 1.8161) (xy 0.446786 2.4003) (xy 0.878586 2.4003)
			)
			(stroke
				(width 0)
				(type default)
			)
			(fill yes)
			(layer "B.SilkS")
		)
		(fp_rect
			(start 1.1176 1.5494)
			(end -1.1176 -1.5494)
			(stroke
				(width 0)
				(type default)
			)
			(fill no)
			(layer "B.CrtYd")
		)
		(fp_line
			(start -1.1176 -1.5494)
			(end -1.1176 1.5494)
			(stroke
				(width 0.1)
				(type default)
			)
			(layer "B.Fab")
		)
		(fp_line
			(start -1.1176 1.5494)
			(end 1.1176 1.5494)
			(stroke
				(width 0.1)
				(type default)
			)
			(layer "B.Fab")
		)
		(fp_line
			(start 1.1176 -1.5494)
			(end -1.1176 -1.5494)
			(stroke
				(width 0.1)
				(type default)
			)
			(layer "B.Fab")
		)
		(fp_line
			(start 1.1176 -1.5494)
			(end 1.1176 -0.254)
			(stroke
				(width 0.1)
				(type default)
			)
			(layer "B.Fab")
		)
		(fp_line
			(start 1.1176 -0.254)
			(end 1.1176 0.254)
			(stroke
				(width 0.1)
				(type default)
			)
			(layer "B.Fab")
		)
		(fp_line
			(start 1.1176 0.254)
			(end 1.1176 1.5494)
			(stroke
				(width 0.1)
				(type default)
			)
			(layer "B.Fab")
		)
		(fp_poly
			(pts
				(xy 0.675386 1.8161) (xy 0.446786 2.4003) (xy 0.878586 2.4003)
			)
			(stroke
				(width 0)
				(type default)
			)
			(fill yes)
			(layer "B.Fab")
		)
		(pad "1" smd rect
			(at 0.649986 0.962406 180)
			(size 0.3302 1.1684)
			(layers "B.Cu" "B.Mask" "B.Paste")
			(net "Net_5")
		)
		(pad "2" smd rect
			(at 0 0.962406 180)
			(size 0.3302 1.1684)
			(layers "B.Cu" "B.Mask" "B.Paste")
			(net "UART_RI_P3_BUFFER_N")
		)
		(pad "3" smd rect
			(at -0.649986 0.962406 180)
			(size 0.3302 1.1684)
			(layers "B.Cu" "B.Mask" "B.Paste")
			(net "GND")
		)
		(pad "4" smd rect
			(at -0.649986 -0.962406 180)
			(size 0.3302 1.1684)
			(layers "B.Cu" "B.Mask" "B.Paste")
			(net "UART_RI_P3_N")
		)
		(pad "5" smd rect
			(at 0.649986 -0.962406 180)
			(size 0.3302 1.1684)
			(layers "B.Cu" "B.Mask" "B.Paste")
			(net "P3V3_NODE1")
		)
	)
	(footprint ""
		(layer "B.Cu")
		(at 57.852818 -85.025738 90)
		(property "Reference" "R100"
			(at 0.969772 -0.022352 270)
			(unlocked yes)
			(layer "B.SilkS")
			(effects
				(font
					(size 0.7874 0.5842)
					(thickness 0.1524)
				)
				(justify left mirror)
			)
		)
		(property "Value" ""
			(at 0 0 90)
			(layer "B.Fab")
			(effects
				(font
					(size 1.27 1.27)
				)
				(justify mirror)
			)
		)
		(duplicate_pad_numbers_are_jumpers no)
		(fp_line
			(start 0.7874 -0.4064)
			(end -0.7874 -0.4064)
			(stroke
				(width 0.1524)
				(type default)
			)
			(layer "B.SilkS")
		)
		(fp_line
			(start -0.7874 -0.4064)
			(end -0.7874 0.4064)
			(stroke
				(width 0.1524)
				(type default)
			)
			(layer "B.SilkS")
		)
		(fp_line
			(start 0.7874 0.4064)
			(end 0.7874 -0.4064)
			(stroke
				(width 0.1524)
				(type default)
			)
			(layer "B.SilkS")
		)
		(fp_line
			(start -0.7874 0.4064)
			(end 0.7874 0.4064)
			(stroke
				(width 0.1524)
				(type default)
			)
			(layer "B.SilkS")
		)
		(fp_poly
			(pts
				(xy 0.508 0.2794) (xy 0.508 0.2286) (xy 0.635 0.2286) (xy 0.635 -0.254) (xy 0.5334 -0.254) (xy 0.5334 -0.2794)
				(xy -0.5334 -0.2794) (xy -0.5334 -0.254) (xy -0.635 -0.254) (xy -0.635 0.254) (xy -0.5334 0.254)
				(xy -0.5334 0.2794)
			)
			(stroke
				(width 0)
				(type default)
			)
			(fill no)
			(layer "B.CrtYd")
		)
		(pad "1" smd rect
			(at -0.40005 0 270)
			(size 0.4572 0.508)
			(layers "B.Cu" "B.Mask" "B.Paste")
			(net "A_CPU_NODE1_MV_GPIO_RCOMP")
		)
		(pad "2" smd rect
			(at 0.40005 0 270)
			(size 0.4572 0.508)
			(layers "B.Cu" "B.Mask" "B.Paste")
			(net "GND")
		)
	)
	(footprint ""
		(layer "B.Cu")
		(at 133.9596 -55.6006 -90)
		(property "Reference" "U145"
			(at -1.75133 0.254 0)
			(unlocked yes)
			(layer "B.SilkS")
			(effects
				(font
					(size 0.7874 0.5842)
					(thickness 0.1524)
				)
				(justify mirror)
			)
		)
		(property "Value" ""
			(at 0 0 90)
			(layer "B.Fab")
			(effects
				(font
					(size 1.27 1.27)
				)
				(justify mirror)
			)
		)
		(duplicate_pad_numbers_are_jumpers no)
		(fp_line
			(start -1.1176 1.7018)
			(end 1.1176 1.7018)
			(stroke
				(width 0.1524)
				(type default)
			)
			(layer "B.SilkS")
		)
		(fp_line
			(start 1.1176 0.254)
			(end 1.1176 1.7018)
			(stroke
				(width 0.1524)
				(type default)
			)
			(layer "B.SilkS")
		)
		(fp_line
			(start 0.7112 0)
			(end 1.1176 0.254)
			(stroke
				(width 0.1524)
				(type default)
			)
			(layer "B.SilkS")
		)
		(fp_line
			(start 1.1176 -0.254)
			(end 0.7112 0)
			(stroke
				(width 0.1524)
				(type default)
			)
			(layer "B.SilkS")
		)
		(fp_line
			(start -1.1176 -1.7018)
			(end -1.1176 1.7018)
			(stroke
				(width 0.1524)
				(type default)
			)
			(layer "B.SilkS")
		)
		(fp_line
			(start 1.1176 -1.7018)
			(end 1.1176 -0.254)
			(stroke
				(width 0.1524)
				(type default)
			)
			(layer "B.SilkS")
		)
		(fp_line
			(start 1.1176 -1.7018)
			(end -1.1176 -1.7018)
			(stroke
				(width 0.1524)
				(type default)
			)
			(layer "B.SilkS")
		)
		(fp_poly
			(pts
				(xy 0.675386 1.8161) (xy 0.446786 2.4003) (xy 0.878586 2.4003)
			)
			(stroke
				(width 0)
				(type default)
			)
			(fill yes)
			(layer "B.SilkS")
		)
		(fp_rect
			(start 1.1176 1.5494)
			(end -1.1176 -1.5494)
			(stroke
				(width 0)
				(type default)
			)
			(fill no)
			(layer "B.CrtYd")
		)
		(fp_line
			(start -1.1176 1.5494)
			(end 1.1176 1.5494)
			(stroke
				(width 0.1)
				(type default)
			)
			(layer "B.Fab")
		)
		(fp_line
			(start 1.1176 0.254)
			(end 1.1176 1.5494)
			(stroke
				(width 0.1)
				(type default)
			)
			(layer "B.Fab")
		)
		(fp_line
			(start 1.1176 -0.254)
			(end 1.1176 0.254)
			(stroke
				(width 0.1)
				(type default)
			)
			(layer "B.Fab")
		)
		(fp_line
			(start -1.1176 -1.5494)
			(end -1.1176 1.5494)
			(stroke
				(width 0.1)
				(type default)
			)
			(layer "B.Fab")
		)
		(fp_line
			(start 1.1176 -1.5494)
			(end 1.1176 -0.254)
			(stroke
				(width 0.1)
				(type default)
			)
			(layer "B.Fab")
		)
		(fp_line
			(start 1.1176 -1.5494)
			(end -1.1176 -1.5494)
			(stroke
				(width 0.1)
				(type default)
			)
			(layer "B.Fab")
		)
		(fp_poly
			(pts
				(xy 0.675386 1.8161) (xy 0.446786 2.4003) (xy 0.878586 2.4003)
			)
			(stroke
				(width 0)
				(type default)
			)
			(fill yes)
			(layer "B.Fab")
		)
		(pad "1" smd rect
			(at 0.649986 0.962406 90)
			(size 0.3302 1.1684)
			(layers "B.Cu" "B.Mask" "B.Paste")
			(net "Net_6")
		)
		(pad "2" smd rect
			(at 0 0.962406 90)
			(size 0.3302 1.1684)
			(layers "B.Cu" "B.Mask" "B.Paste")
			(net "UART_RI_P4_N")
		)
		(pad "3" smd rect
			(at -0.649986 0.962406 90)
			(size 0.3302 1.1684)
			(layers "B.Cu" "B.Mask" "B.Paste")
			(net "GND")
		)
		(pad "4" smd rect
			(at -0.649986 -0.962406 90)
			(size 0.3302 1.1684)
			(layers "B.Cu" "B.Mask" "B.Paste")
			(net "UART_RI_P4_R_N")
		)
		(pad "5" smd rect
			(at 0.649986 -0.962406 90)
			(size 0.3302 1.1684)
			(layers "B.Cu" "B.Mask" "B.Paste")
			(net "P3V3_NODE1")
		)
	)
	(footprint ""
		(layer "B.Cu")
		(at 164.804852 -104.84739 90)
		(property "Reference" "C381"
			(at 1.423416 6.517386 270)
			(unlocked yes)
			(layer "B.SilkS")
			(effects
				(font
					(size 0.7874 0.5842)
					(thickness 0.1524)
				)
				(justify left mirror)
			)
		)
		(property "Value" ""
			(at 0 0 90)
			(layer "B.Fab")
			(effects
				(font
					(size 1.27 1.27)
				)
				(justify mirror)
			)
		)
		(duplicate_pad_numbers_are_jumpers no)
		(fp_line
			(start 0.7874 -0.4064)
			(end -0.7874 -0.4064)
			(stroke
				(width 0.1524)
				(type default)
			)
			(layer "B.SilkS")
		)
		(fp_line
			(start -0.7874 -0.4064)
			(end -0.7874 0.4064)
			(stroke
				(width 0.1524)
				(type default)
			)
			(layer "B.SilkS")
		)
		(fp_line
			(start 0 0.381)
			(end 0 -0.381)
			(stroke
				(width 0.1524)
				(type default)
			)
			(layer "B.SilkS")
		)
		(fp_line
			(start 0.7874 0.4064)
			(end 0.7874 -0.4064)
			(stroke
				(width 0.1524)
				(type default)
			)
			(layer "B.SilkS")
		)
		(fp_line
			(start -0.7874 0.4064)
			(end 0.7874 0.4064)
			(stroke
				(width 0.1524)
				(type default)
			)
			(layer "B.SilkS")
		)
		(fp_poly
			(pts
				(xy 0.5334 0.254) (xy 0.635 0.254) (xy 0.635 0.2286) (xy 0.635 -0.254) (xy 0.5334 -0.254) (xy 0.5334 -0.2794)
				(xy -0.5334 -0.2794) (xy -0.5334 -0.254) (xy -0.635 -0.254) (xy -0.635 0.254) (xy -0.5334 0.254)
				(xy -0.5334 0.2794) (xy 0.508 0.2794) (xy 0.5334 0.2794)
			)
			(stroke
				(width 0)
				(type default)
			)
			(fill no)
			(layer "B.CrtYd")
		)
		(pad "1" smd rect
			(at -0.40005 0 270)
			(size 0.4572 0.508)
			(layers "B.Cu" "B.Mask" "B.Paste")
			(net "GND")
		)
		(pad "2" smd rect
			(at 0.40005 0 270)
			(size 0.4572 0.508)
			(layers "B.Cu" "B.Mask" "B.Paste")
			(net "P3V3_NODE1")
		)
	)
	(footprint ""
		(layer "B.Cu")
		(at 59.102498 -96.315784 -90)
		(property "Reference" "R60"
			(at -6.3627 5.414264 270)
			(unlocked yes)
			(layer "B.SilkS")
			(effects
				(font
					(size 0.7874 0.5842)
					(thickness 0.1524)
				)
				(justify left mirror)
			)
		)
		(property "Value" ""
			(at 0 0 90)
			(layer "B.Fab")
			(effects
				(font
					(size 1.27 1.27)
				)
				(justify mirror)
			)
		)
		(duplicate_pad_numbers_are_jumpers no)
		(fp_line
			(start -0.7874 0.4064)
			(end 0.7874 0.4064)
			(stroke
				(width 0.1524)
				(type default)
			)
			(layer "B.SilkS")
		)
		(fp_line
			(start 0.7874 0.4064)
			(end 0.7874 -0.4064)
			(stroke
				(width 0.1524)
				(type default)
			)
			(layer "B.SilkS")
		)
		(fp_line
			(start -0.7874 -0.4064)
			(end -0.7874 0.4064)
			(stroke
				(width 0.1524)
				(type default)
			)
			(layer "B.SilkS")
		)
		(fp_line
			(start 0.7874 -0.4064)
			(end -0.7874 -0.4064)
			(stroke
				(width 0.1524)
				(type default)
			)
			(layer "B.SilkS")
		)
		(fp_poly
			(pts
				(xy 0.508 0.2794) (xy 0.508 0.2286) (xy 0.635 0.2286) (xy 0.635 -0.254) (xy 0.5334 -0.254) (xy 0.5334 -0.2794)
				(xy -0.5334 -0.2794) (xy -0.5334 -0.254) (xy -0.635 -0.254) (xy -0.635 0.254) (xy -0.5334 0.254)
				(xy -0.5334 0.2794)
			)
			(stroke
				(width 0)
				(type default)
			)
			(fill no)
			(layer "B.CrtYd")
		)
		(pad "1" smd rect
			(at -0.40005 0 90)
			(size 0.4572 0.508)
			(layers "B.Cu" "B.Mask" "B.Paste")
			(net "LPC_CPU_NODE1_LAD3")
		)
		(pad "2" smd rect
			(at 0.40005 0 90)
			(size 0.4572 0.508)
			(layers "B.Cu" "B.Mask" "B.Paste")
			(net "LPC_CPU_NODE1_LAD3_R")
		)
	)
	(footprint ""
		(layer "B.Cu")
		(at 131.3053 -40.62476 180)
		(property "Reference" "R1079"
			(at -0.4699 1.89357 0)
			(unlocked yes)
			(layer "B.SilkS")
			(effects
				(font
					(size 0.7874 0.5842)
					(thickness 0.1524)
				)
				(justify left mirror)
			)
		)
		(property "Value" ""
			(at 0 0 0)
			(layer "B.Fab")
			(effects
				(font
					(size 1.27 1.27)
				)
				(justify mirror)
			)
		)
		(duplicate_pad_numbers_are_jumpers no)
		(fp_line
			(start 0.7874 0.4064)
			(end 0.7874 -0.4064)
			(stroke
				(width 0.1524)
				(type default)
			)
			(layer "B.SilkS")
		)
		(fp_line
			(start 0.7874 -0.4064)
			(end -0.7874 -0.4064)
			(stroke
				(width 0.1524)
				(type default)
			)
			(layer "B.SilkS")
		)
		(fp_line
			(start -0.7874 0.4064)
			(end 0.7874 0.4064)
			(stroke
				(width 0.1524)
				(type default)
			)
			(layer "B.SilkS")
		)
		(fp_line
			(start -0.7874 -0.4064)
			(end -0.7874 0.4064)
			(stroke
				(width 0.1524)
				(type default)
			)
			(layer "B.SilkS")
		)
		(fp_poly
			(pts
				(xy 0.508 0.2794) (xy 0.508 0.2286) (xy 0.635 0.2286) (xy 0.635 -0.254) (xy 0.5334 -0.254) (xy 0.5334 -0.2794)
				(xy -0.5334 -0.2794) (xy -0.5334 -0.254) (xy -0.635 -0.254) (xy -0.635 0.254) (xy -0.5334 0.254)
				(xy -0.5334 0.2794)
			)
			(stroke
				(width 0)
				(type default)
			)
			(fill no)
			(layer "B.CrtYd")
		)
		(pad "1" smd rect
			(at -0.40005 0)
			(size 0.4572 0.508)
			(layers "B.Cu" "B.Mask" "B.Paste")
			(net "SIO_JTAG_CPLD2_TMS")
		)
		(pad "2" smd rect
			(at 0.40005 0)
			(size 0.4572 0.508)
			(layers "B.Cu" "B.Mask" "B.Paste")
			(net "JTAG_CPLD2_TMS")
		)
	)
	(footprint ""
		(layer "B.Cu")
		(at 135.577072 -46.950376 90)
		(property "Reference" "R1137"
			(at 3.113024 11.233658 270)
			(unlocked yes)
			(layer "B.SilkS")
			(effects
				(font
					(size 0.7874 0.5842)
					(thickness 0.1524)
				)
				(justify left mirror)
			)
		)
		(property "Value" ""
			(at 0 0 90)
			(layer "B.Fab")
			(effects
				(font
					(size 1.27 1.27)
				)
				(justify mirror)
			)
		)
		(duplicate_pad_numbers_are_jumpers no)
		(fp_line
			(start 0.7874 -0.4064)
			(end -0.7874 -0.4064)
			(stroke
				(width 0.1524)
				(type default)
			)
			(layer "B.SilkS")
		)
		(fp_line
			(start -0.7874 -0.4064)
			(end -0.7874 0.4064)
			(stroke
				(width 0.1524)
				(type default)
			)
			(layer "B.SilkS")
		)
		(fp_line
			(start 0.7874 0.4064)
			(end 0.7874 -0.4064)
			(stroke
				(width 0.1524)
				(type default)
			)
			(layer "B.SilkS")
		)
		(fp_line
			(start -0.7874 0.4064)
			(end 0.7874 0.4064)
			(stroke
				(width 0.1524)
				(type default)
			)
			(layer "B.SilkS")
		)
		(fp_poly
			(pts
				(xy 0.508 0.2794) (xy 0.508 0.2286) (xy 0.635 0.2286) (xy 0.635 -0.254) (xy 0.5334 -0.254) (xy 0.5334 -0.2794)
				(xy -0.5334 -0.2794) (xy -0.5334 -0.254) (xy -0.635 -0.254) (xy -0.635 0.254) (xy -0.5334 0.254)
				(xy -0.5334 0.2794)
			)
			(stroke
				(width 0)
				(type default)
			)
			(fill no)
			(layer "B.CrtYd")
		)
		(pad "1" smd rect
			(at -0.40005 0 270)
			(size 0.4572 0.508)
			(layers "B.Cu" "B.Mask" "B.Paste")
			(net "GND")
		)
		(pad "2" smd rect
			(at 0.40005 0 270)
			(size 0.4572 0.508)
			(layers "B.Cu" "B.Mask" "B.Paste")
			(net "UART_RTS_P3_R_N")
		)
	)
	(footprint ""
		(layer "B.Cu")
		(at 164.592 -188.087 -90)
		(property "Reference" "R1333"
			(at 2.0066 1.60147 270)
			(unlocked yes)
			(layer "B.SilkS")
			(effects
				(font
					(size 0.7874 0.5842)
					(thickness 0.1524)
				)
				(justify left mirror)
			)
		)
		(property "Value" ""
			(at 0 0 90)
			(layer "B.Fab")
			(effects
				(font
					(size 1.27 1.27)
				)
				(justify mirror)
			)
		)
		(duplicate_pad_numbers_are_jumpers no)
		(fp_line
			(start -0.7874 0.4064)
			(end 0.7874 0.4064)
			(stroke
				(width 0.1524)
				(type default)
			)
			(layer "B.SilkS")
		)
		(fp_line
			(start 0.7874 0.4064)
			(end 0.7874 -0.4064)
			(stroke
				(width 0.1524)
				(type default)
			)
			(layer "B.SilkS")
		)
		(fp_line
			(start -0.7874 -0.4064)
			(end -0.7874 0.4064)
			(stroke
				(width 0.1524)
				(type default)
			)
			(layer "B.SilkS")
		)
		(fp_line
			(start 0.7874 -0.4064)
			(end -0.7874 -0.4064)
			(stroke
				(width 0.1524)
				(type default)
			)
			(layer "B.SilkS")
		)
		(fp_poly
			(pts
				(xy 0.508 0.2794) (xy 0.508 0.2286) (xy 0.635 0.2286) (xy 0.635 -0.254) (xy 0.5334 -0.254) (xy 0.5334 -0.2794)
				(xy -0.5334 -0.2794) (xy -0.5334 -0.254) (xy -0.635 -0.254) (xy -0.635 0.254) (xy -0.5334 0.254)
				(xy -0.5334 0.2794)
			)
			(stroke
				(width 0)
				(type default)
			)
			(fill no)
			(layer "B.CrtYd")
		)
		(pad "1" smd rect
			(at -0.40005 0 90)
			(size 0.4572 0.508)
			(layers "B.Cu" "B.Mask" "B.Paste")
			(net "UART_RI_RP6_L_N_R")
		)
		(pad "2" smd rect
			(at 0.40005 0 90)
			(size 0.4572 0.508)
			(layers "B.Cu" "B.Mask" "B.Paste")
			(net "UART_RI_RP6_L_N")
		)
	)
	(footprint ""
		(layer "B.Cu")
		(at 39.120572 -68.957698 180)
		(property "Reference" "C16"
			(at -3.139948 0.106172 0)
			(unlocked yes)
			(layer "B.SilkS")
			(effects
				(font
					(size 0.7874 0.5842)
					(thickness 0.1524)
				)
				(justify left mirror)
			)
		)
		(property "Value" ""
			(at 0 0 0)
			(layer "B.Fab")
			(effects
				(font
					(size 1.27 1.27)
				)
				(justify mirror)
			)
		)
		(duplicate_pad_numbers_are_jumpers no)
		(fp_line
			(start 0.7874 0.4064)
			(end 0.7874 -0.4064)
			(stroke
				(width 0.1524)
				(type default)
			)
			(layer "B.SilkS")
		)
		(fp_line
			(start 0.7874 -0.4064)
			(end -0.7874 -0.4064)
			(stroke
				(width 0.1524)
				(type default)
			)
			(layer "B.SilkS")
		)
		(fp_line
			(start 0 0.381)
			(end 0 -0.381)
			(stroke
				(width 0.1524)
				(type default)
			)
			(layer "B.SilkS")
		)
		(fp_line
			(start -0.7874 0.4064)
			(end 0.7874 0.4064)
			(stroke
				(width 0.1524)
				(type default)
			)
			(layer "B.SilkS")
		)
		(fp_line
			(start -0.7874 -0.4064)
			(end -0.7874 0.4064)
			(stroke
				(width 0.1524)
				(type default)
			)
			(layer "B.SilkS")
		)
		(fp_poly
			(pts
				(xy 0.5334 0.254) (xy 0.635 0.254) (xy 0.635 0.2286) (xy 0.635 -0.254) (xy 0.5334 -0.254) (xy 0.5334 -0.2794)
				(xy -0.5334 -0.2794) (xy -0.5334 -0.254) (xy -0.635 -0.254) (xy -0.635 0.254) (xy -0.5334 0.254)
				(xy -0.5334 0.2794) (xy 0.508 0.2794) (xy 0.5334 0.2794)
			)
			(stroke
				(width 0)
				(type default)
			)
			(fill no)
			(layer "B.CrtYd")
		)
		(pad "1" smd rect
			(at -0.40005 0)
			(size 0.4572 0.508)
			(layers "B.Cu" "B.Mask" "B.Paste")
			(net "P2E_CPU_PCIE_SW_NODE1_TX_C_DN")
		)
		(pad "2" smd rect
			(at 0.40005 0)
			(size 0.4572 0.508)
			(layers "B.Cu" "B.Mask" "B.Paste")
			(net "P2E_CPU_PCIE_SW_NODE1_TX_DN")
		)
	)
	(footprint ""
		(layer "B.Cu")
		(at 35.713162 -104.82707 90)
		(property "Reference" "C821"
			(at 0.935736 1.886712 270)
			(unlocked yes)
			(layer "B.SilkS")
			(effects
				(font
					(size 0.7874 0.5842)
					(thickness 0.1524)
				)
				(justify left mirror)
			)
		)
		(property "Value" ""
			(at 0 0 90)
			(layer "B.Fab")
			(effects
				(font
					(size 1.27 1.27)
				)
				(justify mirror)
			)
		)
		(duplicate_pad_numbers_are_jumpers no)
		(fp_line
			(start 1.905 -0.8636)
			(end -1.905 -0.8636)
			(stroke
				(width 0.1524)
				(type default)
			)
			(layer "B.SilkS")
		)
		(fp_line
			(start -1.905 -0.8636)
			(end -1.905 0.8636)
			(stroke
				(width 0.1524)
				(type default)
			)
			(layer "B.SilkS")
		)
		(fp_line
			(start 0 0.8382)
			(end 0 -0.8382)
			(stroke
				(width 0.1524)
				(type default)
			)
			(layer "B.SilkS")
		)
		(fp_line
			(start 1.905 0.8636)
			(end 1.905 -0.8636)
			(stroke
				(width 0.1524)
				(type default)
			)
			(layer "B.SilkS")
		)
		(fp_line
			(start -1.905 0.8636)
			(end 1.905 0.8636)
			(stroke
				(width 0.1524)
				(type default)
			)
			(layer "B.SilkS")
		)
		(fp_rect
			(start 1.524 0.7366)
			(end -1.524 -0.7366)
			(stroke
				(width 0)
				(type default)
			)
			(fill no)
			(layer "B.CrtYd")
		)
		(pad "1" smd rect
			(at -0.94996 0 270)
			(size 1.1176 1.3716)
			(layers "B.Cu" "B.Mask" "B.Paste")
			(net "P1V5_SUS_NODE1")
		)
		(pad "2" smd rect
			(at 0.94996 0 270)
			(size 1.1176 1.3716)
			(layers "B.Cu" "B.Mask" "B.Paste")
			(net "GND")
		)
	)
	(footprint ""
		(layer "B.Cu")
		(at 78.21676 -188.126624 -90)
		(property "Reference" "C649"
			(at -4.151884 0.365252 270)
			(unlocked yes)
			(layer "B.SilkS")
			(effects
				(font
					(size 0.7874 0.5842)
					(thickness 0.1524)
				)
				(justify left mirror)
			)
		)
		(property "Value" ""
			(at 0 0 90)
			(layer "B.Fab")
			(effects
				(font
					(size 1.27 1.27)
				)
				(justify mirror)
			)
		)
		(duplicate_pad_numbers_are_jumpers no)
		(fp_line
			(start -0.7874 0.4064)
			(end 0.7874 0.4064)
			(stroke
				(width 0.1524)
				(type default)
			)
			(layer "B.SilkS")
		)
		(fp_line
			(start 0.7874 0.4064)
			(end 0.7874 -0.4064)
			(stroke
				(width 0.1524)
				(type default)
			)
			(layer "B.SilkS")
		)
		(fp_line
			(start 0 0.381)
			(end 0 -0.381)
			(stroke
				(width 0.1524)
				(type default)
			)
			(layer "B.SilkS")
		)
		(fp_line
			(start -0.7874 -0.4064)
			(end -0.7874 0.4064)
			(stroke
				(width 0.1524)
				(type default)
			)
			(layer "B.SilkS")
		)
		(fp_line
			(start 0.7874 -0.4064)
			(end -0.7874 -0.4064)
			(stroke
				(width 0.1524)
				(type default)
			)
			(layer "B.SilkS")
		)
		(fp_poly
			(pts
				(xy 0.5334 0.254) (xy 0.635 0.254) (xy 0.635 0.2286) (xy 0.635 -0.254) (xy 0.5334 -0.254) (xy 0.5334 -0.2794)
				(xy -0.5334 -0.2794) (xy -0.5334 -0.254) (xy -0.635 -0.254) (xy -0.635 0.254) (xy -0.5334 0.254)
				(xy -0.5334 0.2794) (xy 0.508 0.2794) (xy 0.5334 0.2794)
			)
			(stroke
				(width 0)
				(type default)
			)
			(fill no)
			(layer "B.CrtYd")
		)
		(pad "1" smd rect
			(at -0.40005 0 90)
			(size 0.4572 0.508)
			(layers "B.Cu" "B.Mask" "B.Paste")
			(net "T3_NODE2_EN_R")
		)
		(pad "2" smd rect
			(at 0.40005 0 90)
			(size 0.4572 0.508)
			(layers "B.Cu" "B.Mask" "B.Paste")
			(net "GND")
		)
	)
	(footprint ""
		(layer "B.Cu")
		(at 68.379086 -118.758462 -90)
		(property "Reference" "R329"
			(at 5.085334 0.574548 270)
			(unlocked yes)
			(layer "B.SilkS")
			(effects
				(font
					(size 0.7874 0.5842)
					(thickness 0.1524)
				)
				(justify left mirror)
			)
		)
		(property "Value" ""
			(at 0 0 90)
			(layer "B.Fab")
			(effects
				(font
					(size 1.27 1.27)
				)
				(justify mirror)
			)
		)
		(duplicate_pad_numbers_are_jumpers no)
		(fp_line
			(start -0.7874 0.4064)
			(end 0.7874 0.4064)
			(stroke
				(width 0.1524)
				(type default)
			)
			(layer "B.SilkS")
		)
		(fp_line
			(start 0.7874 0.4064)
			(end 0.7874 -0.4064)
			(stroke
				(width 0.1524)
				(type default)
			)
			(layer "B.SilkS")
		)
		(fp_line
			(start -0.7874 -0.4064)
			(end -0.7874 0.4064)
			(stroke
				(width 0.1524)
				(type default)
			)
			(layer "B.SilkS")
		)
		(fp_line
			(start 0.7874 -0.4064)
			(end -0.7874 -0.4064)
			(stroke
				(width 0.1524)
				(type default)
			)
			(layer "B.SilkS")
		)
		(fp_poly
			(pts
				(xy 0.508 0.2794) (xy 0.508 0.2286) (xy 0.635 0.2286) (xy 0.635 -0.254) (xy 0.5334 -0.254) (xy 0.5334 -0.2794)
				(xy -0.5334 -0.2794) (xy -0.5334 -0.254) (xy -0.635 -0.254) (xy -0.635 0.254) (xy -0.5334 0.254)
				(xy -0.5334 0.2794)
			)
			(stroke
				(width 0)
				(type default)
			)
			(fill no)
			(layer "B.CrtYd")
		)
		(pad "1" smd rect
			(at -0.40005 0 90)
			(size 0.4572 0.508)
			(layers "B.Cu" "B.Mask" "B.Paste")
			(net "P3V3_NODE1")
		)
		(pad "2" smd rect
			(at 0.40005 0 90)
			(size 0.4572 0.508)
			(layers "B.Cu" "B.Mask" "B.Paste")
			(net "BMC_ROMA13")
		)
	)
	(footprint ""
		(layer "B.Cu")
		(at 147.305014 -70.635622 180)
		(property "Reference" "C350"
			(at -4.93522 0.558038 0)
			(unlocked yes)
			(layer "B.SilkS")
			(effects
				(font
					(size 0.7874 0.5842)
					(thickness 0.1524)
				)
				(justify left mirror)
			)
		)
		(property "Value" ""
			(at 0 0 0)
			(layer "B.Fab")
			(effects
				(font
					(size 1.27 1.27)
				)
				(justify mirror)
			)
		)
		(duplicate_pad_numbers_are_jumpers no)
		(fp_line
			(start 0.7874 0.4064)
			(end 0.7874 -0.4064)
			(stroke
				(width 0.1524)
				(type default)
			)
			(layer "B.SilkS")
		)
		(fp_line
			(start 0.7874 -0.4064)
			(end -0.7874 -0.4064)
			(stroke
				(width 0.1524)
				(type default)
			)
			(layer "B.SilkS")
		)
		(fp_line
			(start 0 0.381)
			(end 0 -0.381)
			(stroke
				(width 0.1524)
				(type default)
			)
			(layer "B.SilkS")
		)
		(fp_line
			(start -0.7874 0.4064)
			(end 0.7874 0.4064)
			(stroke
				(width 0.1524)
				(type default)
			)
			(layer "B.SilkS")
		)
		(fp_line
			(start -0.7874 -0.4064)
			(end -0.7874 0.4064)
			(stroke
				(width 0.1524)
				(type default)
			)
			(layer "B.SilkS")
		)
		(fp_poly
			(pts
				(xy 0.5334 0.254) (xy 0.635 0.254) (xy 0.635 0.2286) (xy 0.635 -0.254) (xy 0.5334 -0.254) (xy 0.5334 -0.2794)
				(xy -0.5334 -0.2794) (xy -0.5334 -0.254) (xy -0.635 -0.254) (xy -0.635 0.254) (xy -0.5334 0.254)
				(xy -0.5334 0.2794) (xy 0.508 0.2794) (xy 0.5334 0.2794)
			)
			(stroke
				(width 0)
				(type default)
			)
			(fill no)
			(layer "B.CrtYd")
		)
		(pad "1" smd rect
			(at -0.40005 0)
			(size 0.4572 0.508)
			(layers "B.Cu" "B.Mask" "B.Paste")
			(net "P1V8_SATA_AVDD_NODE1")
		)
		(pad "2" smd rect
			(at 0.40005 0)
			(size 0.4572 0.508)
			(layers "B.Cu" "B.Mask" "B.Paste")
			(net "GND")
		)
	)
	(footprint ""
		(layer "B.Cu")
		(at 142.07236 -177.077624 180)
		(property "Reference" "R736"
			(at 1.250188 1.24079 0)
			(unlocked yes)
			(layer "B.SilkS")
			(effects
				(font
					(size 0.7874 0.5842)
					(thickness 0.1524)
				)
				(justify left mirror)
			)
		)
		(property "Value" ""
			(at 0 0 0)
			(layer "B.Fab")
			(effects
				(font
					(size 1.27 1.27)
				)
				(justify mirror)
			)
		)
		(duplicate_pad_numbers_are_jumpers no)
		(fp_line
			(start 0.7874 0.4064)
			(end 0.7874 -0.4064)
			(stroke
				(width 0.1524)
				(type default)
			)
			(layer "B.SilkS")
		)
		(fp_line
			(start 0.7874 -0.4064)
			(end -0.7874 -0.4064)
			(stroke
				(width 0.1524)
				(type default)
			)
			(layer "B.SilkS")
		)
		(fp_line
			(start -0.7874 0.4064)
			(end 0.7874 0.4064)
			(stroke
				(width 0.1524)
				(type default)
			)
			(layer "B.SilkS")
		)
		(fp_line
			(start -0.7874 -0.4064)
			(end -0.7874 0.4064)
			(stroke
				(width 0.1524)
				(type default)
			)
			(layer "B.SilkS")
		)
		(fp_poly
			(pts
				(xy 0.508 0.2794) (xy 0.508 0.2286) (xy 0.635 0.2286) (xy 0.635 -0.254) (xy 0.5334 -0.254) (xy 0.5334 -0.2794)
				(xy -0.5334 -0.2794) (xy -0.5334 -0.254) (xy -0.635 -0.254) (xy -0.635 0.254) (xy -0.5334 0.254)
				(xy -0.5334 0.2794)
			)
			(stroke
				(width 0)
				(type default)
			)
			(fill no)
			(layer "B.CrtYd")
		)
		(pad "1" smd rect
			(at -0.40005 0)
			(size 0.4572 0.508)
			(layers "B.Cu" "B.Mask" "B.Paste")
			(net "T10_NODE3_EN")
		)
		(pad "2" smd rect
			(at 0.40005 0)
			(size 0.4572 0.508)
			(layers "B.Cu" "B.Mask" "B.Paste")
			(net "P5V_NODE1")
		)
	)
	(footprint ""
		(layer "B.Cu")
		(at 180.660294 -159.333692 -90)
		(property "Reference" "C520"
			(at -2.62382 -0.065024 270)
			(unlocked yes)
			(layer "B.SilkS")
			(effects
				(font
					(size 0.7874 0.5842)
					(thickness 0.1524)
				)
				(justify left mirror)
			)
		)
		(property "Value" ""
			(at 0 0 90)
			(layer "B.Fab")
			(effects
				(font
					(size 1.27 1.27)
				)
				(justify mirror)
			)
		)
		(duplicate_pad_numbers_are_jumpers no)
		(fp_line
			(start -0.7874 0.4064)
			(end 0.7874 0.4064)
			(stroke
				(width 0.1524)
				(type default)
			)
			(layer "B.SilkS")
		)
		(fp_line
			(start 0.7874 0.4064)
			(end 0.7874 -0.4064)
			(stroke
				(width 0.1524)
				(type default)
			)
			(layer "B.SilkS")
		)
		(fp_line
			(start 0 0.381)
			(end 0 -0.381)
			(stroke
				(width 0.1524)
				(type default)
			)
			(layer "B.SilkS")
		)
		(fp_line
			(start -0.7874 -0.4064)
			(end -0.7874 0.4064)
			(stroke
				(width 0.1524)
				(type default)
			)
			(layer "B.SilkS")
		)
		(fp_line
			(start 0.7874 -0.4064)
			(end -0.7874 -0.4064)
			(stroke
				(width 0.1524)
				(type default)
			)
			(layer "B.SilkS")
		)
		(fp_poly
			(pts
				(xy 0.5334 0.254) (xy 0.635 0.254) (xy 0.635 0.2286) (xy 0.635 -0.254) (xy 0.5334 -0.254) (xy 0.5334 -0.2794)
				(xy -0.5334 -0.2794) (xy -0.5334 -0.254) (xy -0.635 -0.254) (xy -0.635 0.254) (xy -0.5334 0.254)
				(xy -0.5334 0.2794) (xy 0.508 0.2794) (xy 0.5334 0.2794)
			)
			(stroke
				(width 0)
				(type default)
			)
			(fill no)
			(layer "B.CrtYd")
		)
		(pad "1" smd rect
			(at -0.40005 0 90)
			(size 0.4572 0.508)
			(layers "B.Cu" "B.Mask" "B.Paste")
			(net "P1V9_LAN2")
		)
		(pad "2" smd rect
			(at 0.40005 0 90)
			(size 0.4572 0.508)
			(layers "B.Cu" "B.Mask" "B.Paste")
			(net "GND")
		)
	)
	(footprint ""
		(layer "B.Cu")
		(at 100.44176 -176.569624 -90)
		(property "Reference" "U65"
			(at 0.310388 5.50291 270)
			(unlocked yes)
			(layer "B.SilkS")
			(effects
				(font
					(size 0.7874 0.5842)
					(thickness 0.1524)
				)
				(justify left mirror)
			)
		)
		(property "Value" ""
			(at 0 0 90)
			(layer "B.Fab")
			(effects
				(font
					(size 1.27 1.27)
				)
				(justify mirror)
			)
		)
		(duplicate_pad_numbers_are_jumpers no)
		(fp_line
			(start -3.9624 2.0066)
			(end 3.9624 2.0066)
			(stroke
				(width 0.1524)
				(type default)
			)
			(layer "B.SilkS")
		)
		(fp_line
			(start 3.9624 2.0066)
			(end 3.9624 0.5842)
			(stroke
				(width 0.1524)
				(type default)
			)
			(layer "B.SilkS")
		)
		(fp_line
			(start 3.9624 0.5842)
			(end 3.3782 0)
			(stroke
				(width 0.1524)
				(type default)
			)
			(layer "B.SilkS")
		)
		(fp_line
			(start 3.3782 0)
			(end 3.9624 -0.5842)
			(stroke
				(width 0.1524)
				(type default)
			)
			(layer "B.SilkS")
		)
		(fp_line
			(start 3.9624 -0.5842)
			(end 3.9624 -2.0066)
			(stroke
				(width 0.1524)
				(type default)
			)
			(layer "B.SilkS")
		)
		(fp_line
			(start -3.9624 -2.0066)
			(end -3.9624 2.0066)
			(stroke
				(width 0.1524)
				(type default)
			)
			(layer "B.SilkS")
		)
		(fp_line
			(start 3.9624 -2.0066)
			(end -3.9624 -2.0066)
			(stroke
				(width 0.1524)
				(type default)
			)
			(layer "B.SilkS")
		)
		(fp_circle
			(center 3.429 1.524)
			(end 3.429 1.27)
			(stroke
				(width 0.1524)
				(type default)
			)
			(fill no)
			(layer "B.SilkS")
		)
		(fp_poly
			(pts
				(xy 3.962654 3.6703) (xy 3.974846 -3.6703) (xy -3.9624 -3.6703) (xy -3.9624 3.6703)
			)
			(stroke
				(width 0)
				(type default)
			)
			(fill no)
			(layer "B.CrtYd")
		)
		(pad "1" smd rect
			(at 3.57505 2.921 90)
			(size 0.3556 1.4986)
			(layers "B.Cu" "B.Mask" "B.Paste")
			(net "N21701263")
		)
		(pad "2" smd rect
			(at 2.925064 2.921 90)
			(size 0.3556 1.4986)
			(layers "B.Cu" "B.Mask" "B.Paste")
			(net "N21699606")
		)
		(pad "3" smd rect
			(at 2.275078 2.921 90)
			(size 0.3556 1.4986)
			(layers "B.Cu" "B.Mask" "B.Paste")
			(net "N21701261")
		)
		(pad "4" smd rect
			(at 1.625092 2.921 90)
			(size 0.3556 1.4986)
			(layers "B.Cu" "B.Mask" "B.Paste")
			(net "Net_47")
		)
		(pad "5" smd rect
			(at 0.975106 2.921 90)
			(size 0.3556 1.4986)
			(layers "B.Cu" "B.Mask" "B.Paste")
			(net "Net_46")
		)
		(pad "6" smd rect
			(at 0.32512 2.921 90)
			(size 0.3556 1.4986)
			(layers "B.Cu" "B.Mask" "B.Paste")
			(net "Net_45")
		)
		(pad "7" smd rect
			(at -0.32512 2.921 90)
			(size 0.3556 1.4986)
			(layers "B.Cu" "B.Mask" "B.Paste")
			(net "Net_44")
		)
		(pad "8" smd rect
			(at -0.975106 2.921 90)
			(size 0.3556 1.4986)
			(layers "B.Cu" "B.Mask" "B.Paste")
			(net "Net_43")
		)
		(pad "9" smd rect
			(at -1.625092 2.921 90)
			(size 0.3556 1.4986)
			(layers "B.Cu" "B.Mask" "B.Paste")
			(net "Net_42")
		)
		(pad "10" smd rect
			(at -2.275078 2.921 90)
			(size 0.3556 1.4986)
			(layers "B.Cu" "B.Mask" "B.Paste")
			(net "ATTENTION_LED_N")
		)
		(pad "11" smd rect
			(at -2.925064 2.921 90)
			(size 0.3556 1.4986)
			(layers "B.Cu" "B.Mask" "B.Paste")
			(net "CM_STATUS_LED_N")
		)
		(pad "12" smd rect
			(at -3.57505 2.921 90)
			(size 0.3556 1.4986)
			(layers "B.Cu" "B.Mask" "B.Paste")
			(net "GND")
		)
		(pad "13" smd rect
			(at -3.57505 -2.921 90)
			(size 0.3556 1.4986)
			(layers "B.Cu" "B.Mask" "B.Paste")
			(net "TACKOVER_EN_N")
		)
		(pad "14" smd rect
			(at -2.925064 -2.921 90)
			(size 0.3556 1.4986)
			(layers "B.Cu" "B.Mask" "B.Paste")
			(net "PCA_CPLD_WDT2")
		)
		(pad "15" smd rect
			(at -2.275078 -2.921 90)
			(size 0.3556 1.4986)
			(layers "B.Cu" "B.Mask" "B.Paste")
			(net "POWER_SW1_PWR_CTR_N")
		)
		(pad "16" smd rect
			(at -1.625092 -2.921 90)
			(size 0.3556 1.4986)
			(layers "B.Cu" "B.Mask" "B.Paste")
			(net "POWER_SW2_PWR_CTR_N")
		)
		(pad "17" smd rect
			(at -0.975106 -2.921 90)
			(size 0.3556 1.4986)
			(layers "B.Cu" "B.Mask" "B.Paste")
			(net "POWER_SW3_PWR_CTR_N")
		)
		(pad "18" smd rect
			(at -0.32512 -2.921 90)
			(size 0.3556 1.4986)
			(layers "B.Cu" "B.Mask" "B.Paste")
			(net "Net_320")
		)
		(pad "19" smd rect
			(at 0.32512 -2.921 90)
			(size 0.3556 1.4986)
			(layers "B.Cu" "B.Mask" "B.Paste")
			(net "Net_321")
		)
		(pad "20" smd rect
			(at 0.975106 -2.921 90)
			(size 0.3556 1.4986)
			(layers "B.Cu" "B.Mask" "B.Paste")
			(net "Net_2257")
		)
		(pad "21" smd rect
			(at 1.625092 -2.921 90)
			(size 0.3556 1.4986)
			(layers "B.Cu" "B.Mask" "B.Paste")
			(net "N21698979")
		)
		(pad "22" smd rect
			(at 2.275078 -2.921 90)
			(size 0.3556 1.4986)
			(layers "B.Cu" "B.Mask" "B.Paste")
			(net "I2C_COM3_SCL")
		)
		(pad "23" smd rect
			(at 2.925064 -2.921 90)
			(size 0.3556 1.4986)
			(layers "B.Cu" "B.Mask" "B.Paste")
			(net "I2C_COM3_SDA")
		)
		(pad "24" smd rect
			(at 3.57505 -2.921 90)
			(size 0.3556 1.4986)
			(layers "B.Cu" "B.Mask" "B.Paste")
			(net "P3V3_NODE1")
		)
	)
	(footprint ""
		(layer "B.Cu")
		(at 40.685974 -162.317176 90)
		(property "Reference" "TP2"
			(at 0 0 90)
			(layer "B.SilkS")
			(hide yes)
			(effects
				(font
					(size 1.27 1.27)
				)
				(justify mirror)
			)
		)
		(property "Value" ""
			(at 0 0 90)
			(layer "B.Fab")
			(effects
				(font
					(size 1.27 1.27)
				)
				(justify mirror)
			)
		)
		(duplicate_pad_numbers_are_jumpers no)
		(fp_poly
			(pts
				(arc
					(start 0 -0.381)
					(mid 0 0.381)
					(end 0 -0.381)
				)
			)
			(stroke
				(width 0)
				(type default)
			)
			(fill no)
			(layer "B.CrtYd")
		)
		(pad "1" smd circle
			(at 0 0 270)
			(size 0.762 0.762)
			(layers "B.Cu" "B.Mask" "B.Paste")
			(net "N21311592")
		)
	)
	(footprint ""
		(layer "B.Cu")
		(at 133.4516 -46.9646 90)
		(property "Reference" "R1322"
			(at 3.0988 11.42873 270)
			(unlocked yes)
			(layer "B.SilkS")
			(effects
				(font
					(size 0.7874 0.5842)
					(thickness 0.1524)
				)
				(justify left mirror)
			)
		)
		(property "Value" ""
			(at 0 0 90)
			(layer "B.Fab")
			(effects
				(font
					(size 1.27 1.27)
				)
				(justify mirror)
			)
		)
		(duplicate_pad_numbers_are_jumpers no)
		(fp_line
			(start 0.7874 -0.4064)
			(end -0.7874 -0.4064)
			(stroke
				(width 0.1524)
				(type default)
			)
			(layer "B.SilkS")
		)
		(fp_line
			(start -0.7874 -0.4064)
			(end -0.7874 0.4064)
			(stroke
				(width 0.1524)
				(type default)
			)
			(layer "B.SilkS")
		)
		(fp_line
			(start 0.7874 0.4064)
			(end 0.7874 -0.4064)
			(stroke
				(width 0.1524)
				(type default)
			)
			(layer "B.SilkS")
		)
		(fp_line
			(start -0.7874 0.4064)
			(end 0.7874 0.4064)
			(stroke
				(width 0.1524)
				(type default)
			)
			(layer "B.SilkS")
		)
		(fp_poly
			(pts
				(xy 0.508 0.2794) (xy 0.508 0.2286) (xy 0.635 0.2286) (xy 0.635 -0.254) (xy 0.5334 -0.254) (xy 0.5334 -0.2794)
				(xy -0.5334 -0.2794) (xy -0.5334 -0.254) (xy -0.635 -0.254) (xy -0.635 0.254) (xy -0.5334 0.254)
				(xy -0.5334 0.2794)
			)
			(stroke
				(width 0)
				(type default)
			)
			(fill no)
			(layer "B.CrtYd")
		)
		(pad "1" smd rect
			(at -0.40005 0 270)
			(size 0.4572 0.508)
			(layers "B.Cu" "B.Mask" "B.Paste")
			(net "P5V_NODE1")
		)
		(pad "2" smd rect
			(at 0.40005 0 270)
			(size 0.4572 0.508)
			(layers "B.Cu" "B.Mask" "B.Paste")
			(net "UART_DCD_P4_N")
		)
	)
	(footprint ""
		(layer "B.Cu")
		(at 67.298062 -29.394658 -90)
		(property "Reference" "C142"
			(at -2.17805 0.141732 270)
			(unlocked yes)
			(layer "B.SilkS")
			(effects
				(font
					(size 0.7874 0.5842)
					(thickness 0.1524)
				)
				(justify left mirror)
			)
		)
		(property "Value" ""
			(at 0 0 90)
			(layer "B.Fab")
			(effects
				(font
					(size 1.27 1.27)
				)
				(justify mirror)
			)
		)
		(duplicate_pad_numbers_are_jumpers no)
		(fp_line
			(start -0.7874 0.4064)
			(end 0.7874 0.4064)
			(stroke
				(width 0.1524)
				(type default)
			)
			(layer "B.SilkS")
		)
		(fp_line
			(start 0.7874 0.4064)
			(end 0.7874 -0.4064)
			(stroke
				(width 0.1524)
				(type default)
			)
			(layer "B.SilkS")
		)
		(fp_line
			(start 0 0.381)
			(end 0 -0.381)
			(stroke
				(width 0.1524)
				(type default)
			)
			(layer "B.SilkS")
		)
		(fp_line
			(start -0.7874 -0.4064)
			(end -0.7874 0.4064)
			(stroke
				(width 0.1524)
				(type default)
			)
			(layer "B.SilkS")
		)
		(fp_line
			(start 0.7874 -0.4064)
			(end -0.7874 -0.4064)
			(stroke
				(width 0.1524)
				(type default)
			)
			(layer "B.SilkS")
		)
		(fp_poly
			(pts
				(xy 0.5334 0.254) (xy 0.635 0.254) (xy 0.635 0.2286) (xy 0.635 -0.254) (xy 0.5334 -0.254) (xy 0.5334 -0.2794)
				(xy -0.5334 -0.2794) (xy -0.5334 -0.254) (xy -0.635 -0.254) (xy -0.635 0.254) (xy -0.5334 0.254)
				(xy -0.5334 0.2794) (xy 0.508 0.2794) (xy 0.5334 0.2794)
			)
			(stroke
				(width 0)
				(type default)
			)
			(fill no)
			(layer "B.CrtYd")
		)
		(pad "1" smd rect
			(at -0.40005 0 90)
			(size 0.4572 0.508)
			(layers "B.Cu" "B.Mask" "B.Paste")
			(net "P1V5_NODE1_DDR3_VREF_A_A")
		)
		(pad "2" smd rect
			(at 0.40005 0 90)
			(size 0.4572 0.508)
			(layers "B.Cu" "B.Mask" "B.Paste")
			(net "GND")
		)
	)
	(footprint ""
		(layer "B.Cu")
		(at 100.696014 -171.758102)
		(property "Reference" "R778"
			(at 7.24916 0.977646 0)
			(unlocked yes)
			(layer "B.SilkS")
			(effects
				(font
					(size 0.7874 0.5842)
					(thickness 0.1524)
				)
				(justify left mirror)
			)
		)
		(property "Value" ""
			(at 0 0 0)
			(layer "B.Fab")
			(effects
				(font
					(size 1.27 1.27)
				)
				(justify mirror)
			)
		)
		(duplicate_pad_numbers_are_jumpers no)
		(fp_line
			(start -0.7874 -0.4064)
			(end -0.7874 0.4064)
			(stroke
				(width 0.1524)
				(type default)
			)
			(layer "B.SilkS")
		)
		(fp_line
			(start -0.7874 0.4064)
			(end 0.7874 0.4064)
			(stroke
				(width 0.1524)
				(type default)
			)
			(layer "B.SilkS")
		)
		(fp_line
			(start 0.7874 -0.4064)
			(end -0.7874 -0.4064)
			(stroke
				(width 0.1524)
				(type default)
			)
			(layer "B.SilkS")
		)
		(fp_line
			(start 0.7874 0.4064)
			(end 0.7874 -0.4064)
			(stroke
				(width 0.1524)
				(type default)
			)
			(layer "B.SilkS")
		)
		(fp_poly
			(pts
				(xy 0.508 0.2794) (xy 0.508 0.2286) (xy 0.635 0.2286) (xy 0.635 -0.254) (xy 0.5334 -0.254) (xy 0.5334 -0.2794)
				(xy -0.5334 -0.2794) (xy -0.5334 -0.254) (xy -0.635 -0.254) (xy -0.635 0.254) (xy -0.5334 0.254)
				(xy -0.5334 0.2794)
			)
			(stroke
				(width 0)
				(type default)
			)
			(fill no)
			(layer "B.CrtYd")
		)
		(pad "1" smd rect
			(at -0.40005 0 180)
			(size 0.4572 0.508)
			(layers "B.Cu" "B.Mask" "B.Paste")
			(net "P3V3_NODE1")
		)
		(pad "2" smd rect
			(at 0.40005 0 180)
			(size 0.4572 0.508)
			(layers "B.Cu" "B.Mask" "B.Paste")
			(net "FAN_PWM")
		)
	)
	(footprint ""
		(layer "B.Cu")
		(at 127.60706 -160.840166 180)
		(property "Reference" "U143"
			(at 1.017524 -3.659886 0)
			(unlocked yes)
			(layer "B.SilkS")
			(effects
				(font
					(size 0.7874 0.5842)
					(thickness 0.1524)
				)
				(justify mirror)
			)
		)
		(property "Value" ""
			(at 0 0 0)
			(layer "B.Fab")
			(effects
				(font
					(size 1.27 1.27)
				)
				(justify mirror)
			)
		)
		(duplicate_pad_numbers_are_jumpers no)
		(fp_line
			(start 1.651 1.905)
			(end 1.651 -1.905)
			(stroke
				(width 0.1524)
				(type default)
			)
			(layer "B.SilkS")
		)
		(fp_line
			(start 1.651 -1.905)
			(end -1.651 -1.905)
			(stroke
				(width 0.1524)
				(type default)
			)
			(layer "B.SilkS")
		)
		(fp_line
			(start -1.651 1.905)
			(end 1.651 1.905)
			(stroke
				(width 0.1524)
				(type default)
			)
			(layer "B.SilkS")
		)
		(fp_line
			(start -1.651 -1.905)
			(end -1.651 1.905)
			(stroke
				(width 0.1524)
				(type default)
			)
			(layer "B.SilkS")
		)
		(fp_poly
			(pts
				(xy 1.524 0.7112) (xy 1.524 1.7526) (xy 0.508 1.7526) (xy 0.508 0.6985) (xy -0.508 0.6985) (xy -0.508 1.7526)
				(xy -1.524 1.7526) (xy -1.524 0.6985) (xy -1.524 -0.6985) (xy -0.508 -0.6985) (xy -0.508 -1.7526)
				(xy 0.508 -1.7526) (xy 0.508 -0.6985) (xy 1.524 -0.6985) (xy 1.524 0.6985)
			)
			(stroke
				(width 0)
				(type default)
			)
			(fill no)
			(layer "B.CrtYd")
		)
		(fp_text user "G"
			(at 2.211832 1.385316 0)
			(unlocked yes)
			(layer "B.SilkS")
			(effects
				(font
					(size 0.635 0.4064)
					(thickness 0.1524)
				)
				(justify mirror)
			)
		)
		(fp_text user "D"
			(at -0.79756 -2.563622 0)
			(unlocked yes)
			(layer "B.SilkS")
			(effects
				(font
					(size 0.635 0.4064)
					(thickness 0.1524)
				)
				(justify mirror)
			)
		)
		(fp_text user "S"
			(at -2.055622 2.10185 0)
			(unlocked yes)
			(layer "B.SilkS")
			(effects
				(font
					(size 0.635 0.4064)
					(thickness 0.1524)
				)
				(justify mirror)
			)
		)
		(pad "D" smd rect
			(at 0 -1.1176)
			(size 1.016 1.27)
			(layers "B.Cu" "B.Mask" "B.Paste")
			(net "UART_RI_P6_N")
		)
		(pad "G" smd rect
			(at 1.016 1.1176)
			(size 1.016 1.27)
			(layers "B.Cu" "B.Mask" "B.Paste")
			(net "TACKOVER_EN")
		)
		(pad "S" smd rect
			(at -1.016 1.1176)
			(size 1.016 1.27)
			(layers "B.Cu" "B.Mask" "B.Paste")
			(net "UART_RI_P6_LS_N")
		)
	)
	(footprint ""
		(layer "B.Cu")
		(at 80.6831 -82.902044)
		(property "Reference" "R169"
			(at 3.9878 0.486156 0)
			(unlocked yes)
			(layer "B.SilkS")
			(effects
				(font
					(size 0.7874 0.5842)
					(thickness 0.1524)
				)
				(justify left mirror)
			)
		)
		(property "Value" ""
			(at 0 0 0)
			(layer "B.Fab")
			(effects
				(font
					(size 1.27 1.27)
				)
				(justify mirror)
			)
		)
		(duplicate_pad_numbers_are_jumpers no)
		(fp_line
			(start -0.7874 -0.4064)
			(end -0.7874 0.4064)
			(stroke
				(width 0.1524)
				(type default)
			)
			(layer "B.SilkS")
		)
		(fp_line
			(start -0.7874 0.4064)
			(end 0.7874 0.4064)
			(stroke
				(width 0.1524)
				(type default)
			)
			(layer "B.SilkS")
		)
		(fp_line
			(start 0.7874 -0.4064)
			(end -0.7874 -0.4064)
			(stroke
				(width 0.1524)
				(type default)
			)
			(layer "B.SilkS")
		)
		(fp_line
			(start 0.7874 0.4064)
			(end 0.7874 -0.4064)
			(stroke
				(width 0.1524)
				(type default)
			)
			(layer "B.SilkS")
		)
		(fp_poly
			(pts
				(xy 0.508 0.2794) (xy 0.508 0.2286) (xy 0.635 0.2286) (xy 0.635 -0.254) (xy 0.5334 -0.254) (xy 0.5334 -0.2794)
				(xy -0.5334 -0.2794) (xy -0.5334 -0.254) (xy -0.635 -0.254) (xy -0.635 0.254) (xy -0.5334 0.254)
				(xy -0.5334 0.2794)
			)
			(stroke
				(width 0)
				(type default)
			)
			(fill no)
			(layer "B.CrtYd")
		)
		(pad "1" smd rect
			(at -0.40005 0 180)
			(size 0.4572 0.508)
			(layers "B.Cu" "B.Mask" "B.Paste")
			(net "LPC_CPU_NODE1_CLK0_DS")
		)
		(pad "2" smd rect
			(at 0.40005 0 180)
			(size 0.4572 0.508)
			(layers "B.Cu" "B.Mask" "B.Paste")
			(net "P3V3_NODE1")
		)
	)
	(footprint ""
		(layer "B.Cu")
		(at 54.022498 -96.696784 -90)
		(property "Reference" "R81"
			(at -6.405118 4.421124 270)
			(unlocked yes)
			(layer "B.SilkS")
			(effects
				(font
					(size 0.7874 0.5842)
					(thickness 0.1524)
				)
				(justify left mirror)
			)
		)
		(property "Value" ""
			(at 0 0 90)
			(layer "B.Fab")
			(effects
				(font
					(size 1.27 1.27)
				)
				(justify mirror)
			)
		)
		(duplicate_pad_numbers_are_jumpers no)
		(fp_line
			(start -0.7874 0.4064)
			(end 0.7874 0.4064)
			(stroke
				(width 0.1524)
				(type default)
			)
			(layer "B.SilkS")
		)
		(fp_line
			(start 0.7874 0.4064)
			(end 0.7874 -0.4064)
			(stroke
				(width 0.1524)
				(type default)
			)
			(layer "B.SilkS")
		)
		(fp_line
			(start -0.7874 -0.4064)
			(end -0.7874 0.4064)
			(stroke
				(width 0.1524)
				(type default)
			)
			(layer "B.SilkS")
		)
		(fp_line
			(start 0.7874 -0.4064)
			(end -0.7874 -0.4064)
			(stroke
				(width 0.1524)
				(type default)
			)
			(layer "B.SilkS")
		)
		(fp_poly
			(pts
				(xy 0.508 0.2794) (xy 0.508 0.2286) (xy 0.635 0.2286) (xy 0.635 -0.254) (xy 0.5334 -0.254) (xy 0.5334 -0.2794)
				(xy -0.5334 -0.2794) (xy -0.5334 -0.254) (xy -0.635 -0.254) (xy -0.635 0.254) (xy -0.5334 0.254)
				(xy -0.5334 0.2794)
			)
			(stroke
				(width 0)
				(type default)
			)
			(fill no)
			(layer "B.CrtYd")
		)
		(pad "1" smd rect
			(at -0.40005 0 90)
			(size 0.4572 0.508)
			(layers "B.Cu" "B.Mask" "B.Paste")
			(net "GND")
		)
		(pad "2" smd rect
			(at 0.40005 0 90)
			(size 0.4572 0.508)
			(layers "B.Cu" "B.Mask" "B.Paste")
			(net "PD_CPU_NODE1_DFX_GPIO_GRP0_4")
		)
	)
	(footprint ""
		(layer "B.Cu")
		(at 135.196834 -41.439084 180)
		(property "Reference" "R1192"
			(at 5.415788 -19.031966 0)
			(unlocked yes)
			(layer "B.SilkS")
			(effects
				(font
					(size 0.7874 0.5842)
					(thickness 0.1524)
				)
				(justify left mirror)
			)
		)
		(property "Value" ""
			(at 0 0 0)
			(layer "B.Fab")
			(effects
				(font
					(size 1.27 1.27)
				)
				(justify mirror)
			)
		)
		(duplicate_pad_numbers_are_jumpers no)
		(fp_line
			(start 0.7874 0.4064)
			(end 0.7874 -0.4064)
			(stroke
				(width 0.1524)
				(type default)
			)
			(layer "B.SilkS")
		)
		(fp_line
			(start 0.7874 -0.4064)
			(end -0.7874 -0.4064)
			(stroke
				(width 0.1524)
				(type default)
			)
			(layer "B.SilkS")
		)
		(fp_line
			(start -0.7874 0.4064)
			(end 0.7874 0.4064)
			(stroke
				(width 0.1524)
				(type default)
			)
			(layer "B.SilkS")
		)
		(fp_line
			(start -0.7874 -0.4064)
			(end -0.7874 0.4064)
			(stroke
				(width 0.1524)
				(type default)
			)
			(layer "B.SilkS")
		)
		(fp_poly
			(pts
				(xy 0.508 0.2794) (xy 0.508 0.2286) (xy 0.635 0.2286) (xy 0.635 -0.254) (xy 0.5334 -0.254) (xy 0.5334 -0.2794)
				(xy -0.5334 -0.2794) (xy -0.5334 -0.254) (xy -0.635 -0.254) (xy -0.635 0.254) (xy -0.5334 0.254)
				(xy -0.5334 0.2794)
			)
			(stroke
				(width 0)
				(type default)
			)
			(fill no)
			(layer "B.CrtYd")
		)
		(pad "1" smd rect
			(at -0.40005 0)
			(size 0.4572 0.508)
			(layers "B.Cu" "B.Mask" "B.Paste")
			(net "SIO_JTAG_CPLD2_TCK")
		)
		(pad "2" smd rect
			(at 0.40005 0)
			(size 0.4572 0.508)
			(layers "B.Cu" "B.Mask" "B.Paste")
			(net "GND")
		)
	)
	(footprint ""
		(layer "B.Cu")
		(at 43.00982 -150.22449 90)
		(property "Reference" "C419"
			(at 7.986014 -11.738102 270)
			(unlocked yes)
			(layer "B.SilkS")
			(effects
				(font
					(size 0.7874 0.5842)
					(thickness 0.1524)
				)
				(justify left mirror)
			)
		)
		(property "Value" ""
			(at 0 0 90)
			(layer "B.Fab")
			(effects
				(font
					(size 1.27 1.27)
				)
				(justify mirror)
			)
		)
		(duplicate_pad_numbers_are_jumpers no)
		(fp_line
			(start 0.7874 -0.4064)
			(end -0.7874 -0.4064)
			(stroke
				(width 0.1524)
				(type default)
			)
			(layer "B.SilkS")
		)
		(fp_line
			(start -0.7874 -0.4064)
			(end -0.7874 0.4064)
			(stroke
				(width 0.1524)
				(type default)
			)
			(layer "B.SilkS")
		)
		(fp_line
			(start 0 0.381)
			(end 0 -0.381)
			(stroke
				(width 0.1524)
				(type default)
			)
			(layer "B.SilkS")
		)
		(fp_line
			(start 0.7874 0.4064)
			(end 0.7874 -0.4064)
			(stroke
				(width 0.1524)
				(type default)
			)
			(layer "B.SilkS")
		)
		(fp_line
			(start -0.7874 0.4064)
			(end 0.7874 0.4064)
			(stroke
				(width 0.1524)
				(type default)
			)
			(layer "B.SilkS")
		)
		(fp_poly
			(pts
				(xy 0.5334 0.254) (xy 0.635 0.254) (xy 0.635 0.2286) (xy 0.635 -0.254) (xy 0.5334 -0.254) (xy 0.5334 -0.2794)
				(xy -0.5334 -0.2794) (xy -0.5334 -0.254) (xy -0.635 -0.254) (xy -0.635 0.254) (xy -0.5334 0.254)
				(xy -0.5334 0.2794) (xy 0.508 0.2794) (xy 0.5334 0.2794)
			)
			(stroke
				(width 0)
				(type default)
			)
			(fill no)
			(layer "B.CrtYd")
		)
		(pad "1" smd rect
			(at -0.40005 0 270)
			(size 0.4572 0.508)
			(layers "B.Cu" "B.Mask" "B.Paste")
			(net "P1V05_LAN1")
		)
		(pad "2" smd rect
			(at 0.40005 0 270)
			(size 0.4572 0.508)
			(layers "B.Cu" "B.Mask" "B.Paste")
			(net "GND")
		)
	)
	(footprint ""
		(layer "B.Cu")
		(at 40.376602 -152.636982)
		(property "Reference" "C402"
			(at -6.359652 -10.195814 0)
			(unlocked yes)
			(layer "B.SilkS")
			(effects
				(font
					(size 0.7874 0.5842)
					(thickness 0.1524)
				)
				(justify left mirror)
			)
		)
		(property "Value" ""
			(at 0 0 0)
			(layer "B.Fab")
			(effects
				(font
					(size 1.27 1.27)
				)
				(justify mirror)
			)
		)
		(duplicate_pad_numbers_are_jumpers no)
		(fp_line
			(start -0.7874 -0.4064)
			(end -0.7874 0.4064)
			(stroke
				(width 0.1524)
				(type default)
			)
			(layer "B.SilkS")
		)
		(fp_line
			(start -0.7874 0.4064)
			(end 0.7874 0.4064)
			(stroke
				(width 0.1524)
				(type default)
			)
			(layer "B.SilkS")
		)
		(fp_line
			(start 0 0.381)
			(end 0 -0.381)
			(stroke
				(width 0.1524)
				(type default)
			)
			(layer "B.SilkS")
		)
		(fp_line
			(start 0.7874 -0.4064)
			(end -0.7874 -0.4064)
			(stroke
				(width 0.1524)
				(type default)
			)
			(layer "B.SilkS")
		)
		(fp_line
			(start 0.7874 0.4064)
			(end 0.7874 -0.4064)
			(stroke
				(width 0.1524)
				(type default)
			)
			(layer "B.SilkS")
		)
		(fp_poly
			(pts
				(xy 0.5334 0.254) (xy 0.635 0.254) (xy 0.635 0.2286) (xy 0.635 -0.254) (xy 0.5334 -0.254) (xy 0.5334 -0.2794)
				(xy -0.5334 -0.2794) (xy -0.5334 -0.254) (xy -0.635 -0.254) (xy -0.635 0.254) (xy -0.5334 0.254)
				(xy -0.5334 0.2794) (xy 0.508 0.2794) (xy 0.5334 0.2794)
			)
			(stroke
				(width 0)
				(type default)
			)
			(fill no)
			(layer "B.CrtYd")
		)
		(pad "1" smd rect
			(at -0.40005 0 180)
			(size 0.4572 0.508)
			(layers "B.Cu" "B.Mask" "B.Paste")
			(net "P1V9_LAN1")
		)
		(pad "2" smd rect
			(at 0.40005 0 180)
			(size 0.4572 0.508)
			(layers "B.Cu" "B.Mask" "B.Paste")
			(net "GND")
		)
	)
	(footprint ""
		(layer "B.Cu")
		(at 150.47976 -184.951624 -90)
		(property "Reference" "C720"
			(at -4.357624 3.18516 270)
			(unlocked yes)
			(layer "B.SilkS")
			(effects
				(font
					(size 0.7874 0.5842)
					(thickness 0.1524)
				)
				(justify left mirror)
			)
		)
		(property "Value" ""
			(at 0 0 90)
			(layer "B.Fab")
			(effects
				(font
					(size 1.27 1.27)
				)
				(justify mirror)
			)
		)
		(duplicate_pad_numbers_are_jumpers no)
		(fp_line
			(start -0.7874 0.4064)
			(end 0.7874 0.4064)
			(stroke
				(width 0.1524)
				(type default)
			)
			(layer "B.SilkS")
		)
		(fp_line
			(start 0.7874 0.4064)
			(end 0.7874 -0.4064)
			(stroke
				(width 0.1524)
				(type default)
			)
			(layer "B.SilkS")
		)
		(fp_line
			(start 0 0.381)
			(end 0 -0.381)
			(stroke
				(width 0.1524)
				(type default)
			)
			(layer "B.SilkS")
		)
		(fp_line
			(start -0.7874 -0.4064)
			(end -0.7874 0.4064)
			(stroke
				(width 0.1524)
				(type default)
			)
			(layer "B.SilkS")
		)
		(fp_line
			(start 0.7874 -0.4064)
			(end -0.7874 -0.4064)
			(stroke
				(width 0.1524)
				(type default)
			)
			(layer "B.SilkS")
		)
		(fp_poly
			(pts
				(xy 0.5334 0.254) (xy 0.635 0.254) (xy 0.635 0.2286) (xy 0.635 -0.254) (xy 0.5334 -0.254) (xy 0.5334 -0.2794)
				(xy -0.5334 -0.2794) (xy -0.5334 -0.254) (xy -0.635 -0.254) (xy -0.635 0.254) (xy -0.5334 0.254)
				(xy -0.5334 0.2794) (xy 0.508 0.2794) (xy 0.5334 0.2794)
			)
			(stroke
				(width 0)
				(type default)
			)
			(fill no)
			(layer "B.CrtYd")
		)
		(pad "1" smd rect
			(at -0.40005 0 90)
			(size 0.4572 0.508)
			(layers "B.Cu" "B.Mask" "B.Paste")
			(net "UART_T11_NODE1_RXD")
		)
		(pad "2" smd rect
			(at 0.40005 0 90)
			(size 0.4572 0.508)
			(layers "B.Cu" "B.Mask" "B.Paste")
			(net "GND")
		)
	)
	(footprint ""
		(layer "B.Cu")
		(at 40.376602 -155.176982)
		(property "Reference" "C403"
			(at -6.396482 -9.777984 0)
			(unlocked yes)
			(layer "B.SilkS")
			(effects
				(font
					(size 0.7874 0.5842)
					(thickness 0.1524)
				)
				(justify left mirror)
			)
		)
		(property "Value" ""
			(at 0 0 0)
			(layer "B.Fab")
			(effects
				(font
					(size 1.27 1.27)
				)
				(justify mirror)
			)
		)
		(duplicate_pad_numbers_are_jumpers no)
		(fp_line
			(start -0.7874 -0.4064)
			(end -0.7874 0.4064)
			(stroke
				(width 0.1524)
				(type default)
			)
			(layer "B.SilkS")
		)
		(fp_line
			(start -0.7874 0.4064)
			(end 0.7874 0.4064)
			(stroke
				(width 0.1524)
				(type default)
			)
			(layer "B.SilkS")
		)
		(fp_line
			(start 0 0.381)
			(end 0 -0.381)
			(stroke
				(width 0.1524)
				(type default)
			)
			(layer "B.SilkS")
		)
		(fp_line
			(start 0.7874 -0.4064)
			(end -0.7874 -0.4064)
			(stroke
				(width 0.1524)
				(type default)
			)
			(layer "B.SilkS")
		)
		(fp_line
			(start 0.7874 0.4064)
			(end 0.7874 -0.4064)
			(stroke
				(width 0.1524)
				(type default)
			)
			(layer "B.SilkS")
		)
		(fp_poly
			(pts
				(xy 0.5334 0.254) (xy 0.635 0.254) (xy 0.635 0.2286) (xy 0.635 -0.254) (xy 0.5334 -0.254) (xy 0.5334 -0.2794)
				(xy -0.5334 -0.2794) (xy -0.5334 -0.254) (xy -0.635 -0.254) (xy -0.635 0.254) (xy -0.5334 0.254)
				(xy -0.5334 0.2794) (xy 0.508 0.2794) (xy 0.5334 0.2794)
			)
			(stroke
				(width 0)
				(type default)
			)
			(fill no)
			(layer "B.CrtYd")
		)
		(pad "1" smd rect
			(at -0.40005 0 180)
			(size 0.4572 0.508)
			(layers "B.Cu" "B.Mask" "B.Paste")
			(net "P1V9_LAN1")
		)
		(pad "2" smd rect
			(at 0.40005 0 180)
			(size 0.4572 0.508)
			(layers "B.Cu" "B.Mask" "B.Paste")
			(net "GND")
		)
	)
	(footprint ""
		(layer "B.Cu")
		(at 78.83144 -175.553624 180)
		(property "Reference" "R694"
			(at -30.562296 -20.108164 0)
			(unlocked yes)
			(layer "B.SilkS")
			(effects
				(font
					(size 0.7874 0.5842)
					(thickness 0.1524)
				)
				(justify left mirror)
			)
		)
		(property "Value" ""
			(at 0 0 0)
			(layer "B.Fab")
			(effects
				(font
					(size 1.27 1.27)
				)
				(justify mirror)
			)
		)
		(duplicate_pad_numbers_are_jumpers no)
		(fp_line
			(start 0.7874 0.4064)
			(end 0.7874 -0.4064)
			(stroke
				(width 0.1524)
				(type default)
			)
			(layer "B.SilkS")
		)
		(fp_line
			(start 0.7874 -0.4064)
			(end -0.7874 -0.4064)
			(stroke
				(width 0.1524)
				(type default)
			)
			(layer "B.SilkS")
		)
		(fp_line
			(start -0.7874 0.4064)
			(end 0.7874 0.4064)
			(stroke
				(width 0.1524)
				(type default)
			)
			(layer "B.SilkS")
		)
		(fp_line
			(start -0.7874 -0.4064)
			(end -0.7874 0.4064)
			(stroke
				(width 0.1524)
				(type default)
			)
			(layer "B.SilkS")
		)
		(fp_poly
			(pts
				(xy 0.508 0.2794) (xy 0.508 0.2286) (xy 0.635 0.2286) (xy 0.635 -0.254) (xy 0.5334 -0.254) (xy 0.5334 -0.2794)
				(xy -0.5334 -0.2794) (xy -0.5334 -0.254) (xy -0.635 -0.254) (xy -0.635 0.254) (xy -0.5334 0.254)
				(xy -0.5334 0.2794)
			)
			(stroke
				(width 0)
				(type default)
			)
			(fill no)
			(layer "B.CrtYd")
		)
		(pad "1" smd rect
			(at -0.40005 0)
			(size 0.4572 0.508)
			(layers "B.Cu" "B.Mask" "B.Paste")
			(net "T2_NODE2_EN")
		)
		(pad "2" smd rect
			(at 0.40005 0)
			(size 0.4572 0.508)
			(layers "B.Cu" "B.Mask" "B.Paste")
			(net "P5V_NODE1")
		)
	)
	(footprint ""
		(layer "B.Cu")
		(at 59.636406 -72.479154 90)
		(property "Reference" "C128"
			(at -33.578292 -14.517116 270)
			(unlocked yes)
			(layer "B.SilkS")
			(effects
				(font
					(size 0.7874 0.5842)
					(thickness 0.1524)
				)
				(justify left mirror)
			)
		)
		(property "Value" ""
			(at 0 0 90)
			(layer "B.Fab")
			(effects
				(font
					(size 1.27 1.27)
				)
				(justify mirror)
			)
		)
		(duplicate_pad_numbers_are_jumpers no)
		(fp_line
			(start 0.7874 -0.4064)
			(end -0.7874 -0.4064)
			(stroke
				(width 0.1524)
				(type default)
			)
			(layer "B.SilkS")
		)
		(fp_line
			(start -0.7874 -0.4064)
			(end -0.7874 0.4064)
			(stroke
				(width 0.1524)
				(type default)
			)
			(layer "B.SilkS")
		)
		(fp_line
			(start 0 0.381)
			(end 0 -0.381)
			(stroke
				(width 0.1524)
				(type default)
			)
			(layer "B.SilkS")
		)
		(fp_line
			(start 0.7874 0.4064)
			(end 0.7874 -0.4064)
			(stroke
				(width 0.1524)
				(type default)
			)
			(layer "B.SilkS")
		)
		(fp_line
			(start -0.7874 0.4064)
			(end 0.7874 0.4064)
			(stroke
				(width 0.1524)
				(type default)
			)
			(layer "B.SilkS")
		)
		(fp_poly
			(pts
				(xy 0.5334 0.254) (xy 0.635 0.254) (xy 0.635 0.2286) (xy 0.635 -0.254) (xy 0.5334 -0.254) (xy 0.5334 -0.2794)
				(xy -0.5334 -0.2794) (xy -0.5334 -0.254) (xy -0.635 -0.254) (xy -0.635 0.254) (xy -0.5334 0.254)
				(xy -0.5334 0.2794) (xy 0.508 0.2794) (xy 0.5334 0.2794)
			)
			(stroke
				(width 0)
				(type default)
			)
			(fill no)
			(layer "B.CrtYd")
		)
		(pad "1" smd rect
			(at -0.40005 0 270)
			(size 0.4572 0.508)
			(layers "B.Cu" "B.Mask" "B.Paste")
			(net "P1V05_NODE1")
		)
		(pad "2" smd rect
			(at 0.40005 0 270)
			(size 0.4572 0.508)
			(layers "B.Cu" "B.Mask" "B.Paste")
			(net "GND")
		)
	)
	(footprint ""
		(layer "B.Cu")
		(at 56.392572 -71.751698 -90)
		(property "Reference" "L7"
			(at 31.697168 14.069822 270)
			(unlocked yes)
			(layer "B.SilkS")
			(effects
				(font
					(size 0.7874 0.5842)
					(thickness 0.1524)
				)
				(justify left mirror)
			)
		)
		(property "Value" ""
			(at 0 0 90)
			(layer "B.Fab")
			(effects
				(font
					(size 1.27 1.27)
				)
				(justify mirror)
			)
		)
		(duplicate_pad_numbers_are_jumpers no)
		(fp_line
			(start -0.7874 0.4064)
			(end 0.7874 0.4064)
			(stroke
				(width 0.1524)
				(type default)
			)
			(layer "B.SilkS")
		)
		(fp_line
			(start -0.0889 0.4064)
			(end -0.0889 -0.4064)
			(stroke
				(width 0.1524)
				(type default)
			)
			(layer "B.SilkS")
		)
		(fp_line
			(start 0.0889 0.4064)
			(end 0.0889 -0.4064)
			(stroke
				(width 0.1524)
				(type default)
			)
			(layer "B.SilkS")
		)
		(fp_line
			(start 0.7874 0.4064)
			(end 0.7874 -0.4064)
			(stroke
				(width 0.1524)
				(type default)
			)
			(layer "B.SilkS")
		)
		(fp_line
			(start -0.7874 -0.4064)
			(end -0.7874 0.4064)
			(stroke
				(width 0.1524)
				(type default)
			)
			(layer "B.SilkS")
		)
		(fp_line
			(start 0.7874 -0.4064)
			(end -0.7874 -0.4064)
			(stroke
				(width 0.1524)
				(type default)
			)
			(layer "B.SilkS")
		)
		(fp_poly
			(pts
				(xy 0.5334 0.254) (xy 0.635 0.254) (xy 0.635 0.2286) (xy 0.635 -0.254) (xy 0.5334 -0.254) (xy 0.5334 -0.2794)
				(xy -0.5334 -0.2794) (xy -0.5334 -0.254) (xy -0.635 -0.254) (xy -0.635 0.254) (xy -0.5334 0.254)
				(xy -0.5334 0.2794) (xy 0.508 0.2794) (xy 0.5334 0.2794)
			)
			(stroke
				(width 0)
				(type default)
			)
			(fill no)
			(layer "B.CrtYd")
		)
		(pad "1" smd rect
			(at -0.40005 0 90)
			(size 0.4572 0.508)
			(layers "B.Cu" "B.Mask" "B.Paste")
			(net "P1V05_NODE1")
		)
		(pad "2" smd rect
			(at 0.40005 0 90)
			(size 0.4572 0.508)
			(layers "B.Cu" "B.Mask" "B.Paste")
			(net "P1V05_VCCACLK_DDR3_NODE1")
		)
	)
	(footprint ""
		(layer "B.Cu")
		(at 129.918968 -166.371778)
		(property "Reference" "R1000"
			(at -1.988312 -0.457454 0)
			(unlocked yes)
			(layer "B.SilkS")
			(effects
				(font
					(size 0.7874 0.5842)
					(thickness 0.1524)
				)
				(justify left mirror)
			)
		)
		(property "Value" ""
			(at 0 0 0)
			(layer "B.Fab")
			(effects
				(font
					(size 1.27 1.27)
				)
				(justify mirror)
			)
		)
		(duplicate_pad_numbers_are_jumpers no)
		(fp_line
			(start -0.7874 -0.4064)
			(end -0.7874 0.4064)
			(stroke
				(width 0.1524)
				(type default)
			)
			(layer "B.SilkS")
		)
		(fp_line
			(start -0.7874 0.4064)
			(end 0.7874 0.4064)
			(stroke
				(width 0.1524)
				(type default)
			)
			(layer "B.SilkS")
		)
		(fp_line
			(start 0.7874 -0.4064)
			(end -0.7874 -0.4064)
			(stroke
				(width 0.1524)
				(type default)
			)
			(layer "B.SilkS")
		)
		(fp_line
			(start 0.7874 0.4064)
			(end 0.7874 -0.4064)
			(stroke
				(width 0.1524)
				(type default)
			)
			(layer "B.SilkS")
		)
		(fp_poly
			(pts
				(xy 0.508 0.2794) (xy 0.508 0.2286) (xy 0.635 0.2286) (xy 0.635 -0.254) (xy 0.5334 -0.254) (xy 0.5334 -0.2794)
				(xy -0.5334 -0.2794) (xy -0.5334 -0.254) (xy -0.635 -0.254) (xy -0.635 0.254) (xy -0.5334 0.254)
				(xy -0.5334 0.2794)
			)
			(stroke
				(width 0)
				(type default)
			)
			(fill no)
			(layer "B.CrtYd")
		)
		(pad "1" smd rect
			(at -0.40005 0 180)
			(size 0.4572 0.508)
			(layers "B.Cu" "B.Mask" "B.Paste")
			(net "UART_T8_NODE4_TXD")
		)
		(pad "2" smd rect
			(at 0.40005 0 180)
			(size 0.4572 0.508)
			(layers "B.Cu" "B.Mask" "B.Paste")
			(net "UART_T8_NODE4_TXD_R")
		)
	)
	(footprint ""
		(layer "B.Cu")
		(at 60.057538 -81.309718)
		(property "Reference" "C41"
			(at -13.557758 30.810454 0)
			(unlocked yes)
			(layer "B.SilkS")
			(effects
				(font
					(size 0.7874 0.5842)
					(thickness 0.1524)
				)
				(justify left mirror)
			)
		)
		(property "Value" ""
			(at 0 0 0)
			(layer "B.Fab")
			(effects
				(font
					(size 1.27 1.27)
				)
				(justify mirror)
			)
		)
		(duplicate_pad_numbers_are_jumpers no)
		(fp_line
			(start -0.7874 -0.4064)
			(end -0.7874 0.4064)
			(stroke
				(width 0.1524)
				(type default)
			)
			(layer "B.SilkS")
		)
		(fp_line
			(start -0.7874 0.4064)
			(end 0.7874 0.4064)
			(stroke
				(width 0.1524)
				(type default)
			)
			(layer "B.SilkS")
		)
		(fp_line
			(start 0 0.381)
			(end 0 -0.381)
			(stroke
				(width 0.1524)
				(type default)
			)
			(layer "B.SilkS")
		)
		(fp_line
			(start 0.7874 -0.4064)
			(end -0.7874 -0.4064)
			(stroke
				(width 0.1524)
				(type default)
			)
			(layer "B.SilkS")
		)
		(fp_line
			(start 0.7874 0.4064)
			(end 0.7874 -0.4064)
			(stroke
				(width 0.1524)
				(type default)
			)
			(layer "B.SilkS")
		)
		(fp_poly
			(pts
				(xy 0.5334 0.254) (xy 0.635 0.254) (xy 0.635 0.2286) (xy 0.635 -0.254) (xy 0.5334 -0.254) (xy 0.5334 -0.2794)
				(xy -0.5334 -0.2794) (xy -0.5334 -0.254) (xy -0.635 -0.254) (xy -0.635 0.254) (xy -0.5334 0.254)
				(xy -0.5334 0.2794) (xy 0.508 0.2794) (xy 0.5334 0.2794)
			)
			(stroke
				(width 0)
				(type default)
			)
			(fill no)
			(layer "B.CrtYd")
		)
		(pad "1" smd rect
			(at -0.40005 0 180)
			(size 0.4572 0.508)
			(layers "B.Cu" "B.Mask" "B.Paste")
			(net "P3V3_NODE1")
		)
		(pad "2" smd rect
			(at 0.40005 0 180)
			(size 0.4572 0.508)
			(layers "B.Cu" "B.Mask" "B.Paste")
			(net "GND")
		)
	)
	(footprint ""
		(layer "B.Cu")
		(at 48.75022 -154.39009 180)
		(property "Reference" "C410"
			(at 11.81354 5.305806 0)
			(unlocked yes)
			(layer "B.SilkS")
			(effects
				(font
					(size 0.7874 0.5842)
					(thickness 0.1524)
				)
				(justify left mirror)
			)
		)
		(property "Value" ""
			(at 0 0 0)
			(layer "B.Fab")
			(effects
				(font
					(size 1.27 1.27)
				)
				(justify mirror)
			)
		)
		(duplicate_pad_numbers_are_jumpers no)
		(fp_line
			(start 0.7874 0.4064)
			(end 0.7874 -0.4064)
			(stroke
				(width 0.1524)
				(type default)
			)
			(layer "B.SilkS")
		)
		(fp_line
			(start 0.7874 -0.4064)
			(end -0.7874 -0.4064)
			(stroke
				(width 0.1524)
				(type default)
			)
			(layer "B.SilkS")
		)
		(fp_line
			(start 0 0.381)
			(end 0 -0.381)
			(stroke
				(width 0.1524)
				(type default)
			)
			(layer "B.SilkS")
		)
		(fp_line
			(start -0.7874 0.4064)
			(end 0.7874 0.4064)
			(stroke
				(width 0.1524)
				(type default)
			)
			(layer "B.SilkS")
		)
		(fp_line
			(start -0.7874 -0.4064)
			(end -0.7874 0.4064)
			(stroke
				(width 0.1524)
				(type default)
			)
			(layer "B.SilkS")
		)
		(fp_poly
			(pts
				(xy 0.5334 0.254) (xy 0.635 0.254) (xy 0.635 0.2286) (xy 0.635 -0.254) (xy 0.5334 -0.254) (xy 0.5334 -0.2794)
				(xy -0.5334 -0.2794) (xy -0.5334 -0.254) (xy -0.635 -0.254) (xy -0.635 0.254) (xy -0.5334 0.254)
				(xy -0.5334 0.2794) (xy 0.508 0.2794) (xy 0.5334 0.2794)
			)
			(stroke
				(width 0)
				(type default)
			)
			(fill no)
			(layer "B.CrtYd")
		)
		(pad "1" smd rect
			(at -0.40005 0)
			(size 0.4572 0.508)
			(layers "B.Cu" "B.Mask" "B.Paste")
			(net "P1V9_LAN1")
		)
		(pad "2" smd rect
			(at 0.40005 0)
			(size 0.4572 0.508)
			(layers "B.Cu" "B.Mask" "B.Paste")
			(net "GND")
		)
	)
	(footprint ""
		(layer "B.Cu")
		(at 59.771026 -119.048022 90)
		(property "Reference" "R332"
			(at -5.421122 0.029464 270)
			(unlocked yes)
			(layer "B.SilkS")
			(effects
				(font
					(size 0.7874 0.5842)
					(thickness 0.1524)
				)
				(justify left mirror)
			)
		)
		(property "Value" ""
			(at 0 0 90)
			(layer "B.Fab")
			(effects
				(font
					(size 1.27 1.27)
				)
				(justify mirror)
			)
		)
		(duplicate_pad_numbers_are_jumpers no)
		(fp_line
			(start 0.7874 -0.4064)
			(end -0.7874 -0.4064)
			(stroke
				(width 0.1524)
				(type default)
			)
			(layer "B.SilkS")
		)
		(fp_line
			(start -0.7874 -0.4064)
			(end -0.7874 0.4064)
			(stroke
				(width 0.1524)
				(type default)
			)
			(layer "B.SilkS")
		)
		(fp_line
			(start 0.7874 0.4064)
			(end 0.7874 -0.4064)
			(stroke
				(width 0.1524)
				(type default)
			)
			(layer "B.SilkS")
		)
		(fp_line
			(start -0.7874 0.4064)
			(end 0.7874 0.4064)
			(stroke
				(width 0.1524)
				(type default)
			)
			(layer "B.SilkS")
		)
		(fp_poly
			(pts
				(xy 0.508 0.2794) (xy 0.508 0.2286) (xy 0.635 0.2286) (xy 0.635 -0.254) (xy 0.5334 -0.254) (xy 0.5334 -0.2794)
				(xy -0.5334 -0.2794) (xy -0.5334 -0.254) (xy -0.635 -0.254) (xy -0.635 0.254) (xy -0.5334 0.254)
				(xy -0.5334 0.2794)
			)
			(stroke
				(width 0)
				(type default)
			)
			(fill no)
			(layer "B.CrtYd")
		)
		(pad "1" smd rect
			(at -0.40005 0 270)
			(size 0.4572 0.508)
			(layers "B.Cu" "B.Mask" "B.Paste")
			(net "P3V3_NODE1")
		)
		(pad "2" smd rect
			(at 0.40005 0 270)
			(size 0.4572 0.508)
			(layers "B.Cu" "B.Mask" "B.Paste")
			(net "BMC_ROMA16")
		)
	)
	(footprint ""
		(layer "B.Cu")
		(at 175.16348 -120.660668)
		(property "Reference" "C789"
			(at 9.948418 0.352298 0)
			(unlocked yes)
			(layer "B.SilkS")
			(effects
				(font
					(size 0.7874 0.5842)
					(thickness 0.1524)
				)
				(justify mirror)
			)
		)
		(property "Value" ""
			(at 0 0 0)
			(layer "B.Fab")
			(effects
				(font
					(size 1.27 1.27)
				)
				(justify mirror)
			)
		)
		(duplicate_pad_numbers_are_jumpers no)
		(fp_line
			(start -1.2954 -0.5842)
			(end -1.2954 0.5842)
			(stroke
				(width 0.1524)
				(type default)
			)
			(layer "B.SilkS")
		)
		(fp_line
			(start -1.2954 0.5842)
			(end 1.2954 0.5842)
			(stroke
				(width 0.1524)
				(type default)
			)
			(layer "B.SilkS")
		)
		(fp_line
			(start 0 -0.5842)
			(end 0 0.5842)
			(stroke
				(width 0.1524)
				(type default)
			)
			(layer "B.SilkS")
		)
		(fp_line
			(start 1.2954 -0.5842)
			(end -1.2954 -0.5842)
			(stroke
				(width 0.1524)
				(type default)
			)
			(layer "B.SilkS")
		)
		(fp_line
			(start 1.2954 0.5842)
			(end 1.2954 -0.5842)
			(stroke
				(width 0.1524)
				(type default)
			)
			(layer "B.SilkS")
		)
		(fp_poly
			(pts
				(xy -0.8636 -0.4572) (xy -0.8636 -0.3556) (xy -1.143 -0.3556) (xy -1.143 0.3556) (xy -0.8636 0.3556)
				(xy -0.8636 0.4572) (xy 0.8636 0.4572) (xy 0.8636 0.3556) (xy 1.143 0.3556) (xy 1.143 -0.3556) (xy 0.8636 -0.3556)
				(xy 0.8636 -0.4572)
			)
			(stroke
				(width 0)
				(type default)
			)
			(fill no)
			(layer "B.CrtYd")
		)
		(fp_line
			(start -0.884936 -0.504952)
			(end -0.884936 0.504952)
			(stroke
				(width 0.1)
				(type default)
			)
			(layer "B.Fab")
		)
		(fp_line
			(start -0.884936 0.504952)
			(end 0.884936 0.504952)
			(stroke
				(width 0.1)
				(type default)
			)
			(layer "B.Fab")
		)
		(fp_line
			(start 0.884936 -0.504952)
			(end -0.884936 -0.504952)
			(stroke
				(width 0.1)
				(type default)
			)
			(layer "B.Fab")
		)
		(fp_line
			(start 0.884936 0.504952)
			(end 0.884936 -0.504952)
			(stroke
				(width 0.1)
				(type default)
			)
			(layer "B.Fab")
		)
		(pad "1" smd rect
			(at -0.7366 0 90)
			(size 0.7112 0.8128)
			(layers "B.Cu" "B.Mask" "B.Paste")
			(net "P3V3_STB_NODE1")
		)
		(pad "2" smd rect
			(at 0.7366 0 90)
			(size 0.7112 0.8128)
			(layers "B.Cu" "B.Mask" "B.Paste")
			(net "GND")
		)
	)
	(footprint ""
		(layer "B.Cu")
		(at 153.604214 -62.075822 -90)
		(property "Reference" "C356"
			(at 2.829814 -6.116574 270)
			(unlocked yes)
			(layer "B.SilkS")
			(effects
				(font
					(size 0.7874 0.5842)
					(thickness 0.1524)
				)
				(justify left mirror)
			)
		)
		(property "Value" ""
			(at 0 0 90)
			(layer "B.Fab")
			(effects
				(font
					(size 1.27 1.27)
				)
				(justify mirror)
			)
		)
		(duplicate_pad_numbers_are_jumpers no)
		(fp_line
			(start -0.7874 0.4064)
			(end 0.7874 0.4064)
			(stroke
				(width 0.1524)
				(type default)
			)
			(layer "B.SilkS")
		)
		(fp_line
			(start 0.7874 0.4064)
			(end 0.7874 -0.4064)
			(stroke
				(width 0.1524)
				(type default)
			)
			(layer "B.SilkS")
		)
		(fp_line
			(start 0 0.381)
			(end 0 -0.381)
			(stroke
				(width 0.1524)
				(type default)
			)
			(layer "B.SilkS")
		)
		(fp_line
			(start -0.7874 -0.4064)
			(end -0.7874 0.4064)
			(stroke
				(width 0.1524)
				(type default)
			)
			(layer "B.SilkS")
		)
		(fp_line
			(start 0.7874 -0.4064)
			(end -0.7874 -0.4064)
			(stroke
				(width 0.1524)
				(type default)
			)
			(layer "B.SilkS")
		)
		(fp_poly
			(pts
				(xy 0.5334 0.254) (xy 0.635 0.254) (xy 0.635 0.2286) (xy 0.635 -0.254) (xy 0.5334 -0.254) (xy 0.5334 -0.2794)
				(xy -0.5334 -0.2794) (xy -0.5334 -0.254) (xy -0.635 -0.254) (xy -0.635 0.254) (xy -0.5334 0.254)
				(xy -0.5334 0.2794) (xy 0.508 0.2794) (xy 0.5334 0.2794)
			)
			(stroke
				(width 0)
				(type default)
			)
			(fill no)
			(layer "B.CrtYd")
		)
		(pad "1" smd rect
			(at -0.40005 0 90)
			(size 0.4572 0.508)
			(layers "B.Cu" "B.Mask" "B.Paste")
			(net "P1V8_SATA_VAA2_1_NODE1")
		)
		(pad "2" smd rect
			(at 0.40005 0 90)
			(size 0.4572 0.508)
			(layers "B.Cu" "B.Mask" "B.Paste")
			(net "GND")
		)
	)
	(footprint ""
		(layer "B.Cu")
		(at 50.253138 -76.023724 90)
		(property "Reference" "R39"
			(at -32.673798 -15.415768 270)
			(unlocked yes)
			(layer "B.SilkS")
			(effects
				(font
					(size 0.7874 0.5842)
					(thickness 0.1524)
				)
				(justify left mirror)
			)
		)
		(property "Value" ""
			(at 0 0 90)
			(layer "B.Fab")
			(effects
				(font
					(size 1.27 1.27)
				)
				(justify mirror)
			)
		)
		(duplicate_pad_numbers_are_jumpers no)
		(fp_line
			(start 0.7874 -0.4064)
			(end -0.7874 -0.4064)
			(stroke
				(width 0.1524)
				(type default)
			)
			(layer "B.SilkS")
		)
		(fp_line
			(start -0.7874 -0.4064)
			(end -0.7874 0.4064)
			(stroke
				(width 0.1524)
				(type default)
			)
			(layer "B.SilkS")
		)
		(fp_line
			(start 0.7874 0.4064)
			(end 0.7874 -0.4064)
			(stroke
				(width 0.1524)
				(type default)
			)
			(layer "B.SilkS")
		)
		(fp_line
			(start -0.7874 0.4064)
			(end 0.7874 0.4064)
			(stroke
				(width 0.1524)
				(type default)
			)
			(layer "B.SilkS")
		)
		(fp_poly
			(pts
				(xy 0.508 0.2794) (xy 0.508 0.2286) (xy 0.635 0.2286) (xy 0.635 -0.254) (xy 0.5334 -0.254) (xy 0.5334 -0.2794)
				(xy -0.5334 -0.2794) (xy -0.5334 -0.254) (xy -0.635 -0.254) (xy -0.635 0.254) (xy -0.5334 0.254)
				(xy -0.5334 0.2794)
			)
			(stroke
				(width 0)
				(type default)
			)
			(fill no)
			(layer "B.CrtYd")
		)
		(pad "1" smd rect
			(at -0.40005 0 270)
			(size 0.4572 0.508)
			(layers "B.Cu" "B.Mask" "B.Paste")
			(net "PD_CPU_NODE1_AM23")
		)
		(pad "2" smd rect
			(at 0.40005 0 270)
			(size 0.4572 0.508)
			(layers "B.Cu" "B.Mask" "B.Paste")
			(net "GND")
		)
	)
	(footprint ""
		(layer "B.Cu")
		(at 97.50044 -167.554656 90)
		(property "Reference" "R766"
			(at -2.750566 -2.59969 270)
			(unlocked yes)
			(layer "B.SilkS")
			(effects
				(font
					(size 0.7874 0.5842)
					(thickness 0.1524)
				)
				(justify left mirror)
			)
		)
		(property "Value" ""
			(at 0 0 90)
			(layer "B.Fab")
			(effects
				(font
					(size 1.27 1.27)
				)
				(justify mirror)
			)
		)
		(duplicate_pad_numbers_are_jumpers no)
		(fp_line
			(start 0.7874 -0.4064)
			(end -0.7874 -0.4064)
			(stroke
				(width 0.1524)
				(type default)
			)
			(layer "B.SilkS")
		)
		(fp_line
			(start -0.7874 -0.4064)
			(end -0.7874 0.4064)
			(stroke
				(width 0.1524)
				(type default)
			)
			(layer "B.SilkS")
		)
		(fp_line
			(start 0.7874 0.4064)
			(end 0.7874 -0.4064)
			(stroke
				(width 0.1524)
				(type default)
			)
			(layer "B.SilkS")
		)
		(fp_line
			(start -0.7874 0.4064)
			(end 0.7874 0.4064)
			(stroke
				(width 0.1524)
				(type default)
			)
			(layer "B.SilkS")
		)
		(fp_poly
			(pts
				(xy 0.508 0.2794) (xy 0.508 0.2286) (xy 0.635 0.2286) (xy 0.635 -0.254) (xy 0.5334 -0.254) (xy 0.5334 -0.2794)
				(xy -0.5334 -0.2794) (xy -0.5334 -0.254) (xy -0.635 -0.254) (xy -0.635 0.254) (xy -0.5334 0.254)
				(xy -0.5334 0.2794)
			)
			(stroke
				(width 0)
				(type default)
			)
			(fill no)
			(layer "B.CrtYd")
		)
		(pad "1" smd rect
			(at -0.40005 0 270)
			(size 0.4572 0.508)
			(layers "B.Cu" "B.Mask" "B.Paste")
			(net "TMP05_FUNC2")
		)
		(pad "2" smd rect
			(at 0.40005 0 270)
			(size 0.4572 0.508)
			(layers "B.Cu" "B.Mask" "B.Paste")
			(net "P3V3_NODE1")
		)
	)
	(footprint ""
		(layer "B.Cu")
		(at 78.83144 -171.489624 180)
		(property "Reference" "R690"
			(at -30.603698 -20.648676 0)
			(unlocked yes)
			(layer "B.SilkS")
			(effects
				(font
					(size 0.7874 0.5842)
					(thickness 0.1524)
				)
				(justify left mirror)
			)
		)
		(property "Value" ""
			(at 0 0 0)
			(layer "B.Fab")
			(effects
				(font
					(size 1.27 1.27)
				)
				(justify mirror)
			)
		)
		(duplicate_pad_numbers_are_jumpers no)
		(fp_line
			(start 0.7874 0.4064)
			(end 0.7874 -0.4064)
			(stroke
				(width 0.1524)
				(type default)
			)
			(layer "B.SilkS")
		)
		(fp_line
			(start 0.7874 -0.4064)
			(end -0.7874 -0.4064)
			(stroke
				(width 0.1524)
				(type default)
			)
			(layer "B.SilkS")
		)
		(fp_line
			(start -0.7874 0.4064)
			(end 0.7874 0.4064)
			(stroke
				(width 0.1524)
				(type default)
			)
			(layer "B.SilkS")
		)
		(fp_line
			(start -0.7874 -0.4064)
			(end -0.7874 0.4064)
			(stroke
				(width 0.1524)
				(type default)
			)
			(layer "B.SilkS")
		)
		(fp_poly
			(pts
				(xy 0.508 0.2794) (xy 0.508 0.2286) (xy 0.635 0.2286) (xy 0.635 -0.254) (xy 0.5334 -0.254) (xy 0.5334 -0.2794)
				(xy -0.5334 -0.2794) (xy -0.5334 -0.254) (xy -0.635 -0.254) (xy -0.635 0.254) (xy -0.5334 0.254)
				(xy -0.5334 0.2794)
			)
			(stroke
				(width 0)
				(type default)
			)
			(fill no)
			(layer "B.CrtYd")
		)
		(pad "1" smd rect
			(at -0.40005 0)
			(size 0.4572 0.508)
			(layers "B.Cu" "B.Mask" "B.Paste")
			(net "T1_NODE2_EN")
		)
		(pad "2" smd rect
			(at 0.40005 0)
			(size 0.4572 0.508)
			(layers "B.Cu" "B.Mask" "B.Paste")
			(net "P5V_NODE1")
		)
	)
	(footprint ""
		(layer "B.Cu")
		(at 135.196834 -36.359084)
		(property "Reference" "R1181"
			(at -5.415788 18.22831 0)
			(unlocked yes)
			(layer "B.SilkS")
			(effects
				(font
					(size 0.7874 0.5842)
					(thickness 0.1524)
				)
				(justify left mirror)
			)
		)
		(property "Value" ""
			(at 0 0 0)
			(layer "B.Fab")
			(effects
				(font
					(size 1.27 1.27)
				)
				(justify mirror)
			)
		)
		(duplicate_pad_numbers_are_jumpers no)
		(fp_line
			(start -0.7874 -0.4064)
			(end -0.7874 0.4064)
			(stroke
				(width 0.1524)
				(type default)
			)
			(layer "B.SilkS")
		)
		(fp_line
			(start -0.7874 0.4064)
			(end 0.7874 0.4064)
			(stroke
				(width 0.1524)
				(type default)
			)
			(layer "B.SilkS")
		)
		(fp_line
			(start 0.7874 -0.4064)
			(end -0.7874 -0.4064)
			(stroke
				(width 0.1524)
				(type default)
			)
			(layer "B.SilkS")
		)
		(fp_line
			(start 0.7874 0.4064)
			(end 0.7874 -0.4064)
			(stroke
				(width 0.1524)
				(type default)
			)
			(layer "B.SilkS")
		)
		(fp_poly
			(pts
				(xy 0.508 0.2794) (xy 0.508 0.2286) (xy 0.635 0.2286) (xy 0.635 -0.254) (xy 0.5334 -0.254) (xy 0.5334 -0.2794)
				(xy -0.5334 -0.2794) (xy -0.5334 -0.254) (xy -0.635 -0.254) (xy -0.635 0.254) (xy -0.5334 0.254)
				(xy -0.5334 0.2794)
			)
			(stroke
				(width 0)
				(type default)
			)
			(fill no)
			(layer "B.CrtYd")
		)
		(pad "1" smd rect
			(at -0.40005 0 180)
			(size 0.4572 0.508)
			(layers "B.Cu" "B.Mask" "B.Paste")
			(net "CPLD123_RSV1")
		)
		(pad "2" smd rect
			(at 0.40005 0 180)
			(size 0.4572 0.508)
			(layers "B.Cu" "B.Mask" "B.Paste")
			(net "SIO_CPLD_RSV1_R")
		)
	)
	(footprint ""
		(layer "B.Cu")
		(at 122.0978 -42.700702)
		(property "Reference" "R184"
			(at -2.808732 0.132842 0)
			(unlocked yes)
			(layer "B.SilkS")
			(effects
				(font
					(size 0.7874 0.5842)
					(thickness 0.1524)
				)
				(justify left mirror)
			)
		)
		(property "Value" ""
			(at 0 0 0)
			(layer "B.Fab")
			(effects
				(font
					(size 1.27 1.27)
				)
				(justify mirror)
			)
		)
		(duplicate_pad_numbers_are_jumpers no)
		(fp_line
			(start -0.7874 -0.4064)
			(end -0.7874 0.4064)
			(stroke
				(width 0.1524)
				(type default)
			)
			(layer "B.SilkS")
		)
		(fp_line
			(start -0.7874 0.4064)
			(end 0.7874 0.4064)
			(stroke
				(width 0.1524)
				(type default)
			)
			(layer "B.SilkS")
		)
		(fp_line
			(start 0.7874 -0.4064)
			(end -0.7874 -0.4064)
			(stroke
				(width 0.1524)
				(type default)
			)
			(layer "B.SilkS")
		)
		(fp_line
			(start 0.7874 0.4064)
			(end 0.7874 -0.4064)
			(stroke
				(width 0.1524)
				(type default)
			)
			(layer "B.SilkS")
		)
		(fp_poly
			(pts
				(xy 0.508 0.2794) (xy 0.508 0.2286) (xy 0.635 0.2286) (xy 0.635 -0.254) (xy 0.5334 -0.254) (xy 0.5334 -0.2794)
				(xy -0.5334 -0.2794) (xy -0.5334 -0.254) (xy -0.635 -0.254) (xy -0.635 0.254) (xy -0.5334 0.254)
				(xy -0.5334 0.2794)
			)
			(stroke
				(width 0)
				(type default)
			)
			(fill no)
			(layer "B.CrtYd")
		)
		(pad "1" smd rect
			(at -0.40005 0 180)
			(size 0.4572 0.508)
			(layers "B.Cu" "B.Mask" "B.Paste")
			(net "LPC_CPU_NODE1_LAD2")
		)
		(pad "2" smd rect
			(at 0.40005 0 180)
			(size 0.4572 0.508)
			(layers "B.Cu" "B.Mask" "B.Paste")
			(net "LPC_CPU_NODE1_LAD2_SIO")
		)
	)
	(footprint ""
		(layer "B.Cu")
		(at 143.960596 -68.73113 -90)
		(property "Reference" "C338"
			(at -1.050036 -0.550926 270)
			(unlocked yes)
			(layer "B.SilkS")
			(effects
				(font
					(size 0.7874 0.5842)
					(thickness 0.1524)
				)
				(justify left mirror)
			)
		)
		(property "Value" ""
			(at 0 0 90)
			(layer "B.Fab")
			(effects
				(font
					(size 1.27 1.27)
				)
				(justify mirror)
			)
		)
		(duplicate_pad_numbers_are_jumpers no)
		(fp_line
			(start -0.7874 0.4064)
			(end 0.7874 0.4064)
			(stroke
				(width 0.1524)
				(type default)
			)
			(layer "B.SilkS")
		)
		(fp_line
			(start 0.7874 0.4064)
			(end 0.7874 -0.4064)
			(stroke
				(width 0.1524)
				(type default)
			)
			(layer "B.SilkS")
		)
		(fp_line
			(start 0 0.381)
			(end 0 -0.381)
			(stroke
				(width 0.1524)
				(type default)
			)
			(layer "B.SilkS")
		)
		(fp_line
			(start -0.7874 -0.4064)
			(end -0.7874 0.4064)
			(stroke
				(width 0.1524)
				(type default)
			)
			(layer "B.SilkS")
		)
		(fp_line
			(start 0.7874 -0.4064)
			(end -0.7874 -0.4064)
			(stroke
				(width 0.1524)
				(type default)
			)
			(layer "B.SilkS")
		)
		(fp_poly
			(pts
				(xy 0.5334 0.254) (xy 0.635 0.254) (xy 0.635 0.2286) (xy 0.635 -0.254) (xy 0.5334 -0.254) (xy 0.5334 -0.2794)
				(xy -0.5334 -0.2794) (xy -0.5334 -0.254) (xy -0.635 -0.254) (xy -0.635 0.254) (xy -0.5334 0.254)
				(xy -0.5334 0.2794) (xy 0.508 0.2794) (xy 0.5334 0.2794)
			)
			(stroke
				(width 0)
				(type default)
			)
			(fill no)
			(layer "B.CrtYd")
		)
		(pad "1" smd rect
			(at -0.40005 0 90)
			(size 0.4572 0.508)
			(layers "B.Cu" "B.Mask" "B.Paste")
			(net "P1V0_SATA")
		)
		(pad "2" smd rect
			(at 0.40005 0 90)
			(size 0.4572 0.508)
			(layers "B.Cu" "B.Mask" "B.Paste")
			(net "GND")
		)
	)
	(footprint ""
		(layer "B.Cu")
		(at 90.81262 -162.846512)
		(property "Reference" "R781"
			(at 24.774144 20.136104 0)
			(unlocked yes)
			(layer "B.SilkS")
			(effects
				(font
					(size 0.7874 0.5842)
					(thickness 0.1524)
				)
				(justify left mirror)
			)
		)
		(property "Value" ""
			(at 0 0 0)
			(layer "B.Fab")
			(effects
				(font
					(size 1.27 1.27)
				)
				(justify mirror)
			)
		)
		(duplicate_pad_numbers_are_jumpers no)
		(fp_line
			(start -0.7874 -0.4064)
			(end -0.7874 0.4064)
			(stroke
				(width 0.1524)
				(type default)
			)
			(layer "B.SilkS")
		)
		(fp_line
			(start -0.7874 0.4064)
			(end 0.7874 0.4064)
			(stroke
				(width 0.1524)
				(type default)
			)
			(layer "B.SilkS")
		)
		(fp_line
			(start 0.7874 -0.4064)
			(end -0.7874 -0.4064)
			(stroke
				(width 0.1524)
				(type default)
			)
			(layer "B.SilkS")
		)
		(fp_line
			(start 0.7874 0.4064)
			(end 0.7874 -0.4064)
			(stroke
				(width 0.1524)
				(type default)
			)
			(layer "B.SilkS")
		)
		(fp_poly
			(pts
				(xy 0.508 0.2794) (xy 0.508 0.2286) (xy 0.635 0.2286) (xy 0.635 -0.254) (xy 0.5334 -0.254) (xy 0.5334 -0.2794)
				(xy -0.5334 -0.2794) (xy -0.5334 -0.254) (xy -0.635 -0.254) (xy -0.635 0.254) (xy -0.5334 0.254)
				(xy -0.5334 0.2794)
			)
			(stroke
				(width 0)
				(type default)
			)
			(fill no)
			(layer "B.CrtYd")
		)
		(pad "1" smd rect
			(at -0.40005 0 180)
			(size 0.4572 0.508)
			(layers "B.Cu" "B.Mask" "B.Paste")
			(net "I2C_SDC_SCL")
		)
		(pad "2" smd rect
			(at 0.40005 0 180)
			(size 0.4572 0.508)
			(layers "B.Cu" "B.Mask" "B.Paste")
			(net "P3V3_NODE1")
		)
	)
	(footprint ""
		(layer "B.Cu")
		(at 136.382252 -119.487442 180)
		(property "Reference" "C8"
			(at 0.968502 -0.16383 0)
			(unlocked yes)
			(layer "B.SilkS")
			(effects
				(font
					(size 0.7874 0.5842)
					(thickness 0.1524)
				)
				(justify left mirror)
			)
		)
		(property "Value" ""
			(at 0 0 0)
			(layer "B.Fab")
			(effects
				(font
					(size 1.27 1.27)
				)
				(justify mirror)
			)
		)
		(duplicate_pad_numbers_are_jumpers no)
		(fp_line
			(start 0.7874 0.4064)
			(end 0.7874 -0.4064)
			(stroke
				(width 0.1524)
				(type default)
			)
			(layer "B.SilkS")
		)
		(fp_line
			(start 0.7874 -0.4064)
			(end -0.7874 -0.4064)
			(stroke
				(width 0.1524)
				(type default)
			)
			(layer "B.SilkS")
		)
		(fp_line
			(start 0 0.381)
			(end 0 -0.381)
			(stroke
				(width 0.1524)
				(type default)
			)
			(layer "B.SilkS")
		)
		(fp_line
			(start -0.7874 0.4064)
			(end 0.7874 0.4064)
			(stroke
				(width 0.1524)
				(type default)
			)
			(layer "B.SilkS")
		)
		(fp_line
			(start -0.7874 -0.4064)
			(end -0.7874 0.4064)
			(stroke
				(width 0.1524)
				(type default)
			)
			(layer "B.SilkS")
		)
		(fp_poly
			(pts
				(xy 0.5334 0.254) (xy 0.635 0.254) (xy 0.635 0.2286) (xy 0.635 -0.254) (xy 0.5334 -0.254) (xy 0.5334 -0.2794)
				(xy -0.5334 -0.2794) (xy -0.5334 -0.254) (xy -0.635 -0.254) (xy -0.635 0.254) (xy -0.5334 0.254)
				(xy -0.5334 0.2794) (xy 0.508 0.2794) (xy 0.5334 0.2794)
			)
			(stroke
				(width 0)
				(type default)
			)
			(fill no)
			(layer "B.CrtYd")
		)
		(pad "1" smd rect
			(at -0.40005 0)
			(size 0.4572 0.508)
			(layers "B.Cu" "B.Mask" "B.Paste")
			(net "P1V5_CLK_NODE1")
		)
		(pad "2" smd rect
			(at 0.40005 0)
			(size 0.4572 0.508)
			(layers "B.Cu" "B.Mask" "B.Paste")
			(net "GND")
		)
	)
	(footprint ""
		(layer "B.Cu")
		(at 91.102434 -188.858398)
		(property "Reference" "R909"
			(at -2.352294 -3.284474 0)
			(unlocked yes)
			(layer "B.SilkS")
			(effects
				(font
					(size 0.7874 0.5842)
					(thickness 0.1524)
				)
				(justify left mirror)
			)
		)
		(property "Value" ""
			(at 0 0 0)
			(layer "B.Fab")
			(effects
				(font
					(size 1.27 1.27)
				)
				(justify mirror)
			)
		)
		(duplicate_pad_numbers_are_jumpers no)
		(fp_line
			(start -0.7874 -0.4064)
			(end -0.7874 0.4064)
			(stroke
				(width 0.1524)
				(type default)
			)
			(layer "B.SilkS")
		)
		(fp_line
			(start -0.7874 0.4064)
			(end 0.7874 0.4064)
			(stroke
				(width 0.1524)
				(type default)
			)
			(layer "B.SilkS")
		)
		(fp_line
			(start 0.7874 -0.4064)
			(end -0.7874 -0.4064)
			(stroke
				(width 0.1524)
				(type default)
			)
			(layer "B.SilkS")
		)
		(fp_line
			(start 0.7874 0.4064)
			(end 0.7874 -0.4064)
			(stroke
				(width 0.1524)
				(type default)
			)
			(layer "B.SilkS")
		)
		(fp_poly
			(pts
				(xy 0.508 0.2794) (xy 0.508 0.2286) (xy 0.635 0.2286) (xy 0.635 -0.254) (xy 0.5334 -0.254) (xy 0.5334 -0.2794)
				(xy -0.5334 -0.2794) (xy -0.5334 -0.254) (xy -0.635 -0.254) (xy -0.635 0.254) (xy -0.5334 0.254)
				(xy -0.5334 0.2794)
			)
			(stroke
				(width 0)
				(type default)
			)
			(fill no)
			(layer "B.CrtYd")
		)
		(pad "1" smd rect
			(at -0.40005 0 180)
			(size 0.4572 0.508)
			(layers "B.Cu" "B.Mask" "B.Paste")
			(net "UART_T5_NODE1_RXD")
		)
		(pad "2" smd rect
			(at 0.40005 0 180)
			(size 0.4572 0.508)
			(layers "B.Cu" "B.Mask" "B.Paste")
			(net "UART_T5_NODE1_RXD_R")
		)
	)
	(footprint ""
		(layer "B.Cu")
		(at 154.06116 -175.553624)
		(property "Reference" "R746"
			(at -1.323086 12.476226 0)
			(unlocked yes)
			(layer "B.SilkS")
			(effects
				(font
					(size 0.7874 0.5842)
					(thickness 0.1524)
				)
				(justify left mirror)
			)
		)
		(property "Value" ""
			(at 0 0 0)
			(layer "B.Fab")
			(effects
				(font
					(size 1.27 1.27)
				)
				(justify mirror)
			)
		)
		(duplicate_pad_numbers_are_jumpers no)
		(fp_line
			(start -0.7874 -0.4064)
			(end -0.7874 0.4064)
			(stroke
				(width 0.1524)
				(type default)
			)
			(layer "B.SilkS")
		)
		(fp_line
			(start -0.7874 0.4064)
			(end 0.7874 0.4064)
			(stroke
				(width 0.1524)
				(type default)
			)
			(layer "B.SilkS")
		)
		(fp_line
			(start 0.7874 -0.4064)
			(end -0.7874 -0.4064)
			(stroke
				(width 0.1524)
				(type default)
			)
			(layer "B.SilkS")
		)
		(fp_line
			(start 0.7874 0.4064)
			(end 0.7874 -0.4064)
			(stroke
				(width 0.1524)
				(type default)
			)
			(layer "B.SilkS")
		)
		(fp_poly
			(pts
				(xy 0.508 0.2794) (xy 0.508 0.2286) (xy 0.635 0.2286) (xy 0.635 -0.254) (xy 0.5334 -0.254) (xy 0.5334 -0.2794)
				(xy -0.5334 -0.2794) (xy -0.5334 -0.254) (xy -0.635 -0.254) (xy -0.635 0.254) (xy -0.5334 0.254)
				(xy -0.5334 0.2794)
			)
			(stroke
				(width 0)
				(type default)
			)
			(fill no)
			(layer "B.CrtYd")
		)
		(pad "1" smd rect
			(at -0.40005 0 180)
			(size 0.4572 0.508)
			(layers "B.Cu" "B.Mask" "B.Paste")
			(net "T12_NODE1_EN")
		)
		(pad "2" smd rect
			(at 0.40005 0 180)
			(size 0.4572 0.508)
			(layers "B.Cu" "B.Mask" "B.Paste")
			(net "P5V_NODE1")
		)
	)
	(footprint ""
		(layer "B.Cu")
		(at 185.293 -186.182 90)
		(property "Reference" "C594"
			(at -4.191 -0.33147 270)
			(unlocked yes)
			(layer "B.SilkS")
			(effects
				(font
					(size 0.7874 0.5842)
					(thickness 0.1524)
				)
				(justify left mirror)
			)
		)
		(property "Value" ""
			(at 0 0 90)
			(layer "B.Fab")
			(effects
				(font
					(size 1.27 1.27)
				)
				(justify mirror)
			)
		)
		(duplicate_pad_numbers_are_jumpers no)
		(fp_line
			(start 0.7874 -0.4064)
			(end -0.7874 -0.4064)
			(stroke
				(width 0.1524)
				(type default)
			)
			(layer "B.SilkS")
		)
		(fp_line
			(start -0.7874 -0.4064)
			(end -0.7874 0.4064)
			(stroke
				(width 0.1524)
				(type default)
			)
			(layer "B.SilkS")
		)
		(fp_line
			(start 0 0.381)
			(end 0 -0.381)
			(stroke
				(width 0.1524)
				(type default)
			)
			(layer "B.SilkS")
		)
		(fp_line
			(start 0.7874 0.4064)
			(end 0.7874 -0.4064)
			(stroke
				(width 0.1524)
				(type default)
			)
			(layer "B.SilkS")
		)
		(fp_line
			(start -0.7874 0.4064)
			(end 0.7874 0.4064)
			(stroke
				(width 0.1524)
				(type default)
			)
			(layer "B.SilkS")
		)
		(fp_poly
			(pts
				(xy 0.5334 0.254) (xy 0.635 0.254) (xy 0.635 0.2286) (xy 0.635 -0.254) (xy 0.5334 -0.254) (xy 0.5334 -0.2794)
				(xy -0.5334 -0.2794) (xy -0.5334 -0.254) (xy -0.635 -0.254) (xy -0.635 0.254) (xy -0.5334 0.254)
				(xy -0.5334 0.2794) (xy 0.508 0.2794) (xy 0.5334 0.2794)
			)
			(stroke
				(width 0)
				(type default)
			)
			(fill no)
			(layer "B.CrtYd")
		)
		(pad "1" smd rect
			(at -0.40005 0 270)
			(size 0.4572 0.508)
			(layers "B.Cu" "B.Mask" "B.Paste")
			(net "POWER_SW2_PWR_CTR_12V_R")
		)
		(pad "2" smd rect
			(at 0.40005 0 270)
			(size 0.4572 0.508)
			(layers "B.Cu" "B.Mask" "B.Paste")
			(net "GND")
		)
	)
	(footprint ""
		(layer "B.Cu")
		(at 57.457086 -131.026662)
		(property "Reference" "R257"
			(at -40.250618 53.12664 0)
			(unlocked yes)
			(layer "B.SilkS")
			(effects
				(font
					(size 0.7874 0.5842)
					(thickness 0.1524)
				)
				(justify left mirror)
			)
		)
		(property "Value" ""
			(at 0 0 0)
			(layer "B.Fab")
			(effects
				(font
					(size 1.27 1.27)
				)
				(justify mirror)
			)
		)
		(duplicate_pad_numbers_are_jumpers no)
		(fp_line
			(start -0.7874 -0.4064)
			(end -0.7874 0.4064)
			(stroke
				(width 0.1524)
				(type default)
			)
			(layer "B.SilkS")
		)
		(fp_line
			(start -0.7874 0.4064)
			(end 0.7874 0.4064)
			(stroke
				(width 0.1524)
				(type default)
			)
			(layer "B.SilkS")
		)
		(fp_line
			(start 0.7874 -0.4064)
			(end -0.7874 -0.4064)
			(stroke
				(width 0.1524)
				(type default)
			)
			(layer "B.SilkS")
		)
		(fp_line
			(start 0.7874 0.4064)
			(end 0.7874 -0.4064)
			(stroke
				(width 0.1524)
				(type default)
			)
			(layer "B.SilkS")
		)
		(fp_poly
			(pts
				(xy 0.508 0.2794) (xy 0.508 0.2286) (xy 0.635 0.2286) (xy 0.635 -0.254) (xy 0.5334 -0.254) (xy 0.5334 -0.2794)
				(xy -0.5334 -0.2794) (xy -0.5334 -0.254) (xy -0.635 -0.254) (xy -0.635 0.254) (xy -0.5334 0.254)
				(xy -0.5334 0.2794)
			)
			(stroke
				(width 0)
				(type default)
			)
			(fill no)
			(layer "B.CrtYd")
		)
		(pad "1" smd rect
			(at -0.40005 0 180)
			(size 0.4572 0.508)
			(layers "B.Cu" "B.Mask" "B.Paste")
			(net "GND")
		)
		(pad "2" smd rect
			(at 0.40005 0 180)
			(size 0.4572 0.508)
			(layers "B.Cu" "B.Mask" "B.Paste")
			(net "BMC_NODE1_DDR_IOZ")
		)
	)
	(footprint ""
		(layer "B.Cu")
		(at 38.622732 -94.40037 -90)
		(property "Reference" "C30"
			(at 4.703318 4.661662 270)
			(unlocked yes)
			(layer "B.SilkS")
			(effects
				(font
					(size 0.7874 0.5842)
					(thickness 0.1524)
				)
				(justify left mirror)
			)
		)
		(property "Value" ""
			(at 0 0 90)
			(layer "B.Fab")
			(effects
				(font
					(size 1.27 1.27)
				)
				(justify mirror)
			)
		)
		(duplicate_pad_numbers_are_jumpers no)
		(fp_line
			(start -0.7874 0.4064)
			(end 0.7874 0.4064)
			(stroke
				(width 0.1524)
				(type default)
			)
			(layer "B.SilkS")
		)
		(fp_line
			(start 0.7874 0.4064)
			(end 0.7874 -0.4064)
			(stroke
				(width 0.1524)
				(type default)
			)
			(layer "B.SilkS")
		)
		(fp_line
			(start 0 0.381)
			(end 0 -0.381)
			(stroke
				(width 0.1524)
				(type default)
			)
			(layer "B.SilkS")
		)
		(fp_line
			(start -0.7874 -0.4064)
			(end -0.7874 0.4064)
			(stroke
				(width 0.1524)
				(type default)
			)
			(layer "B.SilkS")
		)
		(fp_line
			(start 0.7874 -0.4064)
			(end -0.7874 -0.4064)
			(stroke
				(width 0.1524)
				(type default)
			)
			(layer "B.SilkS")
		)
		(fp_poly
			(pts
				(xy 0.5334 0.254) (xy 0.635 0.254) (xy 0.635 0.2286) (xy 0.635 -0.254) (xy 0.5334 -0.254) (xy 0.5334 -0.2794)
				(xy -0.5334 -0.2794) (xy -0.5334 -0.254) (xy -0.635 -0.254) (xy -0.635 0.254) (xy -0.5334 0.254)
				(xy -0.5334 0.2794) (xy 0.508 0.2794) (xy 0.5334 0.2794)
			)
			(stroke
				(width 0)
				(type default)
			)
			(fill no)
			(layer "B.CrtYd")
		)
		(pad "1" smd rect
			(at -0.40005 0 90)
			(size 0.4572 0.508)
			(layers "B.Cu" "B.Mask" "B.Paste")
			(net "GND")
		)
		(pad "2" smd rect
			(at 0.40005 0 90)
			(size 0.4572 0.508)
			(layers "B.Cu" "B.Mask" "B.Paste")
			(net "SMB_CPU_NODE1_BMC_CLK_RR")
		)
	)
	(footprint ""
		(layer "B.Cu")
		(at 93.70568 -182.494936 -90)
		(property "Reference" "R1196"
			(at 3.01752 3.62585 270)
			(unlocked yes)
			(layer "B.SilkS")
			(effects
				(font
					(size 0.7874 0.5842)
					(thickness 0.1524)
				)
				(justify left mirror)
			)
		)
		(property "Value" ""
			(at 0 0 90)
			(layer "B.Fab")
			(effects
				(font
					(size 1.27 1.27)
				)
				(justify mirror)
			)
		)
		(duplicate_pad_numbers_are_jumpers no)
		(fp_line
			(start -0.7874 0.4064)
			(end 0.7874 0.4064)
			(stroke
				(width 0.1524)
				(type default)
			)
			(layer "B.SilkS")
		)
		(fp_line
			(start 0.7874 0.4064)
			(end 0.7874 -0.4064)
			(stroke
				(width 0.1524)
				(type default)
			)
			(layer "B.SilkS")
		)
		(fp_line
			(start -0.7874 -0.4064)
			(end -0.7874 0.4064)
			(stroke
				(width 0.1524)
				(type default)
			)
			(layer "B.SilkS")
		)
		(fp_line
			(start 0.7874 -0.4064)
			(end -0.7874 -0.4064)
			(stroke
				(width 0.1524)
				(type default)
			)
			(layer "B.SilkS")
		)
		(fp_poly
			(pts
				(xy 0.508 0.2794) (xy 0.508 0.2286) (xy 0.635 0.2286) (xy 0.635 -0.254) (xy 0.5334 -0.254) (xy 0.5334 -0.2794)
				(xy -0.5334 -0.2794) (xy -0.5334 -0.254) (xy -0.635 -0.254) (xy -0.635 0.254) (xy -0.5334 0.254)
				(xy -0.5334 0.2794)
			)
			(stroke
				(width 0)
				(type default)
			)
			(fill no)
			(layer "B.CrtYd")
		)
		(pad "1" smd rect
			(at -0.40005 0 90)
			(size 0.4572 0.508)
			(layers "B.Cu" "B.Mask" "B.Paste")
			(net "PCA_CPLD_WDT2")
		)
		(pad "2" smd rect
			(at 0.40005 0 90)
			(size 0.4572 0.508)
			(layers "B.Cu" "B.Mask" "B.Paste")
			(net "P3V3_NODE1")
		)
	)
	(footprint ""
		(layer "B.Cu")
		(at 42.686732 -94.40037 -90)
		(property "Reference" "C29"
			(at 4.703318 4.538218 270)
			(unlocked yes)
			(layer "B.SilkS")
			(effects
				(font
					(size 0.7874 0.5842)
					(thickness 0.1524)
				)
				(justify left mirror)
			)
		)
		(property "Value" ""
			(at 0 0 90)
			(layer "B.Fab")
			(effects
				(font
					(size 1.27 1.27)
				)
				(justify mirror)
			)
		)
		(duplicate_pad_numbers_are_jumpers no)
		(fp_line
			(start -0.7874 0.4064)
			(end 0.7874 0.4064)
			(stroke
				(width 0.1524)
				(type default)
			)
			(layer "B.SilkS")
		)
		(fp_line
			(start 0.7874 0.4064)
			(end 0.7874 -0.4064)
			(stroke
				(width 0.1524)
				(type default)
			)
			(layer "B.SilkS")
		)
		(fp_line
			(start 0 0.381)
			(end 0 -0.381)
			(stroke
				(width 0.1524)
				(type default)
			)
			(layer "B.SilkS")
		)
		(fp_line
			(start -0.7874 -0.4064)
			(end -0.7874 0.4064)
			(stroke
				(width 0.1524)
				(type default)
			)
			(layer "B.SilkS")
		)
		(fp_line
			(start 0.7874 -0.4064)
			(end -0.7874 -0.4064)
			(stroke
				(width 0.1524)
				(type default)
			)
			(layer "B.SilkS")
		)
		(fp_poly
			(pts
				(xy 0.5334 0.254) (xy 0.635 0.254) (xy 0.635 0.2286) (xy 0.635 -0.254) (xy 0.5334 -0.254) (xy 0.5334 -0.2794)
				(xy -0.5334 -0.2794) (xy -0.5334 -0.254) (xy -0.635 -0.254) (xy -0.635 0.254) (xy -0.5334 0.254)
				(xy -0.5334 0.2794) (xy 0.508 0.2794) (xy 0.5334 0.2794)
			)
			(stroke
				(width 0)
				(type default)
			)
			(fill no)
			(layer "B.CrtYd")
		)
		(pad "1" smd rect
			(at -0.40005 0 90)
			(size 0.4572 0.508)
			(layers "B.Cu" "B.Mask" "B.Paste")
			(net "GND")
		)
		(pad "2" smd rect
			(at 0.40005 0 90)
			(size 0.4572 0.508)
			(layers "B.Cu" "B.Mask" "B.Paste")
			(net "SMB_CPU_NODE1_MEM_ICS_DAT_R")
		)
	)
	(footprint ""
		(layer "B.Cu")
		(at 64.121538 -63.783718)
		(property "Reference" "R31"
			(at 0.00889 5.27558 0)
			(unlocked yes)
			(layer "B.SilkS")
			(effects
				(font
					(size 0.7874 0.5842)
					(thickness 0.1524)
				)
				(justify left mirror)
			)
		)
		(property "Value" ""
			(at 0 0 0)
			(layer "B.Fab")
			(effects
				(font
					(size 1.27 1.27)
				)
				(justify mirror)
			)
		)
		(duplicate_pad_numbers_are_jumpers no)
		(fp_line
			(start -0.7874 -0.4064)
			(end -0.7874 0.4064)
			(stroke
				(width 0.1524)
				(type default)
			)
			(layer "B.SilkS")
		)
		(fp_line
			(start -0.7874 0.4064)
			(end 0.7874 0.4064)
			(stroke
				(width 0.1524)
				(type default)
			)
			(layer "B.SilkS")
		)
		(fp_line
			(start 0.7874 -0.4064)
			(end -0.7874 -0.4064)
			(stroke
				(width 0.1524)
				(type default)
			)
			(layer "B.SilkS")
		)
		(fp_line
			(start 0.7874 0.4064)
			(end 0.7874 -0.4064)
			(stroke
				(width 0.1524)
				(type default)
			)
			(layer "B.SilkS")
		)
		(fp_poly
			(pts
				(xy 0.508 0.2794) (xy 0.508 0.2286) (xy 0.635 0.2286) (xy 0.635 -0.254) (xy 0.5334 -0.254) (xy 0.5334 -0.2794)
				(xy -0.5334 -0.2794) (xy -0.5334 -0.254) (xy -0.635 -0.254) (xy -0.635 0.254) (xy -0.5334 0.254)
				(xy -0.5334 0.2794)
			)
			(stroke
				(width 0)
				(type default)
			)
			(fill no)
			(layer "B.CrtYd")
		)
		(pad "1" smd rect
			(at -0.40005 0 180)
			(size 0.4572 0.508)
			(layers "B.Cu" "B.Mask" "B.Paste")
			(net "N29180194")
		)
		(pad "2" smd rect
			(at 0.40005 0 180)
			(size 0.4572 0.508)
			(layers "B.Cu" "B.Mask" "B.Paste")
			(net "GND")
		)
	)
	(footprint ""
		(layer "B.Cu")
		(at 90.81262 -173.006512)
		(property "Reference" "R705"
			(at 24.902414 20.163028 0)
			(unlocked yes)
			(layer "B.SilkS")
			(effects
				(font
					(size 0.7874 0.5842)
					(thickness 0.1524)
				)
				(justify left mirror)
			)
		)
		(property "Value" ""
			(at 0 0 0)
			(layer "B.Fab")
			(effects
				(font
					(size 1.27 1.27)
				)
				(justify mirror)
			)
		)
		(duplicate_pad_numbers_are_jumpers no)
		(fp_line
			(start -0.7874 -0.4064)
			(end -0.7874 0.4064)
			(stroke
				(width 0.1524)
				(type default)
			)
			(layer "B.SilkS")
		)
		(fp_line
			(start -0.7874 0.4064)
			(end 0.7874 0.4064)
			(stroke
				(width 0.1524)
				(type default)
			)
			(layer "B.SilkS")
		)
		(fp_line
			(start 0.7874 -0.4064)
			(end -0.7874 -0.4064)
			(stroke
				(width 0.1524)
				(type default)
			)
			(layer "B.SilkS")
		)
		(fp_line
			(start 0.7874 0.4064)
			(end 0.7874 -0.4064)
			(stroke
				(width 0.1524)
				(type default)
			)
			(layer "B.SilkS")
		)
		(fp_poly
			(pts
				(xy 0.508 0.2794) (xy 0.508 0.2286) (xy 0.635 0.2286) (xy 0.635 -0.254) (xy 0.5334 -0.254) (xy 0.5334 -0.2794)
				(xy -0.5334 -0.2794) (xy -0.5334 -0.254) (xy -0.635 -0.254) (xy -0.635 0.254) (xy -0.5334 0.254)
				(xy -0.5334 0.2794)
			)
			(stroke
				(width 0)
				(type default)
			)
			(fill no)
			(layer "B.CrtYd")
		)
		(pad "1" smd rect
			(at -0.40005 0 180)
			(size 0.4572 0.508)
			(layers "B.Cu" "B.Mask" "B.Paste")
			(net "T4_NODE2_EN")
		)
		(pad "2" smd rect
			(at 0.40005 0 180)
			(size 0.4572 0.508)
			(layers "B.Cu" "B.Mask" "B.Paste")
			(net "P5V_NODE1")
		)
	)
	(footprint ""
		(layer "B.Cu")
		(at 78.83144 -169.457624)
		(property "Reference" "R685"
			(at 30.846268 19.625818 0)
			(unlocked yes)
			(layer "B.SilkS")
			(effects
				(font
					(size 0.7874 0.5842)
					(thickness 0.1524)
				)
				(justify left mirror)
			)
		)
		(property "Value" ""
			(at 0 0 0)
			(layer "B.Fab")
			(effects
				(font
					(size 1.27 1.27)
				)
				(justify mirror)
			)
		)
		(duplicate_pad_numbers_are_jumpers no)
		(fp_line
			(start -0.7874 -0.4064)
			(end -0.7874 0.4064)
			(stroke
				(width 0.1524)
				(type default)
			)
			(layer "B.SilkS")
		)
		(fp_line
			(start -0.7874 0.4064)
			(end 0.7874 0.4064)
			(stroke
				(width 0.1524)
				(type default)
			)
			(layer "B.SilkS")
		)
		(fp_line
			(start 0.7874 -0.4064)
			(end -0.7874 -0.4064)
			(stroke
				(width 0.1524)
				(type default)
			)
			(layer "B.SilkS")
		)
		(fp_line
			(start 0.7874 0.4064)
			(end 0.7874 -0.4064)
			(stroke
				(width 0.1524)
				(type default)
			)
			(layer "B.SilkS")
		)
		(fp_poly
			(pts
				(xy 0.508 0.2794) (xy 0.508 0.2286) (xy 0.635 0.2286) (xy 0.635 -0.254) (xy 0.5334 -0.254) (xy 0.5334 -0.2794)
				(xy -0.5334 -0.2794) (xy -0.5334 -0.254) (xy -0.635 -0.254) (xy -0.635 0.254) (xy -0.5334 0.254)
				(xy -0.5334 0.2794)
			)
			(stroke
				(width 0)
				(type default)
			)
			(fill no)
			(layer "B.CrtYd")
		)
		(pad "1" smd rect
			(at -0.40005 0 180)
			(size 0.4572 0.508)
			(layers "B.Cu" "B.Mask" "B.Paste")
			(net "P3V3_NODE1")
		)
		(pad "2" smd rect
			(at 0.40005 0 180)
			(size 0.4572 0.508)
			(layers "B.Cu" "B.Mask" "B.Paste")
			(net "N21699285")
		)
	)
	(footprint ""
		(layer "B.Cu")
		(at 59.636406 -74.2315 -90)
		(property "Reference" "C127"
			(at 32.346646 14.418056 270)
			(unlocked yes)
			(layer "B.SilkS")
			(effects
				(font
					(size 0.7874 0.5842)
					(thickness 0.1524)
				)
				(justify left mirror)
			)
		)
		(property "Value" ""
			(at 0 0 90)
			(layer "B.Fab")
			(effects
				(font
					(size 1.27 1.27)
				)
				(justify mirror)
			)
		)
		(duplicate_pad_numbers_are_jumpers no)
		(fp_line
			(start -0.7874 0.4064)
			(end 0.7874 0.4064)
			(stroke
				(width 0.1524)
				(type default)
			)
			(layer "B.SilkS")
		)
		(fp_line
			(start 0.7874 0.4064)
			(end 0.7874 -0.4064)
			(stroke
				(width 0.1524)
				(type default)
			)
			(layer "B.SilkS")
		)
		(fp_line
			(start 0 0.381)
			(end 0 -0.381)
			(stroke
				(width 0.1524)
				(type default)
			)
			(layer "B.SilkS")
		)
		(fp_line
			(start -0.7874 -0.4064)
			(end -0.7874 0.4064)
			(stroke
				(width 0.1524)
				(type default)
			)
			(layer "B.SilkS")
		)
		(fp_line
			(start 0.7874 -0.4064)
			(end -0.7874 -0.4064)
			(stroke
				(width 0.1524)
				(type default)
			)
			(layer "B.SilkS")
		)
		(fp_poly
			(pts
				(xy 0.5334 0.254) (xy 0.635 0.254) (xy 0.635 0.2286) (xy 0.635 -0.254) (xy 0.5334 -0.254) (xy 0.5334 -0.2794)
				(xy -0.5334 -0.2794) (xy -0.5334 -0.254) (xy -0.635 -0.254) (xy -0.635 0.254) (xy -0.5334 0.254)
				(xy -0.5334 0.2794) (xy 0.508 0.2794) (xy 0.5334 0.2794)
			)
			(stroke
				(width 0)
				(type default)
			)
			(fill no)
			(layer "B.CrtYd")
		)
		(pad "1" smd rect
			(at -0.40005 0 90)
			(size 0.4572 0.508)
			(layers "B.Cu" "B.Mask" "B.Paste")
			(net "P1V05_NODE1")
		)
		(pad "2" smd rect
			(at 0.40005 0 90)
			(size 0.4572 0.508)
			(layers "B.Cu" "B.Mask" "B.Paste")
			(net "GND")
		)
	)
	(footprint ""
		(layer "B.Cu")
		(at 141.005052 -148.79955 90)
		(property "Reference" "C863"
			(at -0.104648 -1.36652 0)
			(unlocked yes)
			(layer "B.SilkS")
			(effects
				(font
					(size 0.7874 0.5842)
					(thickness 0.1524)
				)
				(justify left mirror)
			)
		)
		(property "Value" ""
			(at 0 0 90)
			(layer "B.Fab")
			(effects
				(font
					(size 1.27 1.27)
				)
				(justify mirror)
			)
		)
		(duplicate_pad_numbers_are_jumpers no)
		(fp_line
			(start 0.7874 -0.4064)
			(end -0.7874 -0.4064)
			(stroke
				(width 0.1524)
				(type default)
			)
			(layer "B.SilkS")
		)
		(fp_line
			(start -0.7874 -0.4064)
			(end -0.7874 0.4064)
			(stroke
				(width 0.1524)
				(type default)
			)
			(layer "B.SilkS")
		)
		(fp_line
			(start 0 0.381)
			(end 0 -0.381)
			(stroke
				(width 0.1524)
				(type default)
			)
			(layer "B.SilkS")
		)
		(fp_line
			(start 0.7874 0.4064)
			(end 0.7874 -0.4064)
			(stroke
				(width 0.1524)
				(type default)
			)
			(layer "B.SilkS")
		)
		(fp_line
			(start -0.7874 0.4064)
			(end 0.7874 0.4064)
			(stroke
				(width 0.1524)
				(type default)
			)
			(layer "B.SilkS")
		)
		(fp_poly
			(pts
				(xy 0.5334 0.254) (xy 0.635 0.254) (xy 0.635 0.2286) (xy 0.635 -0.254) (xy 0.5334 -0.254) (xy 0.5334 -0.2794)
				(xy -0.5334 -0.2794) (xy -0.5334 -0.254) (xy -0.635 -0.254) (xy -0.635 0.254) (xy -0.5334 0.254)
				(xy -0.5334 0.2794) (xy 0.508 0.2794) (xy 0.5334 0.2794)
			)
			(stroke
				(width 0)
				(type default)
			)
			(fill no)
			(layer "B.CrtYd")
		)
		(pad "1" smd rect
			(at -0.40005 0 270)
			(size 0.4572 0.508)
			(layers "B.Cu" "B.Mask" "B.Paste")
			(net "P1V0_NODE1")
		)
		(pad "2" smd rect
			(at 0.40005 0 270)
			(size 0.4572 0.508)
			(layers "B.Cu" "B.Mask" "B.Paste")
			(net "GND")
		)
	)
	(footprint ""
		(layer "B.Cu")
		(at 108.478066 -132.290566 90)
		(property "Reference" "PR53"
			(at -4.308856 0.196088 270)
			(unlocked yes)
			(layer "B.SilkS")
			(effects
				(font
					(size 0.7874 0.5842)
					(thickness 0.1524)
				)
				(justify left mirror)
			)
		)
		(property "Value" ""
			(at 0 0 90)
			(layer "B.Fab")
			(effects
				(font
					(size 1.27 1.27)
				)
				(justify mirror)
			)
		)
		(duplicate_pad_numbers_are_jumpers no)
		(fp_line
			(start 0.7874 -0.4064)
			(end -0.7874 -0.4064)
			(stroke
				(width 0.1524)
				(type default)
			)
			(layer "B.SilkS")
		)
		(fp_line
			(start -0.7874 -0.4064)
			(end -0.7874 0.4064)
			(stroke
				(width 0.1524)
				(type default)
			)
			(layer "B.SilkS")
		)
		(fp_line
			(start 0.7874 0.4064)
			(end 0.7874 -0.4064)
			(stroke
				(width 0.1524)
				(type default)
			)
			(layer "B.SilkS")
		)
		(fp_line
			(start -0.7874 0.4064)
			(end 0.7874 0.4064)
			(stroke
				(width 0.1524)
				(type default)
			)
			(layer "B.SilkS")
		)
		(fp_poly
			(pts
				(xy 0.508 0.2794) (xy 0.508 0.2286) (xy 0.635 0.2286) (xy 0.635 -0.254) (xy 0.5334 -0.254) (xy 0.5334 -0.2794)
				(xy -0.5334 -0.2794) (xy -0.5334 -0.254) (xy -0.635 -0.254) (xy -0.635 0.254) (xy -0.5334 0.254)
				(xy -0.5334 0.2794)
			)
			(stroke
				(width 0)
				(type default)
			)
			(fill no)
			(layer "B.CrtYd")
		)
		(pad "1" smd rect
			(at -0.40005 0 270)
			(size 0.4572 0.508)
			(layers "B.Cu" "B.Mask" "B.Paste")
			(net "VR_PVCCP_NODE1_LGATE1")
		)
		(pad "2" smd rect
			(at 0.40005 0 270)
			(size 0.4572 0.508)
			(layers "B.Cu" "B.Mask" "B.Paste")
			(net "GND")
		)
	)
	(footprint ""
		(layer "B.Cu")
		(at 52.310538 -56.417718 180)
		(property "Reference" "C113"
			(at -1.715516 -1.493266 0)
			(unlocked yes)
			(layer "B.SilkS")
			(effects
				(font
					(size 0.7874 0.5842)
					(thickness 0.1524)
				)
				(justify left mirror)
			)
		)
		(property "Value" ""
			(at 0 0 0)
			(layer "B.Fab")
			(effects
				(font
					(size 1.27 1.27)
				)
				(justify mirror)
			)
		)
		(duplicate_pad_numbers_are_jumpers no)
		(fp_line
			(start 1.905 0.8636)
			(end 1.905 -0.8636)
			(stroke
				(width 0.1524)
				(type default)
			)
			(layer "B.SilkS")
		)
		(fp_line
			(start 1.905 -0.8636)
			(end -1.905 -0.8636)
			(stroke
				(width 0.1524)
				(type default)
			)
			(layer "B.SilkS")
		)
		(fp_line
			(start 0 0.8382)
			(end 0 -0.8382)
			(stroke
				(width 0.1524)
				(type default)
			)
			(layer "B.SilkS")
		)
		(fp_line
			(start -1.905 0.8636)
			(end 1.905 0.8636)
			(stroke
				(width 0.1524)
				(type default)
			)
			(layer "B.SilkS")
		)
		(fp_line
			(start -1.905 -0.8636)
			(end -1.905 0.8636)
			(stroke
				(width 0.1524)
				(type default)
			)
			(layer "B.SilkS")
		)
		(fp_rect
			(start 1.524 0.7366)
			(end -1.524 -0.7366)
			(stroke
				(width 0)
				(type default)
			)
			(fill no)
			(layer "B.CrtYd")
		)
		(pad "1" smd rect
			(at -0.94996 0)
			(size 1.1176 1.3716)
			(layers "B.Cu" "B.Mask" "B.Paste")
			(net "PV_VDDR_NODE1")
		)
		(pad "2" smd rect
			(at 0.94996 0)
			(size 1.1176 1.3716)
			(layers "B.Cu" "B.Mask" "B.Paste")
			(net "GND")
		)
	)
	(footprint ""
		(layer "B.Cu")
		(at 142.22476 -184.951624 -90)
		(property "Reference" "C738"
			(at -4.357624 2.170938 270)
			(unlocked yes)
			(layer "B.SilkS")
			(effects
				(font
					(size 0.7874 0.5842)
					(thickness 0.1524)
				)
				(justify left mirror)
			)
		)
		(property "Value" ""
			(at 0 0 90)
			(layer "B.Fab")
			(effects
				(font
					(size 1.27 1.27)
				)
				(justify mirror)
			)
		)
		(duplicate_pad_numbers_are_jumpers no)
		(fp_line
			(start -0.7874 0.4064)
			(end 0.7874 0.4064)
			(stroke
				(width 0.1524)
				(type default)
			)
			(layer "B.SilkS")
		)
		(fp_line
			(start 0.7874 0.4064)
			(end 0.7874 -0.4064)
			(stroke
				(width 0.1524)
				(type default)
			)
			(layer "B.SilkS")
		)
		(fp_line
			(start 0 0.381)
			(end 0 -0.381)
			(stroke
				(width 0.1524)
				(type default)
			)
			(layer "B.SilkS")
		)
		(fp_line
			(start -0.7874 -0.4064)
			(end -0.7874 0.4064)
			(stroke
				(width 0.1524)
				(type default)
			)
			(layer "B.SilkS")
		)
		(fp_line
			(start 0.7874 -0.4064)
			(end -0.7874 -0.4064)
			(stroke
				(width 0.1524)
				(type default)
			)
			(layer "B.SilkS")
		)
		(fp_poly
			(pts
				(xy 0.5334 0.254) (xy 0.635 0.254) (xy 0.635 0.2286) (xy 0.635 -0.254) (xy 0.5334 -0.254) (xy 0.5334 -0.2794)
				(xy -0.5334 -0.2794) (xy -0.5334 -0.254) (xy -0.635 -0.254) (xy -0.635 0.254) (xy -0.5334 0.254)
				(xy -0.5334 0.2794) (xy 0.508 0.2794) (xy 0.5334 0.2794)
			)
			(stroke
				(width 0)
				(type default)
			)
			(fill no)
			(layer "B.CrtYd")
		)
		(pad "1" smd rect
			(at -0.40005 0 90)
			(size 0.4572 0.508)
			(layers "B.Cu" "B.Mask" "B.Paste")
			(net "UART_T11_NODE4_RXD")
		)
		(pad "2" smd rect
			(at 0.40005 0 90)
			(size 0.4572 0.508)
			(layers "B.Cu" "B.Mask" "B.Paste")
			(net "GND")
		)
	)
	(footprint ""
		(layer "B.Cu")
		(at 73.649332 -62.6872 -90)
		(property "Reference" "PJ12"
			(at 1.76149 -3.316986 0)
			(unlocked yes)
			(layer "B.SilkS")
			(effects
				(font
					(size 0.7874 0.5842)
					(thickness 0.1524)
				)
				(justify left mirror)
			)
		)
		(property "Value" ""
			(at 0 0 90)
			(layer "B.Fab")
			(effects
				(font
					(size 1.27 1.27)
				)
				(justify mirror)
			)
		)
		(duplicate_pad_numbers_are_jumpers no)
		(fp_poly
			(pts
				(xy -0.2794 0.907796) (xy -0.254 0.907796) (xy -0.254 1.0414) (xy 0.254 1.0414) (xy 0.254 1.034796)
				(xy 0.254 0.933196) (xy 0.2794 0.933196) (xy 0.2794 -0.133604) (xy 0.254 -0.133604) (xy 0.254 -0.235204)
				(xy -0.254 -0.235204) (xy -0.254 -0.133604) (xy -0.2794 -0.133604)
			)
			(stroke
				(width 0)
				(type default)
			)
			(fill no)
			(layer "B.CrtYd")
		)
		(pad "1" smd custom
			(at 0 -0.000254 90)
			(size 0.127 0.127)
			(layers "B.Cu" "B.Mask" "B.Paste")
			(net "VSENSE_PV_VDDR_NODE1_P")
			(options
				(clearance outline)
				(anchor circle)
			)
			(primitives
				(gr_poly
					(pts
						(xy -0.127 -0.508) (xy -0.127 0.0508) (xy -0.254 0.0508) (xy -0.254 0.508) (xy 0.254 0.508) (xy 0.254 0.0508)
						(xy 0.127 0.0508) (xy 0.127 -0.508)
					)
					(width 0)
					(fill yes)
				)
			)
		)
		(pad "2" smd rect
			(at 0 0.799846)
			(size 0.4572 0.508)
			(layers "B.Cu" "B.Mask" "B.Paste")
			(net "PV_VDDR_NODE1")
		)
		(zone
			(layer "B.Cu")
			(hatch none 0.5)
			(connect_pads
				(clearance 0)
			)
			(min_thickness 0.25)
			(keepout
				(tracks allowed)
				(vias not_allowed)
				(pads allowed)
				(copperpour not_allowed)
				(footprints allowed)
			)
			(placement
				(enabled no)
				(sheetname "")
			)
			(fill
				(thermal_gap 0.5)
				(thermal_bridge_width 0.5)
				(island_removal_mode 0)
			)
			(polygon
				(pts
					(xy 72.563736 -62.3824) (xy 72.563736 -62.992) (xy 73.935336 -62.992) (xy 73.935336 -62.3824)
				)
			)
		)
	)
	(footprint ""
		(layer "B.Cu")
		(at 149.497796 -61.18733 180)
		(property "Reference" "C336"
			(at -0.981456 -1.187958 0)
			(unlocked yes)
			(layer "B.SilkS")
			(effects
				(font
					(size 0.7874 0.5842)
					(thickness 0.1524)
				)
				(justify left mirror)
			)
		)
		(property "Value" ""
			(at 0 0 0)
			(layer "B.Fab")
			(effects
				(font
					(size 1.27 1.27)
				)
				(justify mirror)
			)
		)
		(duplicate_pad_numbers_are_jumpers no)
		(fp_line
			(start 0.7874 0.4064)
			(end 0.7874 -0.4064)
			(stroke
				(width 0.1524)
				(type default)
			)
			(layer "B.SilkS")
		)
		(fp_line
			(start 0.7874 -0.4064)
			(end -0.7874 -0.4064)
			(stroke
				(width 0.1524)
				(type default)
			)
			(layer "B.SilkS")
		)
		(fp_line
			(start 0 0.381)
			(end 0 -0.381)
			(stroke
				(width 0.1524)
				(type default)
			)
			(layer "B.SilkS")
		)
		(fp_line
			(start -0.7874 0.4064)
			(end 0.7874 0.4064)
			(stroke
				(width 0.1524)
				(type default)
			)
			(layer "B.SilkS")
		)
		(fp_line
			(start -0.7874 -0.4064)
			(end -0.7874 0.4064)
			(stroke
				(width 0.1524)
				(type default)
			)
			(layer "B.SilkS")
		)
		(fp_poly
			(pts
				(xy 0.5334 0.254) (xy 0.635 0.254) (xy 0.635 0.2286) (xy 0.635 -0.254) (xy 0.5334 -0.254) (xy 0.5334 -0.2794)
				(xy -0.5334 -0.2794) (xy -0.5334 -0.254) (xy -0.635 -0.254) (xy -0.635 0.254) (xy -0.5334 0.254)
				(xy -0.5334 0.2794) (xy 0.508 0.2794) (xy 0.5334 0.2794)
			)
			(stroke
				(width 0)
				(type default)
			)
			(fill no)
			(layer "B.CrtYd")
		)
		(pad "1" smd rect
			(at -0.40005 0)
			(size 0.4572 0.508)
			(layers "B.Cu" "B.Mask" "B.Paste")
			(net "P1V0_SATA")
		)
		(pad "2" smd rect
			(at 0.40005 0)
			(size 0.4572 0.508)
			(layers "B.Cu" "B.Mask" "B.Paste")
			(net "GND")
		)
	)
	(footprint ""
		(layer "B.Cu")
		(at 128.701546 -36.115244)
		(property "Reference" "R1205"
			(at 1.320038 9.11098 0)
			(unlocked yes)
			(layer "B.SilkS")
			(effects
				(font
					(size 0.7874 0.5842)
					(thickness 0.1524)
				)
				(justify left mirror)
			)
		)
		(property "Value" ""
			(at 0 0 0)
			(layer "B.Fab")
			(effects
				(font
					(size 1.27 1.27)
				)
				(justify mirror)
			)
		)
		(duplicate_pad_numbers_are_jumpers no)
		(fp_line
			(start -0.7874 -0.4064)
			(end -0.7874 0.4064)
			(stroke
				(width 0.1524)
				(type default)
			)
			(layer "B.SilkS")
		)
		(fp_line
			(start -0.7874 0.4064)
			(end 0.7874 0.4064)
			(stroke
				(width 0.1524)
				(type default)
			)
			(layer "B.SilkS")
		)
		(fp_line
			(start 0.7874 -0.4064)
			(end -0.7874 -0.4064)
			(stroke
				(width 0.1524)
				(type default)
			)
			(layer "B.SilkS")
		)
		(fp_line
			(start 0.7874 0.4064)
			(end 0.7874 -0.4064)
			(stroke
				(width 0.1524)
				(type default)
			)
			(layer "B.SilkS")
		)
		(fp_poly
			(pts
				(xy 0.508 0.2794) (xy 0.508 0.2286) (xy 0.635 0.2286) (xy 0.635 -0.254) (xy 0.5334 -0.254) (xy 0.5334 -0.2794)
				(xy -0.5334 -0.2794) (xy -0.5334 -0.254) (xy -0.635 -0.254) (xy -0.635 0.254) (xy -0.5334 0.254)
				(xy -0.5334 0.2794)
			)
			(stroke
				(width 0)
				(type default)
			)
			(fill no)
			(layer "B.CrtYd")
		)
		(pad "1" smd rect
			(at -0.40005 0 180)
			(size 0.4572 0.508)
			(layers "B.Cu" "B.Mask" "B.Paste")
			(net "SIO_JTAG_CPLD3_TDI_R")
		)
		(pad "2" smd rect
			(at 0.40005 0 180)
			(size 0.4572 0.508)
			(layers "B.Cu" "B.Mask" "B.Paste")
			(net "SIO_JTAG_CPLD3_TDI")
		)
	)
	(footprint ""
		(layer "B.Cu")
		(at 66.53276 -185.205624 90)
		(property "Reference" "R859"
			(at 4.15163 0.094488 270)
			(unlocked yes)
			(layer "B.SilkS")
			(effects
				(font
					(size 0.7874 0.5842)
					(thickness 0.1524)
				)
				(justify left mirror)
			)
		)
		(property "Value" ""
			(at 0 0 90)
			(layer "B.Fab")
			(effects
				(font
					(size 1.27 1.27)
				)
				(justify mirror)
			)
		)
		(duplicate_pad_numbers_are_jumpers no)
		(fp_line
			(start 0.7874 -0.4064)
			(end -0.7874 -0.4064)
			(stroke
				(width 0.1524)
				(type default)
			)
			(layer "B.SilkS")
		)
		(fp_line
			(start -0.7874 -0.4064)
			(end -0.7874 0.4064)
			(stroke
				(width 0.1524)
				(type default)
			)
			(layer "B.SilkS")
		)
		(fp_line
			(start 0.7874 0.4064)
			(end 0.7874 -0.4064)
			(stroke
				(width 0.1524)
				(type default)
			)
			(layer "B.SilkS")
		)
		(fp_line
			(start -0.7874 0.4064)
			(end 0.7874 0.4064)
			(stroke
				(width 0.1524)
				(type default)
			)
			(layer "B.SilkS")
		)
		(fp_poly
			(pts
				(xy 0.508 0.2794) (xy 0.508 0.2286) (xy 0.635 0.2286) (xy 0.635 -0.254) (xy 0.5334 -0.254) (xy 0.5334 -0.2794)
				(xy -0.5334 -0.2794) (xy -0.5334 -0.254) (xy -0.635 -0.254) (xy -0.635 0.254) (xy -0.5334 0.254)
				(xy -0.5334 0.2794)
			)
			(stroke
				(width 0)
				(type default)
			)
			(fill no)
			(layer "B.CrtYd")
		)
		(pad "1" smd rect
			(at -0.40005 0 270)
			(size 0.4572 0.508)
			(layers "B.Cu" "B.Mask" "B.Paste")
			(net "T1_NODE1_EN")
		)
		(pad "2" smd rect
			(at 0.40005 0 270)
			(size 0.4572 0.508)
			(layers "B.Cu" "B.Mask" "B.Paste")
			(net "T1_NODE1_EN_R")
		)
	)
	(footprint ""
		(layer "B.Cu")
		(at 63.527686 -146.052286 90)
		(property "Reference" "L14"
			(at 1.451356 1.453896 270)
			(unlocked yes)
			(layer "B.SilkS")
			(effects
				(font
					(size 0.7874 0.5842)
					(thickness 0.1524)
				)
				(justify mirror)
			)
		)
		(property "Value" ""
			(at 0 0 90)
			(layer "B.Fab")
			(effects
				(font
					(size 1.27 1.27)
				)
				(justify mirror)
			)
		)
		(duplicate_pad_numbers_are_jumpers no)
		(fp_line
			(start 1.2954 -0.635)
			(end -1.2954 -0.635)
			(stroke
				(width 0.1524)
				(type default)
			)
			(layer "B.SilkS")
		)
		(fp_line
			(start 1.2954 -0.635)
			(end 1.2954 0.635)
			(stroke
				(width 0.1524)
				(type default)
			)
			(layer "B.SilkS")
		)
		(fp_line
			(start -1.2954 -0.635)
			(end -1.2954 0.635)
			(stroke
				(width 0.1524)
				(type default)
			)
			(layer "B.SilkS")
		)
		(fp_line
			(start 0.127 -0.5842)
			(end 0.127 0.5842)
			(stroke
				(width 0.1524)
				(type default)
			)
			(layer "B.SilkS")
		)
		(fp_line
			(start -0.127 -0.5842)
			(end -0.127 0.5842)
			(stroke
				(width 0.1524)
				(type default)
			)
			(layer "B.SilkS")
		)
		(fp_line
			(start -1.2954 0.635)
			(end 1.2954 0.635)
			(stroke
				(width 0.1524)
				(type default)
			)
			(layer "B.SilkS")
		)
		(fp_poly
			(pts
				(xy 0.9144 0.508) (xy 0.9144 0.3556) (xy 1.143 0.3556) (xy 1.143 -0.3556) (xy 0.9144 -0.3556) (xy 0.9144 -0.508)
				(xy -0.9144 -0.508) (xy -0.9144 -0.3556) (xy -1.143 -0.3556) (xy -1.143 0.3556) (xy -0.9144 0.3556)
				(xy -0.9144 0.508)
			)
			(stroke
				(width 0)
				(type default)
			)
			(fill no)
			(layer "B.CrtYd")
		)
		(pad "1" smd rect
			(at -0.7366 0 180)
			(size 0.7112 0.8128)
			(layers "B.Cu" "B.Mask" "B.Paste")
			(net "BMC_NODE1_ADCAV33")
		)
		(pad "2" smd rect
			(at 0.7366 0 180)
			(size 0.7112 0.8128)
			(layers "B.Cu" "B.Mask" "B.Paste")
			(net "P3V3_NODE1")
		)
	)
	(footprint ""
		(layer "B.Cu")
		(at 90.81262 -167.926512)
		(property "Reference" "R784"
			(at 24.609044 20.0152 0)
			(unlocked yes)
			(layer "B.SilkS")
			(effects
				(font
					(size 0.7874 0.5842)
					(thickness 0.1524)
				)
				(justify left mirror)
			)
		)
		(property "Value" ""
			(at 0 0 0)
			(layer "B.Fab")
			(effects
				(font
					(size 1.27 1.27)
				)
				(justify mirror)
			)
		)
		(duplicate_pad_numbers_are_jumpers no)
		(fp_line
			(start -0.7874 -0.4064)
			(end -0.7874 0.4064)
			(stroke
				(width 0.1524)
				(type default)
			)
			(layer "B.SilkS")
		)
		(fp_line
			(start -0.7874 0.4064)
			(end 0.7874 0.4064)
			(stroke
				(width 0.1524)
				(type default)
			)
			(layer "B.SilkS")
		)
		(fp_line
			(start 0.7874 -0.4064)
			(end -0.7874 -0.4064)
			(stroke
				(width 0.1524)
				(type default)
			)
			(layer "B.SilkS")
		)
		(fp_line
			(start 0.7874 0.4064)
			(end 0.7874 -0.4064)
			(stroke
				(width 0.1524)
				(type default)
			)
			(layer "B.SilkS")
		)
		(fp_poly
			(pts
				(xy 0.508 0.2794) (xy 0.508 0.2286) (xy 0.635 0.2286) (xy 0.635 -0.254) (xy 0.5334 -0.254) (xy 0.5334 -0.2794)
				(xy -0.5334 -0.2794) (xy -0.5334 -0.254) (xy -0.635 -0.254) (xy -0.635 0.254) (xy -0.5334 0.254)
				(xy -0.5334 0.2794)
			)
			(stroke
				(width 0)
				(type default)
			)
			(fill no)
			(layer "B.CrtYd")
		)
		(pad "1" smd rect
			(at -0.40005 0 180)
			(size 0.4572 0.508)
			(layers "B.Cu" "B.Mask" "B.Paste")
			(net "UART_SW_S0_N")
		)
		(pad "2" smd rect
			(at 0.40005 0 180)
			(size 0.4572 0.508)
			(layers "B.Cu" "B.Mask" "B.Paste")
			(net "P3V3_NODE1")
		)
	)
	(footprint ""
		(layer "B.Cu")
		(at 133.766052 -135.87095 -90)
		(property "Reference" "C930"
			(at 5.07365 -0.26797 270)
			(unlocked yes)
			(layer "B.SilkS")
			(effects
				(font
					(size 0.7874 0.5842)
					(thickness 0.1524)
				)
				(justify left mirror)
			)
		)
		(property "Value" ""
			(at 0 0 90)
			(layer "B.Fab")
			(effects
				(font
					(size 1.27 1.27)
				)
				(justify mirror)
			)
		)
		(duplicate_pad_numbers_are_jumpers no)
		(fp_line
			(start -0.7874 0.4064)
			(end 0.7874 0.4064)
			(stroke
				(width 0.1524)
				(type default)
			)
			(layer "B.SilkS")
		)
		(fp_line
			(start 0.7874 0.4064)
			(end 0.7874 -0.4064)
			(stroke
				(width 0.1524)
				(type default)
			)
			(layer "B.SilkS")
		)
		(fp_line
			(start 0 0.381)
			(end 0 -0.381)
			(stroke
				(width 0.1524)
				(type default)
			)
			(layer "B.SilkS")
		)
		(fp_line
			(start -0.7874 -0.4064)
			(end -0.7874 0.4064)
			(stroke
				(width 0.1524)
				(type default)
			)
			(layer "B.SilkS")
		)
		(fp_line
			(start 0.7874 -0.4064)
			(end -0.7874 -0.4064)
			(stroke
				(width 0.1524)
				(type default)
			)
			(layer "B.SilkS")
		)
		(fp_poly
			(pts
				(xy 0.5334 0.254) (xy 0.635 0.254) (xy 0.635 0.2286) (xy 0.635 -0.254) (xy 0.5334 -0.254) (xy 0.5334 -0.2794)
				(xy -0.5334 -0.2794) (xy -0.5334 -0.254) (xy -0.635 -0.254) (xy -0.635 0.254) (xy -0.5334 0.254)
				(xy -0.5334 0.2794) (xy 0.508 0.2794) (xy 0.5334 0.2794)
			)
			(stroke
				(width 0)
				(type default)
			)
			(fill no)
			(layer "B.CrtYd")
		)
		(pad "1" smd rect
			(at -0.40005 0 90)
			(size 0.4572 0.508)
			(layers "B.Cu" "B.Mask" "B.Paste")
			(net "P1V0_PCI_SW_A")
		)
		(pad "2" smd rect
			(at 0.40005 0 90)
			(size 0.4572 0.508)
			(layers "B.Cu" "B.Mask" "B.Paste")
			(net "GND")
		)
	)
	(footprint ""
		(layer "B.Cu")
		(at 167.63238 -150.404322)
		(property "Reference" "C449"
			(at 4.681728 0.013716 0)
			(unlocked yes)
			(layer "B.SilkS")
			(effects
				(font
					(size 0.7874 0.5842)
					(thickness 0.1524)
				)
				(justify left mirror)
			)
		)
		(property "Value" ""
			(at 0 0 0)
			(layer "B.Fab")
			(effects
				(font
					(size 1.27 1.27)
				)
				(justify mirror)
			)
		)
		(duplicate_pad_numbers_are_jumpers no)
		(fp_line
			(start -0.7874 -0.4064)
			(end -0.7874 0.4064)
			(stroke
				(width 0.1524)
				(type default)
			)
			(layer "B.SilkS")
		)
		(fp_line
			(start -0.7874 0.4064)
			(end 0.7874 0.4064)
			(stroke
				(width 0.1524)
				(type default)
			)
			(layer "B.SilkS")
		)
		(fp_line
			(start 0 0.381)
			(end 0 -0.381)
			(stroke
				(width 0.1524)
				(type default)
			)
			(layer "B.SilkS")
		)
		(fp_line
			(start 0.7874 -0.4064)
			(end -0.7874 -0.4064)
			(stroke
				(width 0.1524)
				(type default)
			)
			(layer "B.SilkS")
		)
		(fp_line
			(start 0.7874 0.4064)
			(end 0.7874 -0.4064)
			(stroke
				(width 0.1524)
				(type default)
			)
			(layer "B.SilkS")
		)
		(fp_poly
			(pts
				(xy 0.5334 0.254) (xy 0.635 0.254) (xy 0.635 0.2286) (xy 0.635 -0.254) (xy 0.5334 -0.254) (xy 0.5334 -0.2794)
				(xy -0.5334 -0.2794) (xy -0.5334 -0.254) (xy -0.635 -0.254) (xy -0.635 0.254) (xy -0.5334 0.254)
				(xy -0.5334 0.2794) (xy 0.508 0.2794) (xy 0.5334 0.2794)
			)
			(stroke
				(width 0)
				(type default)
			)
			(fill no)
			(layer "B.CrtYd")
		)
		(pad "1" smd rect
			(at -0.40005 0 180)
			(size 0.4572 0.508)
			(layers "B.Cu" "B.Mask" "B.Paste")
			(net "P1V9_LAN2")
		)
		(pad "2" smd rect
			(at 0.40005 0 180)
			(size 0.4572 0.508)
			(layers "B.Cu" "B.Mask" "B.Paste")
			(net "GND")
		)
	)
	(footprint ""
		(layer "B.Cu")
		(at 129.910586 -170.303952)
		(property "Reference" "R988"
			(at 5.461762 -0.475742 0)
			(unlocked yes)
			(layer "B.SilkS")
			(effects
				(font
					(size 0.7874 0.5842)
					(thickness 0.1524)
				)
				(justify left mirror)
			)
		)
		(property "Value" ""
			(at 0 0 0)
			(layer "B.Fab")
			(effects
				(font
					(size 1.27 1.27)
				)
				(justify mirror)
			)
		)
		(duplicate_pad_numbers_are_jumpers no)
		(fp_line
			(start -0.7874 -0.4064)
			(end -0.7874 0.4064)
			(stroke
				(width 0.1524)
				(type default)
			)
			(layer "B.SilkS")
		)
		(fp_line
			(start -0.7874 0.4064)
			(end 0.7874 0.4064)
			(stroke
				(width 0.1524)
				(type default)
			)
			(layer "B.SilkS")
		)
		(fp_line
			(start 0.7874 -0.4064)
			(end -0.7874 -0.4064)
			(stroke
				(width 0.1524)
				(type default)
			)
			(layer "B.SilkS")
		)
		(fp_line
			(start 0.7874 0.4064)
			(end 0.7874 -0.4064)
			(stroke
				(width 0.1524)
				(type default)
			)
			(layer "B.SilkS")
		)
		(fp_poly
			(pts
				(xy 0.508 0.2794) (xy 0.508 0.2286) (xy 0.635 0.2286) (xy 0.635 -0.254) (xy 0.5334 -0.254) (xy 0.5334 -0.2794)
				(xy -0.5334 -0.2794) (xy -0.5334 -0.254) (xy -0.635 -0.254) (xy -0.635 0.254) (xy -0.5334 0.254)
				(xy -0.5334 0.2794)
			)
			(stroke
				(width 0)
				(type default)
			)
			(fill no)
			(layer "B.CrtYd")
		)
		(pad "1" smd rect
			(at -0.40005 0 180)
			(size 0.4572 0.508)
			(layers "B.Cu" "B.Mask" "B.Paste")
			(net "UART_T8_NODE2_TXD")
		)
		(pad "2" smd rect
			(at 0.40005 0 180)
			(size 0.4572 0.508)
			(layers "B.Cu" "B.Mask" "B.Paste")
			(net "UART_T8_NODE2_TXD_R")
		)
	)
	(footprint ""
		(layer "B.Cu")
		(at 78.83144 -168.441624 180)
		(property "Reference" "R779"
			(at -30.603698 -20.736052 0)
			(unlocked yes)
			(layer "B.SilkS")
			(effects
				(font
					(size 0.7874 0.5842)
					(thickness 0.1524)
				)
				(justify left mirror)
			)
		)
		(property "Value" ""
			(at 0 0 0)
			(layer "B.Fab")
			(effects
				(font
					(size 1.27 1.27)
				)
				(justify mirror)
			)
		)
		(duplicate_pad_numbers_are_jumpers no)
		(fp_line
			(start 0.7874 0.4064)
			(end 0.7874 -0.4064)
			(stroke
				(width 0.1524)
				(type default)
			)
			(layer "B.SilkS")
		)
		(fp_line
			(start 0.7874 -0.4064)
			(end -0.7874 -0.4064)
			(stroke
				(width 0.1524)
				(type default)
			)
			(layer "B.SilkS")
		)
		(fp_line
			(start -0.7874 0.4064)
			(end 0.7874 0.4064)
			(stroke
				(width 0.1524)
				(type default)
			)
			(layer "B.SilkS")
		)
		(fp_line
			(start -0.7874 -0.4064)
			(end -0.7874 0.4064)
			(stroke
				(width 0.1524)
				(type default)
			)
			(layer "B.SilkS")
		)
		(fp_poly
			(pts
				(xy 0.508 0.2794) (xy 0.508 0.2286) (xy 0.635 0.2286) (xy 0.635 -0.254) (xy 0.5334 -0.254) (xy 0.5334 -0.2794)
				(xy -0.5334 -0.2794) (xy -0.5334 -0.254) (xy -0.635 -0.254) (xy -0.635 0.254) (xy -0.5334 0.254)
				(xy -0.5334 0.2794)
			)
			(stroke
				(width 0)
				(type default)
			)
			(fill no)
			(layer "B.CrtYd")
		)
		(pad "1" smd rect
			(at -0.40005 0)
			(size 0.4572 0.508)
			(layers "B.Cu" "B.Mask" "B.Paste")
			(net "CM_CABLE_DET_N")
		)
		(pad "2" smd rect
			(at 0.40005 0)
			(size 0.4572 0.508)
			(layers "B.Cu" "B.Mask" "B.Paste")
			(net "P3V3_NODE1")
		)
	)
	(footprint ""
		(layer "B.Cu")
		(at 58.023506 -72.602852 90)
		(property "Reference" "C43"
			(at -33.175194 -14.611096 270)
			(unlocked yes)
			(layer "B.SilkS")
			(effects
				(font
					(size 0.7874 0.5842)
					(thickness 0.1524)
				)
				(justify left mirror)
			)
		)
		(property "Value" ""
			(at 0 0 90)
			(layer "B.Fab")
			(effects
				(font
					(size 1.27 1.27)
				)
				(justify mirror)
			)
		)
		(duplicate_pad_numbers_are_jumpers no)
		(fp_line
			(start 0.7874 -0.4064)
			(end -0.7874 -0.4064)
			(stroke
				(width 0.1524)
				(type default)
			)
			(layer "B.SilkS")
		)
		(fp_line
			(start -0.7874 -0.4064)
			(end -0.7874 0.4064)
			(stroke
				(width 0.1524)
				(type default)
			)
			(layer "B.SilkS")
		)
		(fp_line
			(start 0 0.381)
			(end 0 -0.381)
			(stroke
				(width 0.1524)
				(type default)
			)
			(layer "B.SilkS")
		)
		(fp_line
			(start 0.7874 0.4064)
			(end 0.7874 -0.4064)
			(stroke
				(width 0.1524)
				(type default)
			)
			(layer "B.SilkS")
		)
		(fp_line
			(start -0.7874 0.4064)
			(end 0.7874 0.4064)
			(stroke
				(width 0.1524)
				(type default)
			)
			(layer "B.SilkS")
		)
		(fp_poly
			(pts
				(xy 0.5334 0.254) (xy 0.635 0.254) (xy 0.635 0.2286) (xy 0.635 -0.254) (xy 0.5334 -0.254) (xy 0.5334 -0.2794)
				(xy -0.5334 -0.2794) (xy -0.5334 -0.254) (xy -0.635 -0.254) (xy -0.635 0.254) (xy -0.5334 0.254)
				(xy -0.5334 0.2794) (xy 0.508 0.2794) (xy 0.5334 0.2794)
			)
			(stroke
				(width 0)
				(type default)
			)
			(fill no)
			(layer "B.CrtYd")
		)
		(pad "1" smd rect
			(at -0.40005 0 270)
			(size 0.4572 0.508)
			(layers "B.Cu" "B.Mask" "B.Paste")
			(net "P1V05_NODE1")
		)
		(pad "2" smd rect
			(at 0.40005 0 270)
			(size 0.4572 0.508)
			(layers "B.Cu" "B.Mask" "B.Paste")
			(net "GND")
		)
	)
	(footprint ""
		(layer "B.Cu")
		(at 182.946294 -159.333692 -90)
		(property "Reference" "C522"
			(at -2.555748 0.166116 270)
			(unlocked yes)
			(layer "B.SilkS")
			(effects
				(font
					(size 0.7874 0.5842)
					(thickness 0.1524)
				)
				(justify left mirror)
			)
		)
		(property "Value" ""
			(at 0 0 90)
			(layer "B.Fab")
			(effects
				(font
					(size 1.27 1.27)
				)
				(justify mirror)
			)
		)
		(duplicate_pad_numbers_are_jumpers no)
		(fp_line
			(start -0.7874 0.406146)
			(end 0.7874 0.406146)
			(stroke
				(width 0.1524)
				(type default)
			)
			(layer "B.SilkS")
		)
		(fp_line
			(start 0.7874 0.406146)
			(end 0.7874 -0.406146)
			(stroke
				(width 0.1524)
				(type default)
			)
			(layer "B.SilkS")
		)
		(fp_line
			(start 0 0.381)
			(end 0 -0.381)
			(stroke
				(width 0.1524)
				(type default)
			)
			(layer "B.SilkS")
		)
		(fp_line
			(start -0.7874 -0.406146)
			(end -0.7874 0.406146)
			(stroke
				(width 0.1524)
				(type default)
			)
			(layer "B.SilkS")
		)
		(fp_line
			(start 0.7874 -0.406146)
			(end -0.7874 -0.406146)
			(stroke
				(width 0.1524)
				(type default)
			)
			(layer "B.SilkS")
		)
		(fp_poly
			(pts
				(xy 0.5334 0.254) (xy 0.635 0.254) (xy 0.635 0.2286) (xy 0.635 -0.254) (xy 0.5334 -0.254) (xy 0.5334 -0.2794)
				(xy -0.5334 -0.2794) (xy -0.5334 -0.254) (xy -0.635 -0.254) (xy -0.635 0.254) (xy -0.5334 0.254)
				(xy -0.5334 0.2794) (xy 0.508 0.2794) (xy 0.5334 0.2794)
			)
			(stroke
				(width 0)
				(type default)
			)
			(fill no)
			(layer "B.CrtYd")
		)
		(pad "1" smd rect
			(at -0.40005 0 90)
			(size 0.4572 0.508)
			(layers "B.Cu" "B.Mask" "B.Paste")
			(net "P1V9_LAN2")
		)
		(pad "2" smd rect
			(at 0.40005 0 90)
			(size 0.4572 0.508)
			(layers "B.Cu" "B.Mask" "B.Paste")
			(net "GND")
		)
	)
	(footprint ""
		(layer "B.Cu")
		(at 143.36776 -187.999624 -90)
		(property "Reference" "C735"
			(at -4.438396 1.753362 270)
			(unlocked yes)
			(layer "B.SilkS")
			(effects
				(font
					(size 0.7874 0.5842)
					(thickness 0.1524)
				)
				(justify left mirror)
			)
		)
		(property "Value" ""
			(at 0 0 90)
			(layer "B.Fab")
			(effects
				(font
					(size 1.27 1.27)
				)
				(justify mirror)
			)
		)
		(duplicate_pad_numbers_are_jumpers no)
		(fp_line
			(start -0.7874 0.4064)
			(end 0.7874 0.4064)
			(stroke
				(width 0.1524)
				(type default)
			)
			(layer "B.SilkS")
		)
		(fp_line
			(start 0.7874 0.4064)
			(end 0.7874 -0.4064)
			(stroke
				(width 0.1524)
				(type default)
			)
			(layer "B.SilkS")
		)
		(fp_line
			(start 0 0.381)
			(end 0 -0.381)
			(stroke
				(width 0.1524)
				(type default)
			)
			(layer "B.SilkS")
		)
		(fp_line
			(start -0.7874 -0.4064)
			(end -0.7874 0.4064)
			(stroke
				(width 0.1524)
				(type default)
			)
			(layer "B.SilkS")
		)
		(fp_line
			(start 0.7874 -0.4064)
			(end -0.7874 -0.4064)
			(stroke
				(width 0.1524)
				(type default)
			)
			(layer "B.SilkS")
		)
		(fp_poly
			(pts
				(xy 0.5334 0.254) (xy 0.635 0.254) (xy 0.635 0.2286) (xy 0.635 -0.254) (xy 0.5334 -0.254) (xy 0.5334 -0.2794)
				(xy -0.5334 -0.2794) (xy -0.5334 -0.254) (xy -0.635 -0.254) (xy -0.635 0.254) (xy -0.5334 0.254)
				(xy -0.5334 0.2794) (xy 0.508 0.2794) (xy 0.5334 0.2794)
			)
			(stroke
				(width 0)
				(type default)
			)
			(fill no)
			(layer "B.CrtYd")
		)
		(pad "1" smd rect
			(at -0.40005 0 90)
			(size 0.4572 0.508)
			(layers "B.Cu" "B.Mask" "B.Paste")
			(net "UART_T11_NODE3_TXD_R")
		)
		(pad "2" smd rect
			(at 0.40005 0 90)
			(size 0.4572 0.508)
			(layers "B.Cu" "B.Mask" "B.Paste")
			(net "GND")
		)
	)
	(footprint ""
		(layer "B.Cu")
		(at 159.62376 -184.949338 90)
		(property "Reference" "R906"
			(at 4.23291 -2.05867 270)
			(unlocked yes)
			(layer "B.SilkS")
			(effects
				(font
					(size 0.7874 0.5842)
					(thickness 0.1524)
				)
				(justify left mirror)
			)
		)
		(property "Value" ""
			(at 0 0 90)
			(layer "B.Fab")
			(effects
				(font
					(size 1.27 1.27)
				)
				(justify mirror)
			)
		)
		(duplicate_pad_numbers_are_jumpers no)
		(fp_line
			(start 0.7874 -0.4064)
			(end -0.7874 -0.4064)
			(stroke
				(width 0.1524)
				(type default)
			)
			(layer "B.SilkS")
		)
		(fp_line
			(start -0.7874 -0.4064)
			(end -0.7874 0.4064)
			(stroke
				(width 0.1524)
				(type default)
			)
			(layer "B.SilkS")
		)
		(fp_line
			(start 0.7874 0.4064)
			(end 0.7874 -0.4064)
			(stroke
				(width 0.1524)
				(type default)
			)
			(layer "B.SilkS")
		)
		(fp_line
			(start -0.7874 0.4064)
			(end 0.7874 0.4064)
			(stroke
				(width 0.1524)
				(type default)
			)
			(layer "B.SilkS")
		)
		(fp_poly
			(pts
				(xy 0.508 0.2794) (xy 0.508 0.2286) (xy 0.635 0.2286) (xy 0.635 -0.254) (xy 0.5334 -0.254) (xy 0.5334 -0.2794)
				(xy -0.5334 -0.2794) (xy -0.5334 -0.254) (xy -0.635 -0.254) (xy -0.635 0.254) (xy -0.5334 0.254)
				(xy -0.5334 0.2794)
			)
			(stroke
				(width 0)
				(type default)
			)
			(fill no)
			(layer "B.CrtYd")
		)
		(pad "1" smd rect
			(at -0.40005 0 270)
			(size 0.4572 0.508)
			(layers "B.Cu" "B.Mask" "B.Paste")
			(net "T12_NODE4_EN")
		)
		(pad "2" smd rect
			(at 0.40005 0 270)
			(size 0.4572 0.508)
			(layers "B.Cu" "B.Mask" "B.Paste")
			(net "T12_NODE4_EN_R")
		)
	)
	(footprint ""
		(layer "B.Cu")
		(at 167.674798 -157.109414)
		(property "Reference" "C457"
			(at 6.03758 -0.088646 0)
			(unlocked yes)
			(layer "B.SilkS")
			(effects
				(font
					(size 0.7874 0.5842)
					(thickness 0.1524)
				)
				(justify left mirror)
			)
		)
		(property "Value" ""
			(at 0 0 0)
			(layer "B.Fab")
			(effects
				(font
					(size 1.27 1.27)
				)
				(justify mirror)
			)
		)
		(duplicate_pad_numbers_are_jumpers no)
		(fp_line
			(start -0.7874 -0.4064)
			(end -0.7874 0.4064)
			(stroke
				(width 0.1524)
				(type default)
			)
			(layer "B.SilkS")
		)
		(fp_line
			(start -0.7874 0.4064)
			(end 0.7874 0.4064)
			(stroke
				(width 0.1524)
				(type default)
			)
			(layer "B.SilkS")
		)
		(fp_line
			(start 0 0.381)
			(end 0 -0.381)
			(stroke
				(width 0.1524)
				(type default)
			)
			(layer "B.SilkS")
		)
		(fp_line
			(start 0.7874 -0.4064)
			(end -0.7874 -0.4064)
			(stroke
				(width 0.1524)
				(type default)
			)
			(layer "B.SilkS")
		)
		(fp_line
			(start 0.7874 0.4064)
			(end 0.7874 -0.4064)
			(stroke
				(width 0.1524)
				(type default)
			)
			(layer "B.SilkS")
		)
		(fp_poly
			(pts
				(xy 0.5334 0.254) (xy 0.635 0.254) (xy 0.635 0.2286) (xy 0.635 -0.254) (xy 0.5334 -0.254) (xy 0.5334 -0.2794)
				(xy -0.5334 -0.2794) (xy -0.5334 -0.254) (xy -0.635 -0.254) (xy -0.635 0.254) (xy -0.5334 0.254)
				(xy -0.5334 0.2794) (xy 0.508 0.2794) (xy 0.5334 0.2794)
			)
			(stroke
				(width 0)
				(type default)
			)
			(fill no)
			(layer "B.CrtYd")
		)
		(pad "1" smd rect
			(at -0.40005 0 180)
			(size 0.4572 0.508)
			(layers "B.Cu" "B.Mask" "B.Paste")
			(net "P1V9_LAN2")
		)
		(pad "2" smd rect
			(at 0.40005 0 180)
			(size 0.4572 0.508)
			(layers "B.Cu" "B.Mask" "B.Paste")
			(net "GND")
		)
	)
	(footprint ""
		(layer "B.Cu")
		(at 110.604554 -64.72555 90)
		(property "Reference" "C182"
			(at -2.854452 0.068072 270)
			(unlocked yes)
			(layer "B.SilkS")
			(effects
				(font
					(size 0.7874 0.5842)
					(thickness 0.1524)
				)
				(justify mirror)
			)
		)
		(property "Value" ""
			(at 0 0 90)
			(layer "B.Fab")
			(effects
				(font
					(size 1.27 1.27)
				)
				(justify mirror)
			)
		)
		(duplicate_pad_numbers_are_jumpers no)
		(fp_line
			(start 1.2954 -0.5842)
			(end -1.2954 -0.5842)
			(stroke
				(width 0.1524)
				(type default)
			)
			(layer "B.SilkS")
		)
		(fp_line
			(start 0 -0.5842)
			(end 0 0.5842)
			(stroke
				(width 0.1524)
				(type default)
			)
			(layer "B.SilkS")
		)
		(fp_line
			(start -1.2954 -0.5842)
			(end -1.2954 0.5842)
			(stroke
				(width 0.1524)
				(type default)
			)
			(layer "B.SilkS")
		)
		(fp_line
			(start 1.2954 0.5842)
			(end 1.2954 -0.5842)
			(stroke
				(width 0.1524)
				(type default)
			)
			(layer "B.SilkS")
		)
		(fp_line
			(start -1.2954 0.5842)
			(end 1.2954 0.5842)
			(stroke
				(width 0.1524)
				(type default)
			)
			(layer "B.SilkS")
		)
		(fp_poly
			(pts
				(xy -0.8636 -0.4572) (xy -0.8636 -0.3556) (xy -1.143 -0.3556) (xy -1.143 0.3556) (xy -0.8636 0.3556)
				(xy -0.8636 0.4572) (xy 0.8636 0.4572) (xy 0.8636 0.3556) (xy 1.143 0.3556) (xy 1.143 -0.3556) (xy 0.8636 -0.3556)
				(xy 0.8636 -0.4572)
			)
			(stroke
				(width 0)
				(type default)
			)
			(fill no)
			(layer "B.CrtYd")
		)
		(fp_line
			(start 0.884936 -0.504952)
			(end -0.884936 -0.504952)
			(stroke
				(width 0.1)
				(type default)
			)
			(layer "B.Fab")
		)
		(fp_line
			(start -0.884936 -0.504952)
			(end -0.884936 0.504952)
			(stroke
				(width 0.1)
				(type default)
			)
			(layer "B.Fab")
		)
		(fp_line
			(start 0.884936 0.504952)
			(end 0.884936 -0.504952)
			(stroke
				(width 0.1)
				(type default)
			)
			(layer "B.Fab")
		)
		(fp_line
			(start -0.884936 0.504952)
			(end 0.884936 0.504952)
			(stroke
				(width 0.1)
				(type default)
			)
			(layer "B.Fab")
		)
		(pad "1" smd rect
			(at -0.7366 0 180)
			(size 0.7112 0.8128)
			(layers "B.Cu" "B.Mask" "B.Paste")
			(net "GND")
		)
		(pad "2" smd rect
			(at 0.7366 0 180)
			(size 0.7112 0.8128)
			(layers "B.Cu" "B.Mask" "B.Paste")
			(net "P1V05_STB_NODE1_XDP_A")
		)
	)
	(footprint ""
		(layer "B.Cu")
		(at 136.50976 -184.951624 90)
		(property "Reference" "R870"
			(at 4.357624 -1.8796 270)
			(unlocked yes)
			(layer "B.SilkS")
			(effects
				(font
					(size 0.7874 0.5842)
					(thickness 0.1524)
				)
				(justify left mirror)
			)
		)
		(property "Value" ""
			(at 0 0 90)
			(layer "B.Fab")
			(effects
				(font
					(size 1.27 1.27)
				)
				(justify mirror)
			)
		)
		(duplicate_pad_numbers_are_jumpers no)
		(fp_line
			(start 0.7874 -0.4064)
			(end -0.7874 -0.4064)
			(stroke
				(width 0.1524)
				(type default)
			)
			(layer "B.SilkS")
		)
		(fp_line
			(start -0.7874 -0.4064)
			(end -0.7874 0.4064)
			(stroke
				(width 0.1524)
				(type default)
			)
			(layer "B.SilkS")
		)
		(fp_line
			(start 0.7874 0.4064)
			(end 0.7874 -0.4064)
			(stroke
				(width 0.1524)
				(type default)
			)
			(layer "B.SilkS")
		)
		(fp_line
			(start -0.7874 0.4064)
			(end 0.7874 0.4064)
			(stroke
				(width 0.1524)
				(type default)
			)
			(layer "B.SilkS")
		)
		(fp_poly
			(pts
				(xy 0.508 0.2794) (xy 0.508 0.2286) (xy 0.635 0.2286) (xy 0.635 -0.254) (xy 0.5334 -0.254) (xy 0.5334 -0.2794)
				(xy -0.5334 -0.2794) (xy -0.5334 -0.254) (xy -0.635 -0.254) (xy -0.635 0.254) (xy -0.5334 0.254)
				(xy -0.5334 0.2794)
			)
			(stroke
				(width 0)
				(type default)
			)
			(fill no)
			(layer "B.CrtYd")
		)
		(pad "1" smd rect
			(at -0.40005 0 270)
			(size 0.4572 0.508)
			(layers "B.Cu" "B.Mask" "B.Paste")
			(net "T9_NODE4_EN")
		)
		(pad "2" smd rect
			(at 0.40005 0 270)
			(size 0.4572 0.508)
			(layers "B.Cu" "B.Mask" "B.Paste")
			(net "T9_NODE4_EN_R")
		)
	)
	(footprint ""
		(layer "B.Cu")
		(at 159.501078 -181.995318 90)
		(property "Reference" "R1176"
			(at -0.921004 3.204972 270)
			(unlocked yes)
			(layer "B.SilkS")
			(effects
				(font
					(size 0.7874 0.5842)
					(thickness 0.1524)
				)
				(justify left mirror)
			)
		)
		(property "Value" ""
			(at 0 0 90)
			(layer "B.Fab")
			(effects
				(font
					(size 1.27 1.27)
				)
				(justify mirror)
			)
		)
		(duplicate_pad_numbers_are_jumpers no)
		(fp_line
			(start 0.7874 -0.4064)
			(end -0.7874 -0.4064)
			(stroke
				(width 0.1524)
				(type default)
			)
			(layer "B.SilkS")
		)
		(fp_line
			(start -0.7874 -0.4064)
			(end -0.7874 0.4064)
			(stroke
				(width 0.1524)
				(type default)
			)
			(layer "B.SilkS")
		)
		(fp_line
			(start 0.7874 0.4064)
			(end 0.7874 -0.4064)
			(stroke
				(width 0.1524)
				(type default)
			)
			(layer "B.SilkS")
		)
		(fp_line
			(start -0.7874 0.4064)
			(end 0.7874 0.4064)
			(stroke
				(width 0.1524)
				(type default)
			)
			(layer "B.SilkS")
		)
		(fp_poly
			(pts
				(xy 0.508 0.2794) (xy 0.508 0.2286) (xy 0.635 0.2286) (xy 0.635 -0.254) (xy 0.5334 -0.254) (xy 0.5334 -0.2794)
				(xy -0.5334 -0.2794) (xy -0.5334 -0.254) (xy -0.635 -0.254) (xy -0.635 0.254) (xy -0.5334 0.254)
				(xy -0.5334 0.2794)
			)
			(stroke
				(width 0)
				(type default)
			)
			(fill no)
			(layer "B.CrtYd")
		)
		(pad "1" smd rect
			(at -0.40005 0 270)
			(size 0.4572 0.508)
			(layers "B.Cu" "B.Mask" "B.Paste")
			(net "CPLD_UART_DTR_P4_R_N")
		)
		(pad "2" smd rect
			(at 0.40005 0 270)
			(size 0.4572 0.508)
			(layers "B.Cu" "B.Mask" "B.Paste")
			(net "CPLD_UART_DTR_P4_N")
		)
	)
	(footprint ""
		(layer "B.Cu")
		(at 142.07236 -168.949624)
		(property "Reference" "R734"
			(at -1.237234 0.53086 0)
			(unlocked yes)
			(layer "B.SilkS")
			(effects
				(font
					(size 0.7874 0.5842)
					(thickness 0.1524)
				)
				(justify left mirror)
			)
		)
		(property "Value" ""
			(at 0 0 0)
			(layer "B.Fab")
			(effects
				(font
					(size 1.27 1.27)
				)
				(justify mirror)
			)
		)
		(duplicate_pad_numbers_are_jumpers no)
		(fp_line
			(start -0.7874 -0.4064)
			(end -0.7874 0.4064)
			(stroke
				(width 0.1524)
				(type default)
			)
			(layer "B.SilkS")
		)
		(fp_line
			(start -0.7874 0.4064)
			(end 0.7874 0.4064)
			(stroke
				(width 0.1524)
				(type default)
			)
			(layer "B.SilkS")
		)
		(fp_line
			(start 0.7874 -0.4064)
			(end -0.7874 -0.4064)
			(stroke
				(width 0.1524)
				(type default)
			)
			(layer "B.SilkS")
		)
		(fp_line
			(start 0.7874 0.4064)
			(end 0.7874 -0.4064)
			(stroke
				(width 0.1524)
				(type default)
			)
			(layer "B.SilkS")
		)
		(fp_poly
			(pts
				(xy 0.508 0.2794) (xy 0.508 0.2286) (xy 0.635 0.2286) (xy 0.635 -0.254) (xy 0.5334 -0.254) (xy 0.5334 -0.2794)
				(xy -0.5334 -0.2794) (xy -0.5334 -0.254) (xy -0.635 -0.254) (xy -0.635 0.254) (xy -0.5334 0.254)
				(xy -0.5334 0.2794)
			)
			(stroke
				(width 0)
				(type default)
			)
			(fill no)
			(layer "B.CrtYd")
		)
		(pad "1" smd rect
			(at -0.40005 0 180)
			(size 0.4572 0.508)
			(layers "B.Cu" "B.Mask" "B.Paste")
			(net "P3V3_NODE1")
		)
		(pad "2" smd rect
			(at 0.40005 0 180)
			(size 0.4572 0.508)
			(layers "B.Cu" "B.Mask" "B.Paste")
			(net "N21700156")
		)
	)
	(footprint ""
		(layer "B.Cu")
		(at 57.38876 -185.205624 -90)
		(property "Reference" "C688"
			(at -4.15163 -0.146812 270)
			(unlocked yes)
			(layer "B.SilkS")
			(effects
				(font
					(size 0.7874 0.5842)
					(thickness 0.1524)
				)
				(justify left mirror)
			)
		)
		(property "Value" ""
			(at 0 0 90)
			(layer "B.Fab")
			(effects
				(font
					(size 1.27 1.27)
				)
				(justify mirror)
			)
		)
		(duplicate_pad_numbers_are_jumpers no)
		(fp_line
			(start -0.7874 0.4064)
			(end 0.7874 0.4064)
			(stroke
				(width 0.1524)
				(type default)
			)
			(layer "B.SilkS")
		)
		(fp_line
			(start 0.7874 0.4064)
			(end 0.7874 -0.4064)
			(stroke
				(width 0.1524)
				(type default)
			)
			(layer "B.SilkS")
		)
		(fp_line
			(start 0 0.381)
			(end 0 -0.381)
			(stroke
				(width 0.1524)
				(type default)
			)
			(layer "B.SilkS")
		)
		(fp_line
			(start -0.7874 -0.4064)
			(end -0.7874 0.4064)
			(stroke
				(width 0.1524)
				(type default)
			)
			(layer "B.SilkS")
		)
		(fp_line
			(start 0.7874 -0.4064)
			(end -0.7874 -0.4064)
			(stroke
				(width 0.1524)
				(type default)
			)
			(layer "B.SilkS")
		)
		(fp_poly
			(pts
				(xy 0.5334 0.254) (xy 0.635 0.254) (xy 0.635 0.2286) (xy 0.635 -0.254) (xy 0.5334 -0.254) (xy 0.5334 -0.2794)
				(xy -0.5334 -0.2794) (xy -0.5334 -0.254) (xy -0.635 -0.254) (xy -0.635 0.254) (xy -0.5334 0.254)
				(xy -0.5334 0.2794) (xy 0.508 0.2794) (xy 0.5334 0.2794)
			)
			(stroke
				(width 0)
				(type default)
			)
			(fill no)
			(layer "B.CrtYd")
		)
		(pad "1" smd rect
			(at -0.40005 0 90)
			(size 0.4572 0.508)
			(layers "B.Cu" "B.Mask" "B.Paste")
			(net "UART_T1_NODE4_RXD")
		)
		(pad "2" smd rect
			(at 0.40005 0 90)
			(size 0.4572 0.508)
			(layers "B.Cu" "B.Mask" "B.Paste")
			(net "GND")
		)
	)
	(footprint ""
		(layer "B.Cu")
		(at 121.40184 -141.388592 180)
		(property "Reference" "C187"
			(at 2.075942 -0.081534 0)
			(unlocked yes)
			(layer "B.SilkS")
			(effects
				(font
					(size 0.7874 0.5842)
					(thickness 0.1524)
				)
				(justify left mirror)
			)
		)
		(property "Value" ""
			(at 0 0 0)
			(layer "B.Fab")
			(effects
				(font
					(size 1.27 1.27)
				)
				(justify mirror)
			)
		)
		(duplicate_pad_numbers_are_jumpers no)
		(fp_line
			(start 0.7874 0.4064)
			(end 0.7874 -0.4064)
			(stroke
				(width 0.1524)
				(type default)
			)
			(layer "B.SilkS")
		)
		(fp_line
			(start 0.7874 -0.4064)
			(end -0.7874 -0.4064)
			(stroke
				(width 0.1524)
				(type default)
			)
			(layer "B.SilkS")
		)
		(fp_line
			(start 0 0.381)
			(end 0 -0.381)
			(stroke
				(width 0.1524)
				(type default)
			)
			(layer "B.SilkS")
		)
		(fp_line
			(start -0.7874 0.4064)
			(end 0.7874 0.4064)
			(stroke
				(width 0.1524)
				(type default)
			)
			(layer "B.SilkS")
		)
		(fp_line
			(start -0.7874 -0.4064)
			(end -0.7874 0.4064)
			(stroke
				(width 0.1524)
				(type default)
			)
			(layer "B.SilkS")
		)
		(fp_poly
			(pts
				(xy 0.5334 0.254) (xy 0.635 0.254) (xy 0.635 0.2286) (xy 0.635 -0.254) (xy 0.5334 -0.254) (xy 0.5334 -0.2794)
				(xy -0.5334 -0.2794) (xy -0.5334 -0.254) (xy -0.635 -0.254) (xy -0.635 0.254) (xy -0.5334 0.254)
				(xy -0.5334 0.2794) (xy 0.508 0.2794) (xy 0.5334 0.2794)
			)
			(stroke
				(width 0)
				(type default)
			)
			(fill no)
			(layer "B.CrtYd")
		)
		(pad "1" smd rect
			(at -0.40005 0)
			(size 0.4572 0.508)
			(layers "B.Cu" "B.Mask" "B.Paste")
			(net "P2E_CPU_BMC_NODE1_TX_C_DP")
		)
		(pad "2" smd rect
			(at 0.40005 0)
			(size 0.4572 0.508)
			(layers "B.Cu" "B.Mask" "B.Paste")
			(net "P2E_CPU_BMC_NODE1_TX_DP")
		)
	)
	(footprint ""
		(layer "B.Cu")
		(at 156.83738 -151.877522)
		(property "Reference" "C464"
			(at 1.076198 -1.312926 0)
			(unlocked yes)
			(layer "B.SilkS")
			(effects
				(font
					(size 0.7874 0.5842)
					(thickness 0.1524)
				)
				(justify left mirror)
			)
		)
		(property "Value" ""
			(at 0 0 0)
			(layer "B.Fab")
			(effects
				(font
					(size 1.27 1.27)
				)
				(justify mirror)
			)
		)
		(duplicate_pad_numbers_are_jumpers no)
		(fp_line
			(start -0.7874 -0.4064)
			(end -0.7874 0.4064)
			(stroke
				(width 0.1524)
				(type default)
			)
			(layer "B.SilkS")
		)
		(fp_line
			(start -0.7874 0.4064)
			(end 0.7874 0.4064)
			(stroke
				(width 0.1524)
				(type default)
			)
			(layer "B.SilkS")
		)
		(fp_line
			(start 0 0.381)
			(end 0 -0.381)
			(stroke
				(width 0.1524)
				(type default)
			)
			(layer "B.SilkS")
		)
		(fp_line
			(start 0.7874 -0.4064)
			(end -0.7874 -0.4064)
			(stroke
				(width 0.1524)
				(type default)
			)
			(layer "B.SilkS")
		)
		(fp_line
			(start 0.7874 0.4064)
			(end 0.7874 -0.4064)
			(stroke
				(width 0.1524)
				(type default)
			)
			(layer "B.SilkS")
		)
		(fp_poly
			(pts
				(xy 0.5334 0.254) (xy 0.635 0.254) (xy 0.635 0.2286) (xy 0.635 -0.254) (xy 0.5334 -0.254) (xy 0.5334 -0.2794)
				(xy -0.5334 -0.2794) (xy -0.5334 -0.254) (xy -0.635 -0.254) (xy -0.635 0.254) (xy -0.5334 0.254)
				(xy -0.5334 0.2794) (xy 0.508 0.2794) (xy 0.5334 0.2794)
			)
			(stroke
				(width 0)
				(type default)
			)
			(fill no)
			(layer "B.CrtYd")
		)
		(pad "1" smd rect
			(at -0.40005 0 180)
			(size 0.4572 0.508)
			(layers "B.Cu" "B.Mask" "B.Paste")
			(net "P1V05_LAN2")
		)
		(pad "2" smd rect
			(at 0.40005 0 180)
			(size 0.4572 0.508)
			(layers "B.Cu" "B.Mask" "B.Paste")
			(net "GND")
		)
	)
	(footprint ""
		(layer "B.Cu")
		(at 77.649832 -129.385822 -90)
		(property "Reference" "R1230"
			(at -1.60274 -0.09525 270)
			(unlocked yes)
			(layer "B.SilkS")
			(effects
				(font
					(size 0.7874 0.5842)
					(thickness 0.1524)
				)
				(justify left mirror)
			)
		)
		(property "Value" ""
			(at 0 0 90)
			(layer "B.Fab")
			(effects
				(font
					(size 1.27 1.27)
				)
				(justify mirror)
			)
		)
		(duplicate_pad_numbers_are_jumpers no)
		(fp_line
			(start -0.7874 0.4064)
			(end 0.7874 0.4064)
			(stroke
				(width 0.1524)
				(type default)
			)
			(layer "B.SilkS")
		)
		(fp_line
			(start 0.7874 0.4064)
			(end 0.7874 -0.4064)
			(stroke
				(width 0.1524)
				(type default)
			)
			(layer "B.SilkS")
		)
		(fp_line
			(start -0.7874 -0.4064)
			(end -0.7874 0.4064)
			(stroke
				(width 0.1524)
				(type default)
			)
			(layer "B.SilkS")
		)
		(fp_line
			(start 0.7874 -0.4064)
			(end -0.7874 -0.4064)
			(stroke
				(width 0.1524)
				(type default)
			)
			(layer "B.SilkS")
		)
		(fp_poly
			(pts
				(xy 0.508 0.2794) (xy 0.508 0.2286) (xy 0.635 0.2286) (xy 0.635 -0.254) (xy 0.5334 -0.254) (xy 0.5334 -0.2794)
				(xy -0.5334 -0.2794) (xy -0.5334 -0.254) (xy -0.635 -0.254) (xy -0.635 0.254) (xy -0.5334 0.254)
				(xy -0.5334 0.2794)
			)
			(stroke
				(width 0)
				(type default)
			)
			(fill no)
			(layer "B.CrtYd")
		)
		(pad "1" smd rect
			(at -0.40005 0 90)
			(size 0.4572 0.508)
			(layers "B.Cu" "B.Mask" "B.Paste")
			(net "GND")
		)
		(pad "2" smd rect
			(at 0.40005 0 90)
			(size 0.4572 0.508)
			(layers "B.Cu" "B.Mask" "B.Paste")
			(net "PD_BMC_LPC")
		)
	)
	(footprint ""
		(layer "B.Cu")
		(at 99.059746 -169.380662 -90)
		(property "Reference" "C766"
			(at 0.98552 1.899412 270)
			(unlocked yes)
			(layer "B.SilkS")
			(effects
				(font
					(size 0.7874 0.5842)
					(thickness 0.1524)
				)
				(justify left mirror)
			)
		)
		(property "Value" ""
			(at 0 0 90)
			(layer "B.Fab")
			(effects
				(font
					(size 1.27 1.27)
				)
				(justify mirror)
			)
		)
		(duplicate_pad_numbers_are_jumpers no)
		(fp_line
			(start -0.7874 0.4064)
			(end 0.7874 0.4064)
			(stroke
				(width 0.1524)
				(type default)
			)
			(layer "B.SilkS")
		)
		(fp_line
			(start 0.7874 0.4064)
			(end 0.7874 -0.4064)
			(stroke
				(width 0.1524)
				(type default)
			)
			(layer "B.SilkS")
		)
		(fp_line
			(start 0 0.381)
			(end 0 -0.381)
			(stroke
				(width 0.1524)
				(type default)
			)
			(layer "B.SilkS")
		)
		(fp_line
			(start -0.7874 -0.4064)
			(end -0.7874 0.4064)
			(stroke
				(width 0.1524)
				(type default)
			)
			(layer "B.SilkS")
		)
		(fp_line
			(start 0.7874 -0.4064)
			(end -0.7874 -0.4064)
			(stroke
				(width 0.1524)
				(type default)
			)
			(layer "B.SilkS")
		)
		(fp_poly
			(pts
				(xy 0.5334 0.254) (xy 0.635 0.254) (xy 0.635 0.2286) (xy 0.635 -0.254) (xy 0.5334 -0.254) (xy 0.5334 -0.2794)
				(xy -0.5334 -0.2794) (xy -0.5334 -0.254) (xy -0.635 -0.254) (xy -0.635 0.254) (xy -0.5334 0.254)
				(xy -0.5334 0.2794) (xy 0.508 0.2794) (xy 0.5334 0.2794)
			)
			(stroke
				(width 0)
				(type default)
			)
			(fill no)
			(layer "B.CrtYd")
		)
		(pad "1" smd rect
			(at -0.40005 0 90)
			(size 0.4572 0.508)
			(layers "B.Cu" "B.Mask" "B.Paste")
			(net "P3V3_NODE1")
		)
		(pad "2" smd rect
			(at 0.40005 0 90)
			(size 0.4572 0.508)
			(layers "B.Cu" "B.Mask" "B.Paste")
			(net "GND")
		)
	)
	(footprint ""
		(layer "B.Cu")
		(at 46.750732 -94.40037 -90)
		(property "Reference" "C27"
			(at 4.703318 4.403852 270)
			(unlocked yes)
			(layer "B.SilkS")
			(effects
				(font
					(size 0.7874 0.5842)
					(thickness 0.1524)
				)
				(justify left mirror)
			)
		)
		(property "Value" ""
			(at 0 0 90)
			(layer "B.Fab")
			(effects
				(font
					(size 1.27 1.27)
				)
				(justify mirror)
			)
		)
		(duplicate_pad_numbers_are_jumpers no)
		(fp_line
			(start -0.7874 0.4064)
			(end 0.7874 0.4064)
			(stroke
				(width 0.1524)
				(type default)
			)
			(layer "B.SilkS")
		)
		(fp_line
			(start 0.7874 0.4064)
			(end 0.7874 -0.4064)
			(stroke
				(width 0.1524)
				(type default)
			)
			(layer "B.SilkS")
		)
		(fp_line
			(start 0 0.381)
			(end 0 -0.381)
			(stroke
				(width 0.1524)
				(type default)
			)
			(layer "B.SilkS")
		)
		(fp_line
			(start -0.7874 -0.4064)
			(end -0.7874 0.4064)
			(stroke
				(width 0.1524)
				(type default)
			)
			(layer "B.SilkS")
		)
		(fp_line
			(start 0.7874 -0.4064)
			(end -0.7874 -0.4064)
			(stroke
				(width 0.1524)
				(type default)
			)
			(layer "B.SilkS")
		)
		(fp_poly
			(pts
				(xy 0.5334 0.254) (xy 0.635 0.254) (xy 0.635 0.2286) (xy 0.635 -0.254) (xy 0.5334 -0.254) (xy 0.5334 -0.2794)
				(xy -0.5334 -0.2794) (xy -0.5334 -0.254) (xy -0.635 -0.254) (xy -0.635 0.254) (xy -0.5334 0.254)
				(xy -0.5334 0.2794) (xy 0.508 0.2794) (xy 0.5334 0.2794)
			)
			(stroke
				(width 0)
				(type default)
			)
			(fill no)
			(layer "B.CrtYd")
		)
		(pad "1" smd rect
			(at -0.40005 0 90)
			(size 0.4572 0.508)
			(layers "B.Cu" "B.Mask" "B.Paste")
			(net "GND")
		)
		(pad "2" smd rect
			(at 0.40005 0 90)
			(size 0.4572 0.508)
			(layers "B.Cu" "B.Mask" "B.Paste")
			(net "SMB_CPU_NODE1_XDP_DAT_R")
		)
	)
	(footprint ""
		(layer "B.Cu")
		(at 154.620214 -62.075822 -90)
		(property "Reference" "C355"
			(at 2.829814 -6.081268 270)
			(unlocked yes)
			(layer "B.SilkS")
			(effects
				(font
					(size 0.7874 0.5842)
					(thickness 0.1524)
				)
				(justify left mirror)
			)
		)
		(property "Value" ""
			(at 0 0 90)
			(layer "B.Fab")
			(effects
				(font
					(size 1.27 1.27)
				)
				(justify mirror)
			)
		)
		(duplicate_pad_numbers_are_jumpers no)
		(fp_line
			(start -0.7874 0.4064)
			(end 0.7874 0.4064)
			(stroke
				(width 0.1524)
				(type default)
			)
			(layer "B.SilkS")
		)
		(fp_line
			(start 0.7874 0.4064)
			(end 0.7874 -0.4064)
			(stroke
				(width 0.1524)
				(type default)
			)
			(layer "B.SilkS")
		)
		(fp_line
			(start 0 0.381)
			(end 0 -0.381)
			(stroke
				(width 0.1524)
				(type default)
			)
			(layer "B.SilkS")
		)
		(fp_line
			(start -0.7874 -0.4064)
			(end -0.7874 0.4064)
			(stroke
				(width 0.1524)
				(type default)
			)
			(layer "B.SilkS")
		)
		(fp_line
			(start 0.7874 -0.4064)
			(end -0.7874 -0.4064)
			(stroke
				(width 0.1524)
				(type default)
			)
			(layer "B.SilkS")
		)
		(fp_poly
			(pts
				(xy 0.5334 0.254) (xy 0.635 0.254) (xy 0.635 0.2286) (xy 0.635 -0.254) (xy 0.5334 -0.254) (xy 0.5334 -0.2794)
				(xy -0.5334 -0.2794) (xy -0.5334 -0.254) (xy -0.635 -0.254) (xy -0.635 0.254) (xy -0.5334 0.254)
				(xy -0.5334 0.2794) (xy 0.508 0.2794) (xy 0.5334 0.2794)
			)
			(stroke
				(width 0)
				(type default)
			)
			(fill no)
			(layer "B.CrtYd")
		)
		(pad "1" smd rect
			(at -0.40005 0 90)
			(size 0.4572 0.508)
			(layers "B.Cu" "B.Mask" "B.Paste")
			(net "P1V8_SATA_VAA2_1_NODE1")
		)
		(pad "2" smd rect
			(at 0.40005 0 90)
			(size 0.4572 0.508)
			(layers "B.Cu" "B.Mask" "B.Paste")
			(net "GND")
		)
	)
	(footprint ""
		(layer "B.Cu")
		(at 135.196834 -34.327084)
		(property "Reference" "R1185"
			(at -5.415788 18.52295 0)
			(unlocked yes)
			(layer "B.SilkS")
			(effects
				(font
					(size 0.7874 0.5842)
					(thickness 0.1524)
				)
				(justify left mirror)
			)
		)
		(property "Value" ""
			(at 0 0 0)
			(layer "B.Fab")
			(effects
				(font
					(size 1.27 1.27)
				)
				(justify mirror)
			)
		)
		(duplicate_pad_numbers_are_jumpers no)
		(fp_line
			(start -0.7874 -0.4064)
			(end -0.7874 0.4064)
			(stroke
				(width 0.1524)
				(type default)
			)
			(layer "B.SilkS")
		)
		(fp_line
			(start -0.7874 0.4064)
			(end 0.7874 0.4064)
			(stroke
				(width 0.1524)
				(type default)
			)
			(layer "B.SilkS")
		)
		(fp_line
			(start 0.7874 -0.4064)
			(end -0.7874 -0.4064)
			(stroke
				(width 0.1524)
				(type default)
			)
			(layer "B.SilkS")
		)
		(fp_line
			(start 0.7874 0.4064)
			(end 0.7874 -0.4064)
			(stroke
				(width 0.1524)
				(type default)
			)
			(layer "B.SilkS")
		)
		(fp_poly
			(pts
				(xy 0.508 0.2794) (xy 0.508 0.2286) (xy 0.635 0.2286) (xy 0.635 -0.254) (xy 0.5334 -0.254) (xy 0.5334 -0.2794)
				(xy -0.5334 -0.2794) (xy -0.5334 -0.254) (xy -0.635 -0.254) (xy -0.635 0.254) (xy -0.5334 0.254)
				(xy -0.5334 0.2794)
			)
			(stroke
				(width 0)
				(type default)
			)
			(fill no)
			(layer "B.CrtYd")
		)
		(pad "1" smd rect
			(at -0.40005 0 180)
			(size 0.4572 0.508)
			(layers "B.Cu" "B.Mask" "B.Paste")
			(net "CPLD123_RSV3")
		)
		(pad "2" smd rect
			(at 0.40005 0 180)
			(size 0.4572 0.508)
			(layers "B.Cu" "B.Mask" "B.Paste")
			(net "SIO_CPLD_RSV3_R")
		)
	)
	(footprint ""
		(layer "B.Cu")
		(at 38.280086 -129.121662 -90)
		(property "Reference" "C230"
			(at 1.251458 1.138428 270)
			(unlocked yes)
			(layer "B.SilkS")
			(effects
				(font
					(size 0.7874 0.5842)
					(thickness 0.1524)
				)
				(justify left mirror)
			)
		)
		(property "Value" ""
			(at 0 0 90)
			(layer "B.Fab")
			(effects
				(font
					(size 1.27 1.27)
				)
				(justify mirror)
			)
		)
		(duplicate_pad_numbers_are_jumpers no)
		(fp_line
			(start -0.7874 0.4064)
			(end 0.7874 0.4064)
			(stroke
				(width 0.1524)
				(type default)
			)
			(layer "B.SilkS")
		)
		(fp_line
			(start 0.7874 0.4064)
			(end 0.7874 -0.4064)
			(stroke
				(width 0.1524)
				(type default)
			)
			(layer "B.SilkS")
		)
		(fp_line
			(start 0 0.381)
			(end 0 -0.381)
			(stroke
				(width 0.1524)
				(type default)
			)
			(layer "B.SilkS")
		)
		(fp_line
			(start -0.7874 -0.4064)
			(end -0.7874 0.4064)
			(stroke
				(width 0.1524)
				(type default)
			)
			(layer "B.SilkS")
		)
		(fp_line
			(start 0.7874 -0.4064)
			(end -0.7874 -0.4064)
			(stroke
				(width 0.1524)
				(type default)
			)
			(layer "B.SilkS")
		)
		(fp_poly
			(pts
				(xy 0.5334 0.254) (xy 0.635 0.254) (xy 0.635 0.2286) (xy 0.635 -0.254) (xy 0.5334 -0.254) (xy 0.5334 -0.2794)
				(xy -0.5334 -0.2794) (xy -0.5334 -0.254) (xy -0.635 -0.254) (xy -0.635 0.254) (xy -0.5334 0.254)
				(xy -0.5334 0.2794) (xy 0.508 0.2794) (xy 0.5334 0.2794)
			)
			(stroke
				(width 0)
				(type default)
			)
			(fill no)
			(layer "B.CrtYd")
		)
		(pad "1" smd rect
			(at -0.40005 0 90)
			(size 0.4572 0.508)
			(layers "B.Cu" "B.Mask" "B.Paste")
			(net "P1V538_BMC_NODE1")
		)
		(pad "2" smd rect
			(at 0.40005 0 90)
			(size 0.4572 0.508)
			(layers "B.Cu" "B.Mask" "B.Paste")
			(net "GND")
		)
	)
	(footprint ""
		(layer "B.Cu")
		(at 162.296602 -175.827436 -90)
		(property "Reference" "U59"
			(at 5.79755 0.536956 0)
			(unlocked yes)
			(layer "B.SilkS")
			(effects
				(font
					(size 0.7874 0.5842)
					(thickness 0.1524)
				)
				(justify left mirror)
			)
		)
		(property "Value" ""
			(at 0 0 90)
			(layer "B.Fab")
			(effects
				(font
					(size 1.27 1.27)
				)
				(justify mirror)
			)
		)
		(duplicate_pad_numbers_are_jumpers no)
		(fp_line
			(start -4.9022 2.0066)
			(end 4.9022 2.0066)
			(stroke
				(width 0.1524)
				(type default)
			)
			(layer "B.SilkS")
		)
		(fp_line
			(start 4.9022 2.0066)
			(end 4.9022 0.5842)
			(stroke
				(width 0.1524)
				(type default)
			)
			(layer "B.SilkS")
		)
		(fp_line
			(start 4.9022 0.5842)
			(end 4.318 0)
			(stroke
				(width 0.1524)
				(type default)
			)
			(layer "B.SilkS")
		)
		(fp_line
			(start 4.318 0)
			(end 4.9022 -0.5842)
			(stroke
				(width 0.1524)
				(type default)
			)
			(layer "B.SilkS")
		)
		(fp_line
			(start 4.9022 -0.5842)
			(end 4.9022 -2.0066)
			(stroke
				(width 0.1524)
				(type default)
			)
			(layer "B.SilkS")
		)
		(fp_line
			(start -4.9022 -2.0066)
			(end -4.9022 2.0066)
			(stroke
				(width 0.1524)
				(type default)
			)
			(layer "B.SilkS")
		)
		(fp_line
			(start 4.9022 -2.0066)
			(end -4.9022 -2.0066)
			(stroke
				(width 0.1524)
				(type default)
			)
			(layer "B.SilkS")
		)
		(fp_circle
			(center 4.318 1.524)
			(end 4.318 1.27)
			(stroke
				(width 0.1524)
				(type default)
			)
			(fill no)
			(layer "B.SilkS")
		)
		(fp_rect
			(start 4.9022 3.6703)
			(end -4.9022 -3.6703)
			(stroke
				(width 0)
				(type default)
			)
			(fill no)
			(layer "B.CrtYd")
		)
		(pad "1" smd rect
			(at 4.225036 2.921 90)
			(size 0.3556 1.4986)
			(layers "B.Cu" "B.Mask" "B.Paste")
			(net "N54365827")
		)
		(pad "2" smd rect
			(at 3.57505 2.921 90)
			(size 0.3556 1.4986)
			(layers "B.Cu" "B.Mask" "B.Paste")
			(net "N54365829")
		)
		(pad "3" smd rect
			(at 2.925064 2.921 90)
			(size 0.3556 1.4986)
			(layers "B.Cu" "B.Mask" "B.Paste")
			(net "N54365837")
		)
		(pad "4" smd rect
			(at 2.275078 2.921 90)
			(size 0.3556 1.4986)
			(layers "B.Cu" "B.Mask" "B.Paste")
			(net "UART_RX_RP6_L")
		)
		(pad "5" smd rect
			(at 1.625092 2.921 90)
			(size 0.3556 1.4986)
			(layers "B.Cu" "B.Mask" "B.Paste")
			(net "UART_RI_RP6_L_N")
		)
		(pad "6" smd rect
			(at 0.975106 2.921 90)
			(size 0.3556 1.4986)
			(layers "B.Cu" "B.Mask" "B.Paste")
			(net "N54365764")
		)
		(pad "7" smd rect
			(at 0.32512 2.921 90)
			(size 0.3556 1.4986)
			(layers "B.Cu" "B.Mask" "B.Paste")
			(net "N54365764")
		)
		(pad "8" smd rect
			(at -0.32512 2.921 90)
			(size 0.3556 1.4986)
			(layers "B.Cu" "B.Mask" "B.Paste")
			(net "N54365764")
		)
		(pad "9" smd rect
			(at -0.975106 2.921 90)
			(size 0.3556 1.4986)
			(layers "B.Cu" "B.Mask" "B.Paste")
			(net "UART_RTS_RP6_L_N")
		)
		(pad "10" smd rect
			(at -1.625092 2.921 90)
			(size 0.3556 1.4986)
			(layers "B.Cu" "B.Mask" "B.Paste")
			(net "UART_TX_RP6_L")
		)
		(pad "11" smd rect
			(at -2.275078 2.921 90)
			(size 0.3556 1.4986)
			(layers "B.Cu" "B.Mask" "B.Paste")
			(net "UART_DTR_RP6_L_N")
		)
		(pad "12" smd rect
			(at -2.925064 2.921 90)
			(size 0.3556 1.4986)
			(layers "B.Cu" "B.Mask" "B.Paste")
			(net "CPLD_UART_DTR_P4_R_N")
		)
		(pad "13" smd rect
			(at -3.57505 2.921 90)
			(size 0.3556 1.4986)
			(layers "B.Cu" "B.Mask" "B.Paste")
			(net "CPLD_UART_TX_P4")
		)
		(pad "14" smd rect
			(at -4.225036 2.921 90)
			(size 0.3556 1.4986)
			(layers "B.Cu" "B.Mask" "B.Paste")
			(net "CPLD_UART_RTS_P4_R_N")
		)
		(pad "15" smd rect
			(at -4.225036 -2.921 90)
			(size 0.3556 1.4986)
			(layers "B.Cu" "B.Mask" "B.Paste")
			(net "Net_2293")
		)
		(pad "16" smd rect
			(at -3.57505 -2.921 90)
			(size 0.3556 1.4986)
			(layers "B.Cu" "B.Mask" "B.Paste")
			(net "Net_2294")
		)
		(pad "17" smd rect
			(at -2.925064 -2.921 90)
			(size 0.3556 1.4986)
			(layers "B.Cu" "B.Mask" "B.Paste")
			(net "Net_2295")
		)
		(pad "18" smd rect
			(at -2.275078 -2.921 90)
			(size 0.3556 1.4986)
			(layers "B.Cu" "B.Mask" "B.Paste")
			(net "CPLD_UART_RI_P4_LS_N")
		)
		(pad "19" smd rect
			(at -1.625092 -2.921 90)
			(size 0.3556 1.4986)
			(layers "B.Cu" "B.Mask" "B.Paste")
			(net "CPLD_UART_RX_P4_R")
		)
		(pad "20" smd rect
			(at -0.975106 -2.921 90)
			(size 0.3556 1.4986)
			(layers "B.Cu" "B.Mask" "B.Paste")
			(net "Net_2296")
		)
		(pad "21" smd rect
			(at -0.32512 -2.921 90)
			(size 0.3556 1.4986)
			(layers "B.Cu" "B.Mask" "B.Paste")
			(net "Net_2297")
		)
		(pad "22" smd rect
			(at 0.32512 -2.921 90)
			(size 0.3556 1.4986)
			(layers "B.Cu" "B.Mask" "B.Paste")
			(net "N54365776")
		)
		(pad "23" smd rect
			(at 0.975106 -2.921 90)
			(size 0.3556 1.4986)
			(layers "B.Cu" "B.Mask" "B.Paste")
			(net "N54365772")
		)
		(pad "24" smd rect
			(at 1.625092 -2.921 90)
			(size 0.3556 1.4986)
			(layers "B.Cu" "B.Mask" "B.Paste")
			(net "N54365823")
		)
		(pad "25" smd rect
			(at 2.275078 -2.921 90)
			(size 0.3556 1.4986)
			(layers "B.Cu" "B.Mask" "B.Paste")
			(net "GND")
		)
		(pad "26" smd rect
			(at 2.925064 -2.921 90)
			(size 0.3556 1.4986)
			(layers "B.Cu" "B.Mask" "B.Paste")
			(net "P3V3_NODE1")
		)
		(pad "27" smd rect
			(at 3.57505 -2.921 90)
			(size 0.3556 1.4986)
			(layers "B.Cu" "B.Mask" "B.Paste")
			(net "N54365835")
		)
		(pad "28" smd rect
			(at 4.225036 -2.921 90)
			(size 0.3556 1.4986)
			(layers "B.Cu" "B.Mask" "B.Paste")
			(net "N54365821")
		)
	)
	(footprint ""
		(layer "B.Cu")
		(at 68.314062 -29.394658 -90)
		(property "Reference" "R203"
			(at -1.23444 0.149352 270)
			(unlocked yes)
			(layer "B.SilkS")
			(effects
				(font
					(size 0.7874 0.5842)
					(thickness 0.1524)
				)
				(justify left mirror)
			)
		)
		(property "Value" ""
			(at 0 0 90)
			(layer "B.Fab")
			(effects
				(font
					(size 1.27 1.27)
				)
				(justify mirror)
			)
		)
		(duplicate_pad_numbers_are_jumpers no)
		(fp_line
			(start -0.7874 0.4064)
			(end 0.7874 0.4064)
			(stroke
				(width 0.1524)
				(type default)
			)
			(layer "B.SilkS")
		)
		(fp_line
			(start 0.7874 0.4064)
			(end 0.7874 -0.4064)
			(stroke
				(width 0.1524)
				(type default)
			)
			(layer "B.SilkS")
		)
		(fp_line
			(start -0.7874 -0.4064)
			(end -0.7874 0.4064)
			(stroke
				(width 0.1524)
				(type default)
			)
			(layer "B.SilkS")
		)
		(fp_line
			(start 0.7874 -0.4064)
			(end -0.7874 -0.4064)
			(stroke
				(width 0.1524)
				(type default)
			)
			(layer "B.SilkS")
		)
		(fp_poly
			(pts
				(xy 0.508 0.2794) (xy 0.508 0.2286) (xy 0.635 0.2286) (xy 0.635 -0.254) (xy 0.5334 -0.254) (xy 0.5334 -0.2794)
				(xy -0.5334 -0.2794) (xy -0.5334 -0.254) (xy -0.635 -0.254) (xy -0.635 0.254) (xy -0.5334 0.254)
				(xy -0.5334 0.2794)
			)
			(stroke
				(width 0)
				(type default)
			)
			(fill no)
			(layer "B.CrtYd")
		)
		(pad "1" smd rect
			(at -0.40005 0 90)
			(size 0.4572 0.508)
			(layers "B.Cu" "B.Mask" "B.Paste")
			(net "P1V5_NODE1_DDR3_VREF_A_A")
		)
		(pad "2" smd rect
			(at 0.40005 0 90)
			(size 0.4572 0.508)
			(layers "B.Cu" "B.Mask" "B.Paste")
			(net "GND")
		)
	)
	(footprint ""
		(layer "B.Cu")
		(at 47.10176 -185.205624 -90)
		(property "Reference" "R847"
			(at -4.15163 -0.163068 270)
			(unlocked yes)
			(layer "B.SilkS")
			(effects
				(font
					(size 0.7874 0.5842)
					(thickness 0.1524)
				)
				(justify left mirror)
			)
		)
		(property "Value" ""
			(at 0 0 90)
			(layer "B.Fab")
			(effects
				(font
					(size 1.27 1.27)
				)
				(justify mirror)
			)
		)
		(duplicate_pad_numbers_are_jumpers no)
		(fp_line
			(start -0.7874 0.4064)
			(end 0.7874 0.4064)
			(stroke
				(width 0.1524)
				(type default)
			)
			(layer "B.SilkS")
		)
		(fp_line
			(start 0.7874 0.4064)
			(end 0.7874 -0.4064)
			(stroke
				(width 0.1524)
				(type default)
			)
			(layer "B.SilkS")
		)
		(fp_line
			(start -0.7874 -0.4064)
			(end -0.7874 0.4064)
			(stroke
				(width 0.1524)
				(type default)
			)
			(layer "B.SilkS")
		)
		(fp_line
			(start 0.7874 -0.4064)
			(end -0.7874 -0.4064)
			(stroke
				(width 0.1524)
				(type default)
			)
			(layer "B.SilkS")
		)
		(fp_poly
			(pts
				(xy 0.508 0.2794) (xy 0.508 0.2286) (xy 0.635 0.2286) (xy 0.635 -0.254) (xy 0.5334 -0.254) (xy 0.5334 -0.2794)
				(xy -0.5334 -0.2794) (xy -0.5334 -0.254) (xy -0.635 -0.254) (xy -0.635 0.254) (xy -0.5334 0.254)
				(xy -0.5334 0.2794)
			)
			(stroke
				(width 0)
				(type default)
			)
			(fill no)
			(layer "B.CrtYd")
		)
		(pad "1" smd rect
			(at -0.40005 0 90)
			(size 0.4572 0.508)
			(layers "B.Cu" "B.Mask" "B.Paste")
			(net "PSU6_DC_OK_R")
		)
		(pad "2" smd rect
			(at 0.40005 0 90)
			(size 0.4572 0.508)
			(layers "B.Cu" "B.Mask" "B.Paste")
			(net "PSU6_DC_OK_R_BUF")
		)
	)
	(footprint ""
		(layer "B.Cu")
		(at 35.86988 -64.748156 180)
		(property "Reference" "C19"
			(at 2.232406 0.057658 0)
			(unlocked yes)
			(layer "B.SilkS")
			(effects
				(font
					(size 0.7874 0.5842)
					(thickness 0.1524)
				)
				(justify left mirror)
			)
		)
		(property "Value" ""
			(at 0 0 0)
			(layer "B.Fab")
			(effects
				(font
					(size 1.27 1.27)
				)
				(justify mirror)
			)
		)
		(duplicate_pad_numbers_are_jumpers no)
		(fp_line
			(start 0.7874 0.4064)
			(end 0.7874 -0.4064)
			(stroke
				(width 0.1524)
				(type default)
			)
			(layer "B.SilkS")
		)
		(fp_line
			(start 0.7874 -0.4064)
			(end -0.7874 -0.4064)
			(stroke
				(width 0.1524)
				(type default)
			)
			(layer "B.SilkS")
		)
		(fp_line
			(start 0 0.381)
			(end 0 -0.381)
			(stroke
				(width 0.1524)
				(type default)
			)
			(layer "B.SilkS")
		)
		(fp_line
			(start -0.7874 0.4064)
			(end 0.7874 0.4064)
			(stroke
				(width 0.1524)
				(type default)
			)
			(layer "B.SilkS")
		)
		(fp_line
			(start -0.7874 -0.4064)
			(end -0.7874 0.4064)
			(stroke
				(width 0.1524)
				(type default)
			)
			(layer "B.SilkS")
		)
		(fp_poly
			(pts
				(xy 0.5334 0.254) (xy 0.635 0.254) (xy 0.635 0.2286) (xy 0.635 -0.254) (xy 0.5334 -0.254) (xy 0.5334 -0.2794)
				(xy -0.5334 -0.2794) (xy -0.5334 -0.254) (xy -0.635 -0.254) (xy -0.635 0.254) (xy -0.5334 0.254)
				(xy -0.5334 0.2794) (xy 0.508 0.2794) (xy 0.5334 0.2794)
			)
			(stroke
				(width 0)
				(type default)
			)
			(fill no)
			(layer "B.CrtYd")
		)
		(pad "1" smd rect
			(at -0.40005 0)
			(size 0.4572 0.508)
			(layers "B.Cu" "B.Mask" "B.Paste")
			(net "P2E_CPU_NIC1_NODE1_TX_C_DP")
		)
		(pad "2" smd rect
			(at 0.40005 0)
			(size 0.4572 0.508)
			(layers "B.Cu" "B.Mask" "B.Paste")
			(net "P2E_CPU_NIC1_NODE1_TX_DP")
		)
	)
	(footprint ""
		(layer "B.Cu")
		(at 61.96076 -188.126624 90)
		(property "Reference" "R913"
			(at 4.276598 -0.10922 270)
			(unlocked yes)
			(layer "B.SilkS")
			(effects
				(font
					(size 0.7874 0.5842)
					(thickness 0.1524)
				)
				(justify left mirror)
			)
		)
		(property "Value" ""
			(at 0 0 90)
			(layer "B.Fab")
			(effects
				(font
					(size 1.27 1.27)
				)
				(justify mirror)
			)
		)
		(duplicate_pad_numbers_are_jumpers no)
		(fp_line
			(start 0.7874 -0.4064)
			(end -0.7874 -0.4064)
			(stroke
				(width 0.1524)
				(type default)
			)
			(layer "B.SilkS")
		)
		(fp_line
			(start -0.7874 -0.4064)
			(end -0.7874 0.4064)
			(stroke
				(width 0.1524)
				(type default)
			)
			(layer "B.SilkS")
		)
		(fp_line
			(start 0.7874 0.4064)
			(end 0.7874 -0.4064)
			(stroke
				(width 0.1524)
				(type default)
			)
			(layer "B.SilkS")
		)
		(fp_line
			(start -0.7874 0.4064)
			(end 0.7874 0.4064)
			(stroke
				(width 0.1524)
				(type default)
			)
			(layer "B.SilkS")
		)
		(fp_poly
			(pts
				(xy 0.508 0.2794) (xy 0.508 0.2286) (xy 0.635 0.2286) (xy 0.635 -0.254) (xy 0.5334 -0.254) (xy 0.5334 -0.2794)
				(xy -0.5334 -0.2794) (xy -0.5334 -0.254) (xy -0.635 -0.254) (xy -0.635 0.254) (xy -0.5334 0.254)
				(xy -0.5334 0.2794)
			)
			(stroke
				(width 0)
				(type default)
			)
			(fill no)
			(layer "B.CrtYd")
		)
		(pad "1" smd rect
			(at -0.40005 0 270)
			(size 0.4572 0.508)
			(layers "B.Cu" "B.Mask" "B.Paste")
			(net "UART_T1_NODE2_RXD")
		)
		(pad "2" smd rect
			(at 0.40005 0 270)
			(size 0.4572 0.508)
			(layers "B.Cu" "B.Mask" "B.Paste")
			(net "UART_T1_NODE2_RXD_R")
		)
	)
	(footprint ""
		(layer "B.Cu")
		(at 106.28376 -188.126624 -90)
		(property "Reference" "C659"
			(at -4.10337 0.150368 270)
			(unlocked yes)
			(layer "B.SilkS")
			(effects
				(font
					(size 0.7874 0.5842)
					(thickness 0.1524)
				)
				(justify left mirror)
			)
		)
		(property "Value" ""
			(at 0 0 90)
			(layer "B.Fab")
			(effects
				(font
					(size 1.27 1.27)
				)
				(justify mirror)
			)
		)
		(duplicate_pad_numbers_are_jumpers no)
		(fp_line
			(start -0.7874 0.4064)
			(end 0.7874 0.4064)
			(stroke
				(width 0.1524)
				(type default)
			)
			(layer "B.SilkS")
		)
		(fp_line
			(start 0.7874 0.4064)
			(end 0.7874 -0.4064)
			(stroke
				(width 0.1524)
				(type default)
			)
			(layer "B.SilkS")
		)
		(fp_line
			(start 0 0.381)
			(end 0 -0.381)
			(stroke
				(width 0.1524)
				(type default)
			)
			(layer "B.SilkS")
		)
		(fp_line
			(start -0.7874 -0.4064)
			(end -0.7874 0.4064)
			(stroke
				(width 0.1524)
				(type default)
			)
			(layer "B.SilkS")
		)
		(fp_line
			(start 0.7874 -0.4064)
			(end -0.7874 -0.4064)
			(stroke
				(width 0.1524)
				(type default)
			)
			(layer "B.SilkS")
		)
		(fp_poly
			(pts
				(xy 0.5334 0.254) (xy 0.635 0.254) (xy 0.635 0.2286) (xy 0.635 -0.254) (xy 0.5334 -0.254) (xy 0.5334 -0.2794)
				(xy -0.5334 -0.2794) (xy -0.5334 -0.254) (xy -0.635 -0.254) (xy -0.635 0.254) (xy -0.5334 0.254)
				(xy -0.5334 0.2794) (xy 0.508 0.2794) (xy 0.5334 0.2794)
			)
			(stroke
				(width 0)
				(type default)
			)
			(fill no)
			(layer "B.CrtYd")
		)
		(pad "1" smd rect
			(at -0.40005 0 90)
			(size 0.4572 0.508)
			(layers "B.Cu" "B.Mask" "B.Paste")
			(net "T5_NODE1_EN_R")
		)
		(pad "2" smd rect
			(at 0.40005 0 90)
			(size 0.4572 0.508)
			(layers "B.Cu" "B.Mask" "B.Paste")
			(net "GND")
		)
	)
	(footprint ""
		(layer "B.Cu")
		(at 130.526282 -36.116006)
		(property "Reference" "R1206"
			(at 5.29463 3.511804 0)
			(unlocked yes)
			(layer "B.SilkS")
			(effects
				(font
					(size 0.7874 0.5842)
					(thickness 0.1524)
				)
				(justify left mirror)
			)
		)
		(property "Value" ""
			(at 0 0 0)
			(layer "B.Fab")
			(effects
				(font
					(size 1.27 1.27)
				)
				(justify mirror)
			)
		)
		(duplicate_pad_numbers_are_jumpers no)
		(fp_line
			(start -0.7874 -0.4064)
			(end -0.7874 0.4064)
			(stroke
				(width 0.1524)
				(type default)
			)
			(layer "B.SilkS")
		)
		(fp_line
			(start -0.7874 0.4064)
			(end 0.7874 0.4064)
			(stroke
				(width 0.1524)
				(type default)
			)
			(layer "B.SilkS")
		)
		(fp_line
			(start 0.7874 -0.4064)
			(end -0.7874 -0.4064)
			(stroke
				(width 0.1524)
				(type default)
			)
			(layer "B.SilkS")
		)
		(fp_line
			(start 0.7874 0.4064)
			(end 0.7874 -0.4064)
			(stroke
				(width 0.1524)
				(type default)
			)
			(layer "B.SilkS")
		)
		(fp_poly
			(pts
				(xy 0.508 0.2794) (xy 0.508 0.2286) (xy 0.635 0.2286) (xy 0.635 -0.254) (xy 0.5334 -0.254) (xy 0.5334 -0.2794)
				(xy -0.5334 -0.2794) (xy -0.5334 -0.254) (xy -0.635 -0.254) (xy -0.635 0.254) (xy -0.5334 0.254)
				(xy -0.5334 0.2794)
			)
			(stroke
				(width 0)
				(type default)
			)
			(fill no)
			(layer "B.CrtYd")
		)
		(pad "1" smd rect
			(at -0.40005 0 180)
			(size 0.4572 0.508)
			(layers "B.Cu" "B.Mask" "B.Paste")
			(net "SIO_JTAG_CPLD3_TDI")
		)
		(pad "2" smd rect
			(at 0.40005 0 180)
			(size 0.4572 0.508)
			(layers "B.Cu" "B.Mask" "B.Paste")
			(net "GND")
		)
	)
	(footprint ""
		(layer "B.Cu")
		(at 81.02727 -21.09724 90)
		(property "Reference" "C165"
			(at -5.806948 -0.770128 270)
			(unlocked yes)
			(layer "B.SilkS")
			(effects
				(font
					(size 0.7874 0.5842)
					(thickness 0.1524)
				)
				(justify left mirror)
			)
		)
		(property "Value" ""
			(at 0 0 90)
			(layer "B.Fab")
			(effects
				(font
					(size 1.27 1.27)
				)
				(justify mirror)
			)
		)
		(duplicate_pad_numbers_are_jumpers no)
		(fp_line
			(start 0.7874 -0.4064)
			(end -0.7874 -0.4064)
			(stroke
				(width 0.1524)
				(type default)
			)
			(layer "B.SilkS")
		)
		(fp_line
			(start -0.7874 -0.4064)
			(end -0.7874 0.4064)
			(stroke
				(width 0.1524)
				(type default)
			)
			(layer "B.SilkS")
		)
		(fp_line
			(start 0 0.381)
			(end 0 -0.381)
			(stroke
				(width 0.1524)
				(type default)
			)
			(layer "B.SilkS")
		)
		(fp_line
			(start 0.7874 0.4064)
			(end 0.7874 -0.4064)
			(stroke
				(width 0.1524)
				(type default)
			)
			(layer "B.SilkS")
		)
		(fp_line
			(start -0.7874 0.4064)
			(end 0.7874 0.4064)
			(stroke
				(width 0.1524)
				(type default)
			)
			(layer "B.SilkS")
		)
		(fp_poly
			(pts
				(xy 0.5334 0.254) (xy 0.635 0.254) (xy 0.635 0.2286) (xy 0.635 -0.254) (xy 0.5334 -0.254) (xy 0.5334 -0.2794)
				(xy -0.5334 -0.2794) (xy -0.5334 -0.254) (xy -0.635 -0.254) (xy -0.635 0.254) (xy -0.5334 0.254)
				(xy -0.5334 0.2794) (xy 0.508 0.2794) (xy 0.5334 0.2794)
			)
			(stroke
				(width 0)
				(type default)
			)
			(fill no)
			(layer "B.CrtYd")
		)
		(pad "1" smd rect
			(at -0.40005 0 270)
			(size 0.4572 0.508)
			(layers "B.Cu" "B.Mask" "B.Paste")
			(net "PV_VDDR_NODE1")
		)
		(pad "2" smd rect
			(at 0.40005 0 270)
			(size 0.4572 0.508)
			(layers "B.Cu" "B.Mask" "B.Paste")
			(net "GND")
		)
	)
	(footprint ""
		(layer "B.Cu")
		(at 61.089286 -146.419062 90)
		(property "Reference" "R292"
			(at 0.935736 -0.36957 270)
			(unlocked yes)
			(layer "B.SilkS")
			(effects
				(font
					(size 0.7874 0.5842)
					(thickness 0.1524)
				)
				(justify left mirror)
			)
		)
		(property "Value" ""
			(at 0 0 90)
			(layer "B.Fab")
			(effects
				(font
					(size 1.27 1.27)
				)
				(justify mirror)
			)
		)
		(duplicate_pad_numbers_are_jumpers no)
		(fp_line
			(start 0.7874 -0.4064)
			(end -0.7874 -0.4064)
			(stroke
				(width 0.1524)
				(type default)
			)
			(layer "B.SilkS")
		)
		(fp_line
			(start -0.7874 -0.4064)
			(end -0.7874 0.4064)
			(stroke
				(width 0.1524)
				(type default)
			)
			(layer "B.SilkS")
		)
		(fp_line
			(start 0.7874 0.4064)
			(end 0.7874 -0.4064)
			(stroke
				(width 0.1524)
				(type default)
			)
			(layer "B.SilkS")
		)
		(fp_line
			(start -0.7874 0.4064)
			(end 0.7874 0.4064)
			(stroke
				(width 0.1524)
				(type default)
			)
			(layer "B.SilkS")
		)
		(fp_poly
			(pts
				(xy 0.508 0.2794) (xy 0.508 0.2286) (xy 0.635 0.2286) (xy 0.635 -0.254) (xy 0.5334 -0.254) (xy 0.5334 -0.2794)
				(xy -0.5334 -0.2794) (xy -0.5334 -0.254) (xy -0.635 -0.254) (xy -0.635 0.254) (xy -0.5334 0.254)
				(xy -0.5334 0.2794)
			)
			(stroke
				(width 0)
				(type default)
			)
			(fill no)
			(layer "B.CrtYd")
		)
		(pad "1" smd rect
			(at -0.40005 0 270)
			(size 0.4572 0.508)
			(layers "B.Cu" "B.Mask" "B.Paste")
			(net "BMC_NODE1_GFX_RED")
		)
		(pad "2" smd rect
			(at 0.40005 0 270)
			(size 0.4572 0.508)
			(layers "B.Cu" "B.Mask" "B.Paste")
			(net "GND")
		)
	)
	(footprint ""
		(layer "B.Cu")
		(at 127.921512 -144.83461 90)
		(property "Reference" "C932"
			(at 0.03302 2.38633 270)
			(unlocked yes)
			(layer "B.SilkS")
			(effects
				(font
					(size 0.7874 0.5842)
					(thickness 0.1524)
				)
				(justify left mirror)
			)
		)
		(property "Value" ""
			(at 0 0 90)
			(layer "B.Fab")
			(effects
				(font
					(size 1.27 1.27)
				)
				(justify mirror)
			)
		)
		(duplicate_pad_numbers_are_jumpers no)
		(fp_line
			(start 0.7874 -0.4064)
			(end -0.7874 -0.4064)
			(stroke
				(width 0.1524)
				(type default)
			)
			(layer "B.SilkS")
		)
		(fp_line
			(start -0.7874 -0.4064)
			(end -0.7874 0.4064)
			(stroke
				(width 0.1524)
				(type default)
			)
			(layer "B.SilkS")
		)
		(fp_line
			(start 0 0.381)
			(end 0 -0.381)
			(stroke
				(width 0.1524)
				(type default)
			)
			(layer "B.SilkS")
		)
		(fp_line
			(start 0.7874 0.4064)
			(end 0.7874 -0.4064)
			(stroke
				(width 0.1524)
				(type default)
			)
			(layer "B.SilkS")
		)
		(fp_line
			(start -0.7874 0.4064)
			(end 0.7874 0.4064)
			(stroke
				(width 0.1524)
				(type default)
			)
			(layer "B.SilkS")
		)
		(fp_poly
			(pts
				(xy 0.5334 0.254) (xy 0.635 0.254) (xy 0.635 0.2286) (xy 0.635 -0.254) (xy 0.5334 -0.254) (xy 0.5334 -0.2794)
				(xy -0.5334 -0.2794) (xy -0.5334 -0.254) (xy -0.635 -0.254) (xy -0.635 0.254) (xy -0.5334 0.254)
				(xy -0.5334 0.2794) (xy 0.508 0.2794) (xy 0.5334 0.2794)
			)
			(stroke
				(width 0)
				(type default)
			)
			(fill no)
			(layer "B.CrtYd")
		)
		(pad "1" smd rect
			(at -0.40005 0 270)
			(size 0.4572 0.508)
			(layers "B.Cu" "B.Mask" "B.Paste")
			(net "P1V0_PCI_SW_A")
		)
		(pad "2" smd rect
			(at 0.40005 0 270)
			(size 0.4572 0.508)
			(layers "B.Cu" "B.Mask" "B.Paste")
			(net "GND")
		)
	)
	(footprint ""
		(layer "B.Cu")
		(at 143.122396 -59.96813 90)
		(property "Reference" "C341"
			(at 1.050036 -0.288798 270)
			(unlocked yes)
			(layer "B.SilkS")
			(effects
				(font
					(size 0.7874 0.5842)
					(thickness 0.1524)
				)
				(justify left mirror)
			)
		)
		(property "Value" ""
			(at 0 0 90)
			(layer "B.Fab")
			(effects
				(font
					(size 1.27 1.27)
				)
				(justify mirror)
			)
		)
		(duplicate_pad_numbers_are_jumpers no)
		(fp_line
			(start 0.7874 -0.4064)
			(end -0.7874 -0.4064)
			(stroke
				(width 0.1524)
				(type default)
			)
			(layer "B.SilkS")
		)
		(fp_line
			(start -0.7874 -0.4064)
			(end -0.7874 0.4064)
			(stroke
				(width 0.1524)
				(type default)
			)
			(layer "B.SilkS")
		)
		(fp_line
			(start 0 0.381)
			(end 0 -0.381)
			(stroke
				(width 0.1524)
				(type default)
			)
			(layer "B.SilkS")
		)
		(fp_line
			(start 0.7874 0.4064)
			(end 0.7874 -0.4064)
			(stroke
				(width 0.1524)
				(type default)
			)
			(layer "B.SilkS")
		)
		(fp_line
			(start -0.7874 0.4064)
			(end 0.7874 0.4064)
			(stroke
				(width 0.1524)
				(type default)
			)
			(layer "B.SilkS")
		)
		(fp_poly
			(pts
				(xy 0.5334 0.254) (xy 0.635 0.254) (xy 0.635 0.2286) (xy 0.635 -0.254) (xy 0.5334 -0.254) (xy 0.5334 -0.2794)
				(xy -0.5334 -0.2794) (xy -0.5334 -0.254) (xy -0.635 -0.254) (xy -0.635 0.254) (xy -0.5334 0.254)
				(xy -0.5334 0.2794) (xy 0.508 0.2794) (xy 0.5334 0.2794)
			)
			(stroke
				(width 0)
				(type default)
			)
			(fill no)
			(layer "B.CrtYd")
		)
		(pad "1" smd rect
			(at -0.40005 0 270)
			(size 0.4572 0.508)
			(layers "B.Cu" "B.Mask" "B.Paste")
			(net "P1V0_SATA")
		)
		(pad "2" smd rect
			(at 0.40005 0 270)
			(size 0.4572 0.508)
			(layers "B.Cu" "B.Mask" "B.Paste")
			(net "GND")
		)
	)
	(footprint ""
		(layer "B.Cu")
		(at 142.07236 -170.981624 180)
		(property "Reference" "R728"
			(at 1.275588 0.274828 0)
			(unlocked yes)
			(layer "B.SilkS")
			(effects
				(font
					(size 0.7874 0.5842)
					(thickness 0.1524)
				)
				(justify left mirror)
			)
		)
		(property "Value" ""
			(at 0 0 0)
			(layer "B.Fab")
			(effects
				(font
					(size 1.27 1.27)
				)
				(justify mirror)
			)
		)
		(duplicate_pad_numbers_are_jumpers no)
		(fp_line
			(start 0.7874 0.4064)
			(end 0.7874 -0.4064)
			(stroke
				(width 0.1524)
				(type default)
			)
			(layer "B.SilkS")
		)
		(fp_line
			(start 0.7874 -0.4064)
			(end -0.7874 -0.4064)
			(stroke
				(width 0.1524)
				(type default)
			)
			(layer "B.SilkS")
		)
		(fp_line
			(start -0.7874 0.4064)
			(end 0.7874 0.4064)
			(stroke
				(width 0.1524)
				(type default)
			)
			(layer "B.SilkS")
		)
		(fp_line
			(start -0.7874 -0.4064)
			(end -0.7874 0.4064)
			(stroke
				(width 0.1524)
				(type default)
			)
			(layer "B.SilkS")
		)
		(fp_poly
			(pts
				(xy 0.508 0.2794) (xy 0.508 0.2286) (xy 0.635 0.2286) (xy 0.635 -0.254) (xy 0.5334 -0.254) (xy 0.5334 -0.2794)
				(xy -0.5334 -0.2794) (xy -0.5334 -0.254) (xy -0.635 -0.254) (xy -0.635 0.254) (xy -0.5334 0.254)
				(xy -0.5334 0.2794)
			)
			(stroke
				(width 0)
				(type default)
			)
			(fill no)
			(layer "B.CrtYd")
		)
		(pad "1" smd rect
			(at -0.40005 0)
			(size 0.4572 0.508)
			(layers "B.Cu" "B.Mask" "B.Paste")
			(net "T9_NODE1_EN")
		)
		(pad "2" smd rect
			(at 0.40005 0)
			(size 0.4572 0.508)
			(layers "B.Cu" "B.Mask" "B.Paste")
			(net "P5V_NODE1")
		)
	)
	(footprint ""
		(layer "B.Cu")
		(at 152.76576 -184.951624 90)
		(property "Reference" "R891"
			(at 4.281424 -2.31013 270)
			(unlocked yes)
			(layer "B.SilkS")
			(effects
				(font
					(size 0.7874 0.5842)
					(thickness 0.1524)
				)
				(justify left mirror)
			)
		)
		(property "Value" ""
			(at 0 0 90)
			(layer "B.Fab")
			(effects
				(font
					(size 1.27 1.27)
				)
				(justify mirror)
			)
		)
		(duplicate_pad_numbers_are_jumpers no)
		(fp_line
			(start 0.7874 -0.4064)
			(end -0.7874 -0.4064)
			(stroke
				(width 0.1524)
				(type default)
			)
			(layer "B.SilkS")
		)
		(fp_line
			(start -0.7874 -0.4064)
			(end -0.7874 0.4064)
			(stroke
				(width 0.1524)
				(type default)
			)
			(layer "B.SilkS")
		)
		(fp_line
			(start 0.7874 0.4064)
			(end 0.7874 -0.4064)
			(stroke
				(width 0.1524)
				(type default)
			)
			(layer "B.SilkS")
		)
		(fp_line
			(start -0.7874 0.4064)
			(end 0.7874 0.4064)
			(stroke
				(width 0.1524)
				(type default)
			)
			(layer "B.SilkS")
		)
		(fp_poly
			(pts
				(xy 0.508 0.2794) (xy 0.508 0.2286) (xy 0.635 0.2286) (xy 0.635 -0.254) (xy 0.5334 -0.254) (xy 0.5334 -0.2794)
				(xy -0.5334 -0.2794) (xy -0.5334 -0.254) (xy -0.635 -0.254) (xy -0.635 0.254) (xy -0.5334 0.254)
				(xy -0.5334 0.2794)
			)
			(stroke
				(width 0)
				(type default)
			)
			(fill no)
			(layer "B.CrtYd")
		)
		(pad "1" smd rect
			(at -0.40005 0 270)
			(size 0.4572 0.508)
			(layers "B.Cu" "B.Mask" "B.Paste")
			(net "T11_NODE3_EN")
		)
		(pad "2" smd rect
			(at 0.40005 0 270)
			(size 0.4572 0.508)
			(layers "B.Cu" "B.Mask" "B.Paste")
			(net "T11_NODE3_EN_R")
		)
	)
	(footprint ""
		(layer "B.Cu")
		(at 33.56229 -127.361188 -90)
		(property "Reference" "C831"
			(at 1.36271 1.55829 270)
			(unlocked yes)
			(layer "B.SilkS")
			(effects
				(font
					(size 0.7874 0.5842)
					(thickness 0.1524)
				)
				(justify left mirror)
			)
		)
		(property "Value" ""
			(at 0 0 90)
			(layer "B.Fab")
			(effects
				(font
					(size 1.27 1.27)
				)
				(justify mirror)
			)
		)
		(duplicate_pad_numbers_are_jumpers no)
		(fp_line
			(start -1.905 0.8636)
			(end 1.905 0.8636)
			(stroke
				(width 0.1524)
				(type default)
			)
			(layer "B.SilkS")
		)
		(fp_line
			(start 1.905 0.8636)
			(end 1.905 -0.8636)
			(stroke
				(width 0.1524)
				(type default)
			)
			(layer "B.SilkS")
		)
		(fp_line
			(start 0 0.8382)
			(end 0 -0.8382)
			(stroke
				(width 0.1524)
				(type default)
			)
			(layer "B.SilkS")
		)
		(fp_line
			(start -1.905 -0.8636)
			(end -1.905 0.8636)
			(stroke
				(width 0.1524)
				(type default)
			)
			(layer "B.SilkS")
		)
		(fp_line
			(start 1.905 -0.8636)
			(end -1.905 -0.8636)
			(stroke
				(width 0.1524)
				(type default)
			)
			(layer "B.SilkS")
		)
		(fp_rect
			(start 1.524 0.7366)
			(end -1.524 -0.7366)
			(stroke
				(width 0)
				(type default)
			)
			(fill no)
			(layer "B.CrtYd")
		)
		(pad "1" smd rect
			(at -0.94996 0 90)
			(size 1.1176 1.3716)
			(layers "B.Cu" "B.Mask" "B.Paste")
			(net "P1V538_BMC_NODE1")
		)
		(pad "2" smd rect
			(at 0.94996 0 90)
			(size 1.1176 1.3716)
			(layers "B.Cu" "B.Mask" "B.Paste")
			(net "GND")
		)
	)
	(footprint ""
		(layer "B.Cu")
		(at 92.68968 -182.494936 -90)
		(property "Reference" "R812"
			(at 2.35204 4.25323 270)
			(unlocked yes)
			(layer "B.SilkS")
			(effects
				(font
					(size 0.7874 0.5842)
					(thickness 0.1524)
				)
				(justify left mirror)
			)
		)
		(property "Value" ""
			(at 0 0 90)
			(layer "B.Fab")
			(effects
				(font
					(size 1.27 1.27)
				)
				(justify mirror)
			)
		)
		(duplicate_pad_numbers_are_jumpers no)
		(fp_line
			(start -0.7874 0.4064)
			(end 0.7874 0.4064)
			(stroke
				(width 0.1524)
				(type default)
			)
			(layer "B.SilkS")
		)
		(fp_line
			(start 0.7874 0.4064)
			(end 0.7874 -0.4064)
			(stroke
				(width 0.1524)
				(type default)
			)
			(layer "B.SilkS")
		)
		(fp_line
			(start -0.7874 -0.4064)
			(end -0.7874 0.4064)
			(stroke
				(width 0.1524)
				(type default)
			)
			(layer "B.SilkS")
		)
		(fp_line
			(start 0.7874 -0.4064)
			(end -0.7874 -0.4064)
			(stroke
				(width 0.1524)
				(type default)
			)
			(layer "B.SilkS")
		)
		(fp_poly
			(pts
				(xy 0.508 0.2794) (xy 0.508 0.2286) (xy 0.635 0.2286) (xy 0.635 -0.254) (xy 0.5334 -0.254) (xy 0.5334 -0.2794)
				(xy -0.5334 -0.2794) (xy -0.5334 -0.254) (xy -0.635 -0.254) (xy -0.635 0.254) (xy -0.5334 0.254)
				(xy -0.5334 0.2794)
			)
			(stroke
				(width 0)
				(type default)
			)
			(fill no)
			(layer "B.CrtYd")
		)
		(pad "1" smd rect
			(at -0.40005 0 90)
			(size 0.4572 0.508)
			(layers "B.Cu" "B.Mask" "B.Paste")
			(net "TACKOVER_EN_N")
		)
		(pad "2" smd rect
			(at 0.40005 0 90)
			(size 0.4572 0.508)
			(layers "B.Cu" "B.Mask" "B.Paste")
			(net "P3V3_NODE1")
		)
	)
	(footprint ""
		(layer "B.Cu")
		(at 68.920106 -21.16328 90)
		(property "Reference" "C155"
			(at -5.872988 -0.810006 270)
			(unlocked yes)
			(layer "B.SilkS")
			(effects
				(font
					(size 0.7874 0.5842)
					(thickness 0.1524)
				)
				(justify left mirror)
			)
		)
		(property "Value" ""
			(at 0 0 90)
			(layer "B.Fab")
			(effects
				(font
					(size 1.27 1.27)
				)
				(justify mirror)
			)
		)
		(duplicate_pad_numbers_are_jumpers no)
		(fp_line
			(start 0.7874 -0.4064)
			(end -0.7874 -0.4064)
			(stroke
				(width 0.1524)
				(type default)
			)
			(layer "B.SilkS")
		)
		(fp_line
			(start -0.7874 -0.4064)
			(end -0.7874 0.4064)
			(stroke
				(width 0.1524)
				(type default)
			)
			(layer "B.SilkS")
		)
		(fp_line
			(start 0 0.381)
			(end 0 -0.381)
			(stroke
				(width 0.1524)
				(type default)
			)
			(layer "B.SilkS")
		)
		(fp_line
			(start 0.7874 0.4064)
			(end 0.7874 -0.4064)
			(stroke
				(width 0.1524)
				(type default)
			)
			(layer "B.SilkS")
		)
		(fp_line
			(start -0.7874 0.4064)
			(end 0.7874 0.4064)
			(stroke
				(width 0.1524)
				(type default)
			)
			(layer "B.SilkS")
		)
		(fp_poly
			(pts
				(xy 0.5334 0.254) (xy 0.635 0.254) (xy 0.635 0.2286) (xy 0.635 -0.254) (xy 0.5334 -0.254) (xy 0.5334 -0.2794)
				(xy -0.5334 -0.2794) (xy -0.5334 -0.254) (xy -0.635 -0.254) (xy -0.635 0.254) (xy -0.5334 0.254)
				(xy -0.5334 0.2794) (xy 0.508 0.2794) (xy 0.5334 0.2794)
			)
			(stroke
				(width 0)
				(type default)
			)
			(fill no)
			(layer "B.CrtYd")
		)
		(pad "1" smd rect
			(at -0.40005 0 270)
			(size 0.4572 0.508)
			(layers "B.Cu" "B.Mask" "B.Paste")
			(net "PV_VDDR_NODE1")
		)
		(pad "2" smd rect
			(at 0.40005 0 270)
			(size 0.4572 0.508)
			(layers "B.Cu" "B.Mask" "B.Paste")
			(net "GND")
		)
	)
	(footprint ""
		(layer "B.Cu")
		(at 37.968428 -133.439662 90)
		(property "Reference" "C226"
			(at -1.92659 -2.218436 270)
			(unlocked yes)
			(layer "B.SilkS")
			(effects
				(font
					(size 0.7874 0.5842)
					(thickness 0.1524)
				)
				(justify left mirror)
			)
		)
		(property "Value" ""
			(at 0 0 90)
			(layer "B.Fab")
			(effects
				(font
					(size 1.27 1.27)
				)
				(justify mirror)
			)
		)
		(duplicate_pad_numbers_are_jumpers no)
		(fp_line
			(start 0.7874 -0.4064)
			(end -0.7874 -0.4064)
			(stroke
				(width 0.1524)
				(type default)
			)
			(layer "B.SilkS")
		)
		(fp_line
			(start -0.7874 -0.4064)
			(end -0.7874 0.4064)
			(stroke
				(width 0.1524)
				(type default)
			)
			(layer "B.SilkS")
		)
		(fp_line
			(start 0 0.381)
			(end 0 -0.381)
			(stroke
				(width 0.1524)
				(type default)
			)
			(layer "B.SilkS")
		)
		(fp_line
			(start 0.7874 0.4064)
			(end 0.7874 -0.4064)
			(stroke
				(width 0.1524)
				(type default)
			)
			(layer "B.SilkS")
		)
		(fp_line
			(start -0.7874 0.4064)
			(end 0.7874 0.4064)
			(stroke
				(width 0.1524)
				(type default)
			)
			(layer "B.SilkS")
		)
		(fp_poly
			(pts
				(xy 0.5334 0.254) (xy 0.635 0.254) (xy 0.635 0.2286) (xy 0.635 -0.254) (xy 0.5334 -0.254) (xy 0.5334 -0.2794)
				(xy -0.5334 -0.2794) (xy -0.5334 -0.254) (xy -0.635 -0.254) (xy -0.635 0.254) (xy -0.5334 0.254)
				(xy -0.5334 0.2794) (xy 0.508 0.2794) (xy 0.5334 0.2794)
			)
			(stroke
				(width 0)
				(type default)
			)
			(fill no)
			(layer "B.CrtYd")
		)
		(pad "1" smd rect
			(at -0.40005 0 270)
			(size 0.4572 0.508)
			(layers "B.Cu" "B.Mask" "B.Paste")
			(net "P1V538_BMC_NODE1")
		)
		(pad "2" smd rect
			(at 0.40005 0 270)
			(size 0.4572 0.508)
			(layers "B.Cu" "B.Mask" "B.Paste")
			(net "P0V75_BMC_VTTREF_NODE1")
		)
	)
	(footprint ""
		(layer "B.Cu")
		(at 148.06676 -173.521624 -90)
		(property "Reference" "U66"
			(at -5.82295 2.102612 0)
			(unlocked yes)
			(layer "B.SilkS")
			(effects
				(font
					(size 0.7874 0.5842)
					(thickness 0.1524)
				)
				(justify left mirror)
			)
		)
		(property "Value" ""
			(at 0 0 90)
			(layer "B.Fab")
			(effects
				(font
					(size 1.27 1.27)
				)
				(justify mirror)
			)
		)
		(duplicate_pad_numbers_are_jumpers no)
		(fp_line
			(start -3.9624 2.0066)
			(end 3.9624 2.0066)
			(stroke
				(width 0.1524)
				(type default)
			)
			(layer "B.SilkS")
		)
		(fp_line
			(start 3.9624 2.0066)
			(end 3.9624 0.5842)
			(stroke
				(width 0.1524)
				(type default)
			)
			(layer "B.SilkS")
		)
		(fp_line
			(start 3.9624 0.5842)
			(end 3.3782 0)
			(stroke
				(width 0.1524)
				(type default)
			)
			(layer "B.SilkS")
		)
		(fp_line
			(start 3.3782 0)
			(end 3.9624 -0.5842)
			(stroke
				(width 0.1524)
				(type default)
			)
			(layer "B.SilkS")
		)
		(fp_line
			(start 3.9624 -0.5842)
			(end 3.9624 -2.0066)
			(stroke
				(width 0.1524)
				(type default)
			)
			(layer "B.SilkS")
		)
		(fp_line
			(start -3.9624 -2.0066)
			(end -3.9624 2.0066)
			(stroke
				(width 0.1524)
				(type default)
			)
			(layer "B.SilkS")
		)
		(fp_line
			(start 3.9624 -2.0066)
			(end -3.9624 -2.0066)
			(stroke
				(width 0.1524)
				(type default)
			)
			(layer "B.SilkS")
		)
		(fp_circle
			(center 3.429 1.524)
			(end 3.429 1.27)
			(stroke
				(width 0.1524)
				(type default)
			)
			(fill no)
			(layer "B.SilkS")
		)
		(fp_poly
			(pts
				(xy 3.962654 3.6703) (xy 3.974846 -3.6703) (xy -3.9624 -3.6703) (xy -3.9624 3.6703)
			)
			(stroke
				(width 0)
				(type default)
			)
			(fill no)
			(layer "B.CrtYd")
		)
		(pad "1" smd rect
			(at 3.57505 2.921 90)
			(size 0.3556 1.4986)
			(layers "B.Cu" "B.Mask" "B.Paste")
			(net "N21700156")
		)
		(pad "2" smd rect
			(at 2.925064 2.921 90)
			(size 0.3556 1.4986)
			(layers "B.Cu" "B.Mask" "B.Paste")
			(net "N21698757")
		)
		(pad "3" smd rect
			(at 2.275078 2.921 90)
			(size 0.3556 1.4986)
			(layers "B.Cu" "B.Mask" "B.Paste")
			(net "N21698959")
		)
		(pad "4" smd rect
			(at 1.625092 2.921 90)
			(size 0.3556 1.4986)
			(layers "B.Cu" "B.Mask" "B.Paste")
			(net "T9_NODE1_EN")
		)
		(pad "5" smd rect
			(at 0.975106 2.921 90)
			(size 0.3556 1.4986)
			(layers "B.Cu" "B.Mask" "B.Paste")
			(net "T9_NODE2_EN")
		)
		(pad "6" smd rect
			(at 0.32512 2.921 90)
			(size 0.3556 1.4986)
			(layers "B.Cu" "B.Mask" "B.Paste")
			(net "T9_NODE3_EN")
		)
		(pad "7" smd rect
			(at -0.32512 2.921 90)
			(size 0.3556 1.4986)
			(layers "B.Cu" "B.Mask" "B.Paste")
			(net "T9_NODE4_EN")
		)
		(pad "8" smd rect
			(at -0.975106 2.921 90)
			(size 0.3556 1.4986)
			(layers "B.Cu" "B.Mask" "B.Paste")
			(net "T10_NODE1_EN")
		)
		(pad "9" smd rect
			(at -1.625092 2.921 90)
			(size 0.3556 1.4986)
			(layers "B.Cu" "B.Mask" "B.Paste")
			(net "T10_NODE2_EN")
		)
		(pad "10" smd rect
			(at -2.275078 2.921 90)
			(size 0.3556 1.4986)
			(layers "B.Cu" "B.Mask" "B.Paste")
			(net "T10_NODE3_EN")
		)
		(pad "11" smd rect
			(at -2.925064 2.921 90)
			(size 0.3556 1.4986)
			(layers "B.Cu" "B.Mask" "B.Paste")
			(net "T10_NODE4_EN")
		)
		(pad "12" smd rect
			(at -3.57505 2.921 90)
			(size 0.3556 1.4986)
			(layers "B.Cu" "B.Mask" "B.Paste")
			(net "GND")
		)
		(pad "13" smd rect
			(at -3.57505 -2.921 90)
			(size 0.3556 1.4986)
			(layers "B.Cu" "B.Mask" "B.Paste")
			(net "T11_NODE1_EN")
		)
		(pad "14" smd rect
			(at -2.925064 -2.921 90)
			(size 0.3556 1.4986)
			(layers "B.Cu" "B.Mask" "B.Paste")
			(net "T11_NODE2_EN")
		)
		(pad "15" smd rect
			(at -2.275078 -2.921 90)
			(size 0.3556 1.4986)
			(layers "B.Cu" "B.Mask" "B.Paste")
			(net "T11_NODE3_EN")
		)
		(pad "16" smd rect
			(at -1.625092 -2.921 90)
			(size 0.3556 1.4986)
			(layers "B.Cu" "B.Mask" "B.Paste")
			(net "T11_NODE4_EN")
		)
		(pad "17" smd rect
			(at -0.975106 -2.921 90)
			(size 0.3556 1.4986)
			(layers "B.Cu" "B.Mask" "B.Paste")
			(net "T12_NODE1_EN")
		)
		(pad "18" smd rect
			(at -0.32512 -2.921 90)
			(size 0.3556 1.4986)
			(layers "B.Cu" "B.Mask" "B.Paste")
			(net "T12_NODE2_EN")
		)
		(pad "19" smd rect
			(at 0.32512 -2.921 90)
			(size 0.3556 1.4986)
			(layers "B.Cu" "B.Mask" "B.Paste")
			(net "T12_NODE3_EN")
		)
		(pad "20" smd rect
			(at 0.975106 -2.921 90)
			(size 0.3556 1.4986)
			(layers "B.Cu" "B.Mask" "B.Paste")
			(net "T12_NODE4_EN")
		)
		(pad "21" smd rect
			(at 1.625092 -2.921 90)
			(size 0.3556 1.4986)
			(layers "B.Cu" "B.Mask" "B.Paste")
			(net "N21698959")
		)
		(pad "22" smd rect
			(at 2.275078 -2.921 90)
			(size 0.3556 1.4986)
			(layers "B.Cu" "B.Mask" "B.Paste")
			(net "I2C_COM3_SCL")
		)
		(pad "23" smd rect
			(at 2.925064 -2.921 90)
			(size 0.3556 1.4986)
			(layers "B.Cu" "B.Mask" "B.Paste")
			(net "I2C_COM3_SDA")
		)
		(pad "24" smd rect
			(at 3.57505 -2.921 90)
			(size 0.3556 1.4986)
			(layers "B.Cu" "B.Mask" "B.Paste")
			(net "P3V3_NODE1")
		)
	)
	(footprint ""
		(layer "B.Cu")
		(at 73.791318 -77.94625)
		(property "Reference" "R117"
			(at 0.861822 1.504188 0)
			(unlocked yes)
			(layer "B.SilkS")
			(effects
				(font
					(size 0.7874 0.5842)
					(thickness 0.1524)
				)
				(justify left mirror)
			)
		)
		(property "Value" ""
			(at 0 0 0)
			(layer "B.Fab")
			(effects
				(font
					(size 1.27 1.27)
				)
				(justify mirror)
			)
		)
		(duplicate_pad_numbers_are_jumpers no)
		(fp_line
			(start -0.7874 -0.4064)
			(end -0.7874 0.4064)
			(stroke
				(width 0.1524)
				(type default)
			)
			(layer "B.SilkS")
		)
		(fp_line
			(start -0.7874 0.4064)
			(end 0.7874 0.4064)
			(stroke
				(width 0.1524)
				(type default)
			)
			(layer "B.SilkS")
		)
		(fp_line
			(start 0.7874 -0.4064)
			(end -0.7874 -0.4064)
			(stroke
				(width 0.1524)
				(type default)
			)
			(layer "B.SilkS")
		)
		(fp_line
			(start 0.7874 0.4064)
			(end 0.7874 -0.4064)
			(stroke
				(width 0.1524)
				(type default)
			)
			(layer "B.SilkS")
		)
		(fp_poly
			(pts
				(xy 0.508 0.2794) (xy 0.508 0.2286) (xy 0.635 0.2286) (xy 0.635 -0.254) (xy 0.5334 -0.254) (xy 0.5334 -0.2794)
				(xy -0.5334 -0.2794) (xy -0.5334 -0.254) (xy -0.635 -0.254) (xy -0.635 0.254) (xy -0.5334 0.254)
				(xy -0.5334 0.2794)
			)
			(stroke
				(width 0)
				(type default)
			)
			(fill no)
			(layer "B.CrtYd")
		)
		(pad "1" smd rect
			(at -0.40005 0 180)
			(size 0.4572 0.508)
			(layers "B.Cu" "B.Mask" "B.Paste")
			(net "SVID_CPU_NODE1_PVCCP_DAT_R")
		)
		(pad "2" smd rect
			(at 0.40005 0 180)
			(size 0.4572 0.508)
			(layers "B.Cu" "B.Mask" "B.Paste")
			(net "SVID_CPU_NODE1_PVCCP_DAT")
		)
	)
	(footprint ""
		(layer "B.Cu")
		(at 110.44936 -180.633624 180)
		(property "Reference" "R716"
			(at 21.356828 -32.269176 0)
			(unlocked yes)
			(layer "B.SilkS")
			(effects
				(font
					(size 0.7874 0.5842)
					(thickness 0.1524)
				)
				(justify left mirror)
			)
		)
		(property "Value" ""
			(at 0 0 0)
			(layer "B.Fab")
			(effects
				(font
					(size 1.27 1.27)
				)
				(justify mirror)
			)
		)
		(duplicate_pad_numbers_are_jumpers no)
		(fp_line
			(start 0.7874 0.4064)
			(end 0.7874 -0.4064)
			(stroke
				(width 0.1524)
				(type default)
			)
			(layer "B.SilkS")
		)
		(fp_line
			(start 0.7874 -0.4064)
			(end -0.7874 -0.4064)
			(stroke
				(width 0.1524)
				(type default)
			)
			(layer "B.SilkS")
		)
		(fp_line
			(start -0.7874 0.4064)
			(end 0.7874 0.4064)
			(stroke
				(width 0.1524)
				(type default)
			)
			(layer "B.SilkS")
		)
		(fp_line
			(start -0.7874 -0.4064)
			(end -0.7874 0.4064)
			(stroke
				(width 0.1524)
				(type default)
			)
			(layer "B.SilkS")
		)
		(fp_poly
			(pts
				(xy 0.508 0.2794) (xy 0.508 0.2286) (xy 0.635 0.2286) (xy 0.635 -0.254) (xy 0.5334 -0.254) (xy 0.5334 -0.2794)
				(xy -0.5334 -0.2794) (xy -0.5334 -0.254) (xy -0.635 -0.254) (xy -0.635 0.254) (xy -0.5334 0.254)
				(xy -0.5334 0.2794)
			)
			(stroke
				(width 0)
				(type default)
			)
			(fill no)
			(layer "B.CrtYd")
		)
		(pad "1" smd rect
			(at -0.40005 0)
			(size 0.4572 0.508)
			(layers "B.Cu" "B.Mask" "B.Paste")
			(net "T6_NODE3_EN")
		)
		(pad "2" smd rect
			(at 0.40005 0)
			(size 0.4572 0.508)
			(layers "B.Cu" "B.Mask" "B.Paste")
			(net "P5V_NODE1")
		)
	)
	(footprint ""
		(layer "B.Cu")
		(at 37.92474 -146.58467)
		(property "Reference" "R552"
			(at -2.549652 0.339852 0)
			(unlocked yes)
			(layer "B.SilkS")
			(effects
				(font
					(size 0.7874 0.5842)
					(thickness 0.1524)
				)
				(justify left mirror)
			)
		)
		(property "Value" ""
			(at 0 0 0)
			(layer "B.Fab")
			(effects
				(font
					(size 1.27 1.27)
				)
				(justify mirror)
			)
		)
		(duplicate_pad_numbers_are_jumpers no)
		(fp_line
			(start -0.7874 -0.4064)
			(end -0.7874 0.4064)
			(stroke
				(width 0.1524)
				(type default)
			)
			(layer "B.SilkS")
		)
		(fp_line
			(start -0.7874 0.4064)
			(end 0.7874 0.4064)
			(stroke
				(width 0.1524)
				(type default)
			)
			(layer "B.SilkS")
		)
		(fp_line
			(start 0.7874 -0.4064)
			(end -0.7874 -0.4064)
			(stroke
				(width 0.1524)
				(type default)
			)
			(layer "B.SilkS")
		)
		(fp_line
			(start 0.7874 0.4064)
			(end 0.7874 -0.4064)
			(stroke
				(width 0.1524)
				(type default)
			)
			(layer "B.SilkS")
		)
		(fp_poly
			(pts
				(xy 0.508 0.2794) (xy 0.508 0.2286) (xy 0.635 0.2286) (xy 0.635 -0.254) (xy 0.5334 -0.254) (xy 0.5334 -0.2794)
				(xy -0.5334 -0.2794) (xy -0.5334 -0.254) (xy -0.635 -0.254) (xy -0.635 0.254) (xy -0.5334 0.254)
				(xy -0.5334 0.2794)
			)
			(stroke
				(width 0)
				(type default)
			)
			(fill no)
			(layer "B.CrtYd")
		)
		(pad "1" smd rect
			(at -0.40005 0 180)
			(size 0.4572 0.508)
			(layers "B.Cu" "B.Mask" "B.Paste")
			(net "GND")
		)
		(pad "2" smd rect
			(at 0.40005 0 180)
			(size 0.4572 0.508)
			(layers "B.Cu" "B.Mask" "B.Paste")
			(net "LAN1_DIS_REG10")
		)
	)
	(footprint ""
		(layer "B.Cu")
		(at 42.239438 -76.301346 -90)
		(property "Reference" "C39"
			(at 0.270256 -1.176528 270)
			(unlocked yes)
			(layer "B.SilkS")
			(effects
				(font
					(size 0.7874 0.5842)
					(thickness 0.1524)
				)
				(justify mirror)
			)
		)
		(property "Value" ""
			(at 0 0 90)
			(layer "B.Fab")
			(effects
				(font
					(size 1.27 1.27)
				)
				(justify mirror)
			)
		)
		(duplicate_pad_numbers_are_jumpers no)
		(fp_line
			(start -1.2954 0.5842)
			(end 1.2954 0.5842)
			(stroke
				(width 0.1524)
				(type default)
			)
			(layer "B.SilkS")
		)
		(fp_line
			(start 1.2954 0.5842)
			(end 1.2954 -0.5842)
			(stroke
				(width 0.1524)
				(type default)
			)
			(layer "B.SilkS")
		)
		(fp_line
			(start -1.2954 -0.5842)
			(end -1.2954 0.5842)
			(stroke
				(width 0.1524)
				(type default)
			)
			(layer "B.SilkS")
		)
		(fp_line
			(start 0 -0.5842)
			(end 0 0.5842)
			(stroke
				(width 0.1524)
				(type default)
			)
			(layer "B.SilkS")
		)
		(fp_line
			(start 1.2954 -0.5842)
			(end -1.2954 -0.5842)
			(stroke
				(width 0.1524)
				(type default)
			)
			(layer "B.SilkS")
		)
		(fp_poly
			(pts
				(xy -0.8636 -0.4572) (xy -0.8636 -0.3556) (xy -1.143 -0.3556) (xy -1.143 0.3556) (xy -0.8636 0.3556)
				(xy -0.8636 0.4572) (xy 0.8636 0.4572) (xy 0.8636 0.3556) (xy 1.143 0.3556) (xy 1.143 -0.3556) (xy 0.8636 -0.3556)
				(xy 0.8636 -0.4572)
			)
			(stroke
				(width 0)
				(type default)
			)
			(fill no)
			(layer "B.CrtYd")
		)
		(fp_line
			(start -0.884936 0.504952)
			(end 0.884936 0.504952)
			(stroke
				(width 0.1)
				(type default)
			)
			(layer "B.Fab")
		)
		(fp_line
			(start 0.884936 0.504952)
			(end 0.884936 -0.504952)
			(stroke
				(width 0.1)
				(type default)
			)
			(layer "B.Fab")
		)
		(fp_line
			(start -0.884936 -0.504952)
			(end -0.884936 0.504952)
			(stroke
				(width 0.1)
				(type default)
			)
			(layer "B.Fab")
		)
		(fp_line
			(start 0.884936 -0.504952)
			(end -0.884936 -0.504952)
			(stroke
				(width 0.1)
				(type default)
			)
			(layer "B.Fab")
		)
		(pad "1" smd rect
			(at -0.7366 0)
			(size 0.7112 0.8128)
			(layers "B.Cu" "B.Mask" "B.Paste")
			(net "P1V05_NODE1")
		)
		(pad "2" smd rect
			(at 0.7366 0)
			(size 0.7112 0.8128)
			(layers "B.Cu" "B.Mask" "B.Paste")
			(net "GND")
		)
	)
	(footprint ""
		(layer "B.Cu")
		(at 90.81262 -176.054512)
		(property "Reference" "R699"
			(at 24.902414 20.083272 0)
			(unlocked yes)
			(layer "B.SilkS")
			(effects
				(font
					(size 0.7874 0.5842)
					(thickness 0.1524)
				)
				(justify left mirror)
			)
		)
		(property "Value" ""
			(at 0 0 0)
			(layer "B.Fab")
			(effects
				(font
					(size 1.27 1.27)
				)
				(justify mirror)
			)
		)
		(duplicate_pad_numbers_are_jumpers no)
		(fp_line
			(start -0.7874 -0.4064)
			(end -0.7874 0.4064)
			(stroke
				(width 0.1524)
				(type default)
			)
			(layer "B.SilkS")
		)
		(fp_line
			(start -0.7874 0.4064)
			(end 0.7874 0.4064)
			(stroke
				(width 0.1524)
				(type default)
			)
			(layer "B.SilkS")
		)
		(fp_line
			(start 0.7874 -0.4064)
			(end -0.7874 -0.4064)
			(stroke
				(width 0.1524)
				(type default)
			)
			(layer "B.SilkS")
		)
		(fp_line
			(start 0.7874 0.4064)
			(end 0.7874 -0.4064)
			(stroke
				(width 0.1524)
				(type default)
			)
			(layer "B.SilkS")
		)
		(fp_poly
			(pts
				(xy 0.508 0.2794) (xy 0.508 0.2286) (xy 0.635 0.2286) (xy 0.635 -0.254) (xy 0.5334 -0.254) (xy 0.5334 -0.2794)
				(xy -0.5334 -0.2794) (xy -0.5334 -0.254) (xy -0.635 -0.254) (xy -0.635 0.254) (xy -0.5334 0.254)
				(xy -0.5334 0.2794)
			)
			(stroke
				(width 0)
				(type default)
			)
			(fill no)
			(layer "B.CrtYd")
		)
		(pad "1" smd rect
			(at -0.40005 0 180)
			(size 0.4572 0.508)
			(layers "B.Cu" "B.Mask" "B.Paste")
			(net "T3_NODE3_EN")
		)
		(pad "2" smd rect
			(at 0.40005 0 180)
			(size 0.4572 0.508)
			(layers "B.Cu" "B.Mask" "B.Paste")
			(net "P5V_NODE1")
		)
	)
	(footprint ""
		(layer "B.Cu")
		(at 46.83506 -146.59229 -90)
		(property "Reference" "C424"
			(at 0.576072 -1.417828 270)
			(unlocked yes)
			(layer "B.SilkS")
			(effects
				(font
					(size 0.7874 0.5842)
					(thickness 0.1524)
				)
				(justify left mirror)
			)
		)
		(property "Value" ""
			(at 0 0 90)
			(layer "B.Fab")
			(effects
				(font
					(size 1.27 1.27)
				)
				(justify mirror)
			)
		)
		(duplicate_pad_numbers_are_jumpers no)
		(fp_line
			(start -1.905 0.8636)
			(end 1.905 0.8636)
			(stroke
				(width 0.1524)
				(type default)
			)
			(layer "B.SilkS")
		)
		(fp_line
			(start 1.905 0.8636)
			(end 1.905 -0.8636)
			(stroke
				(width 0.1524)
				(type default)
			)
			(layer "B.SilkS")
		)
		(fp_line
			(start 0 0.8382)
			(end 0 -0.8382)
			(stroke
				(width 0.1524)
				(type default)
			)
			(layer "B.SilkS")
		)
		(fp_line
			(start -1.905 -0.8636)
			(end -1.905 0.8636)
			(stroke
				(width 0.1524)
				(type default)
			)
			(layer "B.SilkS")
		)
		(fp_line
			(start 1.905 -0.8636)
			(end -1.905 -0.8636)
			(stroke
				(width 0.1524)
				(type default)
			)
			(layer "B.SilkS")
		)
		(fp_rect
			(start 1.524 0.7366)
			(end -1.524 -0.7366)
			(stroke
				(width 0)
				(type default)
			)
			(fill no)
			(layer "B.CrtYd")
		)
		(pad "1" smd rect
			(at -0.94996 0 90)
			(size 1.1176 1.3716)
			(layers "B.Cu" "B.Mask" "B.Paste")
			(net "P1V05_LAN1")
		)
		(pad "2" smd rect
			(at 0.94996 0 90)
			(size 1.1176 1.3716)
			(layers "B.Cu" "B.Mask" "B.Paste")
			(net "GND")
		)
	)
	(footprint ""
		(layer "B.Cu")
		(at 56.68391 -21.495766)
		(property "Reference" "R209"
			(at 4.15163 0.153416 0)
			(unlocked yes)
			(layer "B.SilkS")
			(effects
				(font
					(size 0.7874 0.5842)
					(thickness 0.1524)
				)
				(justify left mirror)
			)
		)
		(property "Value" ""
			(at 0 0 0)
			(layer "B.Fab")
			(effects
				(font
					(size 1.27 1.27)
				)
				(justify mirror)
			)
		)
		(duplicate_pad_numbers_are_jumpers no)
		(fp_line
			(start -0.7874 -0.4064)
			(end -0.7874 0.4064)
			(stroke
				(width 0.1524)
				(type default)
			)
			(layer "B.SilkS")
		)
		(fp_line
			(start -0.7874 0.4064)
			(end 0.7874 0.4064)
			(stroke
				(width 0.1524)
				(type default)
			)
			(layer "B.SilkS")
		)
		(fp_line
			(start 0.7874 -0.4064)
			(end -0.7874 -0.4064)
			(stroke
				(width 0.1524)
				(type default)
			)
			(layer "B.SilkS")
		)
		(fp_line
			(start 0.7874 0.4064)
			(end 0.7874 -0.4064)
			(stroke
				(width 0.1524)
				(type default)
			)
			(layer "B.SilkS")
		)
		(fp_poly
			(pts
				(xy 0.508 0.2794) (xy 0.508 0.2286) (xy 0.635 0.2286) (xy 0.635 -0.254) (xy 0.5334 -0.254) (xy 0.5334 -0.2794)
				(xy -0.5334 -0.2794) (xy -0.5334 -0.254) (xy -0.635 -0.254) (xy -0.635 0.254) (xy -0.5334 0.254)
				(xy -0.5334 0.2794)
			)
			(stroke
				(width 0)
				(type default)
			)
			(fill no)
			(layer "B.CrtYd")
		)
		(pad "1" smd rect
			(at -0.40005 0 180)
			(size 0.4572 0.508)
			(layers "B.Cu" "B.Mask" "B.Paste")
			(net "GND")
		)
		(pad "2" smd rect
			(at 0.40005 0 180)
			(size 0.4572 0.508)
			(layers "B.Cu" "B.Mask" "B.Paste")
			(net "PD_NODE1_DM3")
		)
	)
	(footprint ""
		(layer "B.Cu")
		(at 44.292266 -137.070338)
		(property "Reference" "C231"
			(at 1.275334 1.326388 0)
			(unlocked yes)
			(layer "B.SilkS")
			(effects
				(font
					(size 0.7874 0.5842)
					(thickness 0.1524)
				)
				(justify left mirror)
			)
		)
		(property "Value" ""
			(at 0 0 0)
			(layer "B.Fab")
			(effects
				(font
					(size 1.27 1.27)
				)
				(justify mirror)
			)
		)
		(duplicate_pad_numbers_are_jumpers no)
		(fp_line
			(start -0.7874 -0.4064)
			(end -0.7874 0.4064)
			(stroke
				(width 0.1524)
				(type default)
			)
			(layer "B.SilkS")
		)
		(fp_line
			(start -0.7874 0.4064)
			(end 0.7874 0.4064)
			(stroke
				(width 0.1524)
				(type default)
			)
			(layer "B.SilkS")
		)
		(fp_line
			(start 0 0.381)
			(end 0 -0.381)
			(stroke
				(width 0.1524)
				(type default)
			)
			(layer "B.SilkS")
		)
		(fp_line
			(start 0.7874 -0.4064)
			(end -0.7874 -0.4064)
			(stroke
				(width 0.1524)
				(type default)
			)
			(layer "B.SilkS")
		)
		(fp_line
			(start 0.7874 0.4064)
			(end 0.7874 -0.4064)
			(stroke
				(width 0.1524)
				(type default)
			)
			(layer "B.SilkS")
		)
		(fp_poly
			(pts
				(xy 0.5334 0.254) (xy 0.635 0.254) (xy 0.635 0.2286) (xy 0.635 -0.254) (xy 0.5334 -0.254) (xy 0.5334 -0.2794)
				(xy -0.5334 -0.2794) (xy -0.5334 -0.254) (xy -0.635 -0.254) (xy -0.635 0.254) (xy -0.5334 0.254)
				(xy -0.5334 0.2794) (xy 0.508 0.2794) (xy 0.5334 0.2794)
			)
			(stroke
				(width 0)
				(type default)
			)
			(fill no)
			(layer "B.CrtYd")
		)
		(pad "1" smd rect
			(at -0.40005 0 180)
			(size 0.4572 0.508)
			(layers "B.Cu" "B.Mask" "B.Paste")
			(net "P1V538_BMC_NODE1")
		)
		(pad "2" smd rect
			(at 0.40005 0 180)
			(size 0.4572 0.508)
			(layers "B.Cu" "B.Mask" "B.Paste")
			(net "GND")
		)
	)
	(footprint ""
		(layer "B.Cu")
		(at 76.448158 -151.289512 180)
		(property "Reference" "PC3"
			(at -4.631944 0.558038 0)
			(unlocked yes)
			(layer "B.SilkS")
			(effects
				(font
					(size 0.7874 0.5842)
					(thickness 0.1524)
				)
				(justify left mirror)
			)
		)
		(property "Value" ""
			(at 0 0 0)
			(layer "B.Fab")
			(effects
				(font
					(size 1.27 1.27)
				)
				(justify mirror)
			)
		)
		(duplicate_pad_numbers_are_jumpers no)
		(fp_line
			(start 2.2098 0.9398)
			(end 2.2098 -0.9398)
			(stroke
				(width 0.1524)
				(type default)
			)
			(layer "B.SilkS")
		)
		(fp_line
			(start 2.2098 -0.9398)
			(end -2.2098 -0.9398)
			(stroke
				(width 0.1524)
				(type default)
			)
			(layer "B.SilkS")
		)
		(fp_line
			(start 0 -0.9398)
			(end 0 0.9398)
			(stroke
				(width 0.1524)
				(type default)
			)
			(layer "B.SilkS")
		)
		(fp_line
			(start -2.2098 0.9398)
			(end 2.2098 0.9398)
			(stroke
				(width 0.1524)
				(type default)
			)
			(layer "B.SilkS")
		)
		(fp_line
			(start -2.2098 -0.9398)
			(end -2.2098 0.9398)
			(stroke
				(width 0.1524)
				(type default)
			)
			(layer "B.SilkS")
		)
		(fp_poly
			(pts
				(xy 1.6764 0.889) (xy 1.6764 0.7874) (xy 2.0574 0.7874) (xy 2.0574 -0.7874) (xy 1.6764 -0.7874)
				(xy 1.6764 -0.9398) (xy -1.6764 -0.9398) (xy -1.6764 -0.7874) (xy -2.0574 -0.7874) (xy -2.0574 0.7874)
				(xy -1.6764 0.7874) (xy -1.6764 0.9398) (xy 1.6764 0.9398)
			)
			(stroke
				(width 0)
				(type default)
			)
			(fill no)
			(layer "B.CrtYd")
		)
		(fp_line
			(start 1.700022 0.899922)
			(end 1.700022 -0.899922)
			(stroke
				(width 0.1)
				(type default)
			)
			(layer "B.Fab")
		)
		(fp_line
			(start 1.700022 -0.899922)
			(end -1.700022 -0.899922)
			(stroke
				(width 0.1)
				(type default)
			)
			(layer "B.Fab")
		)
		(fp_line
			(start -1.700022 0.899922)
			(end 1.700022 0.899922)
			(stroke
				(width 0.1)
				(type default)
			)
			(layer "B.Fab")
		)
		(fp_line
			(start -1.700022 -0.899922)
			(end -1.700022 0.899922)
			(stroke
				(width 0.1)
				(type default)
			)
			(layer "B.Fab")
		)
		(pad "1" smd rect
			(at -1.4732 0)
			(size 1.1684 1.5748)
			(layers "B.Cu" "B.Mask" "B.Paste")
			(net "P12V_AUX")
		)
		(pad "2" smd rect
			(at 1.4732 0)
			(size 1.1684 1.5748)
			(layers "B.Cu" "B.Mask" "B.Paste")
			(net "GND")
		)
	)
	(footprint ""
		(layer "B.Cu")
		(at 56.20004 -145.854674 180)
		(property "Reference" "R675"
			(at 0.984504 -2.813558 0)
			(unlocked yes)
			(layer "B.SilkS")
			(effects
				(font
					(size 0.7874 0.5842)
					(thickness 0.1524)
				)
				(justify left mirror)
			)
		)
		(property "Value" ""
			(at 0 0 0)
			(layer "B.Fab")
			(effects
				(font
					(size 1.27 1.27)
				)
				(justify mirror)
			)
		)
		(duplicate_pad_numbers_are_jumpers no)
		(fp_line
			(start 0.7874 0.4064)
			(end 0.7874 -0.4064)
			(stroke
				(width 0.1524)
				(type default)
			)
			(layer "B.SilkS")
		)
		(fp_line
			(start 0.7874 -0.4064)
			(end -0.7874 -0.4064)
			(stroke
				(width 0.1524)
				(type default)
			)
			(layer "B.SilkS")
		)
		(fp_line
			(start -0.7874 0.4064)
			(end 0.7874 0.4064)
			(stroke
				(width 0.1524)
				(type default)
			)
			(layer "B.SilkS")
		)
		(fp_line
			(start -0.7874 -0.4064)
			(end -0.7874 0.4064)
			(stroke
				(width 0.1524)
				(type default)
			)
			(layer "B.SilkS")
		)
		(fp_poly
			(pts
				(xy 0.508 0.2794) (xy 0.508 0.2286) (xy 0.635 0.2286) (xy 0.635 -0.254) (xy 0.5334 -0.254) (xy 0.5334 -0.2794)
				(xy -0.5334 -0.2794) (xy -0.5334 -0.254) (xy -0.635 -0.254) (xy -0.635 0.254) (xy -0.5334 0.254)
				(xy -0.5334 0.2794)
			)
			(stroke
				(width 0)
				(type default)
			)
			(fill no)
			(layer "B.CrtYd")
		)
		(pad "1" smd rect
			(at -0.40005 0)
			(size 0.4572 0.508)
			(layers "B.Cu" "B.Mask" "B.Paste")
			(net "BMC_NODE1_GFX_VSYNC_R")
		)
		(pad "2" smd rect
			(at 0.40005 0)
			(size 0.4572 0.508)
			(layers "B.Cu" "B.Mask" "B.Paste")
			(net "BMC_NODE1_GFX_VSYNC")
		)
	)
	(footprint ""
		(layer "B.Cu")
		(at 139.93876 -184.951624 90)
		(property "Reference" "R861"
			(at 4.357624 -2.004568 270)
			(unlocked yes)
			(layer "B.SilkS")
			(effects
				(font
					(size 0.7874 0.5842)
					(thickness 0.1524)
				)
				(justify left mirror)
			)
		)
		(property "Value" ""
			(at 0 0 90)
			(layer "B.Fab")
			(effects
				(font
					(size 1.27 1.27)
				)
				(justify mirror)
			)
		)
		(duplicate_pad_numbers_are_jumpers no)
		(fp_line
			(start 0.7874 -0.4064)
			(end -0.7874 -0.4064)
			(stroke
				(width 0.1524)
				(type default)
			)
			(layer "B.SilkS")
		)
		(fp_line
			(start -0.7874 -0.4064)
			(end -0.7874 0.4064)
			(stroke
				(width 0.1524)
				(type default)
			)
			(layer "B.SilkS")
		)
		(fp_line
			(start 0.7874 0.4064)
			(end 0.7874 -0.4064)
			(stroke
				(width 0.1524)
				(type default)
			)
			(layer "B.SilkS")
		)
		(fp_line
			(start -0.7874 0.4064)
			(end 0.7874 0.4064)
			(stroke
				(width 0.1524)
				(type default)
			)
			(layer "B.SilkS")
		)
		(fp_poly
			(pts
				(xy 0.508 0.2794) (xy 0.508 0.2286) (xy 0.635 0.2286) (xy 0.635 -0.254) (xy 0.5334 -0.254) (xy 0.5334 -0.2794)
				(xy -0.5334 -0.2794) (xy -0.5334 -0.254) (xy -0.635 -0.254) (xy -0.635 0.254) (xy -0.5334 0.254)
				(xy -0.5334 0.2794)
			)
			(stroke
				(width 0)
				(type default)
			)
			(fill no)
			(layer "B.CrtYd")
		)
		(pad "1" smd rect
			(at -0.40005 0 270)
			(size 0.4572 0.508)
			(layers "B.Cu" "B.Mask" "B.Paste")
			(net "T9_NODE1_EN")
		)
		(pad "2" smd rect
			(at 0.40005 0 270)
			(size 0.4572 0.508)
			(layers "B.Cu" "B.Mask" "B.Paste")
			(net "T9_NODE1_EN_R")
		)
	)
	(footprint ""
		(layer "B.Cu")
		(at 73.586848 -63.54572 -90)
		(property "Reference" "PJ11"
			(at 1.510538 -3.332734 0)
			(unlocked yes)
			(layer "B.SilkS")
			(effects
				(font
					(size 0.7874 0.5842)
					(thickness 0.1524)
				)
				(justify left mirror)
			)
		)
		(property "Value" ""
			(at 0 0 90)
			(layer "B.Fab")
			(effects
				(font
					(size 1.27 1.27)
				)
				(justify mirror)
			)
		)
		(duplicate_pad_numbers_are_jumpers no)
		(fp_poly
			(pts
				(xy -0.2794 0.907796) (xy -0.254 0.907796) (xy -0.254 1.0414) (xy 0.254 1.0414) (xy 0.254 1.034796)
				(xy 0.254 0.933196) (xy 0.2794 0.933196) (xy 0.2794 -0.133604) (xy 0.254 -0.133604) (xy 0.254 -0.235204)
				(xy -0.254 -0.235204) (xy -0.254 -0.133604) (xy -0.2794 -0.133604)
			)
			(stroke
				(width 0)
				(type default)
			)
			(fill no)
			(layer "B.CrtYd")
		)
		(pad "1" smd custom
			(at 0 -0.000254 90)
			(size 0.127 0.127)
			(layers "B.Cu" "B.Mask" "B.Paste")
			(net "VSENSE_PV_VDDR_NODE1_N")
			(options
				(clearance outline)
				(anchor circle)
			)
			(primitives
				(gr_poly
					(pts
						(xy -0.127 -0.508) (xy -0.127 0.0508) (xy -0.254 0.0508) (xy -0.254 0.508) (xy 0.254 0.508) (xy 0.254 0.0508)
						(xy 0.127 0.0508) (xy 0.127 -0.508)
					)
					(width 0)
					(fill yes)
				)
			)
		)
		(pad "2" smd rect
			(at 0 0.799846)
			(size 0.4572 0.508)
			(layers "B.Cu" "B.Mask" "B.Paste")
			(net "GND")
		)
		(zone
			(layer "B.Cu")
			(hatch none 0.5)
			(connect_pads
				(clearance 0)
			)
			(min_thickness 0.25)
			(keepout
				(tracks allowed)
				(vias not_allowed)
				(pads allowed)
				(copperpour not_allowed)
				(footprints allowed)
			)
			(placement
				(enabled no)
				(sheetname "")
			)
			(fill
				(thermal_gap 0.5)
				(thermal_bridge_width 0.5)
				(island_removal_mode 0)
			)
			(polygon
				(pts
					(xy 72.501252 -63.24092) (xy 72.501252 -63.85052) (xy 73.872852 -63.85052) (xy 73.872852 -63.24092)
				)
			)
		)
	)
	(footprint ""
		(layer "B.Cu")
		(at 160.63976 -187.872624 90)
		(property "Reference" "R829"
			(at 4.565396 -4.10083 270)
			(unlocked yes)
			(layer "B.SilkS")
			(effects
				(font
					(size 0.7874 0.5842)
					(thickness 0.1524)
				)
				(justify left mirror)
			)
		)
		(property "Value" ""
			(at 0 0 90)
			(layer "B.Fab")
			(effects
				(font
					(size 1.27 1.27)
				)
				(justify mirror)
			)
		)
		(duplicate_pad_numbers_are_jumpers no)
		(fp_line
			(start 0.7874 -0.406146)
			(end -0.7874 -0.406146)
			(stroke
				(width 0.1524)
				(type default)
			)
			(layer "B.SilkS")
		)
		(fp_line
			(start -0.7874 -0.406146)
			(end -0.7874 0.406146)
			(stroke
				(width 0.1524)
				(type default)
			)
			(layer "B.SilkS")
		)
		(fp_line
			(start 0.7874 0.406146)
			(end 0.7874 -0.406146)
			(stroke
				(width 0.1524)
				(type default)
			)
			(layer "B.SilkS")
		)
		(fp_line
			(start -0.7874 0.406146)
			(end 0.7874 0.406146)
			(stroke
				(width 0.1524)
				(type default)
			)
			(layer "B.SilkS")
		)
		(fp_poly
			(pts
				(xy 0.508 0.2794) (xy 0.508 0.2286) (xy 0.635 0.2286) (xy 0.635 -0.254) (xy 0.5334 -0.254) (xy 0.5334 -0.2794)
				(xy -0.5334 -0.2794) (xy -0.5334 -0.254) (xy -0.635 -0.254) (xy -0.635 0.254) (xy -0.5334 0.254)
				(xy -0.5334 0.2794)
			)
			(stroke
				(width 0)
				(type default)
			)
			(fill no)
			(layer "B.CrtYd")
		)
		(pad "1" smd rect
			(at -0.40005 0 270)
			(size 0.4572 0.508)
			(layers "B.Cu" "B.Mask" "B.Paste")
			(net "FAN5_TACH")
		)
		(pad "2" smd rect
			(at 0.40005 0 270)
			(size 0.4572 0.508)
			(layers "B.Cu" "B.Mask" "B.Paste")
			(net "FAN5_TACH_R")
		)
	)
	(footprint ""
		(layer "B.Cu")
		(at 144.909032 -35.662616)
		(property "Reference" "R1193"
			(at 1.24714 17.425924 0)
			(unlocked yes)
			(layer "B.SilkS")
			(effects
				(font
					(size 0.7874 0.5842)
					(thickness 0.1524)
				)
				(justify left mirror)
			)
		)
		(property "Value" ""
			(at 0 0 0)
			(layer "B.Fab")
			(effects
				(font
					(size 1.27 1.27)
				)
				(justify mirror)
			)
		)
		(duplicate_pad_numbers_are_jumpers no)
		(fp_line
			(start -0.7874 -0.4064)
			(end -0.7874 0.4064)
			(stroke
				(width 0.1524)
				(type default)
			)
			(layer "B.SilkS")
		)
		(fp_line
			(start -0.7874 0.4064)
			(end 0.7874 0.4064)
			(stroke
				(width 0.1524)
				(type default)
			)
			(layer "B.SilkS")
		)
		(fp_line
			(start 0.7874 -0.4064)
			(end -0.7874 -0.4064)
			(stroke
				(width 0.1524)
				(type default)
			)
			(layer "B.SilkS")
		)
		(fp_line
			(start 0.7874 0.4064)
			(end 0.7874 -0.4064)
			(stroke
				(width 0.1524)
				(type default)
			)
			(layer "B.SilkS")
		)
		(fp_poly
			(pts
				(xy 0.508 0.2794) (xy 0.508 0.2286) (xy 0.635 0.2286) (xy 0.635 -0.254) (xy 0.5334 -0.254) (xy 0.5334 -0.2794)
				(xy -0.5334 -0.2794) (xy -0.5334 -0.254) (xy -0.635 -0.254) (xy -0.635 0.254) (xy -0.5334 0.254)
				(xy -0.5334 0.2794)
			)
			(stroke
				(width 0)
				(type default)
			)
			(fill no)
			(layer "B.CrtYd")
		)
		(pad "1" smd rect
			(at -0.40005 0 180)
			(size 0.4572 0.508)
			(layers "B.Cu" "B.Mask" "B.Paste")
			(net "SIO_CPLD_RSV2_R")
		)
		(pad "2" smd rect
			(at 0.40005 0 180)
			(size 0.4572 0.508)
			(layers "B.Cu" "B.Mask" "B.Paste")
			(net "P3V3_NODE1")
		)
	)
	(footprint ""
		(layer "B.Cu")
		(at 45.734732 -94.40037 90)
		(property "Reference" "R132"
			(at -4.703318 -4.440174 270)
			(unlocked yes)
			(layer "B.SilkS")
			(effects
				(font
					(size 0.7874 0.5842)
					(thickness 0.1524)
				)
				(justify left mirror)
			)
		)
		(property "Value" ""
			(at 0 0 90)
			(layer "B.Fab")
			(effects
				(font
					(size 1.27 1.27)
				)
				(justify mirror)
			)
		)
		(duplicate_pad_numbers_are_jumpers no)
		(fp_line
			(start 0.7874 -0.4064)
			(end -0.7874 -0.4064)
			(stroke
				(width 0.1524)
				(type default)
			)
			(layer "B.SilkS")
		)
		(fp_line
			(start -0.7874 -0.4064)
			(end -0.7874 0.4064)
			(stroke
				(width 0.1524)
				(type default)
			)
			(layer "B.SilkS")
		)
		(fp_line
			(start 0.7874 0.4064)
			(end 0.7874 -0.4064)
			(stroke
				(width 0.1524)
				(type default)
			)
			(layer "B.SilkS")
		)
		(fp_line
			(start -0.7874 0.4064)
			(end 0.7874 0.4064)
			(stroke
				(width 0.1524)
				(type default)
			)
			(layer "B.SilkS")
		)
		(fp_poly
			(pts
				(xy 0.508 0.2794) (xy 0.508 0.2286) (xy 0.635 0.2286) (xy 0.635 -0.254) (xy 0.5334 -0.254) (xy 0.5334 -0.2794)
				(xy -0.5334 -0.2794) (xy -0.5334 -0.254) (xy -0.635 -0.254) (xy -0.635 0.254) (xy -0.5334 0.254)
				(xy -0.5334 0.2794)
			)
			(stroke
				(width 0)
				(type default)
			)
			(fill no)
			(layer "B.CrtYd")
		)
		(pad "1" smd rect
			(at -0.40005 0 270)
			(size 0.4572 0.508)
			(layers "B.Cu" "B.Mask" "B.Paste")
			(net "SMB_CPU_NODE1_BMC_DAT_RR")
		)
		(pad "2" smd rect
			(at 0.40005 0 270)
			(size 0.4572 0.508)
			(layers "B.Cu" "B.Mask" "B.Paste")
			(net "SMB_CPU_NODE1_BMC_DAT")
		)
	)
	(footprint ""
		(layer "B.Cu")
		(at 51.69408 -82.904076 90)
		(property "Reference" "R120"
			(at -32.79394 -15.07363 270)
			(unlocked yes)
			(layer "B.SilkS")
			(effects
				(font
					(size 0.7874 0.5842)
					(thickness 0.1524)
				)
				(justify left mirror)
			)
		)
		(property "Value" ""
			(at 0 0 90)
			(layer "B.Fab")
			(effects
				(font
					(size 1.27 1.27)
				)
				(justify mirror)
			)
		)
		(duplicate_pad_numbers_are_jumpers no)
		(fp_line
			(start 0.7874 -0.4064)
			(end -0.7874 -0.4064)
			(stroke
				(width 0.1524)
				(type default)
			)
			(layer "B.SilkS")
		)
		(fp_line
			(start -0.7874 -0.4064)
			(end -0.7874 0.4064)
			(stroke
				(width 0.1524)
				(type default)
			)
			(layer "B.SilkS")
		)
		(fp_line
			(start 0.7874 0.4064)
			(end 0.7874 -0.4064)
			(stroke
				(width 0.1524)
				(type default)
			)
			(layer "B.SilkS")
		)
		(fp_line
			(start -0.7874 0.4064)
			(end 0.7874 0.4064)
			(stroke
				(width 0.1524)
				(type default)
			)
			(layer "B.SilkS")
		)
		(fp_poly
			(pts
				(xy 0.508 0.2794) (xy 0.508 0.2286) (xy 0.635 0.2286) (xy 0.635 -0.254) (xy 0.5334 -0.254) (xy 0.5334 -0.2794)
				(xy -0.5334 -0.2794) (xy -0.5334 -0.254) (xy -0.635 -0.254) (xy -0.635 0.254) (xy -0.5334 0.254)
				(xy -0.5334 0.2794)
			)
			(stroke
				(width 0)
				(type default)
			)
			(fill no)
			(layer "B.CrtYd")
		)
		(pad "1" smd rect
			(at -0.40005 0 270)
			(size 0.4572 0.508)
			(layers "B.Cu" "B.Mask" "B.Paste")
			(net "A_CPU_NODE1_SOC_THERMREFNPAD")
		)
		(pad "2" smd rect
			(at 0.40005 0 270)
			(size 0.4572 0.508)
			(layers "B.Cu" "B.Mask" "B.Paste")
			(net "GND")
		)
	)
	(footprint ""
		(layer "B.Cu")
		(at 68.633086 -124.930662 -90)
		(property "Reference" "C277"
			(at 3.666744 -8.600186 270)
			(unlocked yes)
			(layer "B.SilkS")
			(effects
				(font
					(size 0.7874 0.5842)
					(thickness 0.1524)
				)
				(justify left mirror)
			)
		)
		(property "Value" ""
			(at 0 0 90)
			(layer "B.Fab")
			(effects
				(font
					(size 1.27 1.27)
				)
				(justify mirror)
			)
		)
		(duplicate_pad_numbers_are_jumpers no)
		(fp_line
			(start -0.7874 0.4064)
			(end 0.7874 0.4064)
			(stroke
				(width 0.1524)
				(type default)
			)
			(layer "B.SilkS")
		)
		(fp_line
			(start 0.7874 0.4064)
			(end 0.7874 -0.4064)
			(stroke
				(width 0.1524)
				(type default)
			)
			(layer "B.SilkS")
		)
		(fp_line
			(start 0 0.381)
			(end 0 -0.381)
			(stroke
				(width 0.1524)
				(type default)
			)
			(layer "B.SilkS")
		)
		(fp_line
			(start -0.7874 -0.4064)
			(end -0.7874 0.4064)
			(stroke
				(width 0.1524)
				(type default)
			)
			(layer "B.SilkS")
		)
		(fp_line
			(start 0.7874 -0.4064)
			(end -0.7874 -0.4064)
			(stroke
				(width 0.1524)
				(type default)
			)
			(layer "B.SilkS")
		)
		(fp_poly
			(pts
				(xy 0.5334 0.254) (xy 0.635 0.254) (xy 0.635 0.2286) (xy 0.635 -0.254) (xy 0.5334 -0.254) (xy 0.5334 -0.2794)
				(xy -0.5334 -0.2794) (xy -0.5334 -0.254) (xy -0.635 -0.254) (xy -0.635 0.254) (xy -0.5334 0.254)
				(xy -0.5334 0.2794) (xy 0.508 0.2794) (xy 0.5334 0.2794)
			)
			(stroke
				(width 0)
				(type default)
			)
			(fill no)
			(layer "B.CrtYd")
		)
		(pad "1" smd rect
			(at -0.40005 0 90)
			(size 0.4572 0.508)
			(layers "B.Cu" "B.Mask" "B.Paste")
			(net "BMC_NODE1_VCC_1V8_PCIE")
		)
		(pad "2" smd rect
			(at 0.40005 0 90)
			(size 0.4572 0.508)
			(layers "B.Cu" "B.Mask" "B.Paste")
			(net "GND")
		)
	)
	(footprint ""
		(layer "B.Cu")
		(at 64.139572 -70.608698 180)
		(property "Reference" "C105"
			(at 10.436352 -32.130492 0)
			(unlocked yes)
			(layer "B.SilkS")
			(effects
				(font
					(size 0.7874 0.5842)
					(thickness 0.1524)
				)
				(justify left mirror)
			)
		)
		(property "Value" ""
			(at 0 0 0)
			(layer "B.Fab")
			(effects
				(font
					(size 1.27 1.27)
				)
				(justify mirror)
			)
		)
		(duplicate_pad_numbers_are_jumpers no)
		(fp_line
			(start 0.7874 0.4064)
			(end 0.7874 -0.4064)
			(stroke
				(width 0.1524)
				(type default)
			)
			(layer "B.SilkS")
		)
		(fp_line
			(start 0.7874 -0.4064)
			(end -0.7874 -0.4064)
			(stroke
				(width 0.1524)
				(type default)
			)
			(layer "B.SilkS")
		)
		(fp_line
			(start 0 0.381)
			(end 0 -0.381)
			(stroke
				(width 0.1524)
				(type default)
			)
			(layer "B.SilkS")
		)
		(fp_line
			(start -0.7874 0.4064)
			(end 0.7874 0.4064)
			(stroke
				(width 0.1524)
				(type default)
			)
			(layer "B.SilkS")
		)
		(fp_line
			(start -0.7874 -0.4064)
			(end -0.7874 0.4064)
			(stroke
				(width 0.1524)
				(type default)
			)
			(layer "B.SilkS")
		)
		(fp_poly
			(pts
				(xy 0.5334 0.254) (xy 0.635 0.254) (xy 0.635 0.2286) (xy 0.635 -0.254) (xy 0.5334 -0.254) (xy 0.5334 -0.2794)
				(xy -0.5334 -0.2794) (xy -0.5334 -0.254) (xy -0.635 -0.254) (xy -0.635 0.254) (xy -0.5334 0.254)
				(xy -0.5334 0.2794) (xy 0.508 0.2794) (xy 0.5334 0.2794)
			)
			(stroke
				(width 0)
				(type default)
			)
			(fill no)
			(layer "B.CrtYd")
		)
		(pad "1" smd rect
			(at -0.40005 0)
			(size 0.4572 0.508)
			(layers "B.Cu" "B.Mask" "B.Paste")
			(net "P1V05_NODE1")
		)
		(pad "2" smd rect
			(at 0.40005 0)
			(size 0.4572 0.508)
			(layers "B.Cu" "B.Mask" "B.Paste")
			(net "GND")
		)
	)
	(footprint ""
		(layer "B.Cu")
		(at 63.339472 -138.557762 -90)
		(property "Reference" "C287"
			(at 56.057546 41.102534 270)
			(unlocked yes)
			(layer "B.SilkS")
			(effects
				(font
					(size 0.7874 0.5842)
					(thickness 0.1524)
				)
				(justify left mirror)
			)
		)
		(property "Value" ""
			(at 0 0 90)
			(layer "B.Fab")
			(effects
				(font
					(size 1.27 1.27)
				)
				(justify mirror)
			)
		)
		(duplicate_pad_numbers_are_jumpers no)
		(fp_line
			(start -0.7874 0.4064)
			(end 0.7874 0.4064)
			(stroke
				(width 0.1524)
				(type default)
			)
			(layer "B.SilkS")
		)
		(fp_line
			(start 0.7874 0.4064)
			(end 0.7874 -0.4064)
			(stroke
				(width 0.1524)
				(type default)
			)
			(layer "B.SilkS")
		)
		(fp_line
			(start 0 0.381)
			(end 0 -0.381)
			(stroke
				(width 0.1524)
				(type default)
			)
			(layer "B.SilkS")
		)
		(fp_line
			(start -0.7874 -0.4064)
			(end -0.7874 0.4064)
			(stroke
				(width 0.1524)
				(type default)
			)
			(layer "B.SilkS")
		)
		(fp_line
			(start 0.7874 -0.4064)
			(end -0.7874 -0.4064)
			(stroke
				(width 0.1524)
				(type default)
			)
			(layer "B.SilkS")
		)
		(fp_poly
			(pts
				(xy 0.5334 0.254) (xy 0.635 0.254) (xy 0.635 0.2286) (xy 0.635 -0.254) (xy 0.5334 -0.254) (xy 0.5334 -0.2794)
				(xy -0.5334 -0.2794) (xy -0.5334 -0.254) (xy -0.635 -0.254) (xy -0.635 0.254) (xy -0.5334 0.254)
				(xy -0.5334 0.2794) (xy 0.508 0.2794) (xy 0.5334 0.2794)
			)
			(stroke
				(width 0)
				(type default)
			)
			(fill no)
			(layer "B.CrtYd")
		)
		(pad "1" smd rect
			(at -0.40005 0 90)
			(size 0.4572 0.508)
			(layers "B.Cu" "B.Mask" "B.Paste")
			(net "P1V26_BMC_NODE1")
		)
		(pad "2" smd rect
			(at 0.40005 0 90)
			(size 0.4572 0.508)
			(layers "B.Cu" "B.Mask" "B.Paste")
			(net "GND")
		)
	)
	(footprint ""
		(layer "B.Cu")
		(at 134.934452 -113.975642 90)
		(property "Reference" "C196"
			(at 0.933196 -0.29972 270)
			(unlocked yes)
			(layer "B.SilkS")
			(effects
				(font
					(size 0.7874 0.5842)
					(thickness 0.1524)
				)
				(justify left mirror)
			)
		)
		(property "Value" ""
			(at 0 0 90)
			(layer "B.Fab")
			(effects
				(font
					(size 1.27 1.27)
				)
				(justify mirror)
			)
		)
		(duplicate_pad_numbers_are_jumpers no)
		(fp_line
			(start 0.7874 -0.4064)
			(end -0.7874 -0.4064)
			(stroke
				(width 0.1524)
				(type default)
			)
			(layer "B.SilkS")
		)
		(fp_line
			(start -0.7874 -0.4064)
			(end -0.7874 0.4064)
			(stroke
				(width 0.1524)
				(type default)
			)
			(layer "B.SilkS")
		)
		(fp_line
			(start 0 0.381)
			(end 0 -0.381)
			(stroke
				(width 0.1524)
				(type default)
			)
			(layer "B.SilkS")
		)
		(fp_line
			(start 0.7874 0.4064)
			(end 0.7874 -0.4064)
			(stroke
				(width 0.1524)
				(type default)
			)
			(layer "B.SilkS")
		)
		(fp_line
			(start -0.7874 0.4064)
			(end 0.7874 0.4064)
			(stroke
				(width 0.1524)
				(type default)
			)
			(layer "B.SilkS")
		)
		(fp_poly
			(pts
				(xy 0.5334 0.254) (xy 0.635 0.254) (xy 0.635 0.2286) (xy 0.635 -0.254) (xy 0.5334 -0.254) (xy 0.5334 -0.2794)
				(xy -0.5334 -0.2794) (xy -0.5334 -0.254) (xy -0.635 -0.254) (xy -0.635 0.254) (xy -0.5334 0.254)
				(xy -0.5334 0.2794) (xy 0.508 0.2794) (xy 0.5334 0.2794)
			)
			(stroke
				(width 0)
				(type default)
			)
			(fill no)
			(layer "B.CrtYd")
		)
		(pad "1" smd rect
			(at -0.40005 0 270)
			(size 0.4572 0.508)
			(layers "B.Cu" "B.Mask" "B.Paste")
			(net "P3V3_CLK_NODE1")
		)
		(pad "2" smd rect
			(at 0.40005 0 270)
			(size 0.4572 0.508)
			(layers "B.Cu" "B.Mask" "B.Paste")
			(net "GND")
		)
	)
	(footprint ""
		(layer "B.Cu")
		(at 52.09667 -81.4832)
		(property "Reference" "R200"
			(at -13.00607 32.10687 0)
			(unlocked yes)
			(layer "B.SilkS")
			(effects
				(font
					(size 0.7874 0.5842)
					(thickness 0.1524)
				)
				(justify left mirror)
			)
		)
		(property "Value" ""
			(at 0 0 0)
			(layer "B.Fab")
			(effects
				(font
					(size 1.27 1.27)
				)
				(justify mirror)
			)
		)
		(duplicate_pad_numbers_are_jumpers no)
		(fp_line
			(start -0.7874 -0.4064)
			(end -0.7874 0.4064)
			(stroke
				(width 0.1524)
				(type default)
			)
			(layer "B.SilkS")
		)
		(fp_line
			(start -0.7874 0.4064)
			(end 0.7874 0.4064)
			(stroke
				(width 0.1524)
				(type default)
			)
			(layer "B.SilkS")
		)
		(fp_line
			(start 0.7874 -0.4064)
			(end -0.7874 -0.4064)
			(stroke
				(width 0.1524)
				(type default)
			)
			(layer "B.SilkS")
		)
		(fp_line
			(start 0.7874 0.4064)
			(end 0.7874 -0.4064)
			(stroke
				(width 0.1524)
				(type default)
			)
			(layer "B.SilkS")
		)
		(fp_poly
			(pts
				(xy 0.508 0.2794) (xy 0.508 0.2286) (xy 0.635 0.2286) (xy 0.635 -0.254) (xy 0.5334 -0.254) (xy 0.5334 -0.2794)
				(xy -0.5334 -0.2794) (xy -0.5334 -0.254) (xy -0.635 -0.254) (xy -0.635 0.254) (xy -0.5334 0.254)
				(xy -0.5334 0.2794)
			)
			(stroke
				(width 0)
				(type default)
			)
			(fill no)
			(layer "B.CrtYd")
		)
		(pad "1" smd rect
			(at -0.40005 0 180)
			(size 0.4572 0.508)
			(layers "B.Cu" "B.Mask" "B.Paste")
			(net "A_CPU_NODE1_SOC_THERMREFNPAD")
		)
		(pad "2" smd rect
			(at 0.40005 0 180)
			(size 0.4572 0.508)
			(layers "B.Cu" "B.Mask" "B.Paste")
			(net "P1V05_NODE1")
		)
	)
	(footprint ""
		(layer "B.Cu")
		(at 65.357502 -29.865828)
		(property "Reference" "C172"
			(at -3.013202 -0.287528 0)
			(unlocked yes)
			(layer "B.SilkS")
			(effects
				(font
					(size 0.7874 0.5842)
					(thickness 0.1524)
				)
				(justify mirror)
			)
		)
		(property "Value" ""
			(at 0 0 0)
			(layer "B.Fab")
			(effects
				(font
					(size 1.27 1.27)
				)
				(justify mirror)
			)
		)
		(duplicate_pad_numbers_are_jumpers no)
		(fp_line
			(start -1.2954 -0.5842)
			(end -1.2954 0.5842)
			(stroke
				(width 0.1524)
				(type default)
			)
			(layer "B.SilkS")
		)
		(fp_line
			(start -1.2954 0.5842)
			(end 1.2954 0.5842)
			(stroke
				(width 0.1524)
				(type default)
			)
			(layer "B.SilkS")
		)
		(fp_line
			(start 0 -0.5842)
			(end 0 0.5842)
			(stroke
				(width 0.1524)
				(type default)
			)
			(layer "B.SilkS")
		)
		(fp_line
			(start 1.2954 -0.5842)
			(end -1.2954 -0.5842)
			(stroke
				(width 0.1524)
				(type default)
			)
			(layer "B.SilkS")
		)
		(fp_line
			(start 1.2954 0.5842)
			(end 1.2954 -0.5842)
			(stroke
				(width 0.1524)
				(type default)
			)
			(layer "B.SilkS")
		)
		(fp_poly
			(pts
				(xy -0.8636 -0.4572) (xy -0.8636 -0.3556) (xy -1.143 -0.3556) (xy -1.143 0.3556) (xy -0.8636 0.3556)
				(xy -0.8636 0.4572) (xy 0.8636 0.4572) (xy 0.8636 0.3556) (xy 1.143 0.3556) (xy 1.143 -0.3556) (xy 0.8636 -0.3556)
				(xy 0.8636 -0.4572)
			)
			(stroke
				(width 0)
				(type default)
			)
			(fill no)
			(layer "B.CrtYd")
		)
		(fp_line
			(start -0.884936 -0.504952)
			(end -0.884936 0.504952)
			(stroke
				(width 0.1)
				(type default)
			)
			(layer "B.Fab")
		)
		(fp_line
			(start -0.884936 0.504952)
			(end 0.884936 0.504952)
			(stroke
				(width 0.1)
				(type default)
			)
			(layer "B.Fab")
		)
		(fp_line
			(start 0.884936 -0.504952)
			(end -0.884936 -0.504952)
			(stroke
				(width 0.1)
				(type default)
			)
			(layer "B.Fab")
		)
		(fp_line
			(start 0.884936 0.504952)
			(end 0.884936 -0.504952)
			(stroke
				(width 0.1)
				(type default)
			)
			(layer "B.Fab")
		)
		(pad "1" smd rect
			(at -0.7366 0 90)
			(size 0.7112 0.8128)
			(layers "B.Cu" "B.Mask" "B.Paste")
			(net "PV_VDDR_NODE1")
		)
		(pad "2" smd rect
			(at 0.7366 0 90)
			(size 0.7112 0.8128)
			(layers "B.Cu" "B.Mask" "B.Paste")
			(net "GND")
		)
	)
	(footprint ""
		(layer "B.Cu")
		(at 94.211394 -188.838586 180)
		(property "Reference" "C702"
			(at -1.315466 6.008116 0)
			(unlocked yes)
			(layer "B.SilkS")
			(effects
				(font
					(size 0.7874 0.5842)
					(thickness 0.1524)
				)
				(justify left mirror)
			)
		)
		(property "Value" ""
			(at 0 0 0)
			(layer "B.Fab")
			(effects
				(font
					(size 1.27 1.27)
				)
				(justify mirror)
			)
		)
		(duplicate_pad_numbers_are_jumpers no)
		(fp_line
			(start 0.7874 0.4064)
			(end 0.7874 -0.4064)
			(stroke
				(width 0.1524)
				(type default)
			)
			(layer "B.SilkS")
		)
		(fp_line
			(start 0.7874 -0.4064)
			(end -0.7874 -0.4064)
			(stroke
				(width 0.1524)
				(type default)
			)
			(layer "B.SilkS")
		)
		(fp_line
			(start 0 0.381)
			(end 0 -0.381)
			(stroke
				(width 0.1524)
				(type default)
			)
			(layer "B.SilkS")
		)
		(fp_line
			(start -0.7874 0.4064)
			(end 0.7874 0.4064)
			(stroke
				(width 0.1524)
				(type default)
			)
			(layer "B.SilkS")
		)
		(fp_line
			(start -0.7874 -0.4064)
			(end -0.7874 0.4064)
			(stroke
				(width 0.1524)
				(type default)
			)
			(layer "B.SilkS")
		)
		(fp_poly
			(pts
				(xy 0.5334 0.254) (xy 0.635 0.254) (xy 0.635 0.2286) (xy 0.635 -0.254) (xy 0.5334 -0.254) (xy 0.5334 -0.2794)
				(xy -0.5334 -0.2794) (xy -0.5334 -0.254) (xy -0.635 -0.254) (xy -0.635 0.254) (xy -0.5334 0.254)
				(xy -0.5334 0.2794) (xy 0.508 0.2794) (xy 0.5334 0.2794)
			)
			(stroke
				(width 0)
				(type default)
			)
			(fill no)
			(layer "B.CrtYd")
		)
		(pad "1" smd rect
			(at -0.40005 0)
			(size 0.4572 0.508)
			(layers "B.Cu" "B.Mask" "B.Paste")
			(net "UART_T6_NODE2_RXD")
		)
		(pad "2" smd rect
			(at 0.40005 0)
			(size 0.4572 0.508)
			(layers "B.Cu" "B.Mask" "B.Paste")
			(net "GND")
		)
	)
	(footprint ""
		(layer "B.Cu")
		(at 88.721438 -79.781908)
		(property "Reference" "R115"
			(at -1.91516 9.518142 0)
			(unlocked yes)
			(layer "B.SilkS")
			(effects
				(font
					(size 0.7874 0.5842)
					(thickness 0.1524)
				)
				(justify left mirror)
			)
		)
		(property "Value" ""
			(at 0 0 0)
			(layer "B.Fab")
			(effects
				(font
					(size 1.27 1.27)
				)
				(justify mirror)
			)
		)
		(duplicate_pad_numbers_are_jumpers no)
		(fp_line
			(start -0.7874 -0.4064)
			(end -0.7874 0.4064)
			(stroke
				(width 0.1524)
				(type default)
			)
			(layer "B.SilkS")
		)
		(fp_line
			(start -0.7874 0.4064)
			(end 0.7874 0.4064)
			(stroke
				(width 0.1524)
				(type default)
			)
			(layer "B.SilkS")
		)
		(fp_line
			(start 0.7874 -0.4064)
			(end -0.7874 -0.4064)
			(stroke
				(width 0.1524)
				(type default)
			)
			(layer "B.SilkS")
		)
		(fp_line
			(start 0.7874 0.4064)
			(end 0.7874 -0.4064)
			(stroke
				(width 0.1524)
				(type default)
			)
			(layer "B.SilkS")
		)
		(fp_poly
			(pts
				(xy 0.508 0.2794) (xy 0.508 0.2286) (xy 0.635 0.2286) (xy 0.635 -0.254) (xy 0.5334 -0.254) (xy 0.5334 -0.2794)
				(xy -0.5334 -0.2794) (xy -0.5334 -0.254) (xy -0.635 -0.254) (xy -0.635 0.254) (xy -0.5334 0.254)
				(xy -0.5334 0.2794)
			)
			(stroke
				(width 0)
				(type default)
			)
			(fill no)
			(layer "B.CrtYd")
		)
		(pad "1" smd rect
			(at -0.40005 0 180)
			(size 0.4572 0.508)
			(layers "B.Cu" "B.Mask" "B.Paste")
			(net "H_CPU_NODE1_PROCHOT_L")
		)
		(pad "2" smd rect
			(at 0.40005 0 180)
			(size 0.4572 0.508)
			(layers "B.Cu" "B.Mask" "B.Paste")
			(net "P1V05_NODE1")
		)
	)
	(footprint ""
		(layer "B.Cu")
		(at 40.654732 -94.40037 -90)
		(property "Reference" "C26"
			(at 4.703318 4.59994 270)
			(unlocked yes)
			(layer "B.SilkS")
			(effects
				(font
					(size 0.7874 0.5842)
					(thickness 0.1524)
				)
				(justify left mirror)
			)
		)
		(property "Value" ""
			(at 0 0 90)
			(layer "B.Fab")
			(effects
				(font
					(size 1.27 1.27)
				)
				(justify mirror)
			)
		)
		(duplicate_pad_numbers_are_jumpers no)
		(fp_line
			(start -0.7874 0.4064)
			(end 0.7874 0.4064)
			(stroke
				(width 0.1524)
				(type default)
			)
			(layer "B.SilkS")
		)
		(fp_line
			(start 0.7874 0.4064)
			(end 0.7874 -0.4064)
			(stroke
				(width 0.1524)
				(type default)
			)
			(layer "B.SilkS")
		)
		(fp_line
			(start 0 0.381)
			(end 0 -0.381)
			(stroke
				(width 0.1524)
				(type default)
			)
			(layer "B.SilkS")
		)
		(fp_line
			(start -0.7874 -0.4064)
			(end -0.7874 0.4064)
			(stroke
				(width 0.1524)
				(type default)
			)
			(layer "B.SilkS")
		)
		(fp_line
			(start 0.7874 -0.4064)
			(end -0.7874 -0.4064)
			(stroke
				(width 0.1524)
				(type default)
			)
			(layer "B.SilkS")
		)
		(fp_poly
			(pts
				(xy 0.5334 0.254) (xy 0.635 0.254) (xy 0.635 0.2286) (xy 0.635 -0.254) (xy 0.5334 -0.254) (xy 0.5334 -0.2794)
				(xy -0.5334 -0.2794) (xy -0.5334 -0.254) (xy -0.635 -0.254) (xy -0.635 0.254) (xy -0.5334 0.254)
				(xy -0.5334 0.2794) (xy 0.508 0.2794) (xy 0.5334 0.2794)
			)
			(stroke
				(width 0)
				(type default)
			)
			(fill no)
			(layer "B.CrtYd")
		)
		(pad "1" smd rect
			(at -0.40005 0 90)
			(size 0.4572 0.508)
			(layers "B.Cu" "B.Mask" "B.Paste")
			(net "GND")
		)
		(pad "2" smd rect
			(at 0.40005 0 90)
			(size 0.4572 0.508)
			(layers "B.Cu" "B.Mask" "B.Paste")
			(net "SMB_CPU_NODE1_XDP_CLK_R")
		)
	)
	(footprint ""
		(layer "B.Cu")
		(at 122.0978 -44.732702)
		(property "Reference" "R182"
			(at -2.808732 -0.016256 0)
			(unlocked yes)
			(layer "B.SilkS")
			(effects
				(font
					(size 0.7874 0.5842)
					(thickness 0.1524)
				)
				(justify left mirror)
			)
		)
		(property "Value" ""
			(at 0 0 0)
			(layer "B.Fab")
			(effects
				(font
					(size 1.27 1.27)
				)
				(justify mirror)
			)
		)
		(duplicate_pad_numbers_are_jumpers no)
		(fp_line
			(start -0.7874 -0.4064)
			(end -0.7874 0.4064)
			(stroke
				(width 0.1524)
				(type default)
			)
			(layer "B.SilkS")
		)
		(fp_line
			(start -0.7874 0.4064)
			(end 0.7874 0.4064)
			(stroke
				(width 0.1524)
				(type default)
			)
			(layer "B.SilkS")
		)
		(fp_line
			(start 0.7874 -0.4064)
			(end -0.7874 -0.4064)
			(stroke
				(width 0.1524)
				(type default)
			)
			(layer "B.SilkS")
		)
		(fp_line
			(start 0.7874 0.4064)
			(end 0.7874 -0.4064)
			(stroke
				(width 0.1524)
				(type default)
			)
			(layer "B.SilkS")
		)
		(fp_poly
			(pts
				(xy 0.508 0.2794) (xy 0.508 0.2286) (xy 0.635 0.2286) (xy 0.635 -0.254) (xy 0.5334 -0.254) (xy 0.5334 -0.2794)
				(xy -0.5334 -0.2794) (xy -0.5334 -0.254) (xy -0.635 -0.254) (xy -0.635 0.254) (xy -0.5334 0.254)
				(xy -0.5334 0.2794)
			)
			(stroke
				(width 0)
				(type default)
			)
			(fill no)
			(layer "B.CrtYd")
		)
		(pad "1" smd rect
			(at -0.40005 0 180)
			(size 0.4572 0.508)
			(layers "B.Cu" "B.Mask" "B.Paste")
			(net "LPC_CPU_NODE1_LAD0")
		)
		(pad "2" smd rect
			(at 0.40005 0 180)
			(size 0.4572 0.508)
			(layers "B.Cu" "B.Mask" "B.Paste")
			(net "LPC_CPU_NODE1_LAD0_SIO")
		)
	)
	(footprint ""
		(layer "B.Cu")
		(at 88.77935 -75.717654 180)
		(property "Reference" "R167"
			(at 1.91516 -9.834118 0)
			(unlocked yes)
			(layer "B.SilkS")
			(effects
				(font
					(size 0.7874 0.5842)
					(thickness 0.1524)
				)
				(justify left mirror)
			)
		)
		(property "Value" ""
			(at 0 0 0)
			(layer "B.Fab")
			(effects
				(font
					(size 1.27 1.27)
				)
				(justify mirror)
			)
		)
		(duplicate_pad_numbers_are_jumpers no)
		(fp_line
			(start 0.7874 0.4064)
			(end 0.7874 -0.4064)
			(stroke
				(width 0.1524)
				(type default)
			)
			(layer "B.SilkS")
		)
		(fp_line
			(start 0.7874 -0.4064)
			(end -0.7874 -0.4064)
			(stroke
				(width 0.1524)
				(type default)
			)
			(layer "B.SilkS")
		)
		(fp_line
			(start -0.7874 0.4064)
			(end 0.7874 0.4064)
			(stroke
				(width 0.1524)
				(type default)
			)
			(layer "B.SilkS")
		)
		(fp_line
			(start -0.7874 -0.4064)
			(end -0.7874 0.4064)
			(stroke
				(width 0.1524)
				(type default)
			)
			(layer "B.SilkS")
		)
		(fp_poly
			(pts
				(xy 0.508 0.2794) (xy 0.508 0.2286) (xy 0.635 0.2286) (xy 0.635 -0.254) (xy 0.5334 -0.254) (xy 0.5334 -0.2794)
				(xy -0.5334 -0.2794) (xy -0.5334 -0.254) (xy -0.635 -0.254) (xy -0.635 0.254) (xy -0.5334 0.254)
				(xy -0.5334 0.2794)
			)
			(stroke
				(width 0)
				(type default)
			)
			(fill no)
			(layer "B.CrtYd")
		)
		(pad "1" smd rect
			(at -0.40005 0)
			(size 0.4572 0.508)
			(layers "B.Cu" "B.Mask" "B.Paste")
			(net "GND")
		)
		(pad "2" smd rect
			(at 0.40005 0)
			(size 0.4572 0.508)
			(layers "B.Cu" "B.Mask" "B.Paste")
			(net "PD_CPU_NODE1_MEM_SPEED1")
		)
	)
	(footprint ""
		(layer "B.Cu")
		(at 70.736968 -62.910212)
		(property "Reference" "C116"
			(at 1.576832 1.638808 0)
			(unlocked yes)
			(layer "B.SilkS")
			(effects
				(font
					(size 0.7874 0.5842)
					(thickness 0.1524)
				)
				(justify left mirror)
			)
		)
		(property "Value" ""
			(at 0 0 0)
			(layer "B.Fab")
			(effects
				(font
					(size 1.27 1.27)
				)
				(justify mirror)
			)
		)
		(duplicate_pad_numbers_are_jumpers no)
		(fp_line
			(start -0.7874 -0.4064)
			(end -0.7874 0.4064)
			(stroke
				(width 0.1524)
				(type default)
			)
			(layer "B.SilkS")
		)
		(fp_line
			(start -0.7874 0.4064)
			(end 0.7874 0.4064)
			(stroke
				(width 0.1524)
				(type default)
			)
			(layer "B.SilkS")
		)
		(fp_line
			(start 0 0.381)
			(end 0 -0.381)
			(stroke
				(width 0.1524)
				(type default)
			)
			(layer "B.SilkS")
		)
		(fp_line
			(start 0.7874 -0.4064)
			(end -0.7874 -0.4064)
			(stroke
				(width 0.1524)
				(type default)
			)
			(layer "B.SilkS")
		)
		(fp_line
			(start 0.7874 0.4064)
			(end 0.7874 -0.4064)
			(stroke
				(width 0.1524)
				(type default)
			)
			(layer "B.SilkS")
		)
		(fp_poly
			(pts
				(xy 0.5334 0.254) (xy 0.635 0.254) (xy 0.635 0.2286) (xy 0.635 -0.254) (xy 0.5334 -0.254) (xy 0.5334 -0.2794)
				(xy -0.5334 -0.2794) (xy -0.5334 -0.254) (xy -0.635 -0.254) (xy -0.635 0.254) (xy -0.5334 0.254)
				(xy -0.5334 0.2794) (xy 0.508 0.2794) (xy 0.5334 0.2794)
			)
			(stroke
				(width 0)
				(type default)
			)
			(fill no)
			(layer "B.CrtYd")
		)
		(pad "1" smd rect
			(at -0.40005 0 180)
			(size 0.4572 0.508)
			(layers "B.Cu" "B.Mask" "B.Paste")
			(net "PV_VDDR_NODE1")
		)
		(pad "2" smd rect
			(at 0.40005 0 180)
			(size 0.4572 0.508)
			(layers "B.Cu" "B.Mask" "B.Paste")
			(net "GND")
		)
	)
	(footprint ""
		(layer "B.Cu")
		(at 94.211394 -186.806586 180)
		(property "Reference" "R915"
			(at -1.315466 5.954522 0)
			(unlocked yes)
			(layer "B.SilkS")
			(effects
				(font
					(size 0.7874 0.5842)
					(thickness 0.1524)
				)
				(justify left mirror)
			)
		)
		(property "Value" ""
			(at 0 0 0)
			(layer "B.Fab")
			(effects
				(font
					(size 1.27 1.27)
				)
				(justify mirror)
			)
		)
		(duplicate_pad_numbers_are_jumpers no)
		(fp_line
			(start 0.7874 0.4064)
			(end 0.7874 -0.4064)
			(stroke
				(width 0.1524)
				(type default)
			)
			(layer "B.SilkS")
		)
		(fp_line
			(start 0.7874 -0.4064)
			(end -0.7874 -0.4064)
			(stroke
				(width 0.1524)
				(type default)
			)
			(layer "B.SilkS")
		)
		(fp_line
			(start -0.7874 0.4064)
			(end 0.7874 0.4064)
			(stroke
				(width 0.1524)
				(type default)
			)
			(layer "B.SilkS")
		)
		(fp_line
			(start -0.7874 -0.4064)
			(end -0.7874 0.4064)
			(stroke
				(width 0.1524)
				(type default)
			)
			(layer "B.SilkS")
		)
		(fp_poly
			(pts
				(xy 0.508 0.2794) (xy 0.508 0.2286) (xy 0.635 0.2286) (xy 0.635 -0.254) (xy 0.5334 -0.254) (xy 0.5334 -0.2794)
				(xy -0.5334 -0.2794) (xy -0.5334 -0.254) (xy -0.635 -0.254) (xy -0.635 0.254) (xy -0.5334 0.254)
				(xy -0.5334 0.2794)
			)
			(stroke
				(width 0)
				(type default)
			)
			(fill no)
			(layer "B.CrtYd")
		)
		(pad "1" smd rect
			(at -0.40005 0)
			(size 0.4572 0.508)
			(layers "B.Cu" "B.Mask" "B.Paste")
			(net "UART_T5_NODE2_RXD")
		)
		(pad "2" smd rect
			(at 0.40005 0)
			(size 0.4572 0.508)
			(layers "B.Cu" "B.Mask" "B.Paste")
			(net "UART_T5_NODE2_RXD_R")
		)
	)
	(footprint ""
		(layer "B.Cu")
		(at 129.895092 -172.466508)
		(property "Reference" "R976"
			(at 5.254498 -0.829056 0)
			(unlocked yes)
			(layer "B.SilkS")
			(effects
				(font
					(size 0.7874 0.5842)
					(thickness 0.1524)
				)
				(justify left mirror)
			)
		)
		(property "Value" ""
			(at 0 0 0)
			(layer "B.Fab")
			(effects
				(font
					(size 1.27 1.27)
				)
				(justify mirror)
			)
		)
		(duplicate_pad_numbers_are_jumpers no)
		(fp_line
			(start -0.7874 -0.4064)
			(end -0.7874 0.4064)
			(stroke
				(width 0.1524)
				(type default)
			)
			(layer "B.SilkS")
		)
		(fp_line
			(start -0.7874 0.4064)
			(end 0.7874 0.4064)
			(stroke
				(width 0.1524)
				(type default)
			)
			(layer "B.SilkS")
		)
		(fp_line
			(start 0.7874 -0.4064)
			(end -0.7874 -0.4064)
			(stroke
				(width 0.1524)
				(type default)
			)
			(layer "B.SilkS")
		)
		(fp_line
			(start 0.7874 0.4064)
			(end 0.7874 -0.4064)
			(stroke
				(width 0.1524)
				(type default)
			)
			(layer "B.SilkS")
		)
		(fp_poly
			(pts
				(xy 0.508 0.2794) (xy 0.508 0.2286) (xy 0.635 0.2286) (xy 0.635 -0.254) (xy 0.5334 -0.254) (xy 0.5334 -0.2794)
				(xy -0.5334 -0.2794) (xy -0.5334 -0.254) (xy -0.635 -0.254) (xy -0.635 0.254) (xy -0.5334 0.254)
				(xy -0.5334 0.2794)
			)
			(stroke
				(width 0)
				(type default)
			)
			(fill no)
			(layer "B.CrtYd")
		)
		(pad "1" smd rect
			(at -0.40005 0 180)
			(size 0.4572 0.508)
			(layers "B.Cu" "B.Mask" "B.Paste")
			(net "UART_T7_NODE4_TXD")
		)
		(pad "2" smd rect
			(at 0.40005 0 180)
			(size 0.4572 0.508)
			(layers "B.Cu" "B.Mask" "B.Paste")
			(net "UART_T7_NODE4_TXD_R")
		)
	)
	(footprint ""
		(layer "B.Cu")
		(at 56.86298 -63.885826 180)
		(property "Reference" "R29"
			(at 14.74978 -29.546296 0)
			(unlocked yes)
			(layer "B.SilkS")
			(effects
				(font
					(size 0.7874 0.5842)
					(thickness 0.1524)
				)
				(justify left mirror)
			)
		)
		(property "Value" ""
			(at 0 0 0)
			(layer "B.Fab")
			(effects
				(font
					(size 1.27 1.27)
				)
				(justify mirror)
			)
		)
		(duplicate_pad_numbers_are_jumpers no)
		(fp_line
			(start 0.7874 0.4064)
			(end 0.7874 -0.4064)
			(stroke
				(width 0.1524)
				(type default)
			)
			(layer "B.SilkS")
		)
		(fp_line
			(start 0.7874 -0.4064)
			(end -0.7874 -0.4064)
			(stroke
				(width 0.1524)
				(type default)
			)
			(layer "B.SilkS")
		)
		(fp_line
			(start -0.7874 0.4064)
			(end 0.7874 0.4064)
			(stroke
				(width 0.1524)
				(type default)
			)
			(layer "B.SilkS")
		)
		(fp_line
			(start -0.7874 -0.4064)
			(end -0.7874 0.4064)
			(stroke
				(width 0.1524)
				(type default)
			)
			(layer "B.SilkS")
		)
		(fp_poly
			(pts
				(xy 0.508 0.2794) (xy 0.508 0.2286) (xy 0.635 0.2286) (xy 0.635 -0.254) (xy 0.5334 -0.254) (xy 0.5334 -0.2794)
				(xy -0.5334 -0.2794) (xy -0.5334 -0.254) (xy -0.635 -0.254) (xy -0.635 0.254) (xy -0.5334 0.254)
				(xy -0.5334 0.2794)
			)
			(stroke
				(width 0)
				(type default)
			)
			(fill no)
			(layer "B.CrtYd")
		)
		(pad "1" smd rect
			(at -0.40005 0)
			(size 0.4572 0.508)
			(layers "B.Cu" "B.Mask" "B.Paste")
			(net "M_DDR3_NODE1_DQPU")
		)
		(pad "2" smd rect
			(at 0.40005 0)
			(size 0.4572 0.508)
			(layers "B.Cu" "B.Mask" "B.Paste")
			(net "GND")
		)
	)
	(footprint ""
		(layer "B.Cu")
		(at 167.624252 -97.04959 90)
		(property "Reference" "C370"
			(at -2.14376 -1.108964 270)
			(unlocked yes)
			(layer "B.SilkS")
			(effects
				(font
					(size 0.7874 0.5842)
					(thickness 0.1524)
				)
				(justify left mirror)
			)
		)
		(property "Value" ""
			(at 0 0 90)
			(layer "B.Fab")
			(effects
				(font
					(size 1.27 1.27)
				)
				(justify mirror)
			)
		)
		(duplicate_pad_numbers_are_jumpers no)
		(fp_line
			(start 0.7874 -0.4064)
			(end -0.7874 -0.4064)
			(stroke
				(width 0.1524)
				(type default)
			)
			(layer "B.SilkS")
		)
		(fp_line
			(start -0.7874 -0.4064)
			(end -0.7874 0.4064)
			(stroke
				(width 0.1524)
				(type default)
			)
			(layer "B.SilkS")
		)
		(fp_line
			(start 0 0.381)
			(end 0 -0.381)
			(stroke
				(width 0.1524)
				(type default)
			)
			(layer "B.SilkS")
		)
		(fp_line
			(start 0.7874 0.4064)
			(end 0.7874 -0.4064)
			(stroke
				(width 0.1524)
				(type default)
			)
			(layer "B.SilkS")
		)
		(fp_line
			(start -0.7874 0.4064)
			(end 0.7874 0.4064)
			(stroke
				(width 0.1524)
				(type default)
			)
			(layer "B.SilkS")
		)
		(fp_poly
			(pts
				(xy 0.5334 0.254) (xy 0.635 0.254) (xy 0.635 0.2286) (xy 0.635 -0.254) (xy 0.5334 -0.254) (xy 0.5334 -0.2794)
				(xy -0.5334 -0.2794) (xy -0.5334 -0.254) (xy -0.635 -0.254) (xy -0.635 0.254) (xy -0.5334 0.254)
				(xy -0.5334 0.2794) (xy 0.508 0.2794) (xy 0.5334 0.2794)
			)
			(stroke
				(width 0)
				(type default)
			)
			(fill no)
			(layer "B.CrtYd")
		)
		(pad "1" smd rect
			(at -0.40005 0 270)
			(size 0.4572 0.508)
			(layers "B.Cu" "B.Mask" "B.Paste")
			(net "P1V05_NODE1")
		)
		(pad "2" smd rect
			(at 0.40005 0 270)
			(size 0.4572 0.508)
			(layers "B.Cu" "B.Mask" "B.Paste")
			(net "GND")
		)
	)
	(footprint ""
		(layer "B.Cu")
		(at 128.701546 -34.972244)
		(property "Reference" "R1208"
			(at 1.320038 9.040368 0)
			(unlocked yes)
			(layer "B.SilkS")
			(effects
				(font
					(size 0.7874 0.5842)
					(thickness 0.1524)
				)
				(justify left mirror)
			)
		)
		(property "Value" ""
			(at 0 0 0)
			(layer "B.Fab")
			(effects
				(font
					(size 1.27 1.27)
				)
				(justify mirror)
			)
		)
		(duplicate_pad_numbers_are_jumpers no)
		(fp_line
			(start -0.7874 -0.406146)
			(end -0.7874 0.406146)
			(stroke
				(width 0.1524)
				(type default)
			)
			(layer "B.SilkS")
		)
		(fp_line
			(start -0.7874 0.406146)
			(end 0.7874 0.406146)
			(stroke
				(width 0.1524)
				(type default)
			)
			(layer "B.SilkS")
		)
		(fp_line
			(start 0.7874 -0.406146)
			(end -0.7874 -0.406146)
			(stroke
				(width 0.1524)
				(type default)
			)
			(layer "B.SilkS")
		)
		(fp_line
			(start 0.7874 0.406146)
			(end 0.7874 -0.406146)
			(stroke
				(width 0.1524)
				(type default)
			)
			(layer "B.SilkS")
		)
		(fp_poly
			(pts
				(xy 0.508 0.2794) (xy 0.508 0.2286) (xy 0.635 0.2286) (xy 0.635 -0.254) (xy 0.5334 -0.254) (xy 0.5334 -0.2794)
				(xy -0.5334 -0.2794) (xy -0.5334 -0.254) (xy -0.635 -0.254) (xy -0.635 0.254) (xy -0.5334 0.254)
				(xy -0.5334 0.2794)
			)
			(stroke
				(width 0)
				(type default)
			)
			(fill no)
			(layer "B.CrtYd")
		)
		(pad "1" smd rect
			(at -0.40005 0 180)
			(size 0.4572 0.508)
			(layers "B.Cu" "B.Mask" "B.Paste")
			(net "SIO_JTAG_CPLD3_TMS_R")
		)
		(pad "2" smd rect
			(at 0.40005 0 180)
			(size 0.4572 0.508)
			(layers "B.Cu" "B.Mask" "B.Paste")
			(net "SIO_JTAG_CPLD3_TMS")
		)
	)
	(footprint ""
		(layer "B.Cu")
		(at 98.020632 -181.672992)
		(property "Reference" "R755"
			(at 1.361948 -1.008634 0)
			(unlocked yes)
			(layer "B.SilkS")
			(effects
				(font
					(size 0.7874 0.5842)
					(thickness 0.1524)
				)
				(justify left mirror)
			)
		)
		(property "Value" ""
			(at 0 0 0)
			(layer "B.Fab")
			(effects
				(font
					(size 1.27 1.27)
				)
				(justify mirror)
			)
		)
		(duplicate_pad_numbers_are_jumpers no)
		(fp_line
			(start -0.7874 -0.4064)
			(end -0.7874 0.4064)
			(stroke
				(width 0.1524)
				(type default)
			)
			(layer "B.SilkS")
		)
		(fp_line
			(start -0.7874 0.4064)
			(end 0.7874 0.4064)
			(stroke
				(width 0.1524)
				(type default)
			)
			(layer "B.SilkS")
		)
		(fp_line
			(start 0.7874 -0.4064)
			(end -0.7874 -0.4064)
			(stroke
				(width 0.1524)
				(type default)
			)
			(layer "B.SilkS")
		)
		(fp_line
			(start 0.7874 0.4064)
			(end 0.7874 -0.4064)
			(stroke
				(width 0.1524)
				(type default)
			)
			(layer "B.SilkS")
		)
		(fp_poly
			(pts
				(xy 0.508 0.2794) (xy 0.508 0.2286) (xy 0.635 0.2286) (xy 0.635 -0.254) (xy 0.5334 -0.254) (xy 0.5334 -0.2794)
				(xy -0.5334 -0.2794) (xy -0.5334 -0.254) (xy -0.635 -0.254) (xy -0.635 0.254) (xy -0.5334 0.254)
				(xy -0.5334 0.2794)
			)
			(stroke
				(width 0)
				(type default)
			)
			(fill no)
			(layer "B.CrtYd")
		)
		(pad "1" smd rect
			(at -0.40005 0 180)
			(size 0.4572 0.508)
			(layers "B.Cu" "B.Mask" "B.Paste")
			(net "CPLD_WDT2")
		)
		(pad "2" smd rect
			(at 0.40005 0 180)
			(size 0.4572 0.508)
			(layers "B.Cu" "B.Mask" "B.Paste")
			(net "PCA_CPLD_WDT2")
		)
	)
	(footprint ""
		(layer "B.Cu")
		(at 126.635002 -116.571014 90)
		(property "Reference" "R6"
			(at -0.671576 -1.116076 270)
			(unlocked yes)
			(layer "B.SilkS")
			(effects
				(font
					(size 0.7874 0.5842)
					(thickness 0.1524)
				)
				(justify left mirror)
			)
		)
		(property "Value" ""
			(at 0 0 90)
			(layer "B.Fab")
			(effects
				(font
					(size 1.27 1.27)
				)
				(justify mirror)
			)
		)
		(duplicate_pad_numbers_are_jumpers no)
		(fp_line
			(start 0.7874 -0.4064)
			(end -0.7874 -0.4064)
			(stroke
				(width 0.1524)
				(type default)
			)
			(layer "B.SilkS")
		)
		(fp_line
			(start -0.7874 -0.4064)
			(end -0.7874 0.4064)
			(stroke
				(width 0.1524)
				(type default)
			)
			(layer "B.SilkS")
		)
		(fp_line
			(start 0.7874 0.4064)
			(end 0.7874 -0.4064)
			(stroke
				(width 0.1524)
				(type default)
			)
			(layer "B.SilkS")
		)
		(fp_line
			(start -0.7874 0.4064)
			(end 0.7874 0.4064)
			(stroke
				(width 0.1524)
				(type default)
			)
			(layer "B.SilkS")
		)
		(fp_poly
			(pts
				(xy 0.508 0.2794) (xy 0.508 0.2286) (xy 0.635 0.2286) (xy 0.635 -0.254) (xy 0.5334 -0.254) (xy 0.5334 -0.2794)
				(xy -0.5334 -0.2794) (xy -0.5334 -0.254) (xy -0.635 -0.254) (xy -0.635 0.254) (xy -0.5334 0.254)
				(xy -0.5334 0.2794)
			)
			(stroke
				(width 0)
				(type default)
			)
			(fill no)
			(layer "B.CrtYd")
		)
		(pad "1" smd rect
			(at -0.40005 0 270)
			(size 0.4572 0.508)
			(layers "B.Cu" "B.Mask" "B.Paste")
			(net "P3V3_CLK_NODE1")
		)
		(pad "2" smd rect
			(at 0.40005 0 270)
			(size 0.4572 0.508)
			(layers "B.Cu" "B.Mask" "B.Paste")
			(net "CPU_STP_NODE1")
		)
	)
	(footprint ""
		(layer "B.Cu")
		(at 40.376602 -157.716982)
		(property "Reference" "C404"
			(at -6.504178 -9.453372 0)
			(unlocked yes)
			(layer "B.SilkS")
			(effects
				(font
					(size 0.7874 0.5842)
					(thickness 0.1524)
				)
				(justify left mirror)
			)
		)
		(property "Value" ""
			(at 0 0 0)
			(layer "B.Fab")
			(effects
				(font
					(size 1.27 1.27)
				)
				(justify mirror)
			)
		)
		(duplicate_pad_numbers_are_jumpers no)
		(fp_line
			(start -0.7874 -0.4064)
			(end -0.7874 0.4064)
			(stroke
				(width 0.1524)
				(type default)
			)
			(layer "B.SilkS")
		)
		(fp_line
			(start -0.7874 0.4064)
			(end 0.7874 0.4064)
			(stroke
				(width 0.1524)
				(type default)
			)
			(layer "B.SilkS")
		)
		(fp_line
			(start 0 0.381)
			(end 0 -0.381)
			(stroke
				(width 0.1524)
				(type default)
			)
			(layer "B.SilkS")
		)
		(fp_line
			(start 0.7874 -0.4064)
			(end -0.7874 -0.4064)
			(stroke
				(width 0.1524)
				(type default)
			)
			(layer "B.SilkS")
		)
		(fp_line
			(start 0.7874 0.4064)
			(end 0.7874 -0.4064)
			(stroke
				(width 0.1524)
				(type default)
			)
			(layer "B.SilkS")
		)
		(fp_poly
			(pts
				(xy 0.5334 0.254) (xy 0.635 0.254) (xy 0.635 0.2286) (xy 0.635 -0.254) (xy 0.5334 -0.254) (xy 0.5334 -0.2794)
				(xy -0.5334 -0.2794) (xy -0.5334 -0.254) (xy -0.635 -0.254) (xy -0.635 0.254) (xy -0.5334 0.254)
				(xy -0.5334 0.2794) (xy 0.508 0.2794) (xy 0.5334 0.2794)
			)
			(stroke
				(width 0)
				(type default)
			)
			(fill no)
			(layer "B.CrtYd")
		)
		(pad "1" smd rect
			(at -0.40005 0 180)
			(size 0.4572 0.508)
			(layers "B.Cu" "B.Mask" "B.Paste")
			(net "P1V9_LAN1")
		)
		(pad "2" smd rect
			(at 0.40005 0 180)
			(size 0.4572 0.508)
			(layers "B.Cu" "B.Mask" "B.Paste")
			(net "GND")
		)
	)
	(footprint ""
		(layer "B.Cu")
		(at 140.760196 -62.88913)
		(property "Reference" "C340"
			(at -4.916424 0.066294 0)
			(unlocked yes)
			(layer "B.SilkS")
			(effects
				(font
					(size 0.7874 0.5842)
					(thickness 0.1524)
				)
				(justify left mirror)
			)
		)
		(property "Value" ""
			(at 0 0 0)
			(layer "B.Fab")
			(effects
				(font
					(size 1.27 1.27)
				)
				(justify mirror)
			)
		)
		(duplicate_pad_numbers_are_jumpers no)
		(fp_line
			(start -0.7874 -0.4064)
			(end -0.7874 0.4064)
			(stroke
				(width 0.1524)
				(type default)
			)
			(layer "B.SilkS")
		)
		(fp_line
			(start -0.7874 0.4064)
			(end 0.7874 0.4064)
			(stroke
				(width 0.1524)
				(type default)
			)
			(layer "B.SilkS")
		)
		(fp_line
			(start 0 0.381)
			(end 0 -0.381)
			(stroke
				(width 0.1524)
				(type default)
			)
			(layer "B.SilkS")
		)
		(fp_line
			(start 0.7874 -0.4064)
			(end -0.7874 -0.4064)
			(stroke
				(width 0.1524)
				(type default)
			)
			(layer "B.SilkS")
		)
		(fp_line
			(start 0.7874 0.4064)
			(end 0.7874 -0.4064)
			(stroke
				(width 0.1524)
				(type default)
			)
			(layer "B.SilkS")
		)
		(fp_poly
			(pts
				(xy 0.5334 0.254) (xy 0.635 0.254) (xy 0.635 0.2286) (xy 0.635 -0.254) (xy 0.5334 -0.254) (xy 0.5334 -0.2794)
				(xy -0.5334 -0.2794) (xy -0.5334 -0.254) (xy -0.635 -0.254) (xy -0.635 0.254) (xy -0.5334 0.254)
				(xy -0.5334 0.2794) (xy 0.508 0.2794) (xy 0.5334 0.2794)
			)
			(stroke
				(width 0)
				(type default)
			)
			(fill no)
			(layer "B.CrtYd")
		)
		(pad "1" smd rect
			(at -0.40005 0 180)
			(size 0.4572 0.508)
			(layers "B.Cu" "B.Mask" "B.Paste")
			(net "P1V0_SATA")
		)
		(pad "2" smd rect
			(at 0.40005 0 180)
			(size 0.4572 0.508)
			(layers "B.Cu" "B.Mask" "B.Paste")
			(net "GND")
		)
	)
	(footprint ""
		(layer "B.Cu")
		(at 54.215538 -72.292718 180)
		(property "Reference" "C125"
			(at 12.404598 -31.464758 0)
			(unlocked yes)
			(layer "B.SilkS")
			(effects
				(font
					(size 0.7874 0.5842)
					(thickness 0.1524)
				)
				(justify left mirror)
			)
		)
		(property "Value" ""
			(at 0 0 0)
			(layer "B.Fab")
			(effects
				(font
					(size 1.27 1.27)
				)
				(justify mirror)
			)
		)
		(duplicate_pad_numbers_are_jumpers no)
		(fp_line
			(start 0.7874 0.4064)
			(end 0.7874 -0.4064)
			(stroke
				(width 0.1524)
				(type default)
			)
			(layer "B.SilkS")
		)
		(fp_line
			(start 0.7874 -0.4064)
			(end -0.7874 -0.4064)
			(stroke
				(width 0.1524)
				(type default)
			)
			(layer "B.SilkS")
		)
		(fp_line
			(start 0 0.381)
			(end 0 -0.381)
			(stroke
				(width 0.1524)
				(type default)
			)
			(layer "B.SilkS")
		)
		(fp_line
			(start -0.7874 0.4064)
			(end 0.7874 0.4064)
			(stroke
				(width 0.1524)
				(type default)
			)
			(layer "B.SilkS")
		)
		(fp_line
			(start -0.7874 -0.4064)
			(end -0.7874 0.4064)
			(stroke
				(width 0.1524)
				(type default)
			)
			(layer "B.SilkS")
		)
		(fp_poly
			(pts
				(xy 0.5334 0.254) (xy 0.635 0.254) (xy 0.635 0.2286) (xy 0.635 -0.254) (xy 0.5334 -0.254) (xy 0.5334 -0.2794)
				(xy -0.5334 -0.2794) (xy -0.5334 -0.254) (xy -0.635 -0.254) (xy -0.635 0.254) (xy -0.5334 0.254)
				(xy -0.5334 0.2794) (xy 0.508 0.2794) (xy 0.5334 0.2794)
			)
			(stroke
				(width 0)
				(type default)
			)
			(fill no)
			(layer "B.CrtYd")
		)
		(pad "1" smd rect
			(at -0.40005 0)
			(size 0.4572 0.508)
			(layers "B.Cu" "B.Mask" "B.Paste")
			(net "P1V05_NODE1")
		)
		(pad "2" smd rect
			(at 0.40005 0)
			(size 0.4572 0.508)
			(layers "B.Cu" "B.Mask" "B.Paste")
			(net "GND")
		)
	)
	(footprint ""
		(layer "B.Cu")
		(at 160.816798 -157.77083 -90)
		(property "Reference" "C440"
			(at -2.361184 0.790702 270)
			(unlocked yes)
			(layer "B.SilkS")
			(effects
				(font
					(size 0.7874 0.5842)
					(thickness 0.1524)
				)
				(justify left mirror)
			)
		)
		(property "Value" ""
			(at 0 0 90)
			(layer "B.Fab")
			(effects
				(font
					(size 1.27 1.27)
				)
				(justify mirror)
			)
		)
		(duplicate_pad_numbers_are_jumpers no)
		(fp_line
			(start -0.7874 0.4064)
			(end 0.7874 0.4064)
			(stroke
				(width 0.1524)
				(type default)
			)
			(layer "B.SilkS")
		)
		(fp_line
			(start 0.7874 0.4064)
			(end 0.7874 -0.4064)
			(stroke
				(width 0.1524)
				(type default)
			)
			(layer "B.SilkS")
		)
		(fp_line
			(start 0 0.381)
			(end 0 -0.381)
			(stroke
				(width 0.1524)
				(type default)
			)
			(layer "B.SilkS")
		)
		(fp_line
			(start -0.7874 -0.4064)
			(end -0.7874 0.4064)
			(stroke
				(width 0.1524)
				(type default)
			)
			(layer "B.SilkS")
		)
		(fp_line
			(start 0.7874 -0.4064)
			(end -0.7874 -0.4064)
			(stroke
				(width 0.1524)
				(type default)
			)
			(layer "B.SilkS")
		)
		(fp_poly
			(pts
				(xy 0.5334 0.254) (xy 0.635 0.254) (xy 0.635 0.2286) (xy 0.635 -0.254) (xy 0.5334 -0.254) (xy 0.5334 -0.2794)
				(xy -0.5334 -0.2794) (xy -0.5334 -0.254) (xy -0.635 -0.254) (xy -0.635 0.254) (xy -0.5334 0.254)
				(xy -0.5334 0.2794) (xy 0.508 0.2794) (xy 0.5334 0.2794)
			)
			(stroke
				(width 0)
				(type default)
			)
			(fill no)
			(layer "B.CrtYd")
		)
		(pad "1" smd rect
			(at -0.40005 0 90)
			(size 0.4572 0.508)
			(layers "B.Cu" "B.Mask" "B.Paste")
			(net "P3V3_NODE1")
		)
		(pad "2" smd rect
			(at 0.40005 0 90)
			(size 0.4572 0.508)
			(layers "B.Cu" "B.Mask" "B.Paste")
			(net "GND")
		)
	)
	(footprint ""
		(layer "B.Cu")
		(at 131.93776 -187.872624 -90)
		(property "Reference" "C728"
			(at -4.565396 1.17475 270)
			(unlocked yes)
			(layer "B.SilkS")
			(effects
				(font
					(size 0.7874 0.5842)
					(thickness 0.1524)
				)
				(justify left mirror)
			)
		)
		(property "Value" ""
			(at 0 0 90)
			(layer "B.Fab")
			(effects
				(font
					(size 1.27 1.27)
				)
				(justify mirror)
			)
		)
		(duplicate_pad_numbers_are_jumpers no)
		(fp_line
			(start -0.7874 0.4064)
			(end 0.7874 0.4064)
			(stroke
				(width 0.1524)
				(type default)
			)
			(layer "B.SilkS")
		)
		(fp_line
			(start 0.7874 0.4064)
			(end 0.7874 -0.4064)
			(stroke
				(width 0.1524)
				(type default)
			)
			(layer "B.SilkS")
		)
		(fp_line
			(start 0 0.381)
			(end 0 -0.381)
			(stroke
				(width 0.1524)
				(type default)
			)
			(layer "B.SilkS")
		)
		(fp_line
			(start -0.7874 -0.4064)
			(end -0.7874 0.4064)
			(stroke
				(width 0.1524)
				(type default)
			)
			(layer "B.SilkS")
		)
		(fp_line
			(start 0.7874 -0.4064)
			(end -0.7874 -0.4064)
			(stroke
				(width 0.1524)
				(type default)
			)
			(layer "B.SilkS")
		)
		(fp_poly
			(pts
				(xy 0.5334 0.254) (xy 0.635 0.254) (xy 0.635 0.2286) (xy 0.635 -0.254) (xy 0.5334 -0.254) (xy 0.5334 -0.2794)
				(xy -0.5334 -0.2794) (xy -0.5334 -0.254) (xy -0.635 -0.254) (xy -0.635 0.254) (xy -0.5334 0.254)
				(xy -0.5334 0.2794) (xy 0.508 0.2794) (xy 0.5334 0.2794)
			)
			(stroke
				(width 0)
				(type default)
			)
			(fill no)
			(layer "B.CrtYd")
		)
		(pad "1" smd rect
			(at -0.40005 0 90)
			(size 0.4572 0.508)
			(layers "B.Cu" "B.Mask" "B.Paste")
			(net "UART_T9_NODE2_TXD_R")
		)
		(pad "2" smd rect
			(at 0.40005 0 90)
			(size 0.4572 0.508)
			(layers "B.Cu" "B.Mask" "B.Paste")
			(net "GND")
		)
	)
	(footprint ""
		(layer "B.Cu")
		(at 39.638732 -94.40037 90)
		(property "Reference" "R130"
			(at -4.703318 -4.648454 270)
			(unlocked yes)
			(layer "B.SilkS")
			(effects
				(font
					(size 0.7874 0.5842)
					(thickness 0.1524)
				)
				(justify left mirror)
			)
		)
		(property "Value" ""
			(at 0 0 90)
			(layer "B.Fab")
			(effects
				(font
					(size 1.27 1.27)
				)
				(justify mirror)
			)
		)
		(duplicate_pad_numbers_are_jumpers no)
		(fp_line
			(start 0.7874 -0.4064)
			(end -0.7874 -0.4064)
			(stroke
				(width 0.1524)
				(type default)
			)
			(layer "B.SilkS")
		)
		(fp_line
			(start -0.7874 -0.4064)
			(end -0.7874 0.4064)
			(stroke
				(width 0.1524)
				(type default)
			)
			(layer "B.SilkS")
		)
		(fp_line
			(start 0.7874 0.4064)
			(end 0.7874 -0.4064)
			(stroke
				(width 0.1524)
				(type default)
			)
			(layer "B.SilkS")
		)
		(fp_line
			(start -0.7874 0.4064)
			(end 0.7874 0.4064)
			(stroke
				(width 0.1524)
				(type default)
			)
			(layer "B.SilkS")
		)
		(fp_poly
			(pts
				(xy 0.508 0.2794) (xy 0.508 0.2286) (xy 0.635 0.2286) (xy 0.635 -0.254) (xy 0.5334 -0.254) (xy 0.5334 -0.2794)
				(xy -0.5334 -0.2794) (xy -0.5334 -0.254) (xy -0.635 -0.254) (xy -0.635 0.254) (xy -0.5334 0.254)
				(xy -0.5334 0.2794)
			)
			(stroke
				(width 0)
				(type default)
			)
			(fill no)
			(layer "B.CrtYd")
		)
		(pad "1" smd rect
			(at -0.40005 0 270)
			(size 0.4572 0.508)
			(layers "B.Cu" "B.Mask" "B.Paste")
			(net "SMB_CPU_NODE1_BMC_CLK_RR")
		)
		(pad "2" smd rect
			(at 0.40005 0 270)
			(size 0.4572 0.508)
			(layers "B.Cu" "B.Mask" "B.Paste")
			(net "SMB_CPU_NODE1_BMC_CLK")
		)
	)
	(footprint ""
		(layer "B.Cu")
		(at 128.889252 -142.85595 180)
		(property "Reference" "L53"
			(at -3.670808 0.096266 0)
			(unlocked yes)
			(layer "B.SilkS")
			(effects
				(font
					(size 0.7874 0.5842)
					(thickness 0.1524)
				)
				(justify mirror)
			)
		)
		(property "Value" ""
			(at 0 0 0)
			(layer "B.Fab")
			(effects
				(font
					(size 1.27 1.27)
				)
				(justify mirror)
			)
		)
		(duplicate_pad_numbers_are_jumpers no)
		(fp_line
			(start 1.2954 -0.635)
			(end 1.2954 0.635)
			(stroke
				(width 0.1524)
				(type default)
			)
			(layer "B.SilkS")
		)
		(fp_line
			(start 1.2954 -0.635)
			(end -1.2954 -0.635)
			(stroke
				(width 0.1524)
				(type default)
			)
			(layer "B.SilkS")
		)
		(fp_line
			(start 0.127 -0.5842)
			(end 0.127 0.5842)
			(stroke
				(width 0.1524)
				(type default)
			)
			(layer "B.SilkS")
		)
		(fp_line
			(start -0.127 -0.5842)
			(end -0.127 0.5842)
			(stroke
				(width 0.1524)
				(type default)
			)
			(layer "B.SilkS")
		)
		(fp_line
			(start -1.2954 0.635)
			(end 1.2954 0.635)
			(stroke
				(width 0.1524)
				(type default)
			)
			(layer "B.SilkS")
		)
		(fp_line
			(start -1.2954 -0.635)
			(end -1.2954 0.635)
			(stroke
				(width 0.1524)
				(type default)
			)
			(layer "B.SilkS")
		)
		(fp_poly
			(pts
				(xy 0.9144 0.508) (xy 0.9144 0.3556) (xy 1.143 0.3556) (xy 1.143 -0.3556) (xy 0.9144 -0.3556) (xy 0.9144 -0.508)
				(xy -0.9144 -0.508) (xy -0.9144 -0.3556) (xy -1.143 -0.3556) (xy -1.143 0.3556) (xy -0.9144 0.3556)
				(xy -0.9144 0.508)
			)
			(stroke
				(width 0)
				(type default)
			)
			(fill no)
			(layer "B.CrtYd")
		)
		(pad "1" smd rect
			(at -0.7366 0 270)
			(size 0.7112 0.8128)
			(layers "B.Cu" "B.Mask" "B.Paste")
			(net "P1V0_NODE1")
		)
		(pad "2" smd rect
			(at 0.7366 0 270)
			(size 0.7112 0.8128)
			(layers "B.Cu" "B.Mask" "B.Paste")
			(net "P1V0_PCI_SW_A")
		)
	)
	(footprint ""
		(layer "B.Cu")
		(at 44.91482 -159.16529 -90)
		(property "Reference" "C418"
			(at -7.05485 6.84276 270)
			(unlocked yes)
			(layer "B.SilkS")
			(effects
				(font
					(size 0.7874 0.5842)
					(thickness 0.1524)
				)
				(justify left mirror)
			)
		)
		(property "Value" ""
			(at 0 0 90)
			(layer "B.Fab")
			(effects
				(font
					(size 1.27 1.27)
				)
				(justify mirror)
			)
		)
		(duplicate_pad_numbers_are_jumpers no)
		(fp_line
			(start -0.7874 0.4064)
			(end 0.7874 0.4064)
			(stroke
				(width 0.1524)
				(type default)
			)
			(layer "B.SilkS")
		)
		(fp_line
			(start 0.7874 0.4064)
			(end 0.7874 -0.4064)
			(stroke
				(width 0.1524)
				(type default)
			)
			(layer "B.SilkS")
		)
		(fp_line
			(start 0 0.381)
			(end 0 -0.381)
			(stroke
				(width 0.1524)
				(type default)
			)
			(layer "B.SilkS")
		)
		(fp_line
			(start -0.7874 -0.4064)
			(end -0.7874 0.4064)
			(stroke
				(width 0.1524)
				(type default)
			)
			(layer "B.SilkS")
		)
		(fp_line
			(start 0.7874 -0.4064)
			(end -0.7874 -0.4064)
			(stroke
				(width 0.1524)
				(type default)
			)
			(layer "B.SilkS")
		)
		(fp_poly
			(pts
				(xy 0.5334 0.254) (xy 0.635 0.254) (xy 0.635 0.2286) (xy 0.635 -0.254) (xy 0.5334 -0.254) (xy 0.5334 -0.2794)
				(xy -0.5334 -0.2794) (xy -0.5334 -0.254) (xy -0.635 -0.254) (xy -0.635 0.254) (xy -0.5334 0.254)
				(xy -0.5334 0.2794) (xy 0.508 0.2794) (xy 0.5334 0.2794)
			)
			(stroke
				(width 0)
				(type default)
			)
			(fill no)
			(layer "B.CrtYd")
		)
		(pad "1" smd rect
			(at -0.40005 0 90)
			(size 0.4572 0.508)
			(layers "B.Cu" "B.Mask" "B.Paste")
			(net "P1V05_LAN1")
		)
		(pad "2" smd rect
			(at 0.40005 0 90)
			(size 0.4572 0.508)
			(layers "B.Cu" "B.Mask" "B.Paste")
			(net "GND")
		)
	)
	(footprint ""
		(layer "B.Cu")
		(at 152.588214 -62.075822 90)
		(property "Reference" "C357"
			(at -2.829814 6.128512 270)
			(unlocked yes)
			(layer "B.SilkS")
			(effects
				(font
					(size 0.7874 0.5842)
					(thickness 0.1524)
				)
				(justify left mirror)
			)
		)
		(property "Value" ""
			(at 0 0 90)
			(layer "B.Fab")
			(effects
				(font
					(size 1.27 1.27)
				)
				(justify mirror)
			)
		)
		(duplicate_pad_numbers_are_jumpers no)
		(fp_line
			(start 0.7874 -0.4064)
			(end -0.7874 -0.4064)
			(stroke
				(width 0.1524)
				(type default)
			)
			(layer "B.SilkS")
		)
		(fp_line
			(start -0.7874 -0.4064)
			(end -0.7874 0.4064)
			(stroke
				(width 0.1524)
				(type default)
			)
			(layer "B.SilkS")
		)
		(fp_line
			(start 0 0.381)
			(end 0 -0.381)
			(stroke
				(width 0.1524)
				(type default)
			)
			(layer "B.SilkS")
		)
		(fp_line
			(start 0.7874 0.4064)
			(end 0.7874 -0.4064)
			(stroke
				(width 0.1524)
				(type default)
			)
			(layer "B.SilkS")
		)
		(fp_line
			(start -0.7874 0.4064)
			(end 0.7874 0.4064)
			(stroke
				(width 0.1524)
				(type default)
			)
			(layer "B.SilkS")
		)
		(fp_poly
			(pts
				(xy 0.5334 0.254) (xy 0.635 0.254) (xy 0.635 0.2286) (xy 0.635 -0.254) (xy 0.5334 -0.254) (xy 0.5334 -0.2794)
				(xy -0.5334 -0.2794) (xy -0.5334 -0.254) (xy -0.635 -0.254) (xy -0.635 0.254) (xy -0.5334 0.254)
				(xy -0.5334 0.2794) (xy 0.508 0.2794) (xy 0.5334 0.2794)
			)
			(stroke
				(width 0)
				(type default)
			)
			(fill no)
			(layer "B.CrtYd")
		)
		(pad "1" smd rect
			(at -0.40005 0 270)
			(size 0.4572 0.508)
			(layers "B.Cu" "B.Mask" "B.Paste")
			(net "GND")
		)
		(pad "2" smd rect
			(at 0.40005 0 270)
			(size 0.4572 0.508)
			(layers "B.Cu" "B.Mask" "B.Paste")
			(net "P1V8_SATA_VAA2_1_NODE1")
		)
	)
	(footprint ""
		(layer "B.Cu")
		(at 55.935372 -68.475098 -90)
		(property "Reference" "C93"
			(at 32.281622 14.138402 270)
			(unlocked yes)
			(layer "B.SilkS")
			(effects
				(font
					(size 0.7874 0.5842)
					(thickness 0.1524)
				)
				(justify mirror)
			)
		)
		(property "Value" ""
			(at 0 0 90)
			(layer "B.Fab")
			(effects
				(font
					(size 1.27 1.27)
				)
				(justify mirror)
			)
		)
		(duplicate_pad_numbers_are_jumpers no)
		(fp_line
			(start -1.2954 0.5842)
			(end 1.2954 0.5842)
			(stroke
				(width 0.1524)
				(type default)
			)
			(layer "B.SilkS")
		)
		(fp_line
			(start 1.2954 0.5842)
			(end 1.2954 -0.5842)
			(stroke
				(width 0.1524)
				(type default)
			)
			(layer "B.SilkS")
		)
		(fp_line
			(start -1.2954 -0.5842)
			(end -1.2954 0.5842)
			(stroke
				(width 0.1524)
				(type default)
			)
			(layer "B.SilkS")
		)
		(fp_line
			(start 0 -0.5842)
			(end 0 0.5842)
			(stroke
				(width 0.1524)
				(type default)
			)
			(layer "B.SilkS")
		)
		(fp_line
			(start 1.2954 -0.5842)
			(end -1.2954 -0.5842)
			(stroke
				(width 0.1524)
				(type default)
			)
			(layer "B.SilkS")
		)
		(fp_poly
			(pts
				(xy -0.8636 -0.4572) (xy -0.8636 -0.3556) (xy -1.143 -0.3556) (xy -1.143 0.3556) (xy -0.8636 0.3556)
				(xy -0.8636 0.4572) (xy 0.8636 0.4572) (xy 0.8636 0.3556) (xy 1.143 0.3556) (xy 1.143 -0.3556) (xy 0.8636 -0.3556)
				(xy 0.8636 -0.4572)
			)
			(stroke
				(width 0)
				(type default)
			)
			(fill no)
			(layer "B.CrtYd")
		)
		(fp_line
			(start -0.884936 0.504952)
			(end 0.884936 0.504952)
			(stroke
				(width 0.1)
				(type default)
			)
			(layer "B.Fab")
		)
		(fp_line
			(start 0.884936 0.504952)
			(end 0.884936 -0.504952)
			(stroke
				(width 0.1)
				(type default)
			)
			(layer "B.Fab")
		)
		(fp_line
			(start -0.884936 -0.504952)
			(end -0.884936 0.504952)
			(stroke
				(width 0.1)
				(type default)
			)
			(layer "B.Fab")
		)
		(fp_line
			(start 0.884936 -0.504952)
			(end -0.884936 -0.504952)
			(stroke
				(width 0.1)
				(type default)
			)
			(layer "B.Fab")
		)
		(pad "1" smd rect
			(at -0.7366 0)
			(size 0.7112 0.8128)
			(layers "B.Cu" "B.Mask" "B.Paste")
			(net "P1V5_SFRPLL_NODE1")
		)
		(pad "2" smd rect
			(at 0.7366 0)
			(size 0.7112 0.8128)
			(layers "B.Cu" "B.Mask" "B.Paste")
			(net "GND")
		)
	)
	(footprint ""
		(layer "B.Cu")
		(at 72.178672 -139.190222)
		(property "Reference" "TP7"
			(at 0 0 0)
			(layer "B.SilkS")
			(hide yes)
			(effects
				(font
					(size 1.27 1.27)
				)
				(justify mirror)
			)
		)
		(property "Value" ""
			(at 0 0 0)
			(layer "B.Fab")
			(effects
				(font
					(size 1.27 1.27)
				)
				(justify mirror)
			)
		)
		(duplicate_pad_numbers_are_jumpers no)
		(fp_poly
			(pts
				(arc
					(start 0 -0.381)
					(mid 0 0.381)
					(end 0 -0.381)
				)
			)
			(stroke
				(width 0)
				(type default)
			)
			(fill no)
			(layer "B.CrtYd")
		)
		(pad "1" smd circle
			(at 0 0 180)
			(size 0.762 0.762)
			(layers "B.Cu" "B.Mask" "B.Paste")
			(net "N3975090767")
		)
	)
	(footprint ""
		(layer "B.Cu")
		(at 177.967386 -120.774968 180)
		(property "Reference" "C788"
			(at -10.430764 -0.49022 0)
			(unlocked yes)
			(layer "B.SilkS")
			(effects
				(font
					(size 0.7874 0.5842)
					(thickness 0.1524)
				)
				(justify mirror)
			)
		)
		(property "Value" ""
			(at 0 0 0)
			(layer "B.Fab")
			(effects
				(font
					(size 1.27 1.27)
				)
				(justify mirror)
			)
		)
		(duplicate_pad_numbers_are_jumpers no)
		(fp_line
			(start 1.2954 0.5842)
			(end 1.2954 -0.5842)
			(stroke
				(width 0.1524)
				(type default)
			)
			(layer "B.SilkS")
		)
		(fp_line
			(start 1.2954 -0.5842)
			(end -1.2954 -0.5842)
			(stroke
				(width 0.1524)
				(type default)
			)
			(layer "B.SilkS")
		)
		(fp_line
			(start 0 -0.5842)
			(end 0 0.5842)
			(stroke
				(width 0.1524)
				(type default)
			)
			(layer "B.SilkS")
		)
		(fp_line
			(start -1.2954 0.5842)
			(end 1.2954 0.5842)
			(stroke
				(width 0.1524)
				(type default)
			)
			(layer "B.SilkS")
		)
		(fp_line
			(start -1.2954 -0.5842)
			(end -1.2954 0.5842)
			(stroke
				(width 0.1524)
				(type default)
			)
			(layer "B.SilkS")
		)
		(fp_poly
			(pts
				(xy -0.8636 -0.4572) (xy -0.8636 -0.3556) (xy -1.143 -0.3556) (xy -1.143 0.3556) (xy -0.8636 0.3556)
				(xy -0.8636 0.4572) (xy 0.8636 0.4572) (xy 0.8636 0.3556) (xy 1.143 0.3556) (xy 1.143 -0.3556) (xy 0.8636 -0.3556)
				(xy 0.8636 -0.4572)
			)
			(stroke
				(width 0)
				(type default)
			)
			(fill no)
			(layer "B.CrtYd")
		)
		(fp_line
			(start 0.884936 0.504952)
			(end 0.884936 -0.504952)
			(stroke
				(width 0.1)
				(type default)
			)
			(layer "B.Fab")
		)
		(fp_line
			(start 0.884936 -0.504952)
			(end -0.884936 -0.504952)
			(stroke
				(width 0.1)
				(type default)
			)
			(layer "B.Fab")
		)
		(fp_line
			(start -0.884936 0.504952)
			(end 0.884936 0.504952)
			(stroke
				(width 0.1)
				(type default)
			)
			(layer "B.Fab")
		)
		(fp_line
			(start -0.884936 -0.504952)
			(end -0.884936 0.504952)
			(stroke
				(width 0.1)
				(type default)
			)
			(layer "B.Fab")
		)
		(pad "1" smd rect
			(at -0.7366 0 270)
			(size 0.7112 0.8128)
			(layers "B.Cu" "B.Mask" "B.Paste")
			(net "P3V3_STB_NODE1")
		)
		(pad "2" smd rect
			(at 0.7366 0 270)
			(size 0.7112 0.8128)
			(layers "B.Cu" "B.Mask" "B.Paste")
			(net "GND")
		)
	)
	(footprint ""
		(layer "B.Cu")
		(at 114.701574 -107.855766 180)
		(property "Reference" "PC118"
			(at -5.729732 -0.023368 0)
			(unlocked yes)
			(layer "B.SilkS")
			(effects
				(font
					(size 0.7874 0.5842)
					(thickness 0.1524)
				)
				(justify left mirror)
			)
		)
		(property "Value" ""
			(at 0 0 0)
			(layer "B.Fab")
			(effects
				(font
					(size 1.27 1.27)
				)
				(justify mirror)
			)
		)
		(duplicate_pad_numbers_are_jumpers no)
		(fp_line
			(start 1.905 0.8636)
			(end 1.905 -0.8636)
			(stroke
				(width 0.1524)
				(type default)
			)
			(layer "B.SilkS")
		)
		(fp_line
			(start 1.905 -0.8636)
			(end -1.905 -0.8636)
			(stroke
				(width 0.1524)
				(type default)
			)
			(layer "B.SilkS")
		)
		(fp_line
			(start 0 0.8382)
			(end 0 -0.8382)
			(stroke
				(width 0.1524)
				(type default)
			)
			(layer "B.SilkS")
		)
		(fp_line
			(start -1.905 0.8636)
			(end 1.905 0.8636)
			(stroke
				(width 0.1524)
				(type default)
			)
			(layer "B.SilkS")
		)
		(fp_line
			(start -1.905 -0.8636)
			(end -1.905 0.8636)
			(stroke
				(width 0.1524)
				(type default)
			)
			(layer "B.SilkS")
		)
		(fp_rect
			(start 1.524 0.7366)
			(end -1.524 -0.7366)
			(stroke
				(width 0)
				(type default)
			)
			(fill no)
			(layer "B.CrtYd")
		)
		(pad "1" smd rect
			(at -0.94996 0)
			(size 1.1176 1.3716)
			(layers "B.Cu" "B.Mask" "B.Paste")
			(net "GND")
		)
		(pad "2" smd rect
			(at 0.94996 0)
			(size 1.1176 1.3716)
			(layers "B.Cu" "B.Mask" "B.Paste")
			(net "PV_VCCP_NODE1")
		)
	)
	(footprint ""
		(layer "B.Cu")
		(at 52.81676 -185.205624 -90)
		(property "Reference" "R832"
			(at -4.15163 -0.163068 270)
			(unlocked yes)
			(layer "B.SilkS")
			(effects
				(font
					(size 0.7874 0.5842)
					(thickness 0.1524)
				)
				(justify left mirror)
			)
		)
		(property "Value" ""
			(at 0 0 90)
			(layer "B.Fab")
			(effects
				(font
					(size 1.27 1.27)
				)
				(justify mirror)
			)
		)
		(duplicate_pad_numbers_are_jumpers no)
		(fp_line
			(start -0.7874 0.4064)
			(end 0.7874 0.4064)
			(stroke
				(width 0.1524)
				(type default)
			)
			(layer "B.SilkS")
		)
		(fp_line
			(start 0.7874 0.4064)
			(end 0.7874 -0.4064)
			(stroke
				(width 0.1524)
				(type default)
			)
			(layer "B.SilkS")
		)
		(fp_line
			(start -0.7874 -0.4064)
			(end -0.7874 0.4064)
			(stroke
				(width 0.1524)
				(type default)
			)
			(layer "B.SilkS")
		)
		(fp_line
			(start 0.7874 -0.4064)
			(end -0.7874 -0.4064)
			(stroke
				(width 0.1524)
				(type default)
			)
			(layer "B.SilkS")
		)
		(fp_poly
			(pts
				(xy 0.508 0.2794) (xy 0.508 0.2286) (xy 0.635 0.2286) (xy 0.635 -0.254) (xy 0.5334 -0.254) (xy 0.5334 -0.2794)
				(xy -0.5334 -0.2794) (xy -0.5334 -0.254) (xy -0.635 -0.254) (xy -0.635 0.254) (xy -0.5334 0.254)
				(xy -0.5334 0.2794)
			)
			(stroke
				(width 0)
				(type default)
			)
			(fill no)
			(layer "B.CrtYd")
		)
		(pad "1" smd rect
			(at -0.40005 0 90)
			(size 0.4572 0.508)
			(layers "B.Cu" "B.Mask" "B.Paste")
			(net "PSU1_DC_OK_R")
		)
		(pad "2" smd rect
			(at 0.40005 0 90)
			(size 0.4572 0.508)
			(layers "B.Cu" "B.Mask" "B.Paste")
			(net "PSU1_DC_OK_R_BUF")
		)
	)
	(footprint ""
		(layer "B.Cu")
		(at 49.38776 -185.205624 -90)
		(property "Reference" "R840"
			(at -4.15163 -0.163068 270)
			(unlocked yes)
			(layer "B.SilkS")
			(effects
				(font
					(size 0.7874 0.5842)
					(thickness 0.1524)
				)
				(justify left mirror)
			)
		)
		(property "Value" ""
			(at 0 0 90)
			(layer "B.Fab")
			(effects
				(font
					(size 1.27 1.27)
				)
				(justify mirror)
			)
		)
		(duplicate_pad_numbers_are_jumpers no)
		(fp_line
			(start -0.7874 0.4064)
			(end 0.7874 0.4064)
			(stroke
				(width 0.1524)
				(type default)
			)
			(layer "B.SilkS")
		)
		(fp_line
			(start 0.7874 0.4064)
			(end 0.7874 -0.4064)
			(stroke
				(width 0.1524)
				(type default)
			)
			(layer "B.SilkS")
		)
		(fp_line
			(start -0.7874 -0.4064)
			(end -0.7874 0.4064)
			(stroke
				(width 0.1524)
				(type default)
			)
			(layer "B.SilkS")
		)
		(fp_line
			(start 0.7874 -0.4064)
			(end -0.7874 -0.4064)
			(stroke
				(width 0.1524)
				(type default)
			)
			(layer "B.SilkS")
		)
		(fp_poly
			(pts
				(xy 0.508 0.2794) (xy 0.508 0.2286) (xy 0.635 0.2286) (xy 0.635 -0.254) (xy 0.5334 -0.254) (xy 0.5334 -0.2794)
				(xy -0.5334 -0.2794) (xy -0.5334 -0.254) (xy -0.635 -0.254) (xy -0.635 0.254) (xy -0.5334 0.254)
				(xy -0.5334 0.2794)
			)
			(stroke
				(width 0)
				(type default)
			)
			(fill no)
			(layer "B.CrtYd")
		)
		(pad "1" smd rect
			(at -0.40005 0 90)
			(size 0.4572 0.508)
			(layers "B.Cu" "B.Mask" "B.Paste")
			(net "PSU4_DC_OK_R")
		)
		(pad "2" smd rect
			(at 0.40005 0 90)
			(size 0.4572 0.508)
			(layers "B.Cu" "B.Mask" "B.Paste")
			(net "PSU4_DC_OK_R_BUF")
		)
	)
	(footprint ""
		(layer "B.Cu")
		(at 161.782252 -167.141398 180)
		(property "Reference" "U141"
			(at -0.300228 -2.623058 0)
			(unlocked yes)
			(layer "B.SilkS")
			(effects
				(font
					(size 0.7874 0.5842)
					(thickness 0.1524)
				)
				(justify mirror)
			)
		)
		(property "Value" ""
			(at 0 0 0)
			(layer "B.Fab")
			(effects
				(font
					(size 1.27 1.27)
				)
				(justify mirror)
			)
		)
		(duplicate_pad_numbers_are_jumpers no)
		(fp_line
			(start 1.651 1.905)
			(end 1.651 -1.905)
			(stroke
				(width 0.1524)
				(type default)
			)
			(layer "B.SilkS")
		)
		(fp_line
			(start 1.651 -1.905)
			(end -1.651 -1.905)
			(stroke
				(width 0.1524)
				(type default)
			)
			(layer "B.SilkS")
		)
		(fp_line
			(start -1.651 1.905)
			(end 1.651 1.905)
			(stroke
				(width 0.1524)
				(type default)
			)
			(layer "B.SilkS")
		)
		(fp_line
			(start -1.651 -1.905)
			(end -1.651 1.905)
			(stroke
				(width 0.1524)
				(type default)
			)
			(layer "B.SilkS")
		)
		(fp_poly
			(pts
				(xy 1.524 0.7112) (xy 1.524 1.7526) (xy 0.508 1.7526) (xy 0.508 0.6985) (xy -0.508 0.6985) (xy -0.508 1.7526)
				(xy -1.524 1.7526) (xy -1.524 0.6985) (xy -1.524 -0.6985) (xy -0.508 -0.6985) (xy -0.508 -1.7526)
				(xy 0.508 -1.7526) (xy 0.508 -0.6985) (xy 1.524 -0.6985) (xy 1.524 0.6985)
			)
			(stroke
				(width 0)
				(type default)
			)
			(fill no)
			(layer "B.CrtYd")
		)
		(fp_text user "G"
			(at -0.432308 2.482596 0)
			(unlocked yes)
			(layer "B.SilkS")
			(effects
				(font
					(size 0.635 0.4064)
					(thickness 0.1524)
				)
				(justify mirror)
			)
		)
		(fp_text user "D"
			(at -1.84277 2.612644 0)
			(unlocked yes)
			(layer "B.SilkS")
			(effects
				(font
					(size 0.635 0.4064)
					(thickness 0.1524)
				)
				(justify mirror)
			)
		)
		(fp_text user "S"
			(at -2.016506 -1.532382 0)
			(unlocked yes)
			(layer "B.SilkS")
			(effects
				(font
					(size 0.635 0.4064)
					(thickness 0.1524)
				)
				(justify mirror)
			)
		)
		(pad "D" smd rect
			(at 0 -1.1176)
			(size 1.016 1.27)
			(layers "B.Cu" "B.Mask" "B.Paste")
			(net "CPLD_UART_RI_P3_N")
		)
		(pad "G" smd rect
			(at 1.016 1.1176)
			(size 1.016 1.27)
			(layers "B.Cu" "B.Mask" "B.Paste")
			(net "TACKOVER_EN")
		)
		(pad "S" smd rect
			(at -1.016 1.1176)
			(size 1.016 1.27)
			(layers "B.Cu" "B.Mask" "B.Paste")
			(net "CPLD_UART_RI_P3_LS_N")
		)
	)
	(footprint ""
		(layer "B.Cu")
		(at 104.408224 -67.228466)
		(property "Reference" "C184"
			(at -4.704842 -1.377188 0)
			(unlocked yes)
			(layer "B.SilkS")
			(effects
				(font
					(size 0.7874 0.5842)
					(thickness 0.1524)
				)
				(justify left mirror)
			)
		)
		(property "Value" ""
			(at 0 0 0)
			(layer "B.Fab")
			(effects
				(font
					(size 1.27 1.27)
				)
				(justify mirror)
			)
		)
		(duplicate_pad_numbers_are_jumpers no)
		(fp_line
			(start -0.7874 -0.4064)
			(end -0.7874 0.4064)
			(stroke
				(width 0.1524)
				(type default)
			)
			(layer "B.SilkS")
		)
		(fp_line
			(start -0.7874 0.4064)
			(end 0.7874 0.4064)
			(stroke
				(width 0.1524)
				(type default)
			)
			(layer "B.SilkS")
		)
		(fp_line
			(start 0 0.381)
			(end 0 -0.381)
			(stroke
				(width 0.1524)
				(type default)
			)
			(layer "B.SilkS")
		)
		(fp_line
			(start 0.7874 -0.4064)
			(end -0.7874 -0.4064)
			(stroke
				(width 0.1524)
				(type default)
			)
			(layer "B.SilkS")
		)
		(fp_line
			(start 0.7874 0.4064)
			(end 0.7874 -0.4064)
			(stroke
				(width 0.1524)
				(type default)
			)
			(layer "B.SilkS")
		)
		(fp_poly
			(pts
				(xy 0.5334 0.254) (xy 0.635 0.254) (xy 0.635 0.2286) (xy 0.635 -0.254) (xy 0.5334 -0.254) (xy 0.5334 -0.2794)
				(xy -0.5334 -0.2794) (xy -0.5334 -0.254) (xy -0.635 -0.254) (xy -0.635 0.254) (xy -0.5334 0.254)
				(xy -0.5334 0.2794) (xy 0.508 0.2794) (xy 0.5334 0.2794)
			)
			(stroke
				(width 0)
				(type default)
			)
			(fill no)
			(layer "B.CrtYd")
		)
		(pad "1" smd rect
			(at -0.40005 0 180)
			(size 0.4572 0.508)
			(layers "B.Cu" "B.Mask" "B.Paste")
			(net "GND")
		)
		(pad "2" smd rect
			(at 0.40005 0 180)
			(size 0.4572 0.508)
			(layers "B.Cu" "B.Mask" "B.Paste")
			(net "XDP_CPU_NODE1_PWROK_STALL_L")
		)
	)
	(footprint ""
		(layer "B.Cu")
		(at 170.820588 -94.36354 -90)
		(property "Reference" "C383"
			(at 2.801112 -2.080006 270)
			(unlocked yes)
			(layer "B.SilkS")
			(effects
				(font
					(size 0.7874 0.5842)
					(thickness 0.1524)
				)
				(justify left mirror)
			)
		)
		(property "Value" ""
			(at 0 0 90)
			(layer "B.Fab")
			(effects
				(font
					(size 1.27 1.27)
				)
				(justify mirror)
			)
		)
		(duplicate_pad_numbers_are_jumpers no)
		(fp_line
			(start -0.7874 0.4064)
			(end 0.7874 0.4064)
			(stroke
				(width 0.1524)
				(type default)
			)
			(layer "B.SilkS")
		)
		(fp_line
			(start 0.7874 0.4064)
			(end 0.7874 -0.4064)
			(stroke
				(width 0.1524)
				(type default)
			)
			(layer "B.SilkS")
		)
		(fp_line
			(start 0 0.381)
			(end 0 -0.381)
			(stroke
				(width 0.1524)
				(type default)
			)
			(layer "B.SilkS")
		)
		(fp_line
			(start -0.7874 -0.4064)
			(end -0.7874 0.4064)
			(stroke
				(width 0.1524)
				(type default)
			)
			(layer "B.SilkS")
		)
		(fp_line
			(start 0.7874 -0.4064)
			(end -0.7874 -0.4064)
			(stroke
				(width 0.1524)
				(type default)
			)
			(layer "B.SilkS")
		)
		(fp_poly
			(pts
				(xy 0.5334 0.254) (xy 0.635 0.254) (xy 0.635 0.2286) (xy 0.635 -0.254) (xy 0.5334 -0.254) (xy 0.5334 -0.2794)
				(xy -0.5334 -0.2794) (xy -0.5334 -0.254) (xy -0.635 -0.254) (xy -0.635 0.254) (xy -0.5334 0.254)
				(xy -0.5334 0.2794) (xy 0.508 0.2794) (xy 0.5334 0.2794)
			)
			(stroke
				(width 0)
				(type default)
			)
			(fill no)
			(layer "B.CrtYd")
		)
		(pad "1" smd rect
			(at -0.40005 0 90)
			(size 0.4572 0.508)
			(layers "B.Cu" "B.Mask" "B.Paste")
			(net "P3V3_USB_NODE1")
		)
		(pad "2" smd rect
			(at 0.40005 0 90)
			(size 0.4572 0.508)
			(layers "B.Cu" "B.Mask" "B.Paste")
			(net "GND")
		)
	)
	(footprint ""
		(layer "B.Cu")
		(at 64.647572 -72.238108 180)
		(property "Reference" "C101"
			(at 12.549632 -31.503366 0)
			(unlocked yes)
			(layer "B.SilkS")
			(effects
				(font
					(size 0.7874 0.5842)
					(thickness 0.1524)
				)
				(justify left mirror)
			)
		)
		(property "Value" ""
			(at 0 0 0)
			(layer "B.Fab")
			(effects
				(font
					(size 1.27 1.27)
				)
				(justify mirror)
			)
		)
		(duplicate_pad_numbers_are_jumpers no)
		(fp_line
			(start 0.7874 0.4064)
			(end 0.7874 -0.4064)
			(stroke
				(width 0.1524)
				(type default)
			)
			(layer "B.SilkS")
		)
		(fp_line
			(start 0.7874 -0.4064)
			(end -0.7874 -0.4064)
			(stroke
				(width 0.1524)
				(type default)
			)
			(layer "B.SilkS")
		)
		(fp_line
			(start 0 0.381)
			(end 0 -0.381)
			(stroke
				(width 0.1524)
				(type default)
			)
			(layer "B.SilkS")
		)
		(fp_line
			(start -0.7874 0.4064)
			(end 0.7874 0.4064)
			(stroke
				(width 0.1524)
				(type default)
			)
			(layer "B.SilkS")
		)
		(fp_line
			(start -0.7874 -0.4064)
			(end -0.7874 0.4064)
			(stroke
				(width 0.1524)
				(type default)
			)
			(layer "B.SilkS")
		)
		(fp_poly
			(pts
				(xy 0.5334 0.254) (xy 0.635 0.254) (xy 0.635 0.2286) (xy 0.635 -0.254) (xy 0.5334 -0.254) (xy 0.5334 -0.2794)
				(xy -0.5334 -0.2794) (xy -0.5334 -0.254) (xy -0.635 -0.254) (xy -0.635 0.254) (xy -0.5334 0.254)
				(xy -0.5334 0.2794) (xy 0.508 0.2794) (xy 0.5334 0.2794)
			)
			(stroke
				(width 0)
				(type default)
			)
			(fill no)
			(layer "B.CrtYd")
		)
		(pad "1" smd rect
			(at -0.40005 0)
			(size 0.4572 0.508)
			(layers "B.Cu" "B.Mask" "B.Paste")
			(net "P1V05_NODE1")
		)
		(pad "2" smd rect
			(at 0.40005 0)
			(size 0.4572 0.508)
			(layers "B.Cu" "B.Mask" "B.Paste")
			(net "GND")
		)
	)
	(footprint ""
		(layer "B.Cu")
		(at 37.929312 -155.118308 180)
		(property "Reference" "C427"
			(at 6.877812 8.942832 0)
			(unlocked yes)
			(layer "B.SilkS")
			(effects
				(font
					(size 0.7874 0.5842)
					(thickness 0.1524)
				)
				(justify left mirror)
			)
		)
		(property "Value" ""
			(at 0 0 0)
			(layer "B.Fab")
			(effects
				(font
					(size 1.27 1.27)
				)
				(justify mirror)
			)
		)
		(duplicate_pad_numbers_are_jumpers no)
		(fp_line
			(start 0.7874 0.4064)
			(end 0.7874 -0.4064)
			(stroke
				(width 0.1524)
				(type default)
			)
			(layer "B.SilkS")
		)
		(fp_line
			(start 0.7874 -0.4064)
			(end -0.7874 -0.4064)
			(stroke
				(width 0.1524)
				(type default)
			)
			(layer "B.SilkS")
		)
		(fp_line
			(start 0 0.381)
			(end 0 -0.381)
			(stroke
				(width 0.1524)
				(type default)
			)
			(layer "B.SilkS")
		)
		(fp_line
			(start -0.7874 0.4064)
			(end 0.7874 0.4064)
			(stroke
				(width 0.1524)
				(type default)
			)
			(layer "B.SilkS")
		)
		(fp_line
			(start -0.7874 -0.4064)
			(end -0.7874 0.4064)
			(stroke
				(width 0.1524)
				(type default)
			)
			(layer "B.SilkS")
		)
		(fp_poly
			(pts
				(xy 0.5334 0.254) (xy 0.635 0.254) (xy 0.635 0.2286) (xy 0.635 -0.254) (xy 0.5334 -0.254) (xy 0.5334 -0.2794)
				(xy -0.5334 -0.2794) (xy -0.5334 -0.254) (xy -0.635 -0.254) (xy -0.635 0.254) (xy -0.5334 0.254)
				(xy -0.5334 0.2794) (xy 0.508 0.2794) (xy 0.5334 0.2794)
			)
			(stroke
				(width 0)
				(type default)
			)
			(fill no)
			(layer "B.CrtYd")
		)
		(pad "1" smd rect
			(at -0.40005 0)
			(size 0.4572 0.508)
			(layers "B.Cu" "B.Mask" "B.Paste")
			(net "P1V9_LAN1")
		)
		(pad "2" smd rect
			(at 0.40005 0)
			(size 0.4572 0.508)
			(layers "B.Cu" "B.Mask" "B.Paste")
			(net "GND")
		)
	)
	(footprint ""
		(layer "B.Cu")
		(at 57.107836 -123.485656 180)
		(property "Reference" "L16"
			(at 41.222676 -53.281326 0)
			(unlocked yes)
			(layer "B.SilkS")
			(effects
				(font
					(size 0.7874 0.5842)
					(thickness 0.1524)
				)
				(justify mirror)
			)
		)
		(property "Value" ""
			(at 0 0 0)
			(layer "B.Fab")
			(effects
				(font
					(size 1.27 1.27)
				)
				(justify mirror)
			)
		)
		(duplicate_pad_numbers_are_jumpers no)
		(fp_line
			(start 1.2954 -0.635)
			(end 1.2954 0.635)
			(stroke
				(width 0.1524)
				(type default)
			)
			(layer "B.SilkS")
		)
		(fp_line
			(start 1.2954 -0.635)
			(end -1.2954 -0.635)
			(stroke
				(width 0.1524)
				(type default)
			)
			(layer "B.SilkS")
		)
		(fp_line
			(start 0.127 -0.5842)
			(end 0.127 0.5842)
			(stroke
				(width 0.1524)
				(type default)
			)
			(layer "B.SilkS")
		)
		(fp_line
			(start -0.127 -0.5842)
			(end -0.127 0.5842)
			(stroke
				(width 0.1524)
				(type default)
			)
			(layer "B.SilkS")
		)
		(fp_line
			(start -1.2954 0.635)
			(end 1.2954 0.635)
			(stroke
				(width 0.1524)
				(type default)
			)
			(layer "B.SilkS")
		)
		(fp_line
			(start -1.2954 -0.635)
			(end -1.2954 0.635)
			(stroke
				(width 0.1524)
				(type default)
			)
			(layer "B.SilkS")
		)
		(fp_poly
			(pts
				(xy 0.9144 0.508) (xy 0.9144 0.3556) (xy 1.143 0.3556) (xy 1.143 -0.3556) (xy 0.9144 -0.3556) (xy 0.9144 -0.508)
				(xy -0.9144 -0.508) (xy -0.9144 -0.3556) (xy -1.143 -0.3556) (xy -1.143 0.3556) (xy -0.9144 0.3556)
				(xy -0.9144 0.508)
			)
			(stroke
				(width 0)
				(type default)
			)
			(fill no)
			(layer "B.CrtYd")
		)
		(pad "1" smd rect
			(at -0.7366 0 270)
			(size 0.7112 0.8128)
			(layers "B.Cu" "B.Mask" "B.Paste")
			(net "BMC_NODE1_HPLLAV33")
		)
		(pad "2" smd rect
			(at 0.7366 0 270)
			(size 0.7112 0.8128)
			(layers "B.Cu" "B.Mask" "B.Paste")
			(net "P3V3_NODE1")
		)
	)
	(footprint ""
		(layer "B.Cu")
		(at 168.462452 -104.87279 90)
		(property "Reference" "C378"
			(at 1.398016 6.049264 270)
			(unlocked yes)
			(layer "B.SilkS")
			(effects
				(font
					(size 0.7874 0.5842)
					(thickness 0.1524)
				)
				(justify left mirror)
			)
		)
		(property "Value" ""
			(at 0 0 90)
			(layer "B.Fab")
			(effects
				(font
					(size 1.27 1.27)
				)
				(justify mirror)
			)
		)
		(duplicate_pad_numbers_are_jumpers no)
		(fp_line
			(start 0.7874 -0.4064)
			(end -0.7874 -0.4064)
			(stroke
				(width 0.1524)
				(type default)
			)
			(layer "B.SilkS")
		)
		(fp_line
			(start -0.7874 -0.4064)
			(end -0.7874 0.4064)
			(stroke
				(width 0.1524)
				(type default)
			)
			(layer "B.SilkS")
		)
		(fp_line
			(start 0 0.381)
			(end 0 -0.381)
			(stroke
				(width 0.1524)
				(type default)
			)
			(layer "B.SilkS")
		)
		(fp_line
			(start 0.7874 0.4064)
			(end 0.7874 -0.4064)
			(stroke
				(width 0.1524)
				(type default)
			)
			(layer "B.SilkS")
		)
		(fp_line
			(start -0.7874 0.4064)
			(end 0.7874 0.4064)
			(stroke
				(width 0.1524)
				(type default)
			)
			(layer "B.SilkS")
		)
		(fp_poly
			(pts
				(xy 0.5334 0.254) (xy 0.635 0.254) (xy 0.635 0.2286) (xy 0.635 -0.254) (xy 0.5334 -0.254) (xy 0.5334 -0.2794)
				(xy -0.5334 -0.2794) (xy -0.5334 -0.254) (xy -0.635 -0.254) (xy -0.635 0.254) (xy -0.5334 0.254)
				(xy -0.5334 0.2794) (xy 0.508 0.2794) (xy 0.5334 0.2794)
			)
			(stroke
				(width 0)
				(type default)
			)
			(fill no)
			(layer "B.CrtYd")
		)
		(pad "1" smd rect
			(at -0.40005 0 270)
			(size 0.4572 0.508)
			(layers "B.Cu" "B.Mask" "B.Paste")
			(net "GND")
		)
		(pad "2" smd rect
			(at 0.40005 0 270)
			(size 0.4572 0.508)
			(layers "B.Cu" "B.Mask" "B.Paste")
			(net "P3V3_NODE1")
		)
	)
	(footprint ""
		(layer "B.Cu")
		(at 53.090572 -77.753718 -90)
		(property "Reference" "C103"
			(at 32.20212 14.450822 270)
			(unlocked yes)
			(layer "B.SilkS")
			(effects
				(font
					(size 0.7874 0.5842)
					(thickness 0.1524)
				)
				(justify left mirror)
			)
		)
		(property "Value" ""
			(at 0 0 90)
			(layer "B.Fab")
			(effects
				(font
					(size 1.27 1.27)
				)
				(justify mirror)
			)
		)
		(duplicate_pad_numbers_are_jumpers no)
		(fp_line
			(start -0.7874 0.4064)
			(end 0.7874 0.4064)
			(stroke
				(width 0.1524)
				(type default)
			)
			(layer "B.SilkS")
		)
		(fp_line
			(start 0.7874 0.4064)
			(end 0.7874 -0.4064)
			(stroke
				(width 0.1524)
				(type default)
			)
			(layer "B.SilkS")
		)
		(fp_line
			(start 0 0.381)
			(end 0 -0.381)
			(stroke
				(width 0.1524)
				(type default)
			)
			(layer "B.SilkS")
		)
		(fp_line
			(start -0.7874 -0.4064)
			(end -0.7874 0.4064)
			(stroke
				(width 0.1524)
				(type default)
			)
			(layer "B.SilkS")
		)
		(fp_line
			(start 0.7874 -0.4064)
			(end -0.7874 -0.4064)
			(stroke
				(width 0.1524)
				(type default)
			)
			(layer "B.SilkS")
		)
		(fp_poly
			(pts
				(xy 0.5334 0.254) (xy 0.635 0.254) (xy 0.635 0.2286) (xy 0.635 -0.254) (xy 0.5334 -0.254) (xy 0.5334 -0.2794)
				(xy -0.5334 -0.2794) (xy -0.5334 -0.254) (xy -0.635 -0.254) (xy -0.635 0.254) (xy -0.5334 0.254)
				(xy -0.5334 0.2794) (xy 0.508 0.2794) (xy 0.5334 0.2794)
			)
			(stroke
				(width 0)
				(type default)
			)
			(fill no)
			(layer "B.CrtYd")
		)
		(pad "1" smd rect
			(at -0.40005 0 90)
			(size 0.4572 0.508)
			(layers "B.Cu" "B.Mask" "B.Paste")
			(net "P1V05_NODE1")
		)
		(pad "2" smd rect
			(at 0.40005 0 90)
			(size 0.4572 0.508)
			(layers "B.Cu" "B.Mask" "B.Paste")
			(net "GND")
		)
	)
	(footprint ""
		(layer "B.Cu")
		(at 67.67576 -185.205624 90)
		(property "Reference" "R929"
			(at 4.15163 0.002286 270)
			(unlocked yes)
			(layer "B.SilkS")
			(effects
				(font
					(size 0.7874 0.5842)
					(thickness 0.1524)
				)
				(justify left mirror)
			)
		)
		(property "Value" ""
			(at 0 0 90)
			(layer "B.Fab")
			(effects
				(font
					(size 1.27 1.27)
				)
				(justify mirror)
			)
		)
		(duplicate_pad_numbers_are_jumpers no)
		(fp_line
			(start 0.7874 -0.4064)
			(end -0.7874 -0.4064)
			(stroke
				(width 0.1524)
				(type default)
			)
			(layer "B.SilkS")
		)
		(fp_line
			(start -0.7874 -0.4064)
			(end -0.7874 0.4064)
			(stroke
				(width 0.1524)
				(type default)
			)
			(layer "B.SilkS")
		)
		(fp_line
			(start 0.7874 0.4064)
			(end 0.7874 -0.4064)
			(stroke
				(width 0.1524)
				(type default)
			)
			(layer "B.SilkS")
		)
		(fp_line
			(start -0.7874 0.4064)
			(end 0.7874 0.4064)
			(stroke
				(width 0.1524)
				(type default)
			)
			(layer "B.SilkS")
		)
		(fp_poly
			(pts
				(xy 0.508 0.2794) (xy 0.508 0.2286) (xy 0.635 0.2286) (xy 0.635 -0.254) (xy 0.5334 -0.254) (xy 0.5334 -0.2794)
				(xy -0.5334 -0.2794) (xy -0.5334 -0.254) (xy -0.635 -0.254) (xy -0.635 0.254) (xy -0.5334 0.254)
				(xy -0.5334 0.2794)
			)
			(stroke
				(width 0)
				(type default)
			)
			(fill no)
			(layer "B.CrtYd")
		)
		(pad "1" smd rect
			(at -0.40005 0 270)
			(size 0.4572 0.508)
			(layers "B.Cu" "B.Mask" "B.Paste")
			(net "UART_T3_NODE4_TXD")
		)
		(pad "2" smd rect
			(at 0.40005 0 270)
			(size 0.4572 0.508)
			(layers "B.Cu" "B.Mask" "B.Paste")
			(net "UART_T3_NODE4_TXD_R")
		)
	)
	(footprint ""
		(layer "B.Cu")
		(at 62.18047 -133.027928 180)
		(property "Reference" "C275"
			(at 40.632888 -52.982368 0)
			(unlocked yes)
			(layer "B.SilkS")
			(effects
				(font
					(size 0.7874 0.5842)
					(thickness 0.1524)
				)
				(justify left mirror)
			)
		)
		(property "Value" ""
			(at 0 0 0)
			(layer "B.Fab")
			(effects
				(font
					(size 1.27 1.27)
				)
				(justify mirror)
			)
		)
		(duplicate_pad_numbers_are_jumpers no)
		(fp_line
			(start 0.7874 0.4064)
			(end 0.7874 -0.4064)
			(stroke
				(width 0.1524)
				(type default)
			)
			(layer "B.SilkS")
		)
		(fp_line
			(start 0.7874 -0.4064)
			(end -0.7874 -0.4064)
			(stroke
				(width 0.1524)
				(type default)
			)
			(layer "B.SilkS")
		)
		(fp_line
			(start 0 0.381)
			(end 0 -0.381)
			(stroke
				(width 0.1524)
				(type default)
			)
			(layer "B.SilkS")
		)
		(fp_line
			(start -0.7874 0.4064)
			(end 0.7874 0.4064)
			(stroke
				(width 0.1524)
				(type default)
			)
			(layer "B.SilkS")
		)
		(fp_line
			(start -0.7874 -0.4064)
			(end -0.7874 0.4064)
			(stroke
				(width 0.1524)
				(type default)
			)
			(layer "B.SilkS")
		)
		(fp_poly
			(pts
				(xy 0.5334 0.254) (xy 0.635 0.254) (xy 0.635 0.2286) (xy 0.635 -0.254) (xy 0.5334 -0.254) (xy 0.5334 -0.2794)
				(xy -0.5334 -0.2794) (xy -0.5334 -0.254) (xy -0.635 -0.254) (xy -0.635 0.254) (xy -0.5334 0.254)
				(xy -0.5334 0.2794) (xy 0.508 0.2794) (xy 0.5334 0.2794)
			)
			(stroke
				(width 0)
				(type default)
			)
			(fill no)
			(layer "B.CrtYd")
		)
		(pad "1" smd rect
			(at -0.40005 0)
			(size 0.4572 0.508)
			(layers "B.Cu" "B.Mask" "B.Paste")
			(net "GND")
		)
		(pad "2" smd rect
			(at 0.40005 0)
			(size 0.4572 0.508)
			(layers "B.Cu" "B.Mask" "B.Paste")
			(net "P1V538_BMC_NODE1")
		)
	)
	(footprint ""
		(layer "B.Cu")
		(at 73.31202 -185.149998 -90)
		(property "Reference" "C677"
			(at -4.15163 0.089408 270)
			(unlocked yes)
			(layer "B.SilkS")
			(effects
				(font
					(size 0.7874 0.5842)
					(thickness 0.1524)
				)
				(justify left mirror)
			)
		)
		(property "Value" ""
			(at 0 0 90)
			(layer "B.Fab")
			(effects
				(font
					(size 1.27 1.27)
				)
				(justify mirror)
			)
		)
		(duplicate_pad_numbers_are_jumpers no)
		(fp_line
			(start -0.7874 0.4064)
			(end 0.7874 0.4064)
			(stroke
				(width 0.1524)
				(type default)
			)
			(layer "B.SilkS")
		)
		(fp_line
			(start 0.7874 0.4064)
			(end 0.7874 -0.4064)
			(stroke
				(width 0.1524)
				(type default)
			)
			(layer "B.SilkS")
		)
		(fp_line
			(start 0 0.381)
			(end 0 -0.381)
			(stroke
				(width 0.1524)
				(type default)
			)
			(layer "B.SilkS")
		)
		(fp_line
			(start -0.7874 -0.4064)
			(end -0.7874 0.4064)
			(stroke
				(width 0.1524)
				(type default)
			)
			(layer "B.SilkS")
		)
		(fp_line
			(start 0.7874 -0.4064)
			(end -0.7874 -0.4064)
			(stroke
				(width 0.1524)
				(type default)
			)
			(layer "B.SilkS")
		)
		(fp_poly
			(pts
				(xy 0.5334 0.254) (xy 0.635 0.254) (xy 0.635 0.2286) (xy 0.635 -0.254) (xy 0.5334 -0.254) (xy 0.5334 -0.2794)
				(xy -0.5334 -0.2794) (xy -0.5334 -0.254) (xy -0.635 -0.254) (xy -0.635 0.254) (xy -0.5334 0.254)
				(xy -0.5334 0.2794) (xy 0.508 0.2794) (xy 0.5334 0.2794)
			)
			(stroke
				(width 0)
				(type default)
			)
			(fill no)
			(layer "B.CrtYd")
		)
		(pad "1" smd rect
			(at -0.40005 0 90)
			(size 0.4572 0.508)
			(layers "B.Cu" "B.Mask" "B.Paste")
			(net "UART_T3_NODE2_RXD")
		)
		(pad "2" smd rect
			(at 0.40005 0 90)
			(size 0.4572 0.508)
			(layers "B.Cu" "B.Mask" "B.Paste")
			(net "GND")
		)
	)
	(footprint ""
		(layer "B.Cu")
		(at 106.753406 -177.56759 -90)
		(property "Reference" "R803"
			(at -0.85217 0.474726 270)
			(unlocked yes)
			(layer "B.SilkS")
			(effects
				(font
					(size 0.7874 0.5842)
					(thickness 0.1524)
				)
				(justify left mirror)
			)
		)
		(property "Value" ""
			(at 0 0 90)
			(layer "B.Fab")
			(effects
				(font
					(size 1.27 1.27)
				)
				(justify mirror)
			)
		)
		(duplicate_pad_numbers_are_jumpers no)
		(fp_line
			(start -0.7874 0.4064)
			(end 0.7874 0.4064)
			(stroke
				(width 0.1524)
				(type default)
			)
			(layer "B.SilkS")
		)
		(fp_line
			(start 0.7874 0.4064)
			(end 0.7874 -0.4064)
			(stroke
				(width 0.1524)
				(type default)
			)
			(layer "B.SilkS")
		)
		(fp_line
			(start -0.7874 -0.4064)
			(end -0.7874 0.4064)
			(stroke
				(width 0.1524)
				(type default)
			)
			(layer "B.SilkS")
		)
		(fp_line
			(start 0.7874 -0.4064)
			(end -0.7874 -0.4064)
			(stroke
				(width 0.1524)
				(type default)
			)
			(layer "B.SilkS")
		)
		(fp_poly
			(pts
				(xy 0.508 0.2794) (xy 0.508 0.2286) (xy 0.635 0.2286) (xy 0.635 -0.254) (xy 0.5334 -0.254) (xy 0.5334 -0.2794)
				(xy -0.5334 -0.2794) (xy -0.5334 -0.254) (xy -0.635 -0.254) (xy -0.635 0.254) (xy -0.5334 0.254)
				(xy -0.5334 0.2794)
			)
			(stroke
				(width 0)
				(type default)
			)
			(fill no)
			(layer "B.CrtYd")
		)
		(pad "1" smd rect
			(at -0.40005 0 90)
			(size 0.4572 0.508)
			(layers "B.Cu" "B.Mask" "B.Paste")
			(net "POWER_SW2_PWR_CTR_N")
		)
		(pad "2" smd rect
			(at 0.40005 0 90)
			(size 0.4572 0.508)
			(layers "B.Cu" "B.Mask" "B.Paste")
			(net "P3V3_STB_NODE1")
		)
	)
	(footprint ""
		(layer "B.Cu")
		(at 57.38876 -188.126624 90)
		(property "Reference" "R925"
			(at 4.276598 0.011684 270)
			(unlocked yes)
			(layer "B.SilkS")
			(effects
				(font
					(size 0.7874 0.5842)
					(thickness 0.1524)
				)
				(justify left mirror)
			)
		)
		(property "Value" ""
			(at 0 0 90)
			(layer "B.Fab")
			(effects
				(font
					(size 1.27 1.27)
				)
				(justify mirror)
			)
		)
		(duplicate_pad_numbers_are_jumpers no)
		(fp_line
			(start 0.7874 -0.4064)
			(end -0.7874 -0.4064)
			(stroke
				(width 0.1524)
				(type default)
			)
			(layer "B.SilkS")
		)
		(fp_line
			(start -0.7874 -0.4064)
			(end -0.7874 0.4064)
			(stroke
				(width 0.1524)
				(type default)
			)
			(layer "B.SilkS")
		)
		(fp_line
			(start 0.7874 0.4064)
			(end 0.7874 -0.4064)
			(stroke
				(width 0.1524)
				(type default)
			)
			(layer "B.SilkS")
		)
		(fp_line
			(start -0.7874 0.4064)
			(end 0.7874 0.4064)
			(stroke
				(width 0.1524)
				(type default)
			)
			(layer "B.SilkS")
		)
		(fp_poly
			(pts
				(xy 0.508 0.2794) (xy 0.508 0.2286) (xy 0.635 0.2286) (xy 0.635 -0.254) (xy 0.5334 -0.254) (xy 0.5334 -0.2794)
				(xy -0.5334 -0.2794) (xy -0.5334 -0.254) (xy -0.635 -0.254) (xy -0.635 0.254) (xy -0.5334 0.254)
				(xy -0.5334 0.2794)
			)
			(stroke
				(width 0)
				(type default)
			)
			(fill no)
			(layer "B.CrtYd")
		)
		(pad "1" smd rect
			(at -0.40005 0 270)
			(size 0.4572 0.508)
			(layers "B.Cu" "B.Mask" "B.Paste")
			(net "UART_T1_NODE4_RXD")
		)
		(pad "2" smd rect
			(at 0.40005 0 270)
			(size 0.4572 0.508)
			(layers "B.Cu" "B.Mask" "B.Paste")
			(net "UART_T1_NODE4_RXD_R")
		)
	)
	(footprint ""
		(layer "B.Cu")
		(at 56.240934 -59.828684 90)
		(property "Reference" "C117"
			(at -3.912616 -0.019304 270)
			(unlocked yes)
			(layer "B.SilkS")
			(effects
				(font
					(size 0.7874 0.5842)
					(thickness 0.1524)
				)
				(justify left mirror)
			)
		)
		(property "Value" ""
			(at 0 0 90)
			(layer "B.Fab")
			(effects
				(font
					(size 1.27 1.27)
				)
				(justify mirror)
			)
		)
		(duplicate_pad_numbers_are_jumpers no)
		(fp_line
			(start 0.7874 -0.4064)
			(end -0.7874 -0.4064)
			(stroke
				(width 0.1524)
				(type default)
			)
			(layer "B.SilkS")
		)
		(fp_line
			(start -0.7874 -0.4064)
			(end -0.7874 0.4064)
			(stroke
				(width 0.1524)
				(type default)
			)
			(layer "B.SilkS")
		)
		(fp_line
			(start 0 0.381)
			(end 0 -0.381)
			(stroke
				(width 0.1524)
				(type default)
			)
			(layer "B.SilkS")
		)
		(fp_line
			(start 0.7874 0.4064)
			(end 0.7874 -0.4064)
			(stroke
				(width 0.1524)
				(type default)
			)
			(layer "B.SilkS")
		)
		(fp_line
			(start -0.7874 0.4064)
			(end 0.7874 0.4064)
			(stroke
				(width 0.1524)
				(type default)
			)
			(layer "B.SilkS")
		)
		(fp_poly
			(pts
				(xy 0.5334 0.254) (xy 0.635 0.254) (xy 0.635 0.2286) (xy 0.635 -0.254) (xy 0.5334 -0.254) (xy 0.5334 -0.2794)
				(xy -0.5334 -0.2794) (xy -0.5334 -0.254) (xy -0.635 -0.254) (xy -0.635 0.254) (xy -0.5334 0.254)
				(xy -0.5334 0.2794) (xy 0.508 0.2794) (xy 0.5334 0.2794)
			)
			(stroke
				(width 0)
				(type default)
			)
			(fill no)
			(layer "B.CrtYd")
		)
		(pad "1" smd rect
			(at -0.40005 0 270)
			(size 0.4572 0.508)
			(layers "B.Cu" "B.Mask" "B.Paste")
			(net "PV_VDDR_NODE1")
		)
		(pad "2" smd rect
			(at 0.40005 0 270)
			(size 0.4572 0.508)
			(layers "B.Cu" "B.Mask" "B.Paste")
			(net "GND")
		)
	)
	(footprint ""
		(layer "B.Cu")
		(at 136.255252 -151.28875 90)
		(property "Reference" "C891"
			(at 1.50876 2.526284 270)
			(unlocked yes)
			(layer "B.SilkS")
			(effects
				(font
					(size 0.7874 0.5842)
					(thickness 0.1524)
				)
				(justify left mirror)
			)
		)
		(property "Value" ""
			(at 0 0 90)
			(layer "B.Fab")
			(effects
				(font
					(size 1.27 1.27)
				)
				(justify mirror)
			)
		)
		(duplicate_pad_numbers_are_jumpers no)
		(fp_line
			(start 0.7874 -0.4064)
			(end -0.7874 -0.4064)
			(stroke
				(width 0.1524)
				(type default)
			)
			(layer "B.SilkS")
		)
		(fp_line
			(start -0.7874 -0.4064)
			(end -0.7874 0.4064)
			(stroke
				(width 0.1524)
				(type default)
			)
			(layer "B.SilkS")
		)
		(fp_line
			(start 0 0.381)
			(end 0 -0.381)
			(stroke
				(width 0.1524)
				(type default)
			)
			(layer "B.SilkS")
		)
		(fp_line
			(start 0.7874 0.4064)
			(end 0.7874 -0.4064)
			(stroke
				(width 0.1524)
				(type default)
			)
			(layer "B.SilkS")
		)
		(fp_line
			(start -0.7874 0.4064)
			(end 0.7874 0.4064)
			(stroke
				(width 0.1524)
				(type default)
			)
			(layer "B.SilkS")
		)
		(fp_poly
			(pts
				(xy 0.5334 0.254) (xy 0.635 0.254) (xy 0.635 0.2286) (xy 0.635 -0.254) (xy 0.5334 -0.254) (xy 0.5334 -0.2794)
				(xy -0.5334 -0.2794) (xy -0.5334 -0.254) (xy -0.635 -0.254) (xy -0.635 0.254) (xy -0.5334 0.254)
				(xy -0.5334 0.2794) (xy 0.508 0.2794) (xy 0.5334 0.2794)
			)
			(stroke
				(width 0)
				(type default)
			)
			(fill no)
			(layer "B.CrtYd")
		)
		(pad "1" smd rect
			(at -0.40005 0 270)
			(size 0.4572 0.508)
			(layers "B.Cu" "B.Mask" "B.Paste")
			(net "P1V0_NODE1")
		)
		(pad "2" smd rect
			(at 0.40005 0 270)
			(size 0.4572 0.508)
			(layers "B.Cu" "B.Mask" "B.Paste")
			(net "GND")
		)
	)
	(footprint ""
		(layer "B.Cu")
		(at 55.261256 -63.088266 -90)
		(property "Reference" "R30"
			(at 31.206694 15.867126 270)
			(unlocked yes)
			(layer "B.SilkS")
			(effects
				(font
					(size 0.7874 0.5842)
					(thickness 0.1524)
				)
				(justify left mirror)
			)
		)
		(property "Value" ""
			(at 0 0 90)
			(layer "B.Fab")
			(effects
				(font
					(size 1.27 1.27)
				)
				(justify mirror)
			)
		)
		(duplicate_pad_numbers_are_jumpers no)
		(fp_line
			(start -0.7874 0.4064)
			(end 0.7874 0.4064)
			(stroke
				(width 0.1524)
				(type default)
			)
			(layer "B.SilkS")
		)
		(fp_line
			(start 0.7874 0.4064)
			(end 0.7874 -0.4064)
			(stroke
				(width 0.1524)
				(type default)
			)
			(layer "B.SilkS")
		)
		(fp_line
			(start -0.7874 -0.4064)
			(end -0.7874 0.4064)
			(stroke
				(width 0.1524)
				(type default)
			)
			(layer "B.SilkS")
		)
		(fp_line
			(start 0.7874 -0.4064)
			(end -0.7874 -0.4064)
			(stroke
				(width 0.1524)
				(type default)
			)
			(layer "B.SilkS")
		)
		(fp_poly
			(pts
				(xy 0.508 0.2794) (xy 0.508 0.2286) (xy 0.635 0.2286) (xy 0.635 -0.254) (xy 0.5334 -0.254) (xy 0.5334 -0.2794)
				(xy -0.5334 -0.2794) (xy -0.5334 -0.254) (xy -0.635 -0.254) (xy -0.635 0.254) (xy -0.5334 0.254)
				(xy -0.5334 0.2794)
			)
			(stroke
				(width 0)
				(type default)
			)
			(fill no)
			(layer "B.CrtYd")
		)
		(pad "1" smd rect
			(at -0.40005 0 90)
			(size 0.4572 0.508)
			(layers "B.Cu" "B.Mask" "B.Paste")
			(net "M_DDR3_NODE1_ODTPU")
		)
		(pad "2" smd rect
			(at 0.40005 0 90)
			(size 0.4572 0.508)
			(layers "B.Cu" "B.Mask" "B.Paste")
			(net "GND")
		)
	)
	(footprint ""
		(layer "B.Cu")
		(at 54.741572 -77.118718 -90)
		(property "Reference" "C58"
			(at 32.331406 14.410182 270)
			(unlocked yes)
			(layer "B.SilkS")
			(effects
				(font
					(size 0.7874 0.5842)
					(thickness 0.1524)
				)
				(justify left mirror)
			)
		)
		(property "Value" ""
			(at 0 0 90)
			(layer "B.Fab")
			(effects
				(font
					(size 1.27 1.27)
				)
				(justify mirror)
			)
		)
		(duplicate_pad_numbers_are_jumpers no)
		(fp_line
			(start -0.7874 0.4064)
			(end 0.7874 0.4064)
			(stroke
				(width 0.1524)
				(type default)
			)
			(layer "B.SilkS")
		)
		(fp_line
			(start 0.7874 0.4064)
			(end 0.7874 -0.4064)
			(stroke
				(width 0.1524)
				(type default)
			)
			(layer "B.SilkS")
		)
		(fp_line
			(start 0 0.381)
			(end 0 -0.381)
			(stroke
				(width 0.1524)
				(type default)
			)
			(layer "B.SilkS")
		)
		(fp_line
			(start -0.7874 -0.4064)
			(end -0.7874 0.4064)
			(stroke
				(width 0.1524)
				(type default)
			)
			(layer "B.SilkS")
		)
		(fp_line
			(start 0.7874 -0.4064)
			(end -0.7874 -0.4064)
			(stroke
				(width 0.1524)
				(type default)
			)
			(layer "B.SilkS")
		)
		(fp_poly
			(pts
				(xy 0.5334 0.254) (xy 0.635 0.254) (xy 0.635 0.2286) (xy 0.635 -0.254) (xy 0.5334 -0.254) (xy 0.5334 -0.2794)
				(xy -0.5334 -0.2794) (xy -0.5334 -0.254) (xy -0.635 -0.254) (xy -0.635 0.254) (xy -0.5334 0.254)
				(xy -0.5334 0.2794) (xy 0.508 0.2794) (xy 0.5334 0.2794)
			)
			(stroke
				(width 0)
				(type default)
			)
			(fill no)
			(layer "B.CrtYd")
		)
		(pad "1" smd rect
			(at -0.40005 0 90)
			(size 0.4572 0.508)
			(layers "B.Cu" "B.Mask" "B.Paste")
			(net "P1V05_NODE1")
		)
		(pad "2" smd rect
			(at 0.40005 0 90)
			(size 0.4572 0.508)
			(layers "B.Cu" "B.Mask" "B.Paste")
			(net "GND")
		)
	)
	(footprint ""
		(layer "B.Cu")
		(at 64.074294 -68.76034 90)
		(property "Reference" "L10"
			(at -33.95345 -14.250924 270)
			(unlocked yes)
			(layer "B.SilkS")
			(effects
				(font
					(size 0.7874 0.5842)
					(thickness 0.1524)
				)
				(justify left mirror)
			)
		)
		(property "Value" ""
			(at 0 0 90)
			(layer "B.Fab")
			(effects
				(font
					(size 1.27 1.27)
				)
				(justify mirror)
			)
		)
		(duplicate_pad_numbers_are_jumpers no)
		(fp_line
			(start 0.7874 -0.4064)
			(end -0.7874 -0.4064)
			(stroke
				(width 0.1524)
				(type default)
			)
			(layer "B.SilkS")
		)
		(fp_line
			(start -0.7874 -0.4064)
			(end -0.7874 0.4064)
			(stroke
				(width 0.1524)
				(type default)
			)
			(layer "B.SilkS")
		)
		(fp_line
			(start 0.7874 0.4064)
			(end 0.7874 -0.4064)
			(stroke
				(width 0.1524)
				(type default)
			)
			(layer "B.SilkS")
		)
		(fp_line
			(start 0.0889 0.4064)
			(end 0.0889 -0.4064)
			(stroke
				(width 0.1524)
				(type default)
			)
			(layer "B.SilkS")
		)
		(fp_line
			(start -0.0889 0.4064)
			(end -0.0889 -0.4064)
			(stroke
				(width 0.1524)
				(type default)
			)
			(layer "B.SilkS")
		)
		(fp_line
			(start -0.7874 0.4064)
			(end 0.7874 0.4064)
			(stroke
				(width 0.1524)
				(type default)
			)
			(layer "B.SilkS")
		)
		(fp_poly
			(pts
				(xy 0.5334 0.254) (xy 0.635 0.254) (xy 0.635 0.2286) (xy 0.635 -0.254) (xy 0.5334 -0.254) (xy 0.5334 -0.2794)
				(xy -0.5334 -0.2794) (xy -0.5334 -0.254) (xy -0.635 -0.254) (xy -0.635 0.254) (xy -0.5334 0.254)
				(xy -0.5334 0.2794) (xy 0.508 0.2794) (xy 0.5334 0.2794)
			)
			(stroke
				(width 0)
				(type default)
			)
			(fill no)
			(layer "B.CrtYd")
		)
		(pad "1" smd rect
			(at -0.40005 0 270)
			(size 0.4572 0.508)
			(layers "B.Cu" "B.Mask" "B.Paste")
			(net "PV_VDDR_NODE1")
		)
		(pad "2" smd rect
			(at 0.40005 0 270)
			(size 0.4572 0.508)
			(layers "B.Cu" "B.Mask" "B.Paste")
			(net "PV_VDDR_VCCCLK_DDR3_NODE1")
		)
	)
	(footprint ""
		(layer "B.Cu")
		(at 128.762252 -136.74471 90)
		(property "Reference" "C193"
			(at -5.94741 0.25781 270)
			(unlocked yes)
			(layer "B.SilkS")
			(effects
				(font
					(size 0.7874 0.5842)
					(thickness 0.1524)
				)
				(justify left mirror)
			)
		)
		(property "Value" ""
			(at 0 0 90)
			(layer "B.Fab")
			(effects
				(font
					(size 1.27 1.27)
				)
				(justify mirror)
			)
		)
		(duplicate_pad_numbers_are_jumpers no)
		(fp_line
			(start 0.7874 -0.4064)
			(end -0.7874 -0.4064)
			(stroke
				(width 0.1524)
				(type default)
			)
			(layer "B.SilkS")
		)
		(fp_line
			(start -0.7874 -0.4064)
			(end -0.7874 0.4064)
			(stroke
				(width 0.1524)
				(type default)
			)
			(layer "B.SilkS")
		)
		(fp_line
			(start 0 0.381)
			(end 0 -0.381)
			(stroke
				(width 0.1524)
				(type default)
			)
			(layer "B.SilkS")
		)
		(fp_line
			(start 0.7874 0.4064)
			(end 0.7874 -0.4064)
			(stroke
				(width 0.1524)
				(type default)
			)
			(layer "B.SilkS")
		)
		(fp_line
			(start -0.7874 0.4064)
			(end 0.7874 0.4064)
			(stroke
				(width 0.1524)
				(type default)
			)
			(layer "B.SilkS")
		)
		(fp_poly
			(pts
				(xy 0.5334 0.254) (xy 0.635 0.254) (xy 0.635 0.2286) (xy 0.635 -0.254) (xy 0.5334 -0.254) (xy 0.5334 -0.2794)
				(xy -0.5334 -0.2794) (xy -0.5334 -0.254) (xy -0.635 -0.254) (xy -0.635 0.254) (xy -0.5334 0.254)
				(xy -0.5334 0.2794) (xy 0.508 0.2794) (xy 0.5334 0.2794)
			)
			(stroke
				(width 0)
				(type default)
			)
			(fill no)
			(layer "B.CrtYd")
		)
		(pad "1" smd rect
			(at -0.40005 0 270)
			(size 0.4572 0.508)
			(layers "B.Cu" "B.Mask" "B.Paste")
			(net "CLK_100M_PCIE_SW_NODE1_DN")
		)
		(pad "2" smd rect
			(at 0.40005 0 270)
			(size 0.4572 0.508)
			(layers "B.Cu" "B.Mask" "B.Paste")
			(net "CLK_100M_PCIE_SW_NODE1_C_DN")
		)
	)
	(footprint ""
		(layer "B.Cu")
		(at 64.0715 -79.166466 -90)
		(property "Reference" "C81"
			(at 32.190436 14.44625 270)
			(unlocked yes)
			(layer "B.SilkS")
			(effects
				(font
					(size 0.7874 0.5842)
					(thickness 0.1524)
				)
				(justify left mirror)
			)
		)
		(property "Value" ""
			(at 0 0 90)
			(layer "B.Fab")
			(effects
				(font
					(size 1.27 1.27)
				)
				(justify mirror)
			)
		)
		(duplicate_pad_numbers_are_jumpers no)
		(fp_line
			(start -0.7874 0.4064)
			(end 0.7874 0.4064)
			(stroke
				(width 0.1524)
				(type default)
			)
			(layer "B.SilkS")
		)
		(fp_line
			(start 0.7874 0.4064)
			(end 0.7874 -0.4064)
			(stroke
				(width 0.1524)
				(type default)
			)
			(layer "B.SilkS")
		)
		(fp_line
			(start 0 0.381)
			(end 0 -0.381)
			(stroke
				(width 0.1524)
				(type default)
			)
			(layer "B.SilkS")
		)
		(fp_line
			(start -0.7874 -0.4064)
			(end -0.7874 0.4064)
			(stroke
				(width 0.1524)
				(type default)
			)
			(layer "B.SilkS")
		)
		(fp_line
			(start 0.7874 -0.4064)
			(end -0.7874 -0.4064)
			(stroke
				(width 0.1524)
				(type default)
			)
			(layer "B.SilkS")
		)
		(fp_poly
			(pts
				(xy 0.5334 0.254) (xy 0.635 0.254) (xy 0.635 0.2286) (xy 0.635 -0.254) (xy 0.5334 -0.254) (xy 0.5334 -0.2794)
				(xy -0.5334 -0.2794) (xy -0.5334 -0.254) (xy -0.635 -0.254) (xy -0.635 0.254) (xy -0.5334 0.254)
				(xy -0.5334 0.2794) (xy 0.508 0.2794) (xy 0.5334 0.2794)
			)
			(stroke
				(width 0)
				(type default)
			)
			(fill no)
			(layer "B.CrtYd")
		)
		(pad "1" smd rect
			(at -0.40005 0 90)
			(size 0.4572 0.508)
			(layers "B.Cu" "B.Mask" "B.Paste")
			(net "PV_VCCP_NODE1")
		)
		(pad "2" smd rect
			(at 0.40005 0 90)
			(size 0.4572 0.508)
			(layers "B.Cu" "B.Mask" "B.Paste")
			(net "GND")
		)
	)
	(footprint ""
		(layer "B.Cu")
		(at 56.054498 -96.696784 90)
		(property "Reference" "R54"
			(at 6.405118 -4.364228 270)
			(unlocked yes)
			(layer "B.SilkS")
			(effects
				(font
					(size 0.7874 0.5842)
					(thickness 0.1524)
				)
				(justify left mirror)
			)
		)
		(property "Value" ""
			(at 0 0 90)
			(layer "B.Fab")
			(effects
				(font
					(size 1.27 1.27)
				)
				(justify mirror)
			)
		)
		(duplicate_pad_numbers_are_jumpers no)
		(fp_line
			(start 0.7874 -0.4064)
			(end -0.7874 -0.4064)
			(stroke
				(width 0.1524)
				(type default)
			)
			(layer "B.SilkS")
		)
		(fp_line
			(start -0.7874 -0.4064)
			(end -0.7874 0.4064)
			(stroke
				(width 0.1524)
				(type default)
			)
			(layer "B.SilkS")
		)
		(fp_line
			(start 0.7874 0.4064)
			(end 0.7874 -0.4064)
			(stroke
				(width 0.1524)
				(type default)
			)
			(layer "B.SilkS")
		)
		(fp_line
			(start -0.7874 0.4064)
			(end 0.7874 0.4064)
			(stroke
				(width 0.1524)
				(type default)
			)
			(layer "B.SilkS")
		)
		(fp_poly
			(pts
				(xy 0.508 0.2794) (xy 0.508 0.2286) (xy 0.635 0.2286) (xy 0.635 -0.254) (xy 0.5334 -0.254) (xy 0.5334 -0.2794)
				(xy -0.5334 -0.2794) (xy -0.5334 -0.254) (xy -0.635 -0.254) (xy -0.635 0.254) (xy -0.5334 0.254)
				(xy -0.5334 0.2794)
			)
			(stroke
				(width 0)
				(type default)
			)
			(fill no)
			(layer "B.CrtYd")
		)
		(pad "1" smd rect
			(at -0.40005 0 270)
			(size 0.4572 0.508)
			(layers "B.Cu" "B.Mask" "B.Paste")
			(net "PD_CPU_NODE1_DFX_GPIO_GRP1_2")
		)
		(pad "2" smd rect
			(at 0.40005 0 270)
			(size 0.4572 0.508)
			(layers "B.Cu" "B.Mask" "B.Paste")
			(net "GND")
		)
	)
	(footprint ""
		(layer "B.Cu")
		(at 64.782192 -131.551426 90)
		(property "Reference" "C253"
			(at -54.864 -41.316402 270)
			(unlocked yes)
			(layer "B.SilkS")
			(effects
				(font
					(size 0.7874 0.5842)
					(thickness 0.1524)
				)
				(justify left mirror)
			)
		)
		(property "Value" ""
			(at 0 0 90)
			(layer "B.Fab")
			(effects
				(font
					(size 1.27 1.27)
				)
				(justify mirror)
			)
		)
		(duplicate_pad_numbers_are_jumpers no)
		(fp_line
			(start 0.7874 -0.4064)
			(end -0.7874 -0.4064)
			(stroke
				(width 0.1524)
				(type default)
			)
			(layer "B.SilkS")
		)
		(fp_line
			(start -0.7874 -0.4064)
			(end -0.7874 0.4064)
			(stroke
				(width 0.1524)
				(type default)
			)
			(layer "B.SilkS")
		)
		(fp_line
			(start 0 0.381)
			(end 0 -0.381)
			(stroke
				(width 0.1524)
				(type default)
			)
			(layer "B.SilkS")
		)
		(fp_line
			(start 0.7874 0.4064)
			(end 0.7874 -0.4064)
			(stroke
				(width 0.1524)
				(type default)
			)
			(layer "B.SilkS")
		)
		(fp_line
			(start -0.7874 0.4064)
			(end 0.7874 0.4064)
			(stroke
				(width 0.1524)
				(type default)
			)
			(layer "B.SilkS")
		)
		(fp_poly
			(pts
				(xy 0.5334 0.254) (xy 0.635 0.254) (xy 0.635 0.2286) (xy 0.635 -0.254) (xy 0.5334 -0.254) (xy 0.5334 -0.2794)
				(xy -0.5334 -0.2794) (xy -0.5334 -0.254) (xy -0.635 -0.254) (xy -0.635 0.254) (xy -0.5334 0.254)
				(xy -0.5334 0.2794) (xy 0.508 0.2794) (xy 0.5334 0.2794)
			)
			(stroke
				(width 0)
				(type default)
			)
			(fill no)
			(layer "B.CrtYd")
		)
		(pad "1" smd rect
			(at -0.40005 0 270)
			(size 0.4572 0.508)
			(layers "B.Cu" "B.Mask" "B.Paste")
			(net "P3V3_NODE1")
		)
		(pad "2" smd rect
			(at 0.40005 0 270)
			(size 0.4572 0.508)
			(layers "B.Cu" "B.Mask" "B.Paste")
			(net "GND")
		)
	)
	(footprint ""
		(layer "B.Cu")
		(at 23.847298 -108.443522)
		(property "Reference" "C55"
			(at -3.015996 -0.770382 0)
			(unlocked yes)
			(layer "B.SilkS")
			(effects
				(font
					(size 0.7874 0.5842)
					(thickness 0.1524)
				)
				(justify left mirror)
			)
		)
		(property "Value" ""
			(at 0 0 0)
			(layer "B.Fab")
			(effects
				(font
					(size 1.27 1.27)
				)
				(justify mirror)
			)
		)
		(duplicate_pad_numbers_are_jumpers no)
		(fp_line
			(start -1.905 -0.8636)
			(end -1.905 0.8636)
			(stroke
				(width 0.1524)
				(type default)
			)
			(layer "B.SilkS")
		)
		(fp_line
			(start -1.905 0.8636)
			(end 1.905 0.8636)
			(stroke
				(width 0.1524)
				(type default)
			)
			(layer "B.SilkS")
		)
		(fp_line
			(start 0 0.8382)
			(end 0 -0.8382)
			(stroke
				(width 0.1524)
				(type default)
			)
			(layer "B.SilkS")
		)
		(fp_line
			(start 1.905 -0.8636)
			(end -1.905 -0.8636)
			(stroke
				(width 0.1524)
				(type default)
			)
			(layer "B.SilkS")
		)
		(fp_line
			(start 1.905 0.8636)
			(end 1.905 -0.8636)
			(stroke
				(width 0.1524)
				(type default)
			)
			(layer "B.SilkS")
		)
		(fp_rect
			(start 1.524 0.7366)
			(end -1.524 -0.7366)
			(stroke
				(width 0)
				(type default)
			)
			(fill no)
			(layer "B.CrtYd")
		)
		(pad "1" smd rect
			(at -0.94996 0 180)
			(size 1.1176 1.3716)
			(layers "B.Cu" "B.Mask" "B.Paste")
			(net "P1V05_NODE1")
		)
		(pad "2" smd rect
			(at 0.94996 0 180)
			(size 1.1176 1.3716)
			(layers "B.Cu" "B.Mask" "B.Paste")
			(net "GND")
		)
	)
	(footprint ""
		(layer "B.Cu")
		(at 164.10178 -157.795722 -90)
		(property "Reference" "C441"
			(at -2.140966 0.300228 270)
			(unlocked yes)
			(layer "B.SilkS")
			(effects
				(font
					(size 0.7874 0.5842)
					(thickness 0.1524)
				)
				(justify left mirror)
			)
		)
		(property "Value" ""
			(at 0 0 90)
			(layer "B.Fab")
			(effects
				(font
					(size 1.27 1.27)
				)
				(justify mirror)
			)
		)
		(duplicate_pad_numbers_are_jumpers no)
		(fp_line
			(start -0.7874 0.4064)
			(end 0.7874 0.4064)
			(stroke
				(width 0.1524)
				(type default)
			)
			(layer "B.SilkS")
		)
		(fp_line
			(start 0.7874 0.4064)
			(end 0.7874 -0.4064)
			(stroke
				(width 0.1524)
				(type default)
			)
			(layer "B.SilkS")
		)
		(fp_line
			(start 0 0.381)
			(end 0 -0.381)
			(stroke
				(width 0.1524)
				(type default)
			)
			(layer "B.SilkS")
		)
		(fp_line
			(start -0.7874 -0.4064)
			(end -0.7874 0.4064)
			(stroke
				(width 0.1524)
				(type default)
			)
			(layer "B.SilkS")
		)
		(fp_line
			(start 0.7874 -0.4064)
			(end -0.7874 -0.4064)
			(stroke
				(width 0.1524)
				(type default)
			)
			(layer "B.SilkS")
		)
		(fp_poly
			(pts
				(xy 0.5334 0.254) (xy 0.635 0.254) (xy 0.635 0.2286) (xy 0.635 -0.254) (xy 0.5334 -0.254) (xy 0.5334 -0.2794)
				(xy -0.5334 -0.2794) (xy -0.5334 -0.254) (xy -0.635 -0.254) (xy -0.635 0.254) (xy -0.5334 0.254)
				(xy -0.5334 0.2794) (xy 0.508 0.2794) (xy 0.5334 0.2794)
			)
			(stroke
				(width 0)
				(type default)
			)
			(fill no)
			(layer "B.CrtYd")
		)
		(pad "1" smd rect
			(at -0.40005 0 90)
			(size 0.4572 0.508)
			(layers "B.Cu" "B.Mask" "B.Paste")
			(net "P3V3_NODE1")
		)
		(pad "2" smd rect
			(at 0.40005 0 90)
			(size 0.4572 0.508)
			(layers "B.Cu" "B.Mask" "B.Paste")
			(net "GND")
		)
	)
	(footprint ""
		(layer "B.Cu")
		(at 110.85576 -185.205624 -90)
		(property "Reference" "C730"
			(at -3.957828 -0.466598 270)
			(unlocked yes)
			(layer "B.SilkS")
			(effects
				(font
					(size 0.7874 0.5842)
					(thickness 0.1524)
				)
				(justify left mirror)
			)
		)
		(property "Value" ""
			(at 0 0 90)
			(layer "B.Fab")
			(effects
				(font
					(size 1.27 1.27)
				)
				(justify mirror)
			)
		)
		(duplicate_pad_numbers_are_jumpers no)
		(fp_line
			(start -0.7874 0.4064)
			(end 0.7874 0.4064)
			(stroke
				(width 0.1524)
				(type default)
			)
			(layer "B.SilkS")
		)
		(fp_line
			(start 0.7874 0.4064)
			(end 0.7874 -0.4064)
			(stroke
				(width 0.1524)
				(type default)
			)
			(layer "B.SilkS")
		)
		(fp_line
			(start 0 0.381)
			(end 0 -0.381)
			(stroke
				(width 0.1524)
				(type default)
			)
			(layer "B.SilkS")
		)
		(fp_line
			(start -0.7874 -0.4064)
			(end -0.7874 0.4064)
			(stroke
				(width 0.1524)
				(type default)
			)
			(layer "B.SilkS")
		)
		(fp_line
			(start 0.7874 -0.4064)
			(end -0.7874 -0.4064)
			(stroke
				(width 0.1524)
				(type default)
			)
			(layer "B.SilkS")
		)
		(fp_poly
			(pts
				(xy 0.5334 0.254) (xy 0.635 0.254) (xy 0.635 0.2286) (xy 0.635 -0.254) (xy 0.5334 -0.254) (xy 0.5334 -0.2794)
				(xy -0.5334 -0.2794) (xy -0.5334 -0.254) (xy -0.635 -0.254) (xy -0.635 0.254) (xy -0.5334 0.254)
				(xy -0.5334 0.2794) (xy 0.508 0.2794) (xy 0.5334 0.2794)
			)
			(stroke
				(width 0)
				(type default)
			)
			(fill no)
			(layer "B.CrtYd")
		)
		(pad "1" smd rect
			(at -0.40005 0 90)
			(size 0.4572 0.508)
			(layers "B.Cu" "B.Mask" "B.Paste")
			(net "UART_T7_NODE3_RXD")
		)
		(pad "2" smd rect
			(at 0.40005 0 90)
			(size 0.4572 0.508)
			(layers "B.Cu" "B.Mask" "B.Paste")
			(net "GND")
		)
	)
	(footprint ""
		(layer "B.Cu")
		(at 142.470632 -163.353242 180)
		(property "Reference" "R1001"
			(at -0.293116 -4.485386 270)
			(unlocked yes)
			(layer "B.SilkS")
			(effects
				(font
					(size 0.7874 0.5842)
					(thickness 0.1524)
				)
				(justify left mirror)
			)
		)
		(property "Value" ""
			(at 0 0 0)
			(layer "B.Fab")
			(effects
				(font
					(size 1.27 1.27)
				)
				(justify mirror)
			)
		)
		(duplicate_pad_numbers_are_jumpers no)
		(fp_line
			(start 0.7874 0.4064)
			(end 0.7874 -0.4064)
			(stroke
				(width 0.1524)
				(type default)
			)
			(layer "B.SilkS")
		)
		(fp_line
			(start 0.7874 -0.4064)
			(end -0.7874 -0.4064)
			(stroke
				(width 0.1524)
				(type default)
			)
			(layer "B.SilkS")
		)
		(fp_line
			(start -0.7874 0.4064)
			(end 0.7874 0.4064)
			(stroke
				(width 0.1524)
				(type default)
			)
			(layer "B.SilkS")
		)
		(fp_line
			(start -0.7874 -0.4064)
			(end -0.7874 0.4064)
			(stroke
				(width 0.1524)
				(type default)
			)
			(layer "B.SilkS")
		)
		(fp_poly
			(pts
				(xy 0.508 0.2794) (xy 0.508 0.2286) (xy 0.635 0.2286) (xy 0.635 -0.254) (xy 0.5334 -0.254) (xy 0.5334 -0.2794)
				(xy -0.5334 -0.2794) (xy -0.5334 -0.254) (xy -0.635 -0.254) (xy -0.635 0.254) (xy -0.5334 0.254)
				(xy -0.5334 0.2794)
			)
			(stroke
				(width 0)
				(type default)
			)
			(fill no)
			(layer "B.CrtYd")
		)
		(pad "1" smd rect
			(at -0.40005 0)
			(size 0.4572 0.508)
			(layers "B.Cu" "B.Mask" "B.Paste")
			(net "UART_T10_NODE4_TXD")
		)
		(pad "2" smd rect
			(at 0.40005 0)
			(size 0.4572 0.508)
			(layers "B.Cu" "B.Mask" "B.Paste")
			(net "UART_T10_NODE4_TXD_R")
		)
	)
	(footprint ""
		(layer "B.Cu")
		(at 91.102434 -184.794398 180)
		(property "Reference" "R924"
			(at 2.352294 4.044442 0)
			(unlocked yes)
			(layer "B.SilkS")
			(effects
				(font
					(size 0.7874 0.5842)
					(thickness 0.1524)
				)
				(justify left mirror)
			)
		)
		(property "Value" ""
			(at 0 0 0)
			(layer "B.Fab")
			(effects
				(font
					(size 1.27 1.27)
				)
				(justify mirror)
			)
		)
		(duplicate_pad_numbers_are_jumpers no)
		(fp_line
			(start 0.7874 0.4064)
			(end 0.7874 -0.4064)
			(stroke
				(width 0.1524)
				(type default)
			)
			(layer "B.SilkS")
		)
		(fp_line
			(start 0.7874 -0.4064)
			(end -0.7874 -0.4064)
			(stroke
				(width 0.1524)
				(type default)
			)
			(layer "B.SilkS")
		)
		(fp_line
			(start -0.7874 0.4064)
			(end 0.7874 0.4064)
			(stroke
				(width 0.1524)
				(type default)
			)
			(layer "B.SilkS")
		)
		(fp_line
			(start -0.7874 -0.4064)
			(end -0.7874 0.4064)
			(stroke
				(width 0.1524)
				(type default)
			)
			(layer "B.SilkS")
		)
		(fp_poly
			(pts
				(xy 0.508 0.2794) (xy 0.508 0.2286) (xy 0.635 0.2286) (xy 0.635 -0.254) (xy 0.5334 -0.254) (xy 0.5334 -0.2794)
				(xy -0.5334 -0.2794) (xy -0.5334 -0.254) (xy -0.635 -0.254) (xy -0.635 0.254) (xy -0.5334 0.254)
				(xy -0.5334 0.2794)
			)
			(stroke
				(width 0)
				(type default)
			)
			(fill no)
			(layer "B.CrtYd")
		)
		(pad "1" smd rect
			(at -0.40005 0)
			(size 0.4572 0.508)
			(layers "B.Cu" "B.Mask" "B.Paste")
			(net "UART_T5_NODE3_TXD")
		)
		(pad "2" smd rect
			(at 0.40005 0)
			(size 0.4572 0.508)
			(layers "B.Cu" "B.Mask" "B.Paste")
			(net "UART_T5_NODE3_TXD_R")
		)
	)
	(footprint ""
		(layer "B.Cu")
		(at 78.83144 -167.425624 180)
		(property "Reference" "R790"
			(at -30.603698 -20.726146 0)
			(unlocked yes)
			(layer "B.SilkS")
			(effects
				(font
					(size 0.7874 0.5842)
					(thickness 0.1524)
				)
				(justify left mirror)
			)
		)
		(property "Value" ""
			(at 0 0 0)
			(layer "B.Fab")
			(effects
				(font
					(size 1.27 1.27)
				)
				(justify mirror)
			)
		)
		(duplicate_pad_numbers_are_jumpers no)
		(fp_line
			(start 0.7874 0.4064)
			(end 0.7874 -0.4064)
			(stroke
				(width 0.1524)
				(type default)
			)
			(layer "B.SilkS")
		)
		(fp_line
			(start 0.7874 -0.4064)
			(end -0.7874 -0.4064)
			(stroke
				(width 0.1524)
				(type default)
			)
			(layer "B.SilkS")
		)
		(fp_line
			(start -0.7874 0.4064)
			(end 0.7874 0.4064)
			(stroke
				(width 0.1524)
				(type default)
			)
			(layer "B.SilkS")
		)
		(fp_line
			(start -0.7874 -0.4064)
			(end -0.7874 0.4064)
			(stroke
				(width 0.1524)
				(type default)
			)
			(layer "B.SilkS")
		)
		(fp_poly
			(pts
				(xy 0.508 0.2794) (xy 0.508 0.2286) (xy 0.635 0.2286) (xy 0.635 -0.254) (xy 0.5334 -0.254) (xy 0.5334 -0.2794)
				(xy -0.5334 -0.2794) (xy -0.5334 -0.254) (xy -0.635 -0.254) (xy -0.635 0.254) (xy -0.5334 0.254)
				(xy -0.5334 0.2794)
			)
			(stroke
				(width 0)
				(type default)
			)
			(fill no)
			(layer "B.CrtYd")
		)
		(pad "1" smd rect
			(at -0.40005 0)
			(size 0.4572 0.508)
			(layers "B.Cu" "B.Mask" "B.Paste")
			(net "UART_SW_S4_N")
		)
		(pad "2" smd rect
			(at 0.40005 0)
			(size 0.4572 0.508)
			(layers "B.Cu" "B.Mask" "B.Paste")
			(net "P3V3_NODE1")
		)
	)
	(footprint ""
		(layer "B.Cu")
		(at 94.211394 -187.822586)
		(property "Reference" "C668"
			(at 1.315466 -5.985002 0)
			(unlocked yes)
			(layer "B.SilkS")
			(effects
				(font
					(size 0.7874 0.5842)
					(thickness 0.1524)
				)
				(justify left mirror)
			)
		)
		(property "Value" ""
			(at 0 0 0)
			(layer "B.Fab")
			(effects
				(font
					(size 1.27 1.27)
				)
				(justify mirror)
			)
		)
		(duplicate_pad_numbers_are_jumpers no)
		(fp_line
			(start -0.7874 -0.4064)
			(end -0.7874 0.4064)
			(stroke
				(width 0.1524)
				(type default)
			)
			(layer "B.SilkS")
		)
		(fp_line
			(start -0.7874 0.4064)
			(end 0.7874 0.4064)
			(stroke
				(width 0.1524)
				(type default)
			)
			(layer "B.SilkS")
		)
		(fp_line
			(start 0 0.381)
			(end 0 -0.381)
			(stroke
				(width 0.1524)
				(type default)
			)
			(layer "B.SilkS")
		)
		(fp_line
			(start 0.7874 -0.4064)
			(end -0.7874 -0.4064)
			(stroke
				(width 0.1524)
				(type default)
			)
			(layer "B.SilkS")
		)
		(fp_line
			(start 0.7874 0.4064)
			(end 0.7874 -0.4064)
			(stroke
				(width 0.1524)
				(type default)
			)
			(layer "B.SilkS")
		)
		(fp_poly
			(pts
				(xy 0.5334 0.254) (xy 0.635 0.254) (xy 0.635 0.2286) (xy 0.635 -0.254) (xy 0.5334 -0.254) (xy 0.5334 -0.2794)
				(xy -0.5334 -0.2794) (xy -0.5334 -0.254) (xy -0.635 -0.254) (xy -0.635 0.254) (xy -0.5334 0.254)
				(xy -0.5334 0.2794) (xy 0.508 0.2794) (xy 0.5334 0.2794)
			)
			(stroke
				(width 0)
				(type default)
			)
			(fill no)
			(layer "B.CrtYd")
		)
		(pad "1" smd rect
			(at -0.40005 0 180)
			(size 0.4572 0.508)
			(layers "B.Cu" "B.Mask" "B.Paste")
			(net "T5_NODE4_EN_R")
		)
		(pad "2" smd rect
			(at 0.40005 0 180)
			(size 0.4572 0.508)
			(layers "B.Cu" "B.Mask" "B.Paste")
			(net "GND")
		)
	)
	(footprint ""
		(layer "B.Cu")
		(at 57.430416 -130.01371 180)
		(property "Reference" "C288"
			(at 40.223948 -53.201316 0)
			(unlocked yes)
			(layer "B.SilkS")
			(effects
				(font
					(size 0.7874 0.5842)
					(thickness 0.1524)
				)
				(justify left mirror)
			)
		)
		(property "Value" ""
			(at 0 0 0)
			(layer "B.Fab")
			(effects
				(font
					(size 1.27 1.27)
				)
				(justify mirror)
			)
		)
		(duplicate_pad_numbers_are_jumpers no)
		(fp_line
			(start 0.7874 0.4064)
			(end 0.7874 -0.4064)
			(stroke
				(width 0.1524)
				(type default)
			)
			(layer "B.SilkS")
		)
		(fp_line
			(start 0.7874 -0.4064)
			(end -0.7874 -0.4064)
			(stroke
				(width 0.1524)
				(type default)
			)
			(layer "B.SilkS")
		)
		(fp_line
			(start 0 0.381)
			(end 0 -0.381)
			(stroke
				(width 0.1524)
				(type default)
			)
			(layer "B.SilkS")
		)
		(fp_line
			(start -0.7874 0.4064)
			(end 0.7874 0.4064)
			(stroke
				(width 0.1524)
				(type default)
			)
			(layer "B.SilkS")
		)
		(fp_line
			(start -0.7874 -0.4064)
			(end -0.7874 0.4064)
			(stroke
				(width 0.1524)
				(type default)
			)
			(layer "B.SilkS")
		)
		(fp_poly
			(pts
				(xy 0.5334 0.254) (xy 0.635 0.254) (xy 0.635 0.2286) (xy 0.635 -0.254) (xy 0.5334 -0.254) (xy 0.5334 -0.2794)
				(xy -0.5334 -0.2794) (xy -0.5334 -0.254) (xy -0.635 -0.254) (xy -0.635 0.254) (xy -0.5334 0.254)
				(xy -0.5334 0.2794) (xy 0.508 0.2794) (xy 0.5334 0.2794)
			)
			(stroke
				(width 0)
				(type default)
			)
			(fill no)
			(layer "B.CrtYd")
		)
		(pad "1" smd rect
			(at -0.40005 0)
			(size 0.4572 0.508)
			(layers "B.Cu" "B.Mask" "B.Paste")
			(net "P1V26_BMC_NODE1")
		)
		(pad "2" smd rect
			(at 0.40005 0)
			(size 0.4572 0.508)
			(layers "B.Cu" "B.Mask" "B.Paste")
			(net "GND")
		)
	)
	(footprint ""
		(layer "B.Cu")
		(at 142.07236 -175.045624 180)
		(property "Reference" "R732"
			(at 1.287272 0.298196 0)
			(unlocked yes)
			(layer "B.SilkS")
			(effects
				(font
					(size 0.7874 0.5842)
					(thickness 0.1524)
				)
				(justify left mirror)
			)
		)
		(property "Value" ""
			(at 0 0 0)
			(layer "B.Fab")
			(effects
				(font
					(size 1.27 1.27)
				)
				(justify mirror)
			)
		)
		(duplicate_pad_numbers_are_jumpers no)
		(fp_line
			(start 0.7874 0.4064)
			(end 0.7874 -0.4064)
			(stroke
				(width 0.1524)
				(type default)
			)
			(layer "B.SilkS")
		)
		(fp_line
			(start 0.7874 -0.4064)
			(end -0.7874 -0.4064)
			(stroke
				(width 0.1524)
				(type default)
			)
			(layer "B.SilkS")
		)
		(fp_line
			(start -0.7874 0.4064)
			(end 0.7874 0.4064)
			(stroke
				(width 0.1524)
				(type default)
			)
			(layer "B.SilkS")
		)
		(fp_line
			(start -0.7874 -0.4064)
			(end -0.7874 0.4064)
			(stroke
				(width 0.1524)
				(type default)
			)
			(layer "B.SilkS")
		)
		(fp_poly
			(pts
				(xy 0.508 0.2794) (xy 0.508 0.2286) (xy 0.635 0.2286) (xy 0.635 -0.254) (xy 0.5334 -0.254) (xy 0.5334 -0.2794)
				(xy -0.5334 -0.2794) (xy -0.5334 -0.254) (xy -0.635 -0.254) (xy -0.635 0.254) (xy -0.5334 0.254)
				(xy -0.5334 0.2794)
			)
			(stroke
				(width 0)
				(type default)
			)
			(fill no)
			(layer "B.CrtYd")
		)
		(pad "1" smd rect
			(at -0.40005 0)
			(size 0.4572 0.508)
			(layers "B.Cu" "B.Mask" "B.Paste")
			(net "T10_NODE1_EN")
		)
		(pad "2" smd rect
			(at 0.40005 0)
			(size 0.4572 0.508)
			(layers "B.Cu" "B.Mask" "B.Paste")
			(net "P5V_NODE1")
		)
	)
	(footprint ""
		(layer "B.Cu")
		(at 69.471286 -118.758462 -90)
		(property "Reference" "R339"
			(at 5.09016 0.669544 270)
			(unlocked yes)
			(layer "B.SilkS")
			(effects
				(font
					(size 0.7874 0.5842)
					(thickness 0.1524)
				)
				(justify left mirror)
			)
		)
		(property "Value" ""
			(at 0 0 90)
			(layer "B.Fab")
			(effects
				(font
					(size 1.27 1.27)
				)
				(justify mirror)
			)
		)
		(duplicate_pad_numbers_are_jumpers no)
		(fp_line
			(start -0.7874 0.4064)
			(end 0.7874 0.4064)
			(stroke
				(width 0.1524)
				(type default)
			)
			(layer "B.SilkS")
		)
		(fp_line
			(start 0.7874 0.4064)
			(end 0.7874 -0.4064)
			(stroke
				(width 0.1524)
				(type default)
			)
			(layer "B.SilkS")
		)
		(fp_line
			(start -0.7874 -0.4064)
			(end -0.7874 0.4064)
			(stroke
				(width 0.1524)
				(type default)
			)
			(layer "B.SilkS")
		)
		(fp_line
			(start 0.7874 -0.4064)
			(end -0.7874 -0.4064)
			(stroke
				(width 0.1524)
				(type default)
			)
			(layer "B.SilkS")
		)
		(fp_poly
			(pts
				(xy 0.508 0.2794) (xy 0.508 0.2286) (xy 0.635 0.2286) (xy 0.635 -0.254) (xy 0.5334 -0.254) (xy 0.5334 -0.2794)
				(xy -0.5334 -0.2794) (xy -0.5334 -0.254) (xy -0.635 -0.254) (xy -0.635 0.254) (xy -0.5334 0.254)
				(xy -0.5334 0.2794)
			)
			(stroke
				(width 0)
				(type default)
			)
			(fill no)
			(layer "B.CrtYd")
		)
		(pad "1" smd rect
			(at -0.40005 0 90)
			(size 0.4572 0.508)
			(layers "B.Cu" "B.Mask" "B.Paste")
			(net "P3V3_NODE1")
		)
		(pad "2" smd rect
			(at 0.40005 0 90)
			(size 0.4572 0.508)
			(layers "B.Cu" "B.Mask" "B.Paste")
			(net "BMC_ROMA23")
		)
	)
	(footprint ""
		(layer "B.Cu")
		(at 116.068602 -123.297442 -90)
		(property "Reference" "PC92"
			(at -3.090164 -0.20701 270)
			(unlocked yes)
			(layer "B.SilkS")
			(effects
				(font
					(size 0.7874 0.5842)
					(thickness 0.1524)
				)
				(justify left mirror)
			)
		)
		(property "Value" ""
			(at 0 0 90)
			(layer "B.Fab")
			(effects
				(font
					(size 1.27 1.27)
				)
				(justify mirror)
			)
		)
		(duplicate_pad_numbers_are_jumpers no)
		(fp_line
			(start -2.2098 0.9398)
			(end 2.2098 0.9398)
			(stroke
				(width 0.1524)
				(type default)
			)
			(layer "B.SilkS")
		)
		(fp_line
			(start 2.2098 0.9398)
			(end 2.2098 -0.9398)
			(stroke
				(width 0.1524)
				(type default)
			)
			(layer "B.SilkS")
		)
		(fp_line
			(start -2.2098 -0.9398)
			(end -2.2098 0.9398)
			(stroke
				(width 0.1524)
				(type default)
			)
			(layer "B.SilkS")
		)
		(fp_line
			(start 0 -0.9398)
			(end 0 0.9398)
			(stroke
				(width 0.1524)
				(type default)
			)
			(layer "B.SilkS")
		)
		(fp_line
			(start 2.2098 -0.9398)
			(end -2.2098 -0.9398)
			(stroke
				(width 0.1524)
				(type default)
			)
			(layer "B.SilkS")
		)
		(fp_poly
			(pts
				(xy 1.6764 0.889) (xy 1.6764 0.7874) (xy 2.0574 0.7874) (xy 2.0574 -0.7874) (xy 1.6764 -0.7874)
				(xy 1.6764 -0.9398) (xy -1.6764 -0.9398) (xy -1.6764 -0.7874) (xy -2.0574 -0.7874) (xy -2.0574 0.7874)
				(xy -1.6764 0.7874) (xy -1.6764 0.9398) (xy 1.6764 0.9398)
			)
			(stroke
				(width 0)
				(type default)
			)
			(fill no)
			(layer "B.CrtYd")
		)
		(fp_line
			(start -1.700022 0.899922)
			(end 1.700022 0.899922)
			(stroke
				(width 0.1)
				(type default)
			)
			(layer "B.Fab")
		)
		(fp_line
			(start 1.700022 0.899922)
			(end 1.700022 -0.899922)
			(stroke
				(width 0.1)
				(type default)
			)
			(layer "B.Fab")
		)
		(fp_line
			(start -1.700022 -0.899922)
			(end -1.700022 0.899922)
			(stroke
				(width 0.1)
				(type default)
			)
			(layer "B.Fab")
		)
		(fp_line
			(start 1.700022 -0.899922)
			(end -1.700022 -0.899922)
			(stroke
				(width 0.1)
				(type default)
			)
			(layer "B.Fab")
		)
		(pad "1" smd rect
			(at -1.4732 0 90)
			(size 1.1684 1.5748)
			(layers "B.Cu" "B.Mask" "B.Paste")
			(net "SW_VR_PVCCP_NODE1_VIN_FLT")
		)
		(pad "2" smd rect
			(at 1.4732 0 90)
			(size 1.1684 1.5748)
			(layers "B.Cu" "B.Mask" "B.Paste")
			(net "GND")
		)
	)
	(footprint ""
		(layer "B.Cu")
		(at 129.468372 -171.36364)
		(property "Reference" "R982"
			(at 5.856224 -0.371348 0)
			(unlocked yes)
			(layer "B.SilkS")
			(effects
				(font
					(size 0.7874 0.5842)
					(thickness 0.1524)
				)
				(justify left mirror)
			)
		)
		(property "Value" ""
			(at 0 0 0)
			(layer "B.Fab")
			(effects
				(font
					(size 1.27 1.27)
				)
				(justify mirror)
			)
		)
		(duplicate_pad_numbers_are_jumpers no)
		(fp_line
			(start -0.7874 -0.4064)
			(end -0.7874 0.4064)
			(stroke
				(width 0.1524)
				(type default)
			)
			(layer "B.SilkS")
		)
		(fp_line
			(start -0.7874 0.4064)
			(end 0.7874 0.4064)
			(stroke
				(width 0.1524)
				(type default)
			)
			(layer "B.SilkS")
		)
		(fp_line
			(start 0.7874 -0.4064)
			(end -0.7874 -0.4064)
			(stroke
				(width 0.1524)
				(type default)
			)
			(layer "B.SilkS")
		)
		(fp_line
			(start 0.7874 0.4064)
			(end 0.7874 -0.4064)
			(stroke
				(width 0.1524)
				(type default)
			)
			(layer "B.SilkS")
		)
		(fp_poly
			(pts
				(xy 0.508 0.2794) (xy 0.508 0.2286) (xy 0.635 0.2286) (xy 0.635 -0.254) (xy 0.5334 -0.254) (xy 0.5334 -0.2794)
				(xy -0.5334 -0.2794) (xy -0.5334 -0.254) (xy -0.635 -0.254) (xy -0.635 0.254) (xy -0.5334 0.254)
				(xy -0.5334 0.2794)
			)
			(stroke
				(width 0)
				(type default)
			)
			(fill no)
			(layer "B.CrtYd")
		)
		(pad "1" smd rect
			(at -0.40005 0 180)
			(size 0.4572 0.508)
			(layers "B.Cu" "B.Mask" "B.Paste")
			(net "UART_T8_NODE1_TXD")
		)
		(pad "2" smd rect
			(at 0.40005 0 180)
			(size 0.4572 0.508)
			(layers "B.Cu" "B.Mask" "B.Paste")
			(net "UART_T8_NODE1_TXD_R")
		)
	)
	(footprint ""
		(layer "B.Cu")
		(at 119.49176 -188.126624 -90)
		(property "Reference" "C638"
			(at -4.080256 -0.623316 270)
			(unlocked yes)
			(layer "B.SilkS")
			(effects
				(font
					(size 0.7874 0.5842)
					(thickness 0.1524)
				)
				(justify left mirror)
			)
		)
		(property "Value" ""
			(at 0 0 90)
			(layer "B.Fab")
			(effects
				(font
					(size 1.27 1.27)
				)
				(justify mirror)
			)
		)
		(duplicate_pad_numbers_are_jumpers no)
		(fp_line
			(start -0.7874 0.4064)
			(end 0.7874 0.4064)
			(stroke
				(width 0.1524)
				(type default)
			)
			(layer "B.SilkS")
		)
		(fp_line
			(start 0.7874 0.4064)
			(end 0.7874 -0.4064)
			(stroke
				(width 0.1524)
				(type default)
			)
			(layer "B.SilkS")
		)
		(fp_line
			(start 0 0.381)
			(end 0 -0.381)
			(stroke
				(width 0.1524)
				(type default)
			)
			(layer "B.SilkS")
		)
		(fp_line
			(start -0.7874 -0.4064)
			(end -0.7874 0.4064)
			(stroke
				(width 0.1524)
				(type default)
			)
			(layer "B.SilkS")
		)
		(fp_line
			(start 0.7874 -0.4064)
			(end -0.7874 -0.4064)
			(stroke
				(width 0.1524)
				(type default)
			)
			(layer "B.SilkS")
		)
		(fp_poly
			(pts
				(xy 0.5334 0.254) (xy 0.635 0.254) (xy 0.635 0.2286) (xy 0.635 -0.254) (xy 0.5334 -0.254) (xy 0.5334 -0.2794)
				(xy -0.5334 -0.2794) (xy -0.5334 -0.254) (xy -0.635 -0.254) (xy -0.635 0.254) (xy -0.5334 0.254)
				(xy -0.5334 0.2794) (xy 0.508 0.2794) (xy 0.5334 0.2794)
			)
			(stroke
				(width 0)
				(type default)
			)
			(fill no)
			(layer "B.CrtYd")
		)
		(pad "1" smd rect
			(at -0.40005 0 90)
			(size 0.4572 0.508)
			(layers "B.Cu" "B.Mask" "B.Paste")
			(net "T7_NODE2_EN_R")
		)
		(pad "2" smd rect
			(at 0.40005 0 90)
			(size 0.4572 0.508)
			(layers "B.Cu" "B.Mask" "B.Paste")
			(net "GND")
		)
	)
	(footprint ""
		(layer "B.Cu")
		(at 53.961538 -83.468718 -90)
		(property "Reference" "C37"
			(at -0.917448 0.066548 270)
			(unlocked yes)
			(layer "B.SilkS")
			(effects
				(font
					(size 0.7874 0.5842)
					(thickness 0.1524)
				)
				(justify left mirror)
			)
		)
		(property "Value" ""
			(at 0 0 90)
			(layer "B.Fab")
			(effects
				(font
					(size 1.27 1.27)
				)
				(justify mirror)
			)
		)
		(duplicate_pad_numbers_are_jumpers no)
		(fp_line
			(start -0.7874 0.4064)
			(end 0.7874 0.4064)
			(stroke
				(width 0.1524)
				(type default)
			)
			(layer "B.SilkS")
		)
		(fp_line
			(start 0.7874 0.4064)
			(end 0.7874 -0.4064)
			(stroke
				(width 0.1524)
				(type default)
			)
			(layer "B.SilkS")
		)
		(fp_line
			(start 0 0.381)
			(end 0 -0.381)
			(stroke
				(width 0.1524)
				(type default)
			)
			(layer "B.SilkS")
		)
		(fp_line
			(start -0.7874 -0.4064)
			(end -0.7874 0.4064)
			(stroke
				(width 0.1524)
				(type default)
			)
			(layer "B.SilkS")
		)
		(fp_line
			(start 0.7874 -0.4064)
			(end -0.7874 -0.4064)
			(stroke
				(width 0.1524)
				(type default)
			)
			(layer "B.SilkS")
		)
		(fp_poly
			(pts
				(xy 0.5334 0.254) (xy 0.635 0.254) (xy 0.635 0.2286) (xy 0.635 -0.254) (xy 0.5334 -0.254) (xy 0.5334 -0.2794)
				(xy -0.5334 -0.2794) (xy -0.5334 -0.254) (xy -0.635 -0.254) (xy -0.635 0.254) (xy -0.5334 0.254)
				(xy -0.5334 0.2794) (xy 0.508 0.2794) (xy 0.5334 0.2794)
			)
			(stroke
				(width 0)
				(type default)
			)
			(fill no)
			(layer "B.CrtYd")
		)
		(pad "1" smd rect
			(at -0.40005 0 90)
			(size 0.4572 0.508)
			(layers "B.Cu" "B.Mask" "B.Paste")
			(net "P1V8_NODE1")
		)
		(pad "2" smd rect
			(at 0.40005 0 90)
			(size 0.4572 0.508)
			(layers "B.Cu" "B.Mask" "B.Paste")
			(net "GND")
		)
	)
	(footprint ""
		(layer "B.Cu")
		(at 105.14076 -185.205624 90)
		(property "Reference" "R899"
			(at 3.777996 -0.438658 270)
			(unlocked yes)
			(layer "B.SilkS")
			(effects
				(font
					(size 0.7874 0.5842)
					(thickness 0.1524)
				)
				(justify left mirror)
			)
		)
		(property "Value" ""
			(at 0 0 90)
			(layer "B.Fab")
			(effects
				(font
					(size 1.27 1.27)
				)
				(justify mirror)
			)
		)
		(duplicate_pad_numbers_are_jumpers no)
		(fp_line
			(start 0.7874 -0.4064)
			(end -0.7874 -0.4064)
			(stroke
				(width 0.1524)
				(type default)
			)
			(layer "B.SilkS")
		)
		(fp_line
			(start -0.7874 -0.4064)
			(end -0.7874 0.4064)
			(stroke
				(width 0.1524)
				(type default)
			)
			(layer "B.SilkS")
		)
		(fp_line
			(start 0.7874 0.4064)
			(end 0.7874 -0.4064)
			(stroke
				(width 0.1524)
				(type default)
			)
			(layer "B.SilkS")
		)
		(fp_line
			(start -0.7874 0.4064)
			(end 0.7874 0.4064)
			(stroke
				(width 0.1524)
				(type default)
			)
			(layer "B.SilkS")
		)
		(fp_poly
			(pts
				(xy 0.508 0.2794) (xy 0.508 0.2286) (xy 0.635 0.2286) (xy 0.635 -0.254) (xy 0.5334 -0.254) (xy 0.5334 -0.2794)
				(xy -0.5334 -0.2794) (xy -0.5334 -0.254) (xy -0.635 -0.254) (xy -0.635 0.254) (xy -0.5334 0.254)
				(xy -0.5334 0.2794)
			)
			(stroke
				(width 0)
				(type default)
			)
			(fill no)
			(layer "B.CrtYd")
		)
		(pad "1" smd rect
			(at -0.40005 0 270)
			(size 0.4572 0.508)
			(layers "B.Cu" "B.Mask" "B.Paste")
			(net "T5_NODE2_EN")
		)
		(pad "2" smd rect
			(at 0.40005 0 270)
			(size 0.4572 0.508)
			(layers "B.Cu" "B.Mask" "B.Paste")
			(net "T5_NODE2_EN_R")
		)
	)
	(footprint ""
		(layer "B.Cu")
		(at 157.33776 -184.951624 90)
		(property "Reference" "R828"
			(at 4.230624 -1.943608 270)
			(unlocked yes)
			(layer "B.SilkS")
			(effects
				(font
					(size 0.7874 0.5842)
					(thickness 0.1524)
				)
				(justify left mirror)
			)
		)
		(property "Value" ""
			(at 0 0 90)
			(layer "B.Fab")
			(effects
				(font
					(size 1.27 1.27)
				)
				(justify mirror)
			)
		)
		(duplicate_pad_numbers_are_jumpers no)
		(fp_line
			(start 0.7874 -0.4064)
			(end -0.7874 -0.4064)
			(stroke
				(width 0.1524)
				(type default)
			)
			(layer "B.SilkS")
		)
		(fp_line
			(start -0.7874 -0.4064)
			(end -0.7874 0.4064)
			(stroke
				(width 0.1524)
				(type default)
			)
			(layer "B.SilkS")
		)
		(fp_line
			(start 0.7874 0.4064)
			(end 0.7874 -0.4064)
			(stroke
				(width 0.1524)
				(type default)
			)
			(layer "B.SilkS")
		)
		(fp_line
			(start -0.7874 0.4064)
			(end 0.7874 0.4064)
			(stroke
				(width 0.1524)
				(type default)
			)
			(layer "B.SilkS")
		)
		(fp_poly
			(pts
				(xy 0.508 0.2794) (xy 0.508 0.2286) (xy 0.635 0.2286) (xy 0.635 -0.254) (xy 0.5334 -0.254) (xy 0.5334 -0.2794)
				(xy -0.5334 -0.2794) (xy -0.5334 -0.254) (xy -0.635 -0.254) (xy -0.635 0.254) (xy -0.5334 0.254)
				(xy -0.5334 0.2794)
			)
			(stroke
				(width 0)
				(type default)
			)
			(fill no)
			(layer "B.CrtYd")
		)
		(pad "1" smd rect
			(at -0.40005 0 270)
			(size 0.4572 0.508)
			(layers "B.Cu" "B.Mask" "B.Paste")
			(net "I2C_PSU3_SCL")
		)
		(pad "2" smd rect
			(at 0.40005 0 270)
			(size 0.4572 0.508)
			(layers "B.Cu" "B.Mask" "B.Paste")
			(net "I2C_PSU3_R_SCL")
		)
	)
	(footprint ""
		(layer "B.Cu")
		(at 57.840372 -71.370698)
		(property "Reference" "PJ7"
			(at -14.298422 34.722054 270)
			(unlocked yes)
			(layer "B.SilkS")
			(effects
				(font
					(size 0.7874 0.5842)
					(thickness 0.1524)
				)
				(justify left mirror)
			)
		)
		(property "Value" ""
			(at 0 0 0)
			(layer "B.Fab")
			(effects
				(font
					(size 1.27 1.27)
				)
				(justify mirror)
			)
		)
		(duplicate_pad_numbers_are_jumpers no)
		(fp_poly
			(pts
				(xy -0.2794 0.907796) (xy -0.254 0.907796) (xy -0.254 1.0414) (xy 0.254 1.0414) (xy 0.254 1.034796)
				(xy 0.254 0.933196) (xy 0.2794 0.933196) (xy 0.2794 -0.133604) (xy 0.254 -0.133604) (xy 0.254 -0.235204)
				(xy -0.254 -0.235204) (xy -0.254 -0.133604) (xy -0.2794 -0.133604)
			)
			(stroke
				(width 0)
				(type default)
			)
			(fill no)
			(layer "B.CrtYd")
		)
		(pad "1" smd custom
			(at 0 -0.000254 180)
			(size 0.127 0.127)
			(layers "B.Cu" "B.Mask" "B.Paste")
			(net "GND")
			(options
				(clearance outline)
				(anchor circle)
			)
			(primitives
				(gr_poly
					(pts
						(xy -0.127 -0.508) (xy -0.127 0.0508) (xy -0.254 0.0508) (xy -0.254 0.508) (xy 0.254 0.508) (xy 0.254 0.0508)
						(xy 0.127 0.0508) (xy 0.127 -0.508)
					)
					(width 0)
					(fill yes)
				)
			)
		)
		(pad "2" smd rect
			(at 0 0.799846 90)
			(size 0.4572 0.508)
			(layers "B.Cu" "B.Mask" "B.Paste")
			(net "VSENSE_P1V05_NODE1_N")
		)
		(zone
			(layer "B.Cu")
			(hatch none 0.5)
			(connect_pads
				(clearance 0)
			)
			(min_thickness 0.25)
			(keepout
				(tracks allowed)
				(vias not_allowed)
				(pads allowed)
				(copperpour not_allowed)
				(footprints allowed)
			)
			(placement
				(enabled no)
				(sheetname "")
			)
			(fill
				(thermal_gap 0.5)
				(thermal_bridge_width 0.5)
				(island_removal_mode 0)
			)
			(polygon
				(pts
					(xy 58.145172 -70.285102) (xy 57.535572 -70.285102) (xy 57.535572 -71.656702) (xy 58.145172 -71.656702)
				)
			)
		)
	)
	(footprint ""
		(layer "B.Cu")
		(at 101.858572 -181.928516)
		(property "Reference" "R1060"
			(at 4.933188 -0.15875 0)
			(unlocked yes)
			(layer "B.SilkS")
			(effects
				(font
					(size 0.7874 0.5842)
					(thickness 0.1524)
				)
				(justify left mirror)
			)
		)
		(property "Value" ""
			(at 0 0 0)
			(layer "B.Fab")
			(effects
				(font
					(size 1.27 1.27)
				)
				(justify mirror)
			)
		)
		(duplicate_pad_numbers_are_jumpers no)
		(fp_line
			(start -0.7874 -0.4064)
			(end -0.7874 0.4064)
			(stroke
				(width 0.1524)
				(type default)
			)
			(layer "B.SilkS")
		)
		(fp_line
			(start -0.7874 0.4064)
			(end 0.7874 0.4064)
			(stroke
				(width 0.1524)
				(type default)
			)
			(layer "B.SilkS")
		)
		(fp_line
			(start 0.7874 -0.4064)
			(end -0.7874 -0.4064)
			(stroke
				(width 0.1524)
				(type default)
			)
			(layer "B.SilkS")
		)
		(fp_line
			(start 0.7874 0.4064)
			(end 0.7874 -0.4064)
			(stroke
				(width 0.1524)
				(type default)
			)
			(layer "B.SilkS")
		)
		(fp_poly
			(pts
				(xy 0.508 0.2794) (xy 0.508 0.2286) (xy 0.635 0.2286) (xy 0.635 -0.254) (xy 0.5334 -0.254) (xy 0.5334 -0.2794)
				(xy -0.5334 -0.2794) (xy -0.5334 -0.254) (xy -0.635 -0.254) (xy -0.635 0.254) (xy -0.5334 0.254)
				(xy -0.5334 0.2794)
			)
			(stroke
				(width 0)
				(type default)
			)
			(fill no)
			(layer "B.CrtYd")
		)
		(pad "1" smd rect
			(at -0.40005 0 180)
			(size 0.4572 0.508)
			(layers "B.Cu" "B.Mask" "B.Paste")
			(net "POWER_SW3_PWR_CTR_N")
		)
		(pad "2" smd rect
			(at 0.40005 0 180)
			(size 0.4572 0.508)
			(layers "B.Cu" "B.Mask" "B.Paste")
			(net "P3V3_STB_NODE1")
		)
	)
	(footprint ""
		(layer "B.Cu")
		(at 37.606732 -94.40037 90)
		(property "Reference" "R125"
			(at -4.703318 -4.651502 270)
			(unlocked yes)
			(layer "B.SilkS")
			(effects
				(font
					(size 0.7874 0.5842)
					(thickness 0.1524)
				)
				(justify left mirror)
			)
		)
		(property "Value" ""
			(at 0 0 90)
			(layer "B.Fab")
			(effects
				(font
					(size 1.27 1.27)
				)
				(justify mirror)
			)
		)
		(duplicate_pad_numbers_are_jumpers no)
		(fp_line
			(start 0.7874 -0.4064)
			(end -0.7874 -0.4064)
			(stroke
				(width 0.1524)
				(type default)
			)
			(layer "B.SilkS")
		)
		(fp_line
			(start -0.7874 -0.4064)
			(end -0.7874 0.4064)
			(stroke
				(width 0.1524)
				(type default)
			)
			(layer "B.SilkS")
		)
		(fp_line
			(start 0.7874 0.4064)
			(end 0.7874 -0.4064)
			(stroke
				(width 0.1524)
				(type default)
			)
			(layer "B.SilkS")
		)
		(fp_line
			(start -0.7874 0.4064)
			(end 0.7874 0.4064)
			(stroke
				(width 0.1524)
				(type default)
			)
			(layer "B.SilkS")
		)
		(fp_poly
			(pts
				(xy 0.508 0.2794) (xy 0.508 0.2286) (xy 0.635 0.2286) (xy 0.635 -0.254) (xy 0.5334 -0.254) (xy 0.5334 -0.2794)
				(xy -0.5334 -0.2794) (xy -0.5334 -0.254) (xy -0.635 -0.254) (xy -0.635 0.254) (xy -0.5334 0.254)
				(xy -0.5334 0.2794)
			)
			(stroke
				(width 0)
				(type default)
			)
			(fill no)
			(layer "B.CrtYd")
		)
		(pad "1" smd rect
			(at -0.40005 0 270)
			(size 0.4572 0.508)
			(layers "B.Cu" "B.Mask" "B.Paste")
			(net "SMB_CPU_NODE1_MEM_ICS_CLK_R")
		)
		(pad "2" smd rect
			(at 0.40005 0 270)
			(size 0.4572 0.508)
			(layers "B.Cu" "B.Mask" "B.Paste")
			(net "SMB_MUX_CPU_ICS_NODE1_CLK")
		)
	)
	(footprint ""
		(layer "B.Cu")
		(at 134.756652 -135.87095 90)
		(property "Reference" "C892"
			(at -5.07365 0.33147 270)
			(unlocked yes)
			(layer "B.SilkS")
			(effects
				(font
					(size 0.7874 0.5842)
					(thickness 0.1524)
				)
				(justify left mirror)
			)
		)
		(property "Value" ""
			(at 0 0 90)
			(layer "B.Fab")
			(effects
				(font
					(size 1.27 1.27)
				)
				(justify mirror)
			)
		)
		(duplicate_pad_numbers_are_jumpers no)
		(fp_line
			(start 0.7874 -0.4064)
			(end -0.7874 -0.4064)
			(stroke
				(width 0.1524)
				(type default)
			)
			(layer "B.SilkS")
		)
		(fp_line
			(start -0.7874 -0.4064)
			(end -0.7874 0.4064)
			(stroke
				(width 0.1524)
				(type default)
			)
			(layer "B.SilkS")
		)
		(fp_line
			(start 0 0.381)
			(end 0 -0.381)
			(stroke
				(width 0.1524)
				(type default)
			)
			(layer "B.SilkS")
		)
		(fp_line
			(start 0.7874 0.4064)
			(end 0.7874 -0.4064)
			(stroke
				(width 0.1524)
				(type default)
			)
			(layer "B.SilkS")
		)
		(fp_line
			(start -0.7874 0.4064)
			(end 0.7874 0.4064)
			(stroke
				(width 0.1524)
				(type default)
			)
			(layer "B.SilkS")
		)
		(fp_poly
			(pts
				(xy 0.5334 0.254) (xy 0.635 0.254) (xy 0.635 0.2286) (xy 0.635 -0.254) (xy 0.5334 -0.254) (xy 0.5334 -0.2794)
				(xy -0.5334 -0.2794) (xy -0.5334 -0.254) (xy -0.635 -0.254) (xy -0.635 0.254) (xy -0.5334 0.254)
				(xy -0.5334 0.2794) (xy 0.508 0.2794) (xy 0.5334 0.2794)
			)
			(stroke
				(width 0)
				(type default)
			)
			(fill no)
			(layer "B.CrtYd")
		)
		(pad "1" smd rect
			(at -0.40005 0 270)
			(size 0.4572 0.508)
			(layers "B.Cu" "B.Mask" "B.Paste")
			(net "P1V538_BMC_NODE1")
		)
		(pad "2" smd rect
			(at 0.40005 0 270)
			(size 0.4572 0.508)
			(layers "B.Cu" "B.Mask" "B.Paste")
			(net "GND")
		)
	)
	(footprint ""
		(layer "B.Cu")
		(at 91.47302 -71.200518)
		(property "Reference" "R172"
			(at 4.07797 0.606044 0)
			(unlocked yes)
			(layer "B.SilkS")
			(effects
				(font
					(size 0.7874 0.5842)
					(thickness 0.1524)
				)
				(justify left mirror)
			)
		)
		(property "Value" ""
			(at 0 0 0)
			(layer "B.Fab")
			(effects
				(font
					(size 1.27 1.27)
				)
				(justify mirror)
			)
		)
		(duplicate_pad_numbers_are_jumpers no)
		(fp_line
			(start -0.7874 -0.4064)
			(end -0.7874 0.4064)
			(stroke
				(width 0.1524)
				(type default)
			)
			(layer "B.SilkS")
		)
		(fp_line
			(start -0.7874 0.4064)
			(end 0.7874 0.4064)
			(stroke
				(width 0.1524)
				(type default)
			)
			(layer "B.SilkS")
		)
		(fp_line
			(start 0.7874 -0.4064)
			(end -0.7874 -0.4064)
			(stroke
				(width 0.1524)
				(type default)
			)
			(layer "B.SilkS")
		)
		(fp_line
			(start 0.7874 0.4064)
			(end 0.7874 -0.4064)
			(stroke
				(width 0.1524)
				(type default)
			)
			(layer "B.SilkS")
		)
		(fp_poly
			(pts
				(xy 0.508 0.2794) (xy 0.508 0.2286) (xy 0.635 0.2286) (xy 0.635 -0.254) (xy 0.5334 -0.254) (xy 0.5334 -0.2794)
				(xy -0.5334 -0.2794) (xy -0.5334 -0.254) (xy -0.635 -0.254) (xy -0.635 0.254) (xy -0.5334 0.254)
				(xy -0.5334 0.2794)
			)
			(stroke
				(width 0)
				(type default)
			)
			(fill no)
			(layer "B.CrtYd")
		)
		(pad "1" smd rect
			(at -0.40005 0 180)
			(size 0.4572 0.508)
			(layers "B.Cu" "B.Mask" "B.Paste")
			(net "PD_CPU_NODE1_PUNIT_ST_ADDR1")
		)
		(pad "2" smd rect
			(at 0.40005 0 180)
			(size 0.4572 0.508)
			(layers "B.Cu" "B.Mask" "B.Paste")
			(net "P1V05_SUS_NODE1")
		)
	)
	(footprint ""
		(layer "B.Cu")
		(at 167.000428 -198.83247)
		(property "Reference" "TP11"
			(at 0 0 0)
			(layer "B.SilkS")
			(hide yes)
			(effects
				(font
					(size 1.27 1.27)
				)
				(justify mirror)
			)
		)
		(property "Value" ""
			(at 0 0 0)
			(layer "B.Fab")
			(effects
				(font
					(size 1.27 1.27)
				)
				(justify mirror)
			)
		)
		(duplicate_pad_numbers_are_jumpers no)
		(fp_poly
			(pts
				(arc
					(start 0.381 0)
					(mid -0.381 0)
					(end 0.381 0)
				)
			)
			(stroke
				(width 0)
				(type default)
			)
			(fill no)
			(layer "B.CrtYd")
		)
		(pad "1" smd circle
			(at 0 0 180)
			(size 0.762 0.762)
			(layers "B.Cu" "B.Mask" "B.Paste")
			(net "UART_DSR_RP6_L_N")
		)
	)
	(footprint ""
		(layer "B.Cu")
		(at 116.44376 -177.204624 -90)
		(property "Reference" "U64"
			(at 30.083506 24.9682 0)
			(unlocked yes)
			(layer "B.SilkS")
			(effects
				(font
					(size 0.7874 0.5842)
					(thickness 0.1524)
				)
				(justify left mirror)
			)
		)
		(property "Value" ""
			(at 0 0 90)
			(layer "B.Fab")
			(effects
				(font
					(size 1.27 1.27)
				)
				(justify mirror)
			)
		)
		(duplicate_pad_numbers_are_jumpers no)
		(fp_line
			(start -3.9624 2.0066)
			(end 3.9624 2.0066)
			(stroke
				(width 0.1524)
				(type default)
			)
			(layer "B.SilkS")
		)
		(fp_line
			(start 3.9624 2.0066)
			(end 3.9624 0.5842)
			(stroke
				(width 0.1524)
				(type default)
			)
			(layer "B.SilkS")
		)
		(fp_line
			(start 3.9624 0.5842)
			(end 3.3782 0)
			(stroke
				(width 0.1524)
				(type default)
			)
			(layer "B.SilkS")
		)
		(fp_line
			(start 3.3782 0)
			(end 3.9624 -0.5842)
			(stroke
				(width 0.1524)
				(type default)
			)
			(layer "B.SilkS")
		)
		(fp_line
			(start 3.9624 -0.5842)
			(end 3.9624 -2.0066)
			(stroke
				(width 0.1524)
				(type default)
			)
			(layer "B.SilkS")
		)
		(fp_line
			(start -3.9624 -2.0066)
			(end -3.9624 2.0066)
			(stroke
				(width 0.1524)
				(type default)
			)
			(layer "B.SilkS")
		)
		(fp_line
			(start 3.9624 -2.0066)
			(end -3.9624 -2.0066)
			(stroke
				(width 0.1524)
				(type default)
			)
			(layer "B.SilkS")
		)
		(fp_circle
			(center 3.429 1.524)
			(end 3.429 1.27)
			(stroke
				(width 0.1524)
				(type default)
			)
			(fill no)
			(layer "B.SilkS")
		)
		(fp_poly
			(pts
				(xy 3.962654 3.6703) (xy 3.974846 -3.6703) (xy -3.9624 -3.6703) (xy -3.9624 3.6703)
			)
			(stroke
				(width 0)
				(type default)
			)
			(fill no)
			(layer "B.CrtYd")
		)
		(pad "1" smd rect
			(at 3.57505 2.921 90)
			(size 0.3556 1.4986)
			(layers "B.Cu" "B.Mask" "B.Paste")
			(net "N21699571")
		)
		(pad "2" smd rect
			(at 2.925064 2.921 90)
			(size 0.3556 1.4986)
			(layers "B.Cu" "B.Mask" "B.Paste")
			(net "N21699716")
		)
		(pad "3" smd rect
			(at 2.275078 2.921 90)
			(size 0.3556 1.4986)
			(layers "B.Cu" "B.Mask" "B.Paste")
			(net "N21699716")
		)
		(pad "4" smd rect
			(at 1.625092 2.921 90)
			(size 0.3556 1.4986)
			(layers "B.Cu" "B.Mask" "B.Paste")
			(net "T5_NODE1_EN")
		)
		(pad "5" smd rect
			(at 0.975106 2.921 90)
			(size 0.3556 1.4986)
			(layers "B.Cu" "B.Mask" "B.Paste")
			(net "T5_NODE2_EN")
		)
		(pad "6" smd rect
			(at 0.32512 2.921 90)
			(size 0.3556 1.4986)
			(layers "B.Cu" "B.Mask" "B.Paste")
			(net "T5_NODE3_EN")
		)
		(pad "7" smd rect
			(at -0.32512 2.921 90)
			(size 0.3556 1.4986)
			(layers "B.Cu" "B.Mask" "B.Paste")
			(net "T5_NODE4_EN")
		)
		(pad "8" smd rect
			(at -0.975106 2.921 90)
			(size 0.3556 1.4986)
			(layers "B.Cu" "B.Mask" "B.Paste")
			(net "T6_NODE1_EN")
		)
		(pad "9" smd rect
			(at -1.625092 2.921 90)
			(size 0.3556 1.4986)
			(layers "B.Cu" "B.Mask" "B.Paste")
			(net "T6_NODE2_EN")
		)
		(pad "10" smd rect
			(at -2.275078 2.921 90)
			(size 0.3556 1.4986)
			(layers "B.Cu" "B.Mask" "B.Paste")
			(net "T6_NODE3_EN")
		)
		(pad "11" smd rect
			(at -2.925064 2.921 90)
			(size 0.3556 1.4986)
			(layers "B.Cu" "B.Mask" "B.Paste")
			(net "T6_NODE4_EN")
		)
		(pad "12" smd rect
			(at -3.57505 2.921 90)
			(size 0.3556 1.4986)
			(layers "B.Cu" "B.Mask" "B.Paste")
			(net "GND")
		)
		(pad "13" smd rect
			(at -3.57505 -2.921 90)
			(size 0.3556 1.4986)
			(layers "B.Cu" "B.Mask" "B.Paste")
			(net "T7_NODE1_EN")
		)
		(pad "14" smd rect
			(at -2.925064 -2.921 90)
			(size 0.3556 1.4986)
			(layers "B.Cu" "B.Mask" "B.Paste")
			(net "T7_NODE2_EN")
		)
		(pad "15" smd rect
			(at -2.275078 -2.921 90)
			(size 0.3556 1.4986)
			(layers "B.Cu" "B.Mask" "B.Paste")
			(net "T7_NODE3_EN")
		)
		(pad "16" smd rect
			(at -1.625092 -2.921 90)
			(size 0.3556 1.4986)
			(layers "B.Cu" "B.Mask" "B.Paste")
			(net "T7_NODE4_EN")
		)
		(pad "17" smd rect
			(at -0.975106 -2.921 90)
			(size 0.3556 1.4986)
			(layers "B.Cu" "B.Mask" "B.Paste")
			(net "T8_NODE1_EN")
		)
		(pad "18" smd rect
			(at -0.32512 -2.921 90)
			(size 0.3556 1.4986)
			(layers "B.Cu" "B.Mask" "B.Paste")
			(net "T8_NODE2_EN")
		)
		(pad "19" smd rect
			(at 0.32512 -2.921 90)
			(size 0.3556 1.4986)
			(layers "B.Cu" "B.Mask" "B.Paste")
			(net "T8_NODE3_EN")
		)
		(pad "20" smd rect
			(at 0.975106 -2.921 90)
			(size 0.3556 1.4986)
			(layers "B.Cu" "B.Mask" "B.Paste")
			(net "T8_NODE4_EN")
		)
		(pad "21" smd rect
			(at 1.625092 -2.921 90)
			(size 0.3556 1.4986)
			(layers "B.Cu" "B.Mask" "B.Paste")
			(net "N21699372")
		)
		(pad "22" smd rect
			(at 2.275078 -2.921 90)
			(size 0.3556 1.4986)
			(layers "B.Cu" "B.Mask" "B.Paste")
			(net "I2C_COM3_SCL")
		)
		(pad "23" smd rect
			(at 2.925064 -2.921 90)
			(size 0.3556 1.4986)
			(layers "B.Cu" "B.Mask" "B.Paste")
			(net "I2C_COM3_SDA")
		)
		(pad "24" smd rect
			(at 3.57505 -2.921 90)
			(size 0.3556 1.4986)
			(layers "B.Cu" "B.Mask" "B.Paste")
			(net "P3V3_NODE1")
		)
	)
	(footprint ""
		(layer "B.Cu")
		(at 77.396086 -126.454662)
		(property "Reference" "C284"
			(at 3.903472 0.129032 0)
			(unlocked yes)
			(layer "B.SilkS")
			(effects
				(font
					(size 0.7874 0.5842)
					(thickness 0.1524)
				)
				(justify left mirror)
			)
		)
		(property "Value" ""
			(at 0 0 0)
			(layer "B.Fab")
			(effects
				(font
					(size 1.27 1.27)
				)
				(justify mirror)
			)
		)
		(duplicate_pad_numbers_are_jumpers no)
		(fp_line
			(start -0.7874 -0.4064)
			(end -0.7874 0.4064)
			(stroke
				(width 0.1524)
				(type default)
			)
			(layer "B.SilkS")
		)
		(fp_line
			(start -0.7874 0.4064)
			(end 0.7874 0.4064)
			(stroke
				(width 0.1524)
				(type default)
			)
			(layer "B.SilkS")
		)
		(fp_line
			(start 0 0.381)
			(end 0 -0.381)
			(stroke
				(width 0.1524)
				(type default)
			)
			(layer "B.SilkS")
		)
		(fp_line
			(start 0.7874 -0.4064)
			(end -0.7874 -0.4064)
			(stroke
				(width 0.1524)
				(type default)
			)
			(layer "B.SilkS")
		)
		(fp_line
			(start 0.7874 0.4064)
			(end 0.7874 -0.4064)
			(stroke
				(width 0.1524)
				(type default)
			)
			(layer "B.SilkS")
		)
		(fp_poly
			(pts
				(xy 0.5334 0.254) (xy 0.635 0.254) (xy 0.635 0.2286) (xy 0.635 -0.254) (xy 0.5334 -0.254) (xy 0.5334 -0.2794)
				(xy -0.5334 -0.2794) (xy -0.5334 -0.254) (xy -0.635 -0.254) (xy -0.635 0.254) (xy -0.5334 0.254)
				(xy -0.5334 0.2794) (xy 0.508 0.2794) (xy 0.5334 0.2794)
			)
			(stroke
				(width 0)
				(type default)
			)
			(fill no)
			(layer "B.CrtYd")
		)
		(pad "1" smd rect
			(at -0.40005 0 180)
			(size 0.4572 0.508)
			(layers "B.Cu" "B.Mask" "B.Paste")
			(net "BMC_NODE1_VCC_1V8_PCIEA")
		)
		(pad "2" smd rect
			(at 0.40005 0 180)
			(size 0.4572 0.508)
			(layers "B.Cu" "B.Mask" "B.Paste")
			(net "GND")
		)
	)
	(footprint ""
		(layer "B.Cu")
		(at 167.658288 -152.901904)
		(property "Reference" "C450"
			(at 4.65582 0.340614 0)
			(unlocked yes)
			(layer "B.SilkS")
			(effects
				(font
					(size 0.7874 0.5842)
					(thickness 0.1524)
				)
				(justify left mirror)
			)
		)
		(property "Value" ""
			(at 0 0 0)
			(layer "B.Fab")
			(effects
				(font
					(size 1.27 1.27)
				)
				(justify mirror)
			)
		)
		(duplicate_pad_numbers_are_jumpers no)
		(fp_line
			(start -0.7874 -0.4064)
			(end -0.7874 0.4064)
			(stroke
				(width 0.1524)
				(type default)
			)
			(layer "B.SilkS")
		)
		(fp_line
			(start -0.7874 0.4064)
			(end 0.7874 0.4064)
			(stroke
				(width 0.1524)
				(type default)
			)
			(layer "B.SilkS")
		)
		(fp_line
			(start 0 0.381)
			(end 0 -0.381)
			(stroke
				(width 0.1524)
				(type default)
			)
			(layer "B.SilkS")
		)
		(fp_line
			(start 0.7874 -0.4064)
			(end -0.7874 -0.4064)
			(stroke
				(width 0.1524)
				(type default)
			)
			(layer "B.SilkS")
		)
		(fp_line
			(start 0.7874 0.4064)
			(end 0.7874 -0.4064)
			(stroke
				(width 0.1524)
				(type default)
			)
			(layer "B.SilkS")
		)
		(fp_poly
			(pts
				(xy 0.5334 0.254) (xy 0.635 0.254) (xy 0.635 0.2286) (xy 0.635 -0.254) (xy 0.5334 -0.254) (xy 0.5334 -0.2794)
				(xy -0.5334 -0.2794) (xy -0.5334 -0.254) (xy -0.635 -0.254) (xy -0.635 0.254) (xy -0.5334 0.254)
				(xy -0.5334 0.2794) (xy 0.508 0.2794) (xy 0.5334 0.2794)
			)
			(stroke
				(width 0)
				(type default)
			)
			(fill no)
			(layer "B.CrtYd")
		)
		(pad "1" smd rect
			(at -0.40005 0 180)
			(size 0.4572 0.508)
			(layers "B.Cu" "B.Mask" "B.Paste")
			(net "P1V9_LAN2")
		)
		(pad "2" smd rect
			(at 0.40005 0 180)
			(size 0.4572 0.508)
			(layers "B.Cu" "B.Mask" "B.Paste")
			(net "GND")
		)
	)
	(footprint ""
		(layer "B.Cu")
		(at 110.44936 -178.601624 180)
		(property "Reference" "R714"
			(at 21.356828 -32.269176 0)
			(unlocked yes)
			(layer "B.SilkS")
			(effects
				(font
					(size 0.7874 0.5842)
					(thickness 0.1524)
				)
				(justify left mirror)
			)
		)
		(property "Value" ""
			(at 0 0 0)
			(layer "B.Fab")
			(effects
				(font
					(size 1.27 1.27)
				)
				(justify mirror)
			)
		)
		(duplicate_pad_numbers_are_jumpers no)
		(fp_line
			(start 0.7874 0.4064)
			(end 0.7874 -0.4064)
			(stroke
				(width 0.1524)
				(type default)
			)
			(layer "B.SilkS")
		)
		(fp_line
			(start 0.7874 -0.4064)
			(end -0.7874 -0.4064)
			(stroke
				(width 0.1524)
				(type default)
			)
			(layer "B.SilkS")
		)
		(fp_line
			(start -0.7874 0.4064)
			(end 0.7874 0.4064)
			(stroke
				(width 0.1524)
				(type default)
			)
			(layer "B.SilkS")
		)
		(fp_line
			(start -0.7874 -0.4064)
			(end -0.7874 0.4064)
			(stroke
				(width 0.1524)
				(type default)
			)
			(layer "B.SilkS")
		)
		(fp_poly
			(pts
				(xy 0.508 0.2794) (xy 0.508 0.2286) (xy 0.635 0.2286) (xy 0.635 -0.254) (xy 0.5334 -0.254) (xy 0.5334 -0.2794)
				(xy -0.5334 -0.2794) (xy -0.5334 -0.254) (xy -0.635 -0.254) (xy -0.635 0.254) (xy -0.5334 0.254)
				(xy -0.5334 0.2794)
			)
			(stroke
				(width 0)
				(type default)
			)
			(fill no)
			(layer "B.CrtYd")
		)
		(pad "1" smd rect
			(at -0.40005 0)
			(size 0.4572 0.508)
			(layers "B.Cu" "B.Mask" "B.Paste")
			(net "T6_NODE1_EN")
		)
		(pad "2" smd rect
			(at 0.40005 0)
			(size 0.4572 0.508)
			(layers "B.Cu" "B.Mask" "B.Paste")
			(net "P5V_NODE1")
		)
	)
	(footprint ""
		(layer "B.Cu")
		(at 137.65276 -187.872624 -90)
		(property "Reference" "C630"
			(at -4.565396 1.448308 270)
			(unlocked yes)
			(layer "B.SilkS")
			(effects
				(font
					(size 0.7874 0.5842)
					(thickness 0.1524)
				)
				(justify left mirror)
			)
		)
		(property "Value" ""
			(at 0 0 90)
			(layer "B.Fab")
			(effects
				(font
					(size 1.27 1.27)
				)
				(justify mirror)
			)
		)
		(duplicate_pad_numbers_are_jumpers no)
		(fp_line
			(start -0.7874 0.4064)
			(end 0.7874 0.4064)
			(stroke
				(width 0.1524)
				(type default)
			)
			(layer "B.SilkS")
		)
		(fp_line
			(start 0.7874 0.4064)
			(end 0.7874 -0.4064)
			(stroke
				(width 0.1524)
				(type default)
			)
			(layer "B.SilkS")
		)
		(fp_line
			(start 0 0.381)
			(end 0 -0.381)
			(stroke
				(width 0.1524)
				(type default)
			)
			(layer "B.SilkS")
		)
		(fp_line
			(start -0.7874 -0.4064)
			(end -0.7874 0.4064)
			(stroke
				(width 0.1524)
				(type default)
			)
			(layer "B.SilkS")
		)
		(fp_line
			(start 0.7874 -0.4064)
			(end -0.7874 -0.4064)
			(stroke
				(width 0.1524)
				(type default)
			)
			(layer "B.SilkS")
		)
		(fp_poly
			(pts
				(xy 0.5334 0.254) (xy 0.635 0.254) (xy 0.635 0.2286) (xy 0.635 -0.254) (xy 0.5334 -0.254) (xy 0.5334 -0.2794)
				(xy -0.5334 -0.2794) (xy -0.5334 -0.254) (xy -0.635 -0.254) (xy -0.635 0.254) (xy -0.5334 0.254)
				(xy -0.5334 0.2794) (xy 0.508 0.2794) (xy 0.5334 0.2794)
			)
			(stroke
				(width 0)
				(type default)
			)
			(fill no)
			(layer "B.CrtYd")
		)
		(pad "1" smd rect
			(at -0.40005 0 90)
			(size 0.4572 0.508)
			(layers "B.Cu" "B.Mask" "B.Paste")
			(net "T9_NODE3_EN_R")
		)
		(pad "2" smd rect
			(at 0.40005 0 90)
			(size 0.4572 0.508)
			(layers "B.Cu" "B.Mask" "B.Paste")
			(net "GND")
		)
	)
	(footprint ""
		(layer "B.Cu")
		(at 121.412 -52.959 90)
		(property "Reference" "R1288"
			(at 1.778 -0.15367 270)
			(unlocked yes)
			(layer "B.SilkS")
			(effects
				(font
					(size 0.7874 0.5842)
					(thickness 0.1524)
				)
				(justify left mirror)
			)
		)
		(property "Value" ""
			(at 0 0 90)
			(layer "B.Fab")
			(effects
				(font
					(size 1.27 1.27)
				)
				(justify mirror)
			)
		)
		(duplicate_pad_numbers_are_jumpers no)
		(fp_line
			(start 0.7874 -0.4064)
			(end -0.7874 -0.4064)
			(stroke
				(width 0.1524)
				(type default)
			)
			(layer "B.SilkS")
		)
		(fp_line
			(start -0.7874 -0.4064)
			(end -0.7874 0.4064)
			(stroke
				(width 0.1524)
				(type default)
			)
			(layer "B.SilkS")
		)
		(fp_line
			(start 0.7874 0.4064)
			(end 0.7874 -0.4064)
			(stroke
				(width 0.1524)
				(type default)
			)
			(layer "B.SilkS")
		)
		(fp_line
			(start -0.7874 0.4064)
			(end 0.7874 0.4064)
			(stroke
				(width 0.1524)
				(type default)
			)
			(layer "B.SilkS")
		)
		(fp_poly
			(pts
				(xy 0.508 0.2794) (xy 0.508 0.2286) (xy 0.635 0.2286) (xy 0.635 -0.254) (xy 0.5334 -0.254) (xy 0.5334 -0.2794)
				(xy -0.5334 -0.2794) (xy -0.5334 -0.254) (xy -0.635 -0.254) (xy -0.635 0.254) (xy -0.5334 0.254)
				(xy -0.5334 0.2794)
			)
			(stroke
				(width 0)
				(type default)
			)
			(fill no)
			(layer "B.CrtYd")
		)
		(pad "1" smd rect
			(at -0.40005 0 270)
			(size 0.4572 0.508)
			(layers "B.Cu" "B.Mask" "B.Paste")
			(net "SIO_JTAG_CPLD1_TMS_R")
		)
		(pad "2" smd rect
			(at 0.40005 0 270)
			(size 0.4572 0.508)
			(layers "B.Cu" "B.Mask" "B.Paste")
			(net "P3V3_NODE1")
		)
	)
	(footprint ""
		(layer "B.Cu")
		(at 52.437538 -72.292718)
		(property "Reference" "C126"
			(at -13.565378 31.431738 0)
			(unlocked yes)
			(layer "B.SilkS")
			(effects
				(font
					(size 0.7874 0.5842)
					(thickness 0.1524)
				)
				(justify left mirror)
			)
		)
		(property "Value" ""
			(at 0 0 0)
			(layer "B.Fab")
			(effects
				(font
					(size 1.27 1.27)
				)
				(justify mirror)
			)
		)
		(duplicate_pad_numbers_are_jumpers no)
		(fp_line
			(start -0.7874 -0.4064)
			(end -0.7874 0.4064)
			(stroke
				(width 0.1524)
				(type default)
			)
			(layer "B.SilkS")
		)
		(fp_line
			(start -0.7874 0.4064)
			(end 0.7874 0.4064)
			(stroke
				(width 0.1524)
				(type default)
			)
			(layer "B.SilkS")
		)
		(fp_line
			(start 0 0.381)
			(end 0 -0.381)
			(stroke
				(width 0.1524)
				(type default)
			)
			(layer "B.SilkS")
		)
		(fp_line
			(start 0.7874 -0.4064)
			(end -0.7874 -0.4064)
			(stroke
				(width 0.1524)
				(type default)
			)
			(layer "B.SilkS")
		)
		(fp_line
			(start 0.7874 0.4064)
			(end 0.7874 -0.4064)
			(stroke
				(width 0.1524)
				(type default)
			)
			(layer "B.SilkS")
		)
		(fp_poly
			(pts
				(xy 0.5334 0.254) (xy 0.635 0.254) (xy 0.635 0.2286) (xy 0.635 -0.254) (xy 0.5334 -0.254) (xy 0.5334 -0.2794)
				(xy -0.5334 -0.2794) (xy -0.5334 -0.254) (xy -0.635 -0.254) (xy -0.635 0.254) (xy -0.5334 0.254)
				(xy -0.5334 0.2794) (xy 0.508 0.2794) (xy 0.5334 0.2794)
			)
			(stroke
				(width 0)
				(type default)
			)
			(fill no)
			(layer "B.CrtYd")
		)
		(pad "1" smd rect
			(at -0.40005 0 180)
			(size 0.4572 0.508)
			(layers "B.Cu" "B.Mask" "B.Paste")
			(net "P1V05_NODE1")
		)
		(pad "2" smd rect
			(at 0.40005 0 180)
			(size 0.4572 0.508)
			(layers "B.Cu" "B.Mask" "B.Paste")
			(net "GND")
		)
	)
	(footprint ""
		(layer "B.Cu")
		(at 151.62276 -187.872624 -90)
		(property "Reference" "C657"
			(at -4.565396 3.38201 270)
			(unlocked yes)
			(layer "B.SilkS")
			(effects
				(font
					(size 0.7874 0.5842)
					(thickness 0.1524)
				)
				(justify left mirror)
			)
		)
		(property "Value" ""
			(at 0 0 90)
			(layer "B.Fab")
			(effects
				(font
					(size 1.27 1.27)
				)
				(justify mirror)
			)
		)
		(duplicate_pad_numbers_are_jumpers no)
		(fp_line
			(start -0.7874 0.4064)
			(end 0.7874 0.4064)
			(stroke
				(width 0.1524)
				(type default)
			)
			(layer "B.SilkS")
		)
		(fp_line
			(start 0.7874 0.4064)
			(end 0.7874 -0.4064)
			(stroke
				(width 0.1524)
				(type default)
			)
			(layer "B.SilkS")
		)
		(fp_line
			(start 0 0.381)
			(end 0 -0.381)
			(stroke
				(width 0.1524)
				(type default)
			)
			(layer "B.SilkS")
		)
		(fp_line
			(start -0.7874 -0.4064)
			(end -0.7874 0.4064)
			(stroke
				(width 0.1524)
				(type default)
			)
			(layer "B.SilkS")
		)
		(fp_line
			(start 0.7874 -0.4064)
			(end -0.7874 -0.4064)
			(stroke
				(width 0.1524)
				(type default)
			)
			(layer "B.SilkS")
		)
		(fp_poly
			(pts
				(xy 0.5334 0.254) (xy 0.635 0.254) (xy 0.635 0.2286) (xy 0.635 -0.254) (xy 0.5334 -0.254) (xy 0.5334 -0.2794)
				(xy -0.5334 -0.2794) (xy -0.5334 -0.254) (xy -0.635 -0.254) (xy -0.635 0.254) (xy -0.5334 0.254)
				(xy -0.5334 0.2794) (xy 0.508 0.2794) (xy 0.5334 0.2794)
			)
			(stroke
				(width 0)
				(type default)
			)
			(fill no)
			(layer "B.CrtYd")
		)
		(pad "1" smd rect
			(at -0.40005 0 90)
			(size 0.4572 0.508)
			(layers "B.Cu" "B.Mask" "B.Paste")
			(net "T11_NODE4_EN_R")
		)
		(pad "2" smd rect
			(at 0.40005 0 90)
			(size 0.4572 0.508)
			(layers "B.Cu" "B.Mask" "B.Paste")
			(net "GND")
		)
	)
	(footprint ""
		(layer "B.Cu")
		(at 146.79676 -184.951624 -90)
		(property "Reference" "C726"
			(at -4.357624 1.69799 270)
			(unlocked yes)
			(layer "B.SilkS")
			(effects
				(font
					(size 0.7874 0.5842)
					(thickness 0.1524)
				)
				(justify left mirror)
			)
		)
		(property "Value" ""
			(at 0 0 90)
			(layer "B.Fab")
			(effects
				(font
					(size 1.27 1.27)
				)
				(justify mirror)
			)
		)
		(duplicate_pad_numbers_are_jumpers no)
		(fp_line
			(start -0.7874 0.4064)
			(end 0.7874 0.4064)
			(stroke
				(width 0.1524)
				(type default)
			)
			(layer "B.SilkS")
		)
		(fp_line
			(start 0.7874 0.4064)
			(end 0.7874 -0.4064)
			(stroke
				(width 0.1524)
				(type default)
			)
			(layer "B.SilkS")
		)
		(fp_line
			(start 0 0.381)
			(end 0 -0.381)
			(stroke
				(width 0.1524)
				(type default)
			)
			(layer "B.SilkS")
		)
		(fp_line
			(start -0.7874 -0.4064)
			(end -0.7874 0.4064)
			(stroke
				(width 0.1524)
				(type default)
			)
			(layer "B.SilkS")
		)
		(fp_line
			(start 0.7874 -0.4064)
			(end -0.7874 -0.4064)
			(stroke
				(width 0.1524)
				(type default)
			)
			(layer "B.SilkS")
		)
		(fp_poly
			(pts
				(xy 0.5334 0.254) (xy 0.635 0.254) (xy 0.635 0.2286) (xy 0.635 -0.254) (xy 0.5334 -0.254) (xy 0.5334 -0.2794)
				(xy -0.5334 -0.2794) (xy -0.5334 -0.254) (xy -0.635 -0.254) (xy -0.635 0.254) (xy -0.5334 0.254)
				(xy -0.5334 0.2794) (xy 0.508 0.2794) (xy 0.5334 0.2794)
			)
			(stroke
				(width 0)
				(type default)
			)
			(fill no)
			(layer "B.CrtYd")
		)
		(pad "1" smd rect
			(at -0.40005 0 90)
			(size 0.4572 0.508)
			(layers "B.Cu" "B.Mask" "B.Paste")
			(net "UART_T11_NODE2_RXD")
		)
		(pad "2" smd rect
			(at 0.40005 0 90)
			(size 0.4572 0.508)
			(layers "B.Cu" "B.Mask" "B.Paste")
			(net "GND")
		)
	)
	(footprint ""
		(layer "B.Cu")
		(at 115.42776 -185.205624 -90)
		(property "Reference" "C718"
			(at -3.957828 -0.461518 270)
			(unlocked yes)
			(layer "B.SilkS")
			(effects
				(font
					(size 0.7874 0.5842)
					(thickness 0.1524)
				)
				(justify left mirror)
			)
		)
		(property "Value" ""
			(at 0 0 90)
			(layer "B.Fab")
			(effects
				(font
					(size 1.27 1.27)
				)
				(justify mirror)
			)
		)
		(duplicate_pad_numbers_are_jumpers no)
		(fp_line
			(start -0.7874 0.4064)
			(end 0.7874 0.4064)
			(stroke
				(width 0.1524)
				(type default)
			)
			(layer "B.SilkS")
		)
		(fp_line
			(start 0.7874 0.4064)
			(end 0.7874 -0.4064)
			(stroke
				(width 0.1524)
				(type default)
			)
			(layer "B.SilkS")
		)
		(fp_line
			(start 0 0.381)
			(end 0 -0.381)
			(stroke
				(width 0.1524)
				(type default)
			)
			(layer "B.SilkS")
		)
		(fp_line
			(start -0.7874 -0.4064)
			(end -0.7874 0.4064)
			(stroke
				(width 0.1524)
				(type default)
			)
			(layer "B.SilkS")
		)
		(fp_line
			(start 0.7874 -0.4064)
			(end -0.7874 -0.4064)
			(stroke
				(width 0.1524)
				(type default)
			)
			(layer "B.SilkS")
		)
		(fp_poly
			(pts
				(xy 0.5334 0.254) (xy 0.635 0.254) (xy 0.635 0.2286) (xy 0.635 -0.254) (xy 0.5334 -0.254) (xy 0.5334 -0.2794)
				(xy -0.5334 -0.2794) (xy -0.5334 -0.254) (xy -0.635 -0.254) (xy -0.635 0.254) (xy -0.5334 0.254)
				(xy -0.5334 0.2794) (xy 0.508 0.2794) (xy 0.5334 0.2794)
			)
			(stroke
				(width 0)
				(type default)
			)
			(fill no)
			(layer "B.CrtYd")
		)
		(pad "1" smd rect
			(at -0.40005 0 90)
			(size 0.4572 0.508)
			(layers "B.Cu" "B.Mask" "B.Paste")
			(net "UART_T7_NODE1_RXD")
		)
		(pad "2" smd rect
			(at 0.40005 0 90)
			(size 0.4572 0.508)
			(layers "B.Cu" "B.Mask" "B.Paste")
			(net "GND")
		)
	)
	(footprint ""
		(layer "B.Cu")
		(at 62.137036 -67.215258 90)
		(property "Reference" "R1040"
			(at -35.93592 -14.487906 270)
			(unlocked yes)
			(layer "B.SilkS")
			(effects
				(font
					(size 0.7874 0.5842)
					(thickness 0.1524)
				)
				(justify left mirror)
			)
		)
		(property "Value" ""
			(at 0 0 90)
			(layer "B.Fab")
			(effects
				(font
					(size 1.27 1.27)
				)
				(justify mirror)
			)
		)
		(duplicate_pad_numbers_are_jumpers no)
		(fp_line
			(start 0.7874 -0.4064)
			(end -0.7874 -0.4064)
			(stroke
				(width 0.1524)
				(type default)
			)
			(layer "B.SilkS")
		)
		(fp_line
			(start -0.7874 -0.4064)
			(end -0.7874 0.4064)
			(stroke
				(width 0.1524)
				(type default)
			)
			(layer "B.SilkS")
		)
		(fp_line
			(start 0.7874 0.4064)
			(end 0.7874 -0.4064)
			(stroke
				(width 0.1524)
				(type default)
			)
			(layer "B.SilkS")
		)
		(fp_line
			(start -0.7874 0.4064)
			(end 0.7874 0.4064)
			(stroke
				(width 0.1524)
				(type default)
			)
			(layer "B.SilkS")
		)
		(fp_poly
			(pts
				(xy 0.508 0.2794) (xy 0.508 0.2286) (xy 0.635 0.2286) (xy 0.635 -0.254) (xy 0.5334 -0.254) (xy 0.5334 -0.2794)
				(xy -0.5334 -0.2794) (xy -0.5334 -0.254) (xy -0.635 -0.254) (xy -0.635 0.254) (xy -0.5334 0.254)
				(xy -0.5334 0.2794)
			)
			(stroke
				(width 0)
				(type default)
			)
			(fill no)
			(layer "B.CrtYd")
		)
		(pad "1" smd rect
			(at -0.40005 0 270)
			(size 0.4572 0.508)
			(layers "B.Cu" "B.Mask" "B.Paste")
			(net "PWRGD_NODE1_DDR3_DRAM_POK")
		)
		(pad "2" smd rect
			(at 0.40005 0 270)
			(size 0.4572 0.508)
			(layers "B.Cu" "B.Mask" "B.Paste")
			(net "PV_VDDR_NODE1")
		)
	)
	(footprint ""
		(layer "B.Cu")
		(at 104.408224 -66.164206 180)
		(property "Reference" "R219"
			(at 4.686046 -0.798322 0)
			(unlocked yes)
			(layer "B.SilkS")
			(effects
				(font
					(size 0.7874 0.5842)
					(thickness 0.1524)
				)
				(justify left mirror)
			)
		)
		(property "Value" ""
			(at 0 0 0)
			(layer "B.Fab")
			(effects
				(font
					(size 1.27 1.27)
				)
				(justify mirror)
			)
		)
		(duplicate_pad_numbers_are_jumpers no)
		(fp_line
			(start 0.7874 0.4064)
			(end 0.7874 -0.4064)
			(stroke
				(width 0.1524)
				(type default)
			)
			(layer "B.SilkS")
		)
		(fp_line
			(start 0.7874 -0.4064)
			(end -0.7874 -0.4064)
			(stroke
				(width 0.1524)
				(type default)
			)
			(layer "B.SilkS")
		)
		(fp_line
			(start -0.7874 0.4064)
			(end 0.7874 0.4064)
			(stroke
				(width 0.1524)
				(type default)
			)
			(layer "B.SilkS")
		)
		(fp_line
			(start -0.7874 -0.4064)
			(end -0.7874 0.4064)
			(stroke
				(width 0.1524)
				(type default)
			)
			(layer "B.SilkS")
		)
		(fp_poly
			(pts
				(xy 0.508 0.2794) (xy 0.508 0.2286) (xy 0.635 0.2286) (xy 0.635 -0.254) (xy 0.5334 -0.254) (xy 0.5334 -0.2794)
				(xy -0.5334 -0.2794) (xy -0.5334 -0.254) (xy -0.635 -0.254) (xy -0.635 0.254) (xy -0.5334 0.254)
				(xy -0.5334 0.2794)
			)
			(stroke
				(width 0)
				(type default)
			)
			(fill no)
			(layer "B.CrtYd")
		)
		(pad "1" smd rect
			(at -0.40005 0)
			(size 0.4572 0.508)
			(layers "B.Cu" "B.Mask" "B.Paste")
			(net "XDP_CPU_NODE1_PWROK_R")
		)
		(pad "2" smd rect
			(at 0.40005 0)
			(size 0.4572 0.508)
			(layers "B.Cu" "B.Mask" "B.Paste")
			(net "XDP_CPU_NODE1_PWROK")
		)
	)
	(footprint ""
		(layer "B.Cu")
		(at 110.44936 -181.649624 180)
		(property "Reference" "R717"
			(at 21.356828 -32.269176 0)
			(unlocked yes)
			(layer "B.SilkS")
			(effects
				(font
					(size 0.7874 0.5842)
					(thickness 0.1524)
				)
				(justify left mirror)
			)
		)
		(property "Value" ""
			(at 0 0 0)
			(layer "B.Fab")
			(effects
				(font
					(size 1.27 1.27)
				)
				(justify mirror)
			)
		)
		(duplicate_pad_numbers_are_jumpers no)
		(fp_line
			(start 0.7874 0.4064)
			(end 0.7874 -0.4064)
			(stroke
				(width 0.1524)
				(type default)
			)
			(layer "B.SilkS")
		)
		(fp_line
			(start 0.7874 -0.4064)
			(end -0.7874 -0.4064)
			(stroke
				(width 0.1524)
				(type default)
			)
			(layer "B.SilkS")
		)
		(fp_line
			(start -0.7874 0.4064)
			(end 0.7874 0.4064)
			(stroke
				(width 0.1524)
				(type default)
			)
			(layer "B.SilkS")
		)
		(fp_line
			(start -0.7874 -0.4064)
			(end -0.7874 0.4064)
			(stroke
				(width 0.1524)
				(type default)
			)
			(layer "B.SilkS")
		)
		(fp_poly
			(pts
				(xy 0.508 0.2794) (xy 0.508 0.2286) (xy 0.635 0.2286) (xy 0.635 -0.254) (xy 0.5334 -0.254) (xy 0.5334 -0.2794)
				(xy -0.5334 -0.2794) (xy -0.5334 -0.254) (xy -0.635 -0.254) (xy -0.635 0.254) (xy -0.5334 0.254)
				(xy -0.5334 0.2794)
			)
			(stroke
				(width 0)
				(type default)
			)
			(fill no)
			(layer "B.CrtYd")
		)
		(pad "1" smd rect
			(at -0.40005 0)
			(size 0.4572 0.508)
			(layers "B.Cu" "B.Mask" "B.Paste")
			(net "T6_NODE4_EN")
		)
		(pad "2" smd rect
			(at 0.40005 0)
			(size 0.4572 0.508)
			(layers "B.Cu" "B.Mask" "B.Paste")
			(net "P5V_NODE1")
		)
	)
	(footprint ""
		(layer "B.Cu")
		(at 156.828998 -149.76983)
		(property "Reference" "C442"
			(at 1.026414 3.42265 0)
			(unlocked yes)
			(layer "B.SilkS")
			(effects
				(font
					(size 0.7874 0.5842)
					(thickness 0.1524)
				)
				(justify left mirror)
			)
		)
		(property "Value" ""
			(at 0 0 0)
			(layer "B.Fab")
			(effects
				(font
					(size 1.27 1.27)
				)
				(justify mirror)
			)
		)
		(duplicate_pad_numbers_are_jumpers no)
		(fp_line
			(start -0.7874 -0.4064)
			(end -0.7874 0.4064)
			(stroke
				(width 0.1524)
				(type default)
			)
			(layer "B.SilkS")
		)
		(fp_line
			(start -0.7874 0.4064)
			(end 0.7874 0.4064)
			(stroke
				(width 0.1524)
				(type default)
			)
			(layer "B.SilkS")
		)
		(fp_line
			(start 0 0.381)
			(end 0 -0.381)
			(stroke
				(width 0.1524)
				(type default)
			)
			(layer "B.SilkS")
		)
		(fp_line
			(start 0.7874 -0.4064)
			(end -0.7874 -0.4064)
			(stroke
				(width 0.1524)
				(type default)
			)
			(layer "B.SilkS")
		)
		(fp_line
			(start 0.7874 0.4064)
			(end 0.7874 -0.4064)
			(stroke
				(width 0.1524)
				(type default)
			)
			(layer "B.SilkS")
		)
		(fp_poly
			(pts
				(xy 0.5334 0.254) (xy 0.635 0.254) (xy 0.635 0.2286) (xy 0.635 -0.254) (xy 0.5334 -0.254) (xy 0.5334 -0.2794)
				(xy -0.5334 -0.2794) (xy -0.5334 -0.254) (xy -0.635 -0.254) (xy -0.635 0.254) (xy -0.5334 0.254)
				(xy -0.5334 0.2794) (xy 0.508 0.2794) (xy 0.5334 0.2794)
			)
			(stroke
				(width 0)
				(type default)
			)
			(fill no)
			(layer "B.CrtYd")
		)
		(pad "1" smd rect
			(at -0.40005 0 180)
			(size 0.4572 0.508)
			(layers "B.Cu" "B.Mask" "B.Paste")
			(net "P3V3_NODE1")
		)
		(pad "2" smd rect
			(at 0.40005 0 180)
			(size 0.4572 0.508)
			(layers "B.Cu" "B.Mask" "B.Paste")
			(net "GND")
		)
	)
	(footprint ""
		(layer "B.Cu")
		(at 55.81015 -74.444352 180)
		(property "Reference" "C121"
			(at 13.409168 -31.563056 0)
			(unlocked yes)
			(layer "B.SilkS")
			(effects
				(font
					(size 0.7874 0.5842)
					(thickness 0.1524)
				)
				(justify left mirror)
			)
		)
		(property "Value" ""
			(at 0 0 0)
			(layer "B.Fab")
			(effects
				(font
					(size 1.27 1.27)
				)
				(justify mirror)
			)
		)
		(duplicate_pad_numbers_are_jumpers no)
		(fp_line
			(start 0.7874 0.4064)
			(end 0.7874 -0.4064)
			(stroke
				(width 0.1524)
				(type default)
			)
			(layer "B.SilkS")
		)
		(fp_line
			(start 0.7874 -0.4064)
			(end -0.7874 -0.4064)
			(stroke
				(width 0.1524)
				(type default)
			)
			(layer "B.SilkS")
		)
		(fp_line
			(start 0 0.381)
			(end 0 -0.381)
			(stroke
				(width 0.1524)
				(type default)
			)
			(layer "B.SilkS")
		)
		(fp_line
			(start -0.7874 0.4064)
			(end 0.7874 0.4064)
			(stroke
				(width 0.1524)
				(type default)
			)
			(layer "B.SilkS")
		)
		(fp_line
			(start -0.7874 -0.4064)
			(end -0.7874 0.4064)
			(stroke
				(width 0.1524)
				(type default)
			)
			(layer "B.SilkS")
		)
		(fp_poly
			(pts
				(xy 0.5334 0.254) (xy 0.635 0.254) (xy 0.635 0.2286) (xy 0.635 -0.254) (xy 0.5334 -0.254) (xy 0.5334 -0.2794)
				(xy -0.5334 -0.2794) (xy -0.5334 -0.254) (xy -0.635 -0.254) (xy -0.635 0.254) (xy -0.5334 0.254)
				(xy -0.5334 0.2794) (xy 0.508 0.2794) (xy 0.5334 0.2794)
			)
			(stroke
				(width 0)
				(type default)
			)
			(fill no)
			(layer "B.CrtYd")
		)
		(pad "1" smd rect
			(at -0.40005 0)
			(size 0.4572 0.508)
			(layers "B.Cu" "B.Mask" "B.Paste")
			(net "P1V05_NODE1")
		)
		(pad "2" smd rect
			(at 0.40005 0)
			(size 0.4572 0.508)
			(layers "B.Cu" "B.Mask" "B.Paste")
			(net "GND")
		)
	)
	(footprint ""
		(layer "B.Cu")
		(at 66.194686 -121.044462 90)
		(property "Reference" "R325"
			(at -7.37235 9.910826 270)
			(unlocked yes)
			(layer "B.SilkS")
			(effects
				(font
					(size 0.7874 0.5842)
					(thickness 0.1524)
				)
				(justify left mirror)
			)
		)
		(property "Value" ""
			(at 0 0 90)
			(layer "B.Fab")
			(effects
				(font
					(size 1.27 1.27)
				)
				(justify mirror)
			)
		)
		(duplicate_pad_numbers_are_jumpers no)
		(fp_line
			(start 0.7874 -0.4064)
			(end -0.7874 -0.4064)
			(stroke
				(width 0.1524)
				(type default)
			)
			(layer "B.SilkS")
		)
		(fp_line
			(start -0.7874 -0.4064)
			(end -0.7874 0.4064)
			(stroke
				(width 0.1524)
				(type default)
			)
			(layer "B.SilkS")
		)
		(fp_line
			(start 0.7874 0.4064)
			(end 0.7874 -0.4064)
			(stroke
				(width 0.1524)
				(type default)
			)
			(layer "B.SilkS")
		)
		(fp_line
			(start -0.7874 0.4064)
			(end 0.7874 0.4064)
			(stroke
				(width 0.1524)
				(type default)
			)
			(layer "B.SilkS")
		)
		(fp_poly
			(pts
				(xy 0.508 0.2794) (xy 0.508 0.2286) (xy 0.635 0.2286) (xy 0.635 -0.254) (xy 0.5334 -0.254) (xy 0.5334 -0.2794)
				(xy -0.5334 -0.2794) (xy -0.5334 -0.254) (xy -0.635 -0.254) (xy -0.635 0.254) (xy -0.5334 0.254)
				(xy -0.5334 0.2794)
			)
			(stroke
				(width 0)
				(type default)
			)
			(fill no)
			(layer "B.CrtYd")
		)
		(pad "1" smd rect
			(at -0.40005 0 270)
			(size 0.4572 0.508)
			(layers "B.Cu" "B.Mask" "B.Paste")
			(net "P3V3_NODE1")
		)
		(pad "2" smd rect
			(at 0.40005 0 270)
			(size 0.4572 0.508)
			(layers "B.Cu" "B.Mask" "B.Paste")
			(net "BMC_ROMA9")
		)
	)
	(footprint ""
		(layer "B.Cu")
		(at 46.281086 -132.093462 180)
		(property "Reference" "C223"
			(at -4.582414 -0.37211 0)
			(unlocked yes)
			(layer "B.SilkS")
			(effects
				(font
					(size 0.7874 0.5842)
					(thickness 0.1524)
				)
				(justify left mirror)
			)
		)
		(property "Value" ""
			(at 0 0 0)
			(layer "B.Fab")
			(effects
				(font
					(size 1.27 1.27)
				)
				(justify mirror)
			)
		)
		(duplicate_pad_numbers_are_jumpers no)
		(fp_line
			(start 0.7874 0.4064)
			(end 0.7874 -0.4064)
			(stroke
				(width 0.1524)
				(type default)
			)
			(layer "B.SilkS")
		)
		(fp_line
			(start 0.7874 -0.4064)
			(end -0.7874 -0.4064)
			(stroke
				(width 0.1524)
				(type default)
			)
			(layer "B.SilkS")
		)
		(fp_line
			(start 0 0.381)
			(end 0 -0.381)
			(stroke
				(width 0.1524)
				(type default)
			)
			(layer "B.SilkS")
		)
		(fp_line
			(start -0.7874 0.4064)
			(end 0.7874 0.4064)
			(stroke
				(width 0.1524)
				(type default)
			)
			(layer "B.SilkS")
		)
		(fp_line
			(start -0.7874 -0.4064)
			(end -0.7874 0.4064)
			(stroke
				(width 0.1524)
				(type default)
			)
			(layer "B.SilkS")
		)
		(fp_poly
			(pts
				(xy 0.5334 0.254) (xy 0.635 0.254) (xy 0.635 0.2286) (xy 0.635 -0.254) (xy 0.5334 -0.254) (xy 0.5334 -0.2794)
				(xy -0.5334 -0.2794) (xy -0.5334 -0.254) (xy -0.635 -0.254) (xy -0.635 0.254) (xy -0.5334 0.254)
				(xy -0.5334 0.2794) (xy 0.508 0.2794) (xy 0.5334 0.2794)
			)
			(stroke
				(width 0)
				(type default)
			)
			(fill no)
			(layer "B.CrtYd")
		)
		(pad "1" smd rect
			(at -0.40005 0)
			(size 0.4572 0.508)
			(layers "B.Cu" "B.Mask" "B.Paste")
			(net "GND")
		)
		(pad "2" smd rect
			(at 0.40005 0)
			(size 0.4572 0.508)
			(layers "B.Cu" "B.Mask" "B.Paste")
			(net "P0V75_BMC_VTTREF_NODE1")
		)
	)
	(footprint ""
		(layer "B.Cu")
		(at 58.879486 -146.419062 90)
		(property "Reference" "R290"
			(at 1.521206 -1.398778 270)
			(unlocked yes)
			(layer "B.SilkS")
			(effects
				(font
					(size 0.7874 0.5842)
					(thickness 0.1524)
				)
				(justify left mirror)
			)
		)
		(property "Value" ""
			(at 0 0 90)
			(layer "B.Fab")
			(effects
				(font
					(size 1.27 1.27)
				)
				(justify mirror)
			)
		)
		(duplicate_pad_numbers_are_jumpers no)
		(fp_line
			(start 0.7874 -0.4064)
			(end -0.7874 -0.4064)
			(stroke
				(width 0.1524)
				(type default)
			)
			(layer "B.SilkS")
		)
		(fp_line
			(start -0.7874 -0.4064)
			(end -0.7874 0.4064)
			(stroke
				(width 0.1524)
				(type default)
			)
			(layer "B.SilkS")
		)
		(fp_line
			(start 0.7874 0.4064)
			(end 0.7874 -0.4064)
			(stroke
				(width 0.1524)
				(type default)
			)
			(layer "B.SilkS")
		)
		(fp_line
			(start -0.7874 0.4064)
			(end 0.7874 0.4064)
			(stroke
				(width 0.1524)
				(type default)
			)
			(layer "B.SilkS")
		)
		(fp_poly
			(pts
				(xy 0.508 0.2794) (xy 0.508 0.2286) (xy 0.635 0.2286) (xy 0.635 -0.254) (xy 0.5334 -0.254) (xy 0.5334 -0.2794)
				(xy -0.5334 -0.2794) (xy -0.5334 -0.254) (xy -0.635 -0.254) (xy -0.635 0.254) (xy -0.5334 0.254)
				(xy -0.5334 0.2794)
			)
			(stroke
				(width 0)
				(type default)
			)
			(fill no)
			(layer "B.CrtYd")
		)
		(pad "1" smd rect
			(at -0.40005 0 270)
			(size 0.4572 0.508)
			(layers "B.Cu" "B.Mask" "B.Paste")
			(net "BMC_NODE1_GFX_BLUE")
		)
		(pad "2" smd rect
			(at 0.40005 0 270)
			(size 0.4572 0.508)
			(layers "B.Cu" "B.Mask" "B.Paste")
			(net "GND")
		)
	)
	(footprint ""
		(layer "B.Cu")
		(at 56.171338 -81.182718 180)
		(property "Reference" "C57"
			(at 13.617956 -30.014672 0)
			(unlocked yes)
			(layer "B.SilkS")
			(effects
				(font
					(size 0.7874 0.5842)
					(thickness 0.1524)
				)
				(justify left mirror)
			)
		)
		(property "Value" ""
			(at 0 0 0)
			(layer "B.Fab")
			(effects
				(font
					(size 1.27 1.27)
				)
				(justify mirror)
			)
		)
		(duplicate_pad_numbers_are_jumpers no)
		(fp_line
			(start 0.7874 0.4064)
			(end 0.7874 -0.4064)
			(stroke
				(width 0.1524)
				(type default)
			)
			(layer "B.SilkS")
		)
		(fp_line
			(start 0.7874 -0.4064)
			(end -0.7874 -0.4064)
			(stroke
				(width 0.1524)
				(type default)
			)
			(layer "B.SilkS")
		)
		(fp_line
			(start 0 0.381)
			(end 0 -0.381)
			(stroke
				(width 0.1524)
				(type default)
			)
			(layer "B.SilkS")
		)
		(fp_line
			(start -0.7874 0.4064)
			(end 0.7874 0.4064)
			(stroke
				(width 0.1524)
				(type default)
			)
			(layer "B.SilkS")
		)
		(fp_line
			(start -0.7874 -0.4064)
			(end -0.7874 0.4064)
			(stroke
				(width 0.1524)
				(type default)
			)
			(layer "B.SilkS")
		)
		(fp_poly
			(pts
				(xy 0.5334 0.254) (xy 0.635 0.254) (xy 0.635 0.2286) (xy 0.635 -0.254) (xy 0.5334 -0.254) (xy 0.5334 -0.2794)
				(xy -0.5334 -0.2794) (xy -0.5334 -0.254) (xy -0.635 -0.254) (xy -0.635 0.254) (xy -0.5334 0.254)
				(xy -0.5334 0.2794) (xy 0.508 0.2794) (xy 0.5334 0.2794)
			)
			(stroke
				(width 0)
				(type default)
			)
			(fill no)
			(layer "B.CrtYd")
		)
		(pad "1" smd rect
			(at -0.40005 0)
			(size 0.4572 0.508)
			(layers "B.Cu" "B.Mask" "B.Paste")
			(net "P1V05_NODE1")
		)
		(pad "2" smd rect
			(at 0.40005 0)
			(size 0.4572 0.508)
			(layers "B.Cu" "B.Mask" "B.Paste")
			(net "GND")
		)
	)
	(footprint ""
		(layer "B.Cu")
		(at 88.43518 -84.118704)
		(property "Reference" "C34"
			(at 0.271272 -1.659382 0)
			(unlocked yes)
			(layer "B.SilkS")
			(effects
				(font
					(size 0.7874 0.5842)
					(thickness 0.1524)
				)
				(justify left mirror)
			)
		)
		(property "Value" ""
			(at 0 0 0)
			(layer "B.Fab")
			(effects
				(font
					(size 1.27 1.27)
				)
				(justify mirror)
			)
		)
		(duplicate_pad_numbers_are_jumpers no)
		(fp_line
			(start -1.905 -0.8636)
			(end -1.905 0.8636)
			(stroke
				(width 0.1524)
				(type default)
			)
			(layer "B.SilkS")
		)
		(fp_line
			(start -1.905 0.8636)
			(end 1.905 0.8636)
			(stroke
				(width 0.1524)
				(type default)
			)
			(layer "B.SilkS")
		)
		(fp_line
			(start 0 0.8382)
			(end 0 -0.8382)
			(stroke
				(width 0.1524)
				(type default)
			)
			(layer "B.SilkS")
		)
		(fp_line
			(start 1.905 -0.8636)
			(end -1.905 -0.8636)
			(stroke
				(width 0.1524)
				(type default)
			)
			(layer "B.SilkS")
		)
		(fp_line
			(start 1.905 0.8636)
			(end 1.905 -0.8636)
			(stroke
				(width 0.1524)
				(type default)
			)
			(layer "B.SilkS")
		)
		(fp_rect
			(start 1.524 0.7366)
			(end -1.524 -0.7366)
			(stroke
				(width 0)
				(type default)
			)
			(fill no)
			(layer "B.CrtYd")
		)
		(pad "1" smd rect
			(at -0.94996 0 180)
			(size 1.1176 1.3716)
			(layers "B.Cu" "B.Mask" "B.Paste")
			(net "P3V3_RTC_NODE1")
		)
		(pad "2" smd rect
			(at 0.94996 0 180)
			(size 1.1176 1.3716)
			(layers "B.Cu" "B.Mask" "B.Paste")
			(net "GND")
		)
	)
	(footprint ""
		(layer "B.Cu")
		(at 141.099032 -163.498022 90)
		(property "Reference" "R995"
			(at -4.650486 -0.070866 270)
			(unlocked yes)
			(layer "B.SilkS")
			(effects
				(font
					(size 0.7874 0.5842)
					(thickness 0.1524)
				)
				(justify left mirror)
			)
		)
		(property "Value" ""
			(at 0 0 90)
			(layer "B.Fab")
			(effects
				(font
					(size 1.27 1.27)
				)
				(justify mirror)
			)
		)
		(duplicate_pad_numbers_are_jumpers no)
		(fp_line
			(start 0.7874 -0.4064)
			(end -0.7874 -0.4064)
			(stroke
				(width 0.1524)
				(type default)
			)
			(layer "B.SilkS")
		)
		(fp_line
			(start -0.7874 -0.4064)
			(end -0.7874 0.4064)
			(stroke
				(width 0.1524)
				(type default)
			)
			(layer "B.SilkS")
		)
		(fp_line
			(start 0.7874 0.4064)
			(end 0.7874 -0.4064)
			(stroke
				(width 0.1524)
				(type default)
			)
			(layer "B.SilkS")
		)
		(fp_line
			(start -0.7874 0.4064)
			(end 0.7874 0.4064)
			(stroke
				(width 0.1524)
				(type default)
			)
			(layer "B.SilkS")
		)
		(fp_poly
			(pts
				(xy 0.508 0.2794) (xy 0.508 0.2286) (xy 0.635 0.2286) (xy 0.635 -0.254) (xy 0.5334 -0.254) (xy 0.5334 -0.2794)
				(xy -0.5334 -0.2794) (xy -0.5334 -0.254) (xy -0.635 -0.254) (xy -0.635 0.254) (xy -0.5334 0.254)
				(xy -0.5334 0.2794)
			)
			(stroke
				(width 0)
				(type default)
			)
			(fill no)
			(layer "B.CrtYd")
		)
		(pad "1" smd rect
			(at -0.40005 0 270)
			(size 0.4572 0.508)
			(layers "B.Cu" "B.Mask" "B.Paste")
			(net "UART_T10_NODE3_TXD")
		)
		(pad "2" smd rect
			(at 0.40005 0 270)
			(size 0.4572 0.508)
			(layers "B.Cu" "B.Mask" "B.Paste")
			(net "UART_T10_NODE3_TXD_R")
		)
	)
	(footprint ""
		(layer "B.Cu")
		(at 70.97776 -188.126624 90)
		(property "Reference" "R920"
			(at 4.318254 -0.346202 270)
			(unlocked yes)
			(layer "B.SilkS")
			(effects
				(font
					(size 0.7874 0.5842)
					(thickness 0.1524)
				)
				(justify left mirror)
			)
		)
		(property "Value" ""
			(at 0 0 90)
			(layer "B.Fab")
			(effects
				(font
					(size 1.27 1.27)
				)
				(justify mirror)
			)
		)
		(duplicate_pad_numbers_are_jumpers no)
		(fp_line
			(start 0.7874 -0.4064)
			(end -0.7874 -0.4064)
			(stroke
				(width 0.1524)
				(type default)
			)
			(layer "B.SilkS")
		)
		(fp_line
			(start -0.7874 -0.4064)
			(end -0.7874 0.4064)
			(stroke
				(width 0.1524)
				(type default)
			)
			(layer "B.SilkS")
		)
		(fp_line
			(start 0.7874 0.4064)
			(end 0.7874 -0.4064)
			(stroke
				(width 0.1524)
				(type default)
			)
			(layer "B.SilkS")
		)
		(fp_line
			(start -0.7874 0.4064)
			(end 0.7874 0.4064)
			(stroke
				(width 0.1524)
				(type default)
			)
			(layer "B.SilkS")
		)
		(fp_poly
			(pts
				(xy 0.508 0.2794) (xy 0.508 0.2286) (xy 0.635 0.2286) (xy 0.635 -0.254) (xy 0.5334 -0.254) (xy 0.5334 -0.2794)
				(xy -0.5334 -0.2794) (xy -0.5334 -0.254) (xy -0.635 -0.254) (xy -0.635 0.254) (xy -0.5334 0.254)
				(xy -0.5334 0.2794)
			)
			(stroke
				(width 0)
				(type default)
			)
			(fill no)
			(layer "B.CrtYd")
		)
		(pad "1" smd rect
			(at -0.40005 0 270)
			(size 0.4572 0.508)
			(layers "B.Cu" "B.Mask" "B.Paste")
			(net "UART_T3_NODE3_RXD")
		)
		(pad "2" smd rect
			(at 0.40005 0 270)
			(size 0.4572 0.508)
			(layers "B.Cu" "B.Mask" "B.Paste")
			(net "UART_T3_NODE3_RXD_R")
		)
	)
	(footprint ""
		(layer "B.Cu")
		(at 123.70816 -177.458624)
		(property "Reference" "R724"
			(at -28.598876 31.521146 0)
			(unlocked yes)
			(layer "B.SilkS")
			(effects
				(font
					(size 0.7874 0.5842)
					(thickness 0.1524)
				)
				(justify left mirror)
			)
		)
		(property "Value" ""
			(at 0 0 0)
			(layer "B.Fab")
			(effects
				(font
					(size 1.27 1.27)
				)
				(justify mirror)
			)
		)
		(duplicate_pad_numbers_are_jumpers no)
		(fp_line
			(start -0.7874 -0.4064)
			(end -0.7874 0.4064)
			(stroke
				(width 0.1524)
				(type default)
			)
			(layer "B.SilkS")
		)
		(fp_line
			(start -0.7874 0.4064)
			(end 0.7874 0.4064)
			(stroke
				(width 0.1524)
				(type default)
			)
			(layer "B.SilkS")
		)
		(fp_line
			(start 0.7874 -0.4064)
			(end -0.7874 -0.4064)
			(stroke
				(width 0.1524)
				(type default)
			)
			(layer "B.SilkS")
		)
		(fp_line
			(start 0.7874 0.4064)
			(end 0.7874 -0.4064)
			(stroke
				(width 0.1524)
				(type default)
			)
			(layer "B.SilkS")
		)
		(fp_poly
			(pts
				(xy 0.508 0.2794) (xy 0.508 0.2286) (xy 0.635 0.2286) (xy 0.635 -0.254) (xy 0.5334 -0.254) (xy 0.5334 -0.2794)
				(xy -0.5334 -0.2794) (xy -0.5334 -0.254) (xy -0.635 -0.254) (xy -0.635 0.254) (xy -0.5334 0.254)
				(xy -0.5334 0.2794)
			)
			(stroke
				(width 0)
				(type default)
			)
			(fill no)
			(layer "B.CrtYd")
		)
		(pad "1" smd rect
			(at -0.40005 0 180)
			(size 0.4572 0.508)
			(layers "B.Cu" "B.Mask" "B.Paste")
			(net "T8_NODE1_EN")
		)
		(pad "2" smd rect
			(at 0.40005 0 180)
			(size 0.4572 0.508)
			(layers "B.Cu" "B.Mask" "B.Paste")
			(net "P5V_NODE1")
		)
	)
	(footprint ""
		(layer "B.Cu")
		(at 66.53276 -188.126624 -90)
		(property "Reference" "C622"
			(at -4.318254 0.375666 270)
			(unlocked yes)
			(layer "B.SilkS")
			(effects
				(font
					(size 0.7874 0.5842)
					(thickness 0.1524)
				)
				(justify left mirror)
			)
		)
		(property "Value" ""
			(at 0 0 90)
			(layer "B.Fab")
			(effects
				(font
					(size 1.27 1.27)
				)
				(justify mirror)
			)
		)
		(duplicate_pad_numbers_are_jumpers no)
		(fp_line
			(start -0.7874 0.4064)
			(end 0.7874 0.4064)
			(stroke
				(width 0.1524)
				(type default)
			)
			(layer "B.SilkS")
		)
		(fp_line
			(start 0.7874 0.4064)
			(end 0.7874 -0.4064)
			(stroke
				(width 0.1524)
				(type default)
			)
			(layer "B.SilkS")
		)
		(fp_line
			(start 0 0.381)
			(end 0 -0.381)
			(stroke
				(width 0.1524)
				(type default)
			)
			(layer "B.SilkS")
		)
		(fp_line
			(start -0.7874 -0.4064)
			(end -0.7874 0.4064)
			(stroke
				(width 0.1524)
				(type default)
			)
			(layer "B.SilkS")
		)
		(fp_line
			(start 0.7874 -0.4064)
			(end -0.7874 -0.4064)
			(stroke
				(width 0.1524)
				(type default)
			)
			(layer "B.SilkS")
		)
		(fp_poly
			(pts
				(xy 0.5334 0.254) (xy 0.635 0.254) (xy 0.635 0.2286) (xy 0.635 -0.254) (xy 0.5334 -0.254) (xy 0.5334 -0.2794)
				(xy -0.5334 -0.2794) (xy -0.5334 -0.254) (xy -0.635 -0.254) (xy -0.635 0.254) (xy -0.5334 0.254)
				(xy -0.5334 0.2794) (xy 0.508 0.2794) (xy 0.5334 0.2794)
			)
			(stroke
				(width 0)
				(type default)
			)
			(fill no)
			(layer "B.CrtYd")
		)
		(pad "1" smd rect
			(at -0.40005 0 90)
			(size 0.4572 0.508)
			(layers "B.Cu" "B.Mask" "B.Paste")
			(net "T1_NODE1_EN_R")
		)
		(pad "2" smd rect
			(at 0.40005 0 90)
			(size 0.4572 0.508)
			(layers "B.Cu" "B.Mask" "B.Paste")
			(net "GND")
		)
	)
	(footprint ""
		(layer "B.Cu")
		(at 114.15776 -188.126624 90)
		(property "Reference" "R961"
			(at 4.080256 0.757682 270)
			(unlocked yes)
			(layer "B.SilkS")
			(effects
				(font
					(size 0.7874 0.5842)
					(thickness 0.1524)
				)
				(justify left mirror)
			)
		)
		(property "Value" ""
			(at 0 0 90)
			(layer "B.Fab")
			(effects
				(font
					(size 1.27 1.27)
				)
				(justify mirror)
			)
		)
		(duplicate_pad_numbers_are_jumpers no)
		(fp_line
			(start 0.7874 -0.4064)
			(end -0.7874 -0.4064)
			(stroke
				(width 0.1524)
				(type default)
			)
			(layer "B.SilkS")
		)
		(fp_line
			(start -0.7874 -0.4064)
			(end -0.7874 0.4064)
			(stroke
				(width 0.1524)
				(type default)
			)
			(layer "B.SilkS")
		)
		(fp_line
			(start 0.7874 0.4064)
			(end 0.7874 -0.4064)
			(stroke
				(width 0.1524)
				(type default)
			)
			(layer "B.SilkS")
		)
		(fp_line
			(start -0.7874 0.4064)
			(end 0.7874 0.4064)
			(stroke
				(width 0.1524)
				(type default)
			)
			(layer "B.SilkS")
		)
		(fp_poly
			(pts
				(xy 0.508 0.2794) (xy 0.508 0.2286) (xy 0.635 0.2286) (xy 0.635 -0.254) (xy 0.5334 -0.254) (xy 0.5334 -0.2794)
				(xy -0.5334 -0.2794) (xy -0.5334 -0.254) (xy -0.635 -0.254) (xy -0.635 0.254) (xy -0.5334 0.254)
				(xy -0.5334 0.2794)
			)
			(stroke
				(width 0)
				(type default)
			)
			(fill no)
			(layer "B.CrtYd")
		)
		(pad "1" smd rect
			(at -0.40005 0 270)
			(size 0.4572 0.508)
			(layers "B.Cu" "B.Mask" "B.Paste")
			(net "UART_T7_NODE2_RXD")
		)
		(pad "2" smd rect
			(at 0.40005 0 270)
			(size 0.4572 0.508)
			(layers "B.Cu" "B.Mask" "B.Paste")
			(net "UART_T7_NODE2_RXD_R")
		)
	)
	(footprint ""
		(layer "B.Cu")
		(at 142.07236 -169.965624)
		(property "Reference" "R743"
			(at -1.237234 0.53086 0)
			(unlocked yes)
			(layer "B.SilkS")
			(effects
				(font
					(size 0.7874 0.5842)
					(thickness 0.1524)
				)
				(justify left mirror)
			)
		)
		(property "Value" ""
			(at 0 0 0)
			(layer "B.Fab")
			(effects
				(font
					(size 1.27 1.27)
				)
				(justify mirror)
			)
		)
		(duplicate_pad_numbers_are_jumpers no)
		(fp_line
			(start -0.7874 -0.4064)
			(end -0.7874 0.4064)
			(stroke
				(width 0.1524)
				(type default)
			)
			(layer "B.SilkS")
		)
		(fp_line
			(start -0.7874 0.4064)
			(end 0.7874 0.4064)
			(stroke
				(width 0.1524)
				(type default)
			)
			(layer "B.SilkS")
		)
		(fp_line
			(start 0.7874 -0.4064)
			(end -0.7874 -0.4064)
			(stroke
				(width 0.1524)
				(type default)
			)
			(layer "B.SilkS")
		)
		(fp_line
			(start 0.7874 0.4064)
			(end 0.7874 -0.4064)
			(stroke
				(width 0.1524)
				(type default)
			)
			(layer "B.SilkS")
		)
		(fp_poly
			(pts
				(xy 0.508 0.2794) (xy 0.508 0.2286) (xy 0.635 0.2286) (xy 0.635 -0.254) (xy 0.5334 -0.254) (xy 0.5334 -0.2794)
				(xy -0.5334 -0.2794) (xy -0.5334 -0.254) (xy -0.635 -0.254) (xy -0.635 0.254) (xy -0.5334 0.254)
				(xy -0.5334 0.2794)
			)
			(stroke
				(width 0)
				(type default)
			)
			(fill no)
			(layer "B.CrtYd")
		)
		(pad "1" smd rect
			(at -0.40005 0 180)
			(size 0.4572 0.508)
			(layers "B.Cu" "B.Mask" "B.Paste")
			(net "P3V3_NODE1")
		)
		(pad "2" smd rect
			(at 0.40005 0 180)
			(size 0.4572 0.508)
			(layers "B.Cu" "B.Mask" "B.Paste")
			(net "N21698757")
		)
	)
	(footprint ""
		(layer "B.Cu")
		(at 61.884306 -61.525912)
		(property "Reference" "R35"
			(at -0.221234 2.098802 0)
			(unlocked yes)
			(layer "B.SilkS")
			(effects
				(font
					(size 0.7874 0.5842)
					(thickness 0.1524)
				)
				(justify left mirror)
			)
		)
		(property "Value" ""
			(at 0 0 0)
			(layer "B.Fab")
			(effects
				(font
					(size 1.27 1.27)
				)
				(justify mirror)
			)
		)
		(duplicate_pad_numbers_are_jumpers no)
		(fp_line
			(start -0.7874 -0.4064)
			(end -0.7874 0.4064)
			(stroke
				(width 0.1524)
				(type default)
			)
			(layer "B.SilkS")
		)
		(fp_line
			(start -0.7874 0.4064)
			(end 0.7874 0.4064)
			(stroke
				(width 0.1524)
				(type default)
			)
			(layer "B.SilkS")
		)
		(fp_line
			(start 0.7874 -0.4064)
			(end -0.7874 -0.4064)
			(stroke
				(width 0.1524)
				(type default)
			)
			(layer "B.SilkS")
		)
		(fp_line
			(start 0.7874 0.4064)
			(end 0.7874 -0.4064)
			(stroke
				(width 0.1524)
				(type default)
			)
			(layer "B.SilkS")
		)
		(fp_poly
			(pts
				(xy 0.508 0.2794) (xy 0.508 0.2286) (xy 0.635 0.2286) (xy 0.635 -0.254) (xy 0.5334 -0.254) (xy 0.5334 -0.2794)
				(xy -0.5334 -0.2794) (xy -0.5334 -0.254) (xy -0.635 -0.254) (xy -0.635 0.254) (xy -0.5334 0.254)
				(xy -0.5334 0.2794)
			)
			(stroke
				(width 0)
				(type default)
			)
			(fill no)
			(layer "B.CrtYd")
		)
		(pad "1" smd rect
			(at -0.40005 0 180)
			(size 0.4572 0.508)
			(layers "B.Cu" "B.Mask" "B.Paste")
			(net "M_DDR3_NODE1_MON2P")
		)
		(pad "2" smd rect
			(at 0.40005 0 180)
			(size 0.4572 0.508)
			(layers "B.Cu" "B.Mask" "B.Paste")
			(net "M_DDR3_NODE1_MON2N")
		)
	)
	(footprint ""
		(layer "B.Cu")
		(at 55.044086 -123.152662 90)
		(property "Reference" "C295"
			(at -55.125874 -42.18559 270)
			(unlocked yes)
			(layer "B.SilkS")
			(effects
				(font
					(size 0.7874 0.5842)
					(thickness 0.1524)
				)
				(justify left mirror)
			)
		)
		(property "Value" ""
			(at 0 0 90)
			(layer "B.Fab")
			(effects
				(font
					(size 1.27 1.27)
				)
				(justify mirror)
			)
		)
		(duplicate_pad_numbers_are_jumpers no)
		(fp_line
			(start 0.7874 -0.4064)
			(end -0.7874 -0.4064)
			(stroke
				(width 0.1524)
				(type default)
			)
			(layer "B.SilkS")
		)
		(fp_line
			(start -0.7874 -0.4064)
			(end -0.7874 0.4064)
			(stroke
				(width 0.1524)
				(type default)
			)
			(layer "B.SilkS")
		)
		(fp_line
			(start 0 0.381)
			(end 0 -0.381)
			(stroke
				(width 0.1524)
				(type default)
			)
			(layer "B.SilkS")
		)
		(fp_line
			(start 0.7874 0.4064)
			(end 0.7874 -0.4064)
			(stroke
				(width 0.1524)
				(type default)
			)
			(layer "B.SilkS")
		)
		(fp_line
			(start -0.7874 0.4064)
			(end 0.7874 0.4064)
			(stroke
				(width 0.1524)
				(type default)
			)
			(layer "B.SilkS")
		)
		(fp_poly
			(pts
				(xy 0.5334 0.254) (xy 0.635 0.254) (xy 0.635 0.2286) (xy 0.635 -0.254) (xy 0.5334 -0.254) (xy 0.5334 -0.2794)
				(xy -0.5334 -0.2794) (xy -0.5334 -0.254) (xy -0.635 -0.254) (xy -0.635 0.254) (xy -0.5334 0.254)
				(xy -0.5334 0.2794) (xy 0.508 0.2794) (xy 0.5334 0.2794)
			)
			(stroke
				(width 0)
				(type default)
			)
			(fill no)
			(layer "B.CrtYd")
		)
		(pad "1" smd rect
			(at -0.40005 0 270)
			(size 0.4572 0.508)
			(layers "B.Cu" "B.Mask" "B.Paste")
			(net "BMC_NODE1_V1PLLAV12")
		)
		(pad "2" smd rect
			(at 0.40005 0 270)
			(size 0.4572 0.508)
			(layers "B.Cu" "B.Mask" "B.Paste")
			(net "GND")
		)
	)
	(footprint ""
		(layer "B.Cu")
		(at 56.24576 -185.205624 90)
		(property "Reference" "R928"
			(at 4.15163 0.203962 270)
			(unlocked yes)
			(layer "B.SilkS")
			(effects
				(font
					(size 0.7874 0.5842)
					(thickness 0.1524)
				)
				(justify left mirror)
			)
		)
		(property "Value" ""
			(at 0 0 90)
			(layer "B.Fab")
			(effects
				(font
					(size 1.27 1.27)
				)
				(justify mirror)
			)
		)
		(duplicate_pad_numbers_are_jumpers no)
		(fp_line
			(start 0.7874 -0.4064)
			(end -0.7874 -0.4064)
			(stroke
				(width 0.1524)
				(type default)
			)
			(layer "B.SilkS")
		)
		(fp_line
			(start -0.7874 -0.4064)
			(end -0.7874 0.4064)
			(stroke
				(width 0.1524)
				(type default)
			)
			(layer "B.SilkS")
		)
		(fp_line
			(start 0.7874 0.4064)
			(end 0.7874 -0.4064)
			(stroke
				(width 0.1524)
				(type default)
			)
			(layer "B.SilkS")
		)
		(fp_line
			(start -0.7874 0.4064)
			(end 0.7874 0.4064)
			(stroke
				(width 0.1524)
				(type default)
			)
			(layer "B.SilkS")
		)
		(fp_poly
			(pts
				(xy 0.508 0.2794) (xy 0.508 0.2286) (xy 0.635 0.2286) (xy 0.635 -0.254) (xy 0.5334 -0.254) (xy 0.5334 -0.2794)
				(xy -0.5334 -0.2794) (xy -0.5334 -0.254) (xy -0.635 -0.254) (xy -0.635 0.254) (xy -0.5334 0.254)
				(xy -0.5334 0.2794)
			)
			(stroke
				(width 0)
				(type default)
			)
			(fill no)
			(layer "B.CrtYd")
		)
		(pad "1" smd rect
			(at -0.40005 0 270)
			(size 0.4572 0.508)
			(layers "B.Cu" "B.Mask" "B.Paste")
			(net "UART_T1_NODE4_TXD")
		)
		(pad "2" smd rect
			(at 0.40005 0 270)
			(size 0.4572 0.508)
			(layers "B.Cu" "B.Mask" "B.Paste")
			(net "UART_T1_NODE4_TXD_R")
		)
	)
	(footprint ""
		(layer "B.Cu")
		(at 90.81262 -165.894512)
		(property "Reference" "R786"
			(at 24.774144 20.136104 0)
			(unlocked yes)
			(layer "B.SilkS")
			(effects
				(font
					(size 0.7874 0.5842)
					(thickness 0.1524)
				)
				(justify left mirror)
			)
		)
		(property "Value" ""
			(at 0 0 0)
			(layer "B.Fab")
			(effects
				(font
					(size 1.27 1.27)
				)
				(justify mirror)
			)
		)
		(duplicate_pad_numbers_are_jumpers no)
		(fp_line
			(start -0.7874 -0.4064)
			(end -0.7874 0.4064)
			(stroke
				(width 0.1524)
				(type default)
			)
			(layer "B.SilkS")
		)
		(fp_line
			(start -0.7874 0.4064)
			(end 0.7874 0.4064)
			(stroke
				(width 0.1524)
				(type default)
			)
			(layer "B.SilkS")
		)
		(fp_line
			(start 0.7874 -0.4064)
			(end -0.7874 -0.4064)
			(stroke
				(width 0.1524)
				(type default)
			)
			(layer "B.SilkS")
		)
		(fp_line
			(start 0.7874 0.4064)
			(end 0.7874 -0.4064)
			(stroke
				(width 0.1524)
				(type default)
			)
			(layer "B.SilkS")
		)
		(fp_poly
			(pts
				(xy 0.508 0.2794) (xy 0.508 0.2286) (xy 0.635 0.2286) (xy 0.635 -0.254) (xy 0.5334 -0.254) (xy 0.5334 -0.2794)
				(xy -0.5334 -0.2794) (xy -0.5334 -0.254) (xy -0.635 -0.254) (xy -0.635 0.254) (xy -0.5334 0.254)
				(xy -0.5334 0.2794)
			)
			(stroke
				(width 0)
				(type default)
			)
			(fill no)
			(layer "B.CrtYd")
		)
		(pad "1" smd rect
			(at -0.40005 0 180)
			(size 0.4572 0.508)
			(layers "B.Cu" "B.Mask" "B.Paste")
			(net "UART_SW_S2_N")
		)
		(pad "2" smd rect
			(at 0.40005 0 180)
			(size 0.4572 0.508)
			(layers "B.Cu" "B.Mask" "B.Paste")
			(net "P3V3_NODE1")
		)
	)
	(footprint ""
		(layer "B.Cu")
		(at 132.4356 -46.9646 90)
		(property "Reference" "R1324"
			(at 3.048 11.42873 270)
			(unlocked yes)
			(layer "B.SilkS")
			(effects
				(font
					(size 0.7874 0.5842)
					(thickness 0.1524)
				)
				(justify left mirror)
			)
		)
		(property "Value" ""
			(at 0 0 90)
			(layer "B.Fab")
			(effects
				(font
					(size 1.27 1.27)
				)
				(justify mirror)
			)
		)
		(duplicate_pad_numbers_are_jumpers no)
		(fp_line
			(start 0.7874 -0.4064)
			(end -0.7874 -0.4064)
			(stroke
				(width 0.1524)
				(type default)
			)
			(layer "B.SilkS")
		)
		(fp_line
			(start -0.7874 -0.4064)
			(end -0.7874 0.4064)
			(stroke
				(width 0.1524)
				(type default)
			)
			(layer "B.SilkS")
		)
		(fp_line
			(start 0.7874 0.4064)
			(end 0.7874 -0.4064)
			(stroke
				(width 0.1524)
				(type default)
			)
			(layer "B.SilkS")
		)
		(fp_line
			(start -0.7874 0.4064)
			(end 0.7874 0.4064)
			(stroke
				(width 0.1524)
				(type default)
			)
			(layer "B.SilkS")
		)
		(fp_poly
			(pts
				(xy 0.508 0.2794) (xy 0.508 0.2286) (xy 0.635 0.2286) (xy 0.635 -0.254) (xy 0.5334 -0.254) (xy 0.5334 -0.2794)
				(xy -0.5334 -0.2794) (xy -0.5334 -0.254) (xy -0.635 -0.254) (xy -0.635 0.254) (xy -0.5334 0.254)
				(xy -0.5334 0.2794)
			)
			(stroke
				(width 0)
				(type default)
			)
			(fill no)
			(layer "B.CrtYd")
		)
		(pad "1" smd rect
			(at -0.40005 0 270)
			(size 0.4572 0.508)
			(layers "B.Cu" "B.Mask" "B.Paste")
			(net "UART_RI_P4_N")
		)
		(pad "2" smd rect
			(at 0.40005 0 270)
			(size 0.4572 0.508)
			(layers "B.Cu" "B.Mask" "B.Paste")
			(net "UART_RI_P4_R_N")
		)
	)
	(footprint ""
		(layer "B.Cu")
		(at 81.784698 -136.557258 -90)
		(property "Reference" "R1098"
			(at -1.358138 0.544322 270)
			(unlocked yes)
			(layer "B.SilkS")
			(effects
				(font
					(size 0.7874 0.5842)
					(thickness 0.1524)
				)
				(justify left mirror)
			)
		)
		(property "Value" ""
			(at 0 0 90)
			(layer "B.Fab")
			(effects
				(font
					(size 1.27 1.27)
				)
				(justify mirror)
			)
		)
		(duplicate_pad_numbers_are_jumpers no)
		(fp_line
			(start -0.7874 0.4064)
			(end 0.7874 0.4064)
			(stroke
				(width 0.1524)
				(type default)
			)
			(layer "B.SilkS")
		)
		(fp_line
			(start 0.7874 0.4064)
			(end 0.7874 -0.4064)
			(stroke
				(width 0.1524)
				(type default)
			)
			(layer "B.SilkS")
		)
		(fp_line
			(start -0.7874 -0.4064)
			(end -0.7874 0.4064)
			(stroke
				(width 0.1524)
				(type default)
			)
			(layer "B.SilkS")
		)
		(fp_line
			(start 0.7874 -0.4064)
			(end -0.7874 -0.4064)
			(stroke
				(width 0.1524)
				(type default)
			)
			(layer "B.SilkS")
		)
		(fp_poly
			(pts
				(xy 0.508 0.2794) (xy 0.508 0.2286) (xy 0.635 0.2286) (xy 0.635 -0.254) (xy 0.5334 -0.254) (xy 0.5334 -0.2794)
				(xy -0.5334 -0.2794) (xy -0.5334 -0.254) (xy -0.635 -0.254) (xy -0.635 0.254) (xy -0.5334 0.254)
				(xy -0.5334 0.2794)
			)
			(stroke
				(width 0)
				(type default)
			)
			(fill no)
			(layer "B.CrtYd")
		)
		(pad "1" smd rect
			(at -0.40005 0 90)
			(size 0.4572 0.508)
			(layers "B.Cu" "B.Mask" "B.Paste")
			(net "P1V26_BMC_NODE1_ADJ")
		)
		(pad "2" smd rect
			(at 0.40005 0 90)
			(size 0.4572 0.508)
			(layers "B.Cu" "B.Mask" "B.Paste")
			(net "GND")
		)
	)
	(footprint ""
		(layer "B.Cu")
		(at 36.590732 -94.40037 -90)
		(property "Reference" "C28"
			(at 4.703318 4.676394 270)
			(unlocked yes)
			(layer "B.SilkS")
			(effects
				(font
					(size 0.7874 0.5842)
					(thickness 0.1524)
				)
				(justify left mirror)
			)
		)
		(property "Value" ""
			(at 0 0 90)
			(layer "B.Fab")
			(effects
				(font
					(size 1.27 1.27)
				)
				(justify mirror)
			)
		)
		(duplicate_pad_numbers_are_jumpers no)
		(fp_line
			(start -0.7874 0.4064)
			(end 0.7874 0.4064)
			(stroke
				(width 0.1524)
				(type default)
			)
			(layer "B.SilkS")
		)
		(fp_line
			(start 0.7874 0.4064)
			(end 0.7874 -0.4064)
			(stroke
				(width 0.1524)
				(type default)
			)
			(layer "B.SilkS")
		)
		(fp_line
			(start 0 0.381)
			(end 0 -0.381)
			(stroke
				(width 0.1524)
				(type default)
			)
			(layer "B.SilkS")
		)
		(fp_line
			(start -0.7874 -0.4064)
			(end -0.7874 0.4064)
			(stroke
				(width 0.1524)
				(type default)
			)
			(layer "B.SilkS")
		)
		(fp_line
			(start 0.7874 -0.4064)
			(end -0.7874 -0.4064)
			(stroke
				(width 0.1524)
				(type default)
			)
			(layer "B.SilkS")
		)
		(fp_poly
			(pts
				(xy 0.5334 0.254) (xy 0.635 0.254) (xy 0.635 0.2286) (xy 0.635 -0.254) (xy 0.5334 -0.254) (xy 0.5334 -0.2794)
				(xy -0.5334 -0.2794) (xy -0.5334 -0.254) (xy -0.635 -0.254) (xy -0.635 0.254) (xy -0.5334 0.254)
				(xy -0.5334 0.2794) (xy 0.508 0.2794) (xy 0.5334 0.2794)
			)
			(stroke
				(width 0)
				(type default)
			)
			(fill no)
			(layer "B.CrtYd")
		)
		(pad "1" smd rect
			(at -0.40005 0 90)
			(size 0.4572 0.508)
			(layers "B.Cu" "B.Mask" "B.Paste")
			(net "GND")
		)
		(pad "2" smd rect
			(at 0.40005 0 90)
			(size 0.4572 0.508)
			(layers "B.Cu" "B.Mask" "B.Paste")
			(net "SMB_CPU_NODE1_MEM_ICS_CLK_R")
		)
	)
	(footprint ""
		(layer "B.Cu")
		(at 55.993538 -82.579718 -90)
		(property "Reference" "C38"
			(at -0.971296 0.116078 270)
			(unlocked yes)
			(layer "B.SilkS")
			(effects
				(font
					(size 0.7874 0.5842)
					(thickness 0.1524)
				)
				(justify left mirror)
			)
		)
		(property "Value" ""
			(at 0 0 90)
			(layer "B.Fab")
			(effects
				(font
					(size 1.27 1.27)
				)
				(justify mirror)
			)
		)
		(duplicate_pad_numbers_are_jumpers no)
		(fp_line
			(start -0.7874 0.4064)
			(end 0.7874 0.4064)
			(stroke
				(width 0.1524)
				(type default)
			)
			(layer "B.SilkS")
		)
		(fp_line
			(start 0.7874 0.4064)
			(end 0.7874 -0.4064)
			(stroke
				(width 0.1524)
				(type default)
			)
			(layer "B.SilkS")
		)
		(fp_line
			(start 0 0.381)
			(end 0 -0.381)
			(stroke
				(width 0.1524)
				(type default)
			)
			(layer "B.SilkS")
		)
		(fp_line
			(start -0.7874 -0.4064)
			(end -0.7874 0.4064)
			(stroke
				(width 0.1524)
				(type default)
			)
			(layer "B.SilkS")
		)
		(fp_line
			(start 0.7874 -0.4064)
			(end -0.7874 -0.4064)
			(stroke
				(width 0.1524)
				(type default)
			)
			(layer "B.SilkS")
		)
		(fp_poly
			(pts
				(xy 0.5334 0.254) (xy 0.635 0.254) (xy 0.635 0.2286) (xy 0.635 -0.254) (xy 0.5334 -0.254) (xy 0.5334 -0.2794)
				(xy -0.5334 -0.2794) (xy -0.5334 -0.254) (xy -0.635 -0.254) (xy -0.635 0.254) (xy -0.5334 0.254)
				(xy -0.5334 0.2794) (xy 0.508 0.2794) (xy 0.5334 0.2794)
			)
			(stroke
				(width 0)
				(type default)
			)
			(fill no)
			(layer "B.CrtYd")
		)
		(pad "1" smd rect
			(at -0.40005 0 90)
			(size 0.4572 0.508)
			(layers "B.Cu" "B.Mask" "B.Paste")
			(net "P1V8_NODE1")
		)
		(pad "2" smd rect
			(at 0.40005 0 90)
			(size 0.4572 0.508)
			(layers "B.Cu" "B.Mask" "B.Paste")
			(net "GND")
		)
	)
	(footprint ""
		(layer "B.Cu")
		(at 118.47576 -188.126624 -90)
		(property "Reference" "C641"
			(at -4.080256 -0.707644 270)
			(unlocked yes)
			(layer "B.SilkS")
			(effects
				(font
					(size 0.7874 0.5842)
					(thickness 0.1524)
				)
				(justify left mirror)
			)
		)
		(property "Value" ""
			(at 0 0 90)
			(layer "B.Fab")
			(effects
				(font
					(size 1.27 1.27)
				)
				(justify mirror)
			)
		)
		(duplicate_pad_numbers_are_jumpers no)
		(fp_line
			(start -0.7874 0.406146)
			(end 0.7874 0.406146)
			(stroke
				(width 0.1524)
				(type default)
			)
			(layer "B.SilkS")
		)
		(fp_line
			(start 0.7874 0.406146)
			(end 0.7874 -0.406146)
			(stroke
				(width 0.1524)
				(type default)
			)
			(layer "B.SilkS")
		)
		(fp_line
			(start 0 0.381)
			(end 0 -0.381)
			(stroke
				(width 0.1524)
				(type default)
			)
			(layer "B.SilkS")
		)
		(fp_line
			(start -0.7874 -0.406146)
			(end -0.7874 0.406146)
			(stroke
				(width 0.1524)
				(type default)
			)
			(layer "B.SilkS")
		)
		(fp_line
			(start 0.7874 -0.406146)
			(end -0.7874 -0.406146)
			(stroke
				(width 0.1524)
				(type default)
			)
			(layer "B.SilkS")
		)
		(fp_poly
			(pts
				(xy 0.5334 0.254) (xy 0.635 0.254) (xy 0.635 0.2286) (xy 0.635 -0.254) (xy 0.5334 -0.254) (xy 0.5334 -0.2794)
				(xy -0.5334 -0.2794) (xy -0.5334 -0.254) (xy -0.635 -0.254) (xy -0.635 0.254) (xy -0.5334 0.254)
				(xy -0.5334 0.2794) (xy 0.508 0.2794) (xy 0.5334 0.2794)
			)
			(stroke
				(width 0)
				(type default)
			)
			(fill no)
			(layer "B.CrtYd")
		)
		(pad "1" smd rect
			(at -0.40005 0 90)
			(size 0.4572 0.508)
			(layers "B.Cu" "B.Mask" "B.Paste")
			(net "T7_NODE3_EN_R")
		)
		(pad "2" smd rect
			(at 0.40005 0 90)
			(size 0.4572 0.508)
			(layers "B.Cu" "B.Mask" "B.Paste")
			(net "GND")
		)
	)
	(footprint ""
		(layer "B.Cu")
		(at 130.570986 -58.039 90)
		(property "Reference" "C599"
			(at 1.143 0.339344 270)
			(unlocked yes)
			(layer "B.SilkS")
			(effects
				(font
					(size 0.7874 0.5842)
					(thickness 0.1524)
				)
				(justify left mirror)
			)
		)
		(property "Value" ""
			(at 0 0 90)
			(layer "B.Fab")
			(effects
				(font
					(size 1.27 1.27)
				)
				(justify mirror)
			)
		)
		(duplicate_pad_numbers_are_jumpers no)
		(fp_line
			(start 0.7874 -0.4064)
			(end -0.7874 -0.4064)
			(stroke
				(width 0.1524)
				(type default)
			)
			(layer "B.SilkS")
		)
		(fp_line
			(start -0.7874 -0.4064)
			(end -0.7874 0.4064)
			(stroke
				(width 0.1524)
				(type default)
			)
			(layer "B.SilkS")
		)
		(fp_line
			(start 0 0.381)
			(end 0 -0.381)
			(stroke
				(width 0.1524)
				(type default)
			)
			(layer "B.SilkS")
		)
		(fp_line
			(start 0.7874 0.4064)
			(end 0.7874 -0.4064)
			(stroke
				(width 0.1524)
				(type default)
			)
			(layer "B.SilkS")
		)
		(fp_line
			(start -0.7874 0.4064)
			(end 0.7874 0.4064)
			(stroke
				(width 0.1524)
				(type default)
			)
			(layer "B.SilkS")
		)
		(fp_poly
			(pts
				(xy 0.5334 0.254) (xy 0.635 0.254) (xy 0.635 0.2286) (xy 0.635 -0.254) (xy 0.5334 -0.254) (xy 0.5334 -0.2794)
				(xy -0.5334 -0.2794) (xy -0.5334 -0.254) (xy -0.635 -0.254) (xy -0.635 0.254) (xy -0.5334 0.254)
				(xy -0.5334 0.2794) (xy 0.508 0.2794) (xy 0.5334 0.2794)
			)
			(stroke
				(width 0)
				(type default)
			)
			(fill no)
			(layer "B.CrtYd")
		)
		(pad "1" smd rect
			(at -0.40005 0 270)
			(size 0.4572 0.508)
			(layers "B.Cu" "B.Mask" "B.Paste")
			(net "P3V3_NODE1")
		)
		(pad "2" smd rect
			(at 0.40005 0 270)
			(size 0.4572 0.508)
			(layers "B.Cu" "B.Mask" "B.Paste")
			(net "GND")
		)
	)
	(footprint ""
		(layer "B.Cu")
		(at 70.159372 -80.514698 90)
		(property "Reference" "C71"
			(at -32.158686 -14.55039 270)
			(unlocked yes)
			(layer "B.SilkS")
			(effects
				(font
					(size 0.7874 0.5842)
					(thickness 0.1524)
				)
				(justify left mirror)
			)
		)
		(property "Value" ""
			(at 0 0 90)
			(layer "B.Fab")
			(effects
				(font
					(size 1.27 1.27)
				)
				(justify mirror)
			)
		)
		(duplicate_pad_numbers_are_jumpers no)
		(fp_line
			(start 0.7874 -0.4064)
			(end -0.7874 -0.4064)
			(stroke
				(width 0.1524)
				(type default)
			)
			(layer "B.SilkS")
		)
		(fp_line
			(start -0.7874 -0.4064)
			(end -0.7874 0.4064)
			(stroke
				(width 0.1524)
				(type default)
			)
			(layer "B.SilkS")
		)
		(fp_line
			(start 0 0.381)
			(end 0 -0.381)
			(stroke
				(width 0.1524)
				(type default)
			)
			(layer "B.SilkS")
		)
		(fp_line
			(start 0.7874 0.4064)
			(end 0.7874 -0.4064)
			(stroke
				(width 0.1524)
				(type default)
			)
			(layer "B.SilkS")
		)
		(fp_line
			(start -0.7874 0.4064)
			(end 0.7874 0.4064)
			(stroke
				(width 0.1524)
				(type default)
			)
			(layer "B.SilkS")
		)
		(fp_poly
			(pts
				(xy 0.5334 0.254) (xy 0.635 0.254) (xy 0.635 0.2286) (xy 0.635 -0.254) (xy 0.5334 -0.254) (xy 0.5334 -0.2794)
				(xy -0.5334 -0.2794) (xy -0.5334 -0.254) (xy -0.635 -0.254) (xy -0.635 0.254) (xy -0.5334 0.254)
				(xy -0.5334 0.2794) (xy 0.508 0.2794) (xy 0.5334 0.2794)
			)
			(stroke
				(width 0)
				(type default)
			)
			(fill no)
			(layer "B.CrtYd")
		)
		(pad "1" smd rect
			(at -0.40005 0 270)
			(size 0.4572 0.508)
			(layers "B.Cu" "B.Mask" "B.Paste")
			(net "PV_VCCP_NODE1")
		)
		(pad "2" smd rect
			(at 0.40005 0 270)
			(size 0.4572 0.508)
			(layers "B.Cu" "B.Mask" "B.Paste")
			(net "GND")
		)
	)
	(footprint ""
		(layer "B.Cu")
		(at 69.326252 -134.473188 180)
		(property "Reference" "C249"
			(at 35.998912 -52.684426 0)
			(unlocked yes)
			(layer "B.SilkS")
			(effects
				(font
					(size 0.7874 0.5842)
					(thickness 0.1524)
				)
				(justify left mirror)
			)
		)
		(property "Value" ""
			(at 0 0 0)
			(layer "B.Fab")
			(effects
				(font
					(size 1.27 1.27)
				)
				(justify mirror)
			)
		)
		(duplicate_pad_numbers_are_jumpers no)
		(fp_line
			(start 0.7874 0.4064)
			(end 0.7874 -0.4064)
			(stroke
				(width 0.1524)
				(type default)
			)
			(layer "B.SilkS")
		)
		(fp_line
			(start 0.7874 -0.4064)
			(end -0.7874 -0.4064)
			(stroke
				(width 0.1524)
				(type default)
			)
			(layer "B.SilkS")
		)
		(fp_line
			(start 0 0.381)
			(end 0 -0.381)
			(stroke
				(width 0.1524)
				(type default)
			)
			(layer "B.SilkS")
		)
		(fp_line
			(start -0.7874 0.4064)
			(end 0.7874 0.4064)
			(stroke
				(width 0.1524)
				(type default)
			)
			(layer "B.SilkS")
		)
		(fp_line
			(start -0.7874 -0.4064)
			(end -0.7874 0.4064)
			(stroke
				(width 0.1524)
				(type default)
			)
			(layer "B.SilkS")
		)
		(fp_poly
			(pts
				(xy 0.5334 0.254) (xy 0.635 0.254) (xy 0.635 0.2286) (xy 0.635 -0.254) (xy 0.5334 -0.254) (xy 0.5334 -0.2794)
				(xy -0.5334 -0.2794) (xy -0.5334 -0.254) (xy -0.635 -0.254) (xy -0.635 0.254) (xy -0.5334 0.254)
				(xy -0.5334 0.2794) (xy 0.508 0.2794) (xy 0.5334 0.2794)
			)
			(stroke
				(width 0)
				(type default)
			)
			(fill no)
			(layer "B.CrtYd")
		)
		(pad "1" smd rect
			(at -0.40005 0)
			(size 0.4572 0.508)
			(layers "B.Cu" "B.Mask" "B.Paste")
			(net "P3V3_NODE1")
		)
		(pad "2" smd rect
			(at 0.40005 0)
			(size 0.4572 0.508)
			(layers "B.Cu" "B.Mask" "B.Paste")
			(net "GND")
		)
	)
	(footprint ""
		(layer "B.Cu")
		(at 149.33676 -187.872624 -90)
		(property "Reference" "C723"
			(at -4.565396 3.09245 270)
			(unlocked yes)
			(layer "B.SilkS")
			(effects
				(font
					(size 0.7874 0.5842)
					(thickness 0.1524)
				)
				(justify left mirror)
			)
		)
		(property "Value" ""
			(at 0 0 90)
			(layer "B.Fab")
			(effects
				(font
					(size 1.27 1.27)
				)
				(justify mirror)
			)
		)
		(duplicate_pad_numbers_are_jumpers no)
		(fp_line
			(start -0.7874 0.4064)
			(end 0.7874 0.4064)
			(stroke
				(width 0.1524)
				(type default)
			)
			(layer "B.SilkS")
		)
		(fp_line
			(start 0.7874 0.4064)
			(end 0.7874 -0.4064)
			(stroke
				(width 0.1524)
				(type default)
			)
			(layer "B.SilkS")
		)
		(fp_line
			(start 0 0.381)
			(end 0 -0.381)
			(stroke
				(width 0.1524)
				(type default)
			)
			(layer "B.SilkS")
		)
		(fp_line
			(start -0.7874 -0.4064)
			(end -0.7874 0.4064)
			(stroke
				(width 0.1524)
				(type default)
			)
			(layer "B.SilkS")
		)
		(fp_line
			(start 0.7874 -0.4064)
			(end -0.7874 -0.4064)
			(stroke
				(width 0.1524)
				(type default)
			)
			(layer "B.SilkS")
		)
		(fp_poly
			(pts
				(xy 0.5334 0.254) (xy 0.635 0.254) (xy 0.635 0.2286) (xy 0.635 -0.254) (xy 0.5334 -0.254) (xy 0.5334 -0.2794)
				(xy -0.5334 -0.2794) (xy -0.5334 -0.254) (xy -0.635 -0.254) (xy -0.635 0.254) (xy -0.5334 0.254)
				(xy -0.5334 0.2794) (xy 0.508 0.2794) (xy 0.5334 0.2794)
			)
			(stroke
				(width 0)
				(type default)
			)
			(fill no)
			(layer "B.CrtYd")
		)
		(pad "1" smd rect
			(at -0.40005 0 90)
			(size 0.4572 0.508)
			(layers "B.Cu" "B.Mask" "B.Paste")
			(net "UART_T11_NODE1_TXD_R")
		)
		(pad "2" smd rect
			(at 0.40005 0 90)
			(size 0.4572 0.508)
			(layers "B.Cu" "B.Mask" "B.Paste")
			(net "GND")
		)
	)
	(footprint ""
		(layer "B.Cu")
		(at 61.462666 -118.910862 -90)
		(property "Reference" "R319"
			(at 5.202682 -0.004064 270)
			(unlocked yes)
			(layer "B.SilkS")
			(effects
				(font
					(size 0.7874 0.5842)
					(thickness 0.1524)
				)
				(justify left mirror)
			)
		)
		(property "Value" ""
			(at 0 0 90)
			(layer "B.Fab")
			(effects
				(font
					(size 1.27 1.27)
				)
				(justify mirror)
			)
		)
		(duplicate_pad_numbers_are_jumpers no)
		(fp_line
			(start -0.7874 0.4064)
			(end 0.7874 0.4064)
			(stroke
				(width 0.1524)
				(type default)
			)
			(layer "B.SilkS")
		)
		(fp_line
			(start 0.7874 0.4064)
			(end 0.7874 -0.4064)
			(stroke
				(width 0.1524)
				(type default)
			)
			(layer "B.SilkS")
		)
		(fp_line
			(start -0.7874 -0.4064)
			(end -0.7874 0.4064)
			(stroke
				(width 0.1524)
				(type default)
			)
			(layer "B.SilkS")
		)
		(fp_line
			(start 0.7874 -0.4064)
			(end -0.7874 -0.4064)
			(stroke
				(width 0.1524)
				(type default)
			)
			(layer "B.SilkS")
		)
		(fp_poly
			(pts
				(xy 0.508 0.2794) (xy 0.508 0.2286) (xy 0.635 0.2286) (xy 0.635 -0.254) (xy 0.5334 -0.254) (xy 0.5334 -0.2794)
				(xy -0.5334 -0.2794) (xy -0.5334 -0.254) (xy -0.635 -0.254) (xy -0.635 0.254) (xy -0.5334 0.254)
				(xy -0.5334 0.2794)
			)
			(stroke
				(width 0)
				(type default)
			)
			(fill no)
			(layer "B.CrtYd")
		)
		(pad "1" smd rect
			(at -0.40005 0 90)
			(size 0.4572 0.508)
			(layers "B.Cu" "B.Mask" "B.Paste")
			(net "P3V3_NODE1")
		)
		(pad "2" smd rect
			(at 0.40005 0 90)
			(size 0.4572 0.508)
			(layers "B.Cu" "B.Mask" "B.Paste")
			(net "BMC_ROMA3")
		)
	)
	(footprint ""
		(layer "B.Cu")
		(at 165.186106 -168.146222 -90)
		(property "Reference" "R1064"
			(at 4.911344 -1.026668 270)
			(unlocked yes)
			(layer "B.SilkS")
			(effects
				(font
					(size 0.7874 0.5842)
					(thickness 0.1524)
				)
				(justify left mirror)
			)
		)
		(property "Value" ""
			(at 0 0 90)
			(layer "B.Fab")
			(effects
				(font
					(size 1.27 1.27)
				)
				(justify mirror)
			)
		)
		(duplicate_pad_numbers_are_jumpers no)
		(fp_line
			(start -0.7874 0.4064)
			(end 0.7874 0.4064)
			(stroke
				(width 0.1524)
				(type default)
			)
			(layer "B.SilkS")
		)
		(fp_line
			(start 0.7874 0.4064)
			(end 0.7874 -0.4064)
			(stroke
				(width 0.1524)
				(type default)
			)
			(layer "B.SilkS")
		)
		(fp_line
			(start -0.7874 -0.4064)
			(end -0.7874 0.4064)
			(stroke
				(width 0.1524)
				(type default)
			)
			(layer "B.SilkS")
		)
		(fp_line
			(start 0.7874 -0.4064)
			(end -0.7874 -0.4064)
			(stroke
				(width 0.1524)
				(type default)
			)
			(layer "B.SilkS")
		)
		(fp_poly
			(pts
				(xy 0.508 0.2794) (xy 0.508 0.2286) (xy 0.635 0.2286) (xy 0.635 -0.254) (xy 0.5334 -0.254) (xy 0.5334 -0.2794)
				(xy -0.5334 -0.2794) (xy -0.5334 -0.254) (xy -0.635 -0.254) (xy -0.635 0.254) (xy -0.5334 0.254)
				(xy -0.5334 0.2794)
			)
			(stroke
				(width 0)
				(type default)
			)
			(fill no)
			(layer "B.CrtYd")
		)
		(pad "1" smd rect
			(at -0.40005 0 90)
			(size 0.4572 0.508)
			(layers "B.Cu" "B.Mask" "B.Paste")
			(net "CPLD_UART_RI_P4_LS_N")
		)
		(pad "2" smd rect
			(at 0.40005 0 90)
			(size 0.4572 0.508)
			(layers "B.Cu" "B.Mask" "B.Paste")
			(net "CPLD_UART_RI_P4_N")
		)
	)
	(footprint ""
		(layer "B.Cu")
		(at 140.507466 -41.285414 180)
		(property "Reference" "R1189"
			(at 2.019808 -18.796254 0)
			(unlocked yes)
			(layer "B.SilkS")
			(effects
				(font
					(size 0.7874 0.5842)
					(thickness 0.1524)
				)
				(justify left mirror)
			)
		)
		(property "Value" ""
			(at 0 0 0)
			(layer "B.Fab")
			(effects
				(font
					(size 1.27 1.27)
				)
				(justify mirror)
			)
		)
		(duplicate_pad_numbers_are_jumpers no)
		(fp_line
			(start 0.7874 0.4064)
			(end 0.7874 -0.4064)
			(stroke
				(width 0.1524)
				(type default)
			)
			(layer "B.SilkS")
		)
		(fp_line
			(start 0.7874 -0.4064)
			(end -0.7874 -0.4064)
			(stroke
				(width 0.1524)
				(type default)
			)
			(layer "B.SilkS")
		)
		(fp_line
			(start -0.7874 0.4064)
			(end 0.7874 0.4064)
			(stroke
				(width 0.1524)
				(type default)
			)
			(layer "B.SilkS")
		)
		(fp_line
			(start -0.7874 -0.4064)
			(end -0.7874 0.4064)
			(stroke
				(width 0.1524)
				(type default)
			)
			(layer "B.SilkS")
		)
		(fp_poly
			(pts
				(xy 0.508 0.2794) (xy 0.508 0.2286) (xy 0.635 0.2286) (xy 0.635 -0.254) (xy 0.5334 -0.254) (xy 0.5334 -0.2794)
				(xy -0.5334 -0.2794) (xy -0.5334 -0.254) (xy -0.635 -0.254) (xy -0.635 0.254) (xy -0.5334 0.254)
				(xy -0.5334 0.2794)
			)
			(stroke
				(width 0)
				(type default)
			)
			(fill no)
			(layer "B.CrtYd")
		)
		(pad "1" smd rect
			(at -0.40005 0)
			(size 0.4572 0.508)
			(layers "B.Cu" "B.Mask" "B.Paste")
			(net "SIO_JTAG_CPLD2_TCK_R")
		)
		(pad "2" smd rect
			(at 0.40005 0)
			(size 0.4572 0.508)
			(layers "B.Cu" "B.Mask" "B.Paste")
			(net "SIO_JTAG_CPLD2_TCK")
		)
	)
	(footprint ""
		(layer "B.Cu")
		(at 90.81262 -178.086512)
		(property "Reference" "R697"
			(at 24.902414 20.083272 0)
			(unlocked yes)
			(layer "B.SilkS")
			(effects
				(font
					(size 0.7874 0.5842)
					(thickness 0.1524)
				)
				(justify left mirror)
			)
		)
		(property "Value" ""
			(at 0 0 0)
			(layer "B.Fab")
			(effects
				(font
					(size 1.27 1.27)
				)
				(justify mirror)
			)
		)
		(duplicate_pad_numbers_are_jumpers no)
		(fp_line
			(start -0.7874 -0.4064)
			(end -0.7874 0.4064)
			(stroke
				(width 0.1524)
				(type default)
			)
			(layer "B.SilkS")
		)
		(fp_line
			(start -0.7874 0.4064)
			(end 0.7874 0.4064)
			(stroke
				(width 0.1524)
				(type default)
			)
			(layer "B.SilkS")
		)
		(fp_line
			(start 0.7874 -0.4064)
			(end -0.7874 -0.4064)
			(stroke
				(width 0.1524)
				(type default)
			)
			(layer "B.SilkS")
		)
		(fp_line
			(start 0.7874 0.4064)
			(end 0.7874 -0.4064)
			(stroke
				(width 0.1524)
				(type default)
			)
			(layer "B.SilkS")
		)
		(fp_poly
			(pts
				(xy 0.508 0.2794) (xy 0.508 0.2286) (xy 0.635 0.2286) (xy 0.635 -0.254) (xy 0.5334 -0.254) (xy 0.5334 -0.2794)
				(xy -0.5334 -0.2794) (xy -0.5334 -0.254) (xy -0.635 -0.254) (xy -0.635 0.254) (xy -0.5334 0.254)
				(xy -0.5334 0.2794)
			)
			(stroke
				(width 0)
				(type default)
			)
			(fill no)
			(layer "B.CrtYd")
		)
		(pad "1" smd rect
			(at -0.40005 0 180)
			(size 0.4572 0.508)
			(layers "B.Cu" "B.Mask" "B.Paste")
			(net "T3_NODE1_EN")
		)
		(pad "2" smd rect
			(at 0.40005 0 180)
			(size 0.4572 0.508)
			(layers "B.Cu" "B.Mask" "B.Paste")
			(net "P5V_NODE1")
		)
	)
	(footprint ""
		(layer "B.Cu")
		(at 135.84047 -105.186734 90)
		(property "Reference" "L2"
			(at -1.768094 -1.67005 270)
			(unlocked yes)
			(layer "B.SilkS")
			(effects
				(font
					(size 0.7874 0.5842)
					(thickness 0.1524)
				)
				(justify left mirror)
			)
		)
		(property "Value" ""
			(at 0 0 90)
			(layer "B.Fab")
			(effects
				(font
					(size 1.27 1.27)
				)
				(justify mirror)
			)
		)
		(duplicate_pad_numbers_are_jumpers no)
		(fp_line
			(start 1.905 -0.8636)
			(end -1.905 -0.8636)
			(stroke
				(width 0.1524)
				(type default)
			)
			(layer "B.SilkS")
		)
		(fp_line
			(start 1.905 0.8382)
			(end 1.905 -0.8382)
			(stroke
				(width 0.1524)
				(type default)
			)
			(layer "B.SilkS")
		)
		(fp_line
			(start 0.127 0.8382)
			(end 0.127 -0.8382)
			(stroke
				(width 0.1524)
				(type default)
			)
			(layer "B.SilkS")
		)
		(fp_line
			(start -0.127 0.8382)
			(end -0.127 -0.8382)
			(stroke
				(width 0.1524)
				(type default)
			)
			(layer "B.SilkS")
		)
		(fp_line
			(start -1.905 0.8382)
			(end -1.905 -0.8382)
			(stroke
				(width 0.1524)
				(type default)
			)
			(layer "B.SilkS")
		)
		(fp_line
			(start -1.905 0.8636)
			(end 1.905 0.8636)
			(stroke
				(width 0.1524)
				(type default)
			)
			(layer "B.SilkS")
		)
		(fp_rect
			(start 1.524 0.7112)
			(end -1.524 -0.7366)
			(stroke
				(width 0)
				(type default)
			)
			(fill no)
			(layer "B.CrtYd")
		)
		(pad "1" smd rect
			(at -0.94996 0 270)
			(size 1.1176 1.3716)
			(layers "B.Cu" "B.Mask" "B.Paste")
			(net "P3V3_CLK_NODE1_R")
		)
		(pad "2" smd rect
			(at 0.94996 0 270)
			(size 1.1176 1.3716)
			(layers "B.Cu" "B.Mask" "B.Paste")
			(net "P3V3_CLK_NODE1")
		)
	)
	(footprint ""
		(layer "B.Cu")
		(at 108.44276 -188.126624 -90)
		(property "Reference" "C739"
			(at -4.080256 -0.63246 270)
			(unlocked yes)
			(layer "B.SilkS")
			(effects
				(font
					(size 0.7874 0.5842)
					(thickness 0.1524)
				)
				(justify left mirror)
			)
		)
		(property "Value" ""
			(at 0 0 90)
			(layer "B.Fab")
			(effects
				(font
					(size 1.27 1.27)
				)
				(justify mirror)
			)
		)
		(duplicate_pad_numbers_are_jumpers no)
		(fp_line
			(start -0.7874 0.4064)
			(end 0.7874 0.4064)
			(stroke
				(width 0.1524)
				(type default)
			)
			(layer "B.SilkS")
		)
		(fp_line
			(start 0.7874 0.4064)
			(end 0.7874 -0.4064)
			(stroke
				(width 0.1524)
				(type default)
			)
			(layer "B.SilkS")
		)
		(fp_line
			(start 0 0.381)
			(end 0 -0.381)
			(stroke
				(width 0.1524)
				(type default)
			)
			(layer "B.SilkS")
		)
		(fp_line
			(start -0.7874 -0.4064)
			(end -0.7874 0.4064)
			(stroke
				(width 0.1524)
				(type default)
			)
			(layer "B.SilkS")
		)
		(fp_line
			(start 0.7874 -0.4064)
			(end -0.7874 -0.4064)
			(stroke
				(width 0.1524)
				(type default)
			)
			(layer "B.SilkS")
		)
		(fp_poly
			(pts
				(xy 0.5334 0.254) (xy 0.635 0.254) (xy 0.635 0.2286) (xy 0.635 -0.254) (xy 0.5334 -0.254) (xy 0.5334 -0.2794)
				(xy -0.5334 -0.2794) (xy -0.5334 -0.254) (xy -0.635 -0.254) (xy -0.635 0.254) (xy -0.5334 0.254)
				(xy -0.5334 0.2794) (xy 0.508 0.2794) (xy 0.5334 0.2794)
			)
			(stroke
				(width 0)
				(type default)
			)
			(fill no)
			(layer "B.CrtYd")
		)
		(pad "1" smd rect
			(at -0.40005 0 90)
			(size 0.4572 0.508)
			(layers "B.Cu" "B.Mask" "B.Paste")
			(net "UART_T7_NODE4_TXD_R")
		)
		(pad "2" smd rect
			(at 0.40005 0 90)
			(size 0.4572 0.508)
			(layers "B.Cu" "B.Mask" "B.Paste")
			(net "GND")
		)
	)
	(footprint ""
		(layer "B.Cu")
		(at 45.642022 -184.922668 -90)
		(property "Reference" "R835"
			(at -4.434586 -0.062738 270)
			(unlocked yes)
			(layer "B.SilkS")
			(effects
				(font
					(size 0.7874 0.5842)
					(thickness 0.1524)
				)
				(justify left mirror)
			)
		)
		(property "Value" ""
			(at 0 0 90)
			(layer "B.Fab")
			(effects
				(font
					(size 1.27 1.27)
				)
				(justify mirror)
			)
		)
		(duplicate_pad_numbers_are_jumpers no)
		(fp_line
			(start -0.7874 0.4064)
			(end 0.7874 0.4064)
			(stroke
				(width 0.1524)
				(type default)
			)
			(layer "B.SilkS")
		)
		(fp_line
			(start 0.7874 0.4064)
			(end 0.7874 -0.4064)
			(stroke
				(width 0.1524)
				(type default)
			)
			(layer "B.SilkS")
		)
		(fp_line
			(start -0.7874 -0.4064)
			(end -0.7874 0.4064)
			(stroke
				(width 0.1524)
				(type default)
			)
			(layer "B.SilkS")
		)
		(fp_line
			(start 0.7874 -0.4064)
			(end -0.7874 -0.4064)
			(stroke
				(width 0.1524)
				(type default)
			)
			(layer "B.SilkS")
		)
		(fp_poly
			(pts
				(xy 0.508 0.2794) (xy 0.508 0.2286) (xy 0.635 0.2286) (xy 0.635 -0.254) (xy 0.5334 -0.254) (xy 0.5334 -0.2794)
				(xy -0.5334 -0.2794) (xy -0.5334 -0.254) (xy -0.635 -0.254) (xy -0.635 0.254) (xy -0.5334 0.254)
				(xy -0.5334 0.2794)
			)
			(stroke
				(width 0)
				(type default)
			)
			(fill no)
			(layer "B.CrtYd")
		)
		(pad "1" smd rect
			(at -0.40005 0 90)
			(size 0.4572 0.508)
			(layers "B.Cu" "B.Mask" "B.Paste")
			(net "MATE_R_N")
		)
		(pad "2" smd rect
			(at 0.40005 0 90)
			(size 0.4572 0.508)
			(layers "B.Cu" "B.Mask" "B.Paste")
			(net "MATE_N")
		)
	)
	(footprint ""
		(layer "B.Cu")
		(at 85.692742 -29.793438 180)
		(property "Reference" "R208"
			(at -2.110994 -1.18237 0)
			(unlocked yes)
			(layer "B.SilkS")
			(effects
				(font
					(size 0.7874 0.5842)
					(thickness 0.1524)
				)
				(justify left mirror)
			)
		)
		(property "Value" ""
			(at 0 0 0)
			(layer "B.Fab")
			(effects
				(font
					(size 1.27 1.27)
				)
				(justify mirror)
			)
		)
		(duplicate_pad_numbers_are_jumpers no)
		(fp_line
			(start 0.7874 0.4064)
			(end 0.7874 -0.4064)
			(stroke
				(width 0.1524)
				(type default)
			)
			(layer "B.SilkS")
		)
		(fp_line
			(start 0.7874 -0.4064)
			(end -0.7874 -0.4064)
			(stroke
				(width 0.1524)
				(type default)
			)
			(layer "B.SilkS")
		)
		(fp_line
			(start -0.7874 0.4064)
			(end 0.7874 0.4064)
			(stroke
				(width 0.1524)
				(type default)
			)
			(layer "B.SilkS")
		)
		(fp_line
			(start -0.7874 -0.4064)
			(end -0.7874 0.4064)
			(stroke
				(width 0.1524)
				(type default)
			)
			(layer "B.SilkS")
		)
		(fp_poly
			(pts
				(xy 0.508 0.2794) (xy 0.508 0.2286) (xy 0.635 0.2286) (xy 0.635 -0.254) (xy 0.5334 -0.254) (xy 0.5334 -0.2794)
				(xy -0.5334 -0.2794) (xy -0.5334 -0.254) (xy -0.635 -0.254) (xy -0.635 0.254) (xy -0.5334 0.254)
				(xy -0.5334 0.2794)
			)
			(stroke
				(width 0)
				(type default)
			)
			(fill no)
			(layer "B.CrtYd")
		)
		(pad "1" smd rect
			(at -0.40005 0)
			(size 0.4572 0.508)
			(layers "B.Cu" "B.Mask" "B.Paste")
			(net "GND")
		)
		(pad "2" smd rect
			(at 0.40005 0)
			(size 0.4572 0.508)
			(layers "B.Cu" "B.Mask" "B.Paste")
			(net "PD_NODE1_DM4")
		)
	)
	(footprint ""
		(layer "B.Cu")
		(at 64.731392 -137.893806 180)
		(property "Reference" "C251"
			(at 38.960806 -54.881018 0)
			(unlocked yes)
			(layer "B.SilkS")
			(effects
				(font
					(size 0.7874 0.5842)
					(thickness 0.1524)
				)
				(justify left mirror)
			)
		)
		(property "Value" ""
			(at 0 0 0)
			(layer "B.Fab")
			(effects
				(font
					(size 1.27 1.27)
				)
				(justify mirror)
			)
		)
		(duplicate_pad_numbers_are_jumpers no)
		(fp_line
			(start 0.7874 0.4064)
			(end 0.7874 -0.4064)
			(stroke
				(width 0.1524)
				(type default)
			)
			(layer "B.SilkS")
		)
		(fp_line
			(start 0.7874 -0.4064)
			(end -0.7874 -0.4064)
			(stroke
				(width 0.1524)
				(type default)
			)
			(layer "B.SilkS")
		)
		(fp_line
			(start 0 0.381)
			(end 0 -0.381)
			(stroke
				(width 0.1524)
				(type default)
			)
			(layer "B.SilkS")
		)
		(fp_line
			(start -0.7874 0.4064)
			(end 0.7874 0.4064)
			(stroke
				(width 0.1524)
				(type default)
			)
			(layer "B.SilkS")
		)
		(fp_line
			(start -0.7874 -0.4064)
			(end -0.7874 0.4064)
			(stroke
				(width 0.1524)
				(type default)
			)
			(layer "B.SilkS")
		)
		(fp_poly
			(pts
				(xy 0.5334 0.254) (xy 0.635 0.254) (xy 0.635 0.2286) (xy 0.635 -0.254) (xy 0.5334 -0.254) (xy 0.5334 -0.2794)
				(xy -0.5334 -0.2794) (xy -0.5334 -0.254) (xy -0.635 -0.254) (xy -0.635 0.254) (xy -0.5334 0.254)
				(xy -0.5334 0.2794) (xy 0.508 0.2794) (xy 0.5334 0.2794)
			)
			(stroke
				(width 0)
				(type default)
			)
			(fill no)
			(layer "B.CrtYd")
		)
		(pad "1" smd rect
			(at -0.40005 0)
			(size 0.4572 0.508)
			(layers "B.Cu" "B.Mask" "B.Paste")
			(net "P3V3_NODE1")
		)
		(pad "2" smd rect
			(at 0.40005 0)
			(size 0.4572 0.508)
			(layers "B.Cu" "B.Mask" "B.Paste")
			(net "GND")
		)
	)
	(footprint ""
		(layer "B.Cu")
		(at 59.45124 -70.133718 -90)
		(property "Reference" "L5"
			(at 32.046926 10.44067 270)
			(unlocked yes)
			(layer "B.SilkS")
			(effects
				(font
					(size 0.7874 0.5842)
					(thickness 0.1524)
				)
				(justify left mirror)
			)
		)
		(property "Value" ""
			(at 0 0 90)
			(layer "B.Fab")
			(effects
				(font
					(size 1.27 1.27)
				)
				(justify mirror)
			)
		)
		(duplicate_pad_numbers_are_jumpers no)
		(fp_line
			(start -0.7874 0.4064)
			(end 0.7874 0.4064)
			(stroke
				(width 0.1524)
				(type default)
			)
			(layer "B.SilkS")
		)
		(fp_line
			(start -0.0889 0.4064)
			(end -0.0889 -0.4064)
			(stroke
				(width 0.1524)
				(type default)
			)
			(layer "B.SilkS")
		)
		(fp_line
			(start 0.0889 0.4064)
			(end 0.0889 -0.4064)
			(stroke
				(width 0.1524)
				(type default)
			)
			(layer "B.SilkS")
		)
		(fp_line
			(start 0.7874 0.4064)
			(end 0.7874 -0.4064)
			(stroke
				(width 0.1524)
				(type default)
			)
			(layer "B.SilkS")
		)
		(fp_line
			(start -0.7874 -0.4064)
			(end -0.7874 0.4064)
			(stroke
				(width 0.1524)
				(type default)
			)
			(layer "B.SilkS")
		)
		(fp_line
			(start 0.7874 -0.4064)
			(end -0.7874 -0.4064)
			(stroke
				(width 0.1524)
				(type default)
			)
			(layer "B.SilkS")
		)
		(fp_poly
			(pts
				(xy 0.5334 0.254) (xy 0.635 0.254) (xy 0.635 0.2286) (xy 0.635 -0.254) (xy 0.5334 -0.254) (xy 0.5334 -0.2794)
				(xy -0.5334 -0.2794) (xy -0.5334 -0.254) (xy -0.635 -0.254) (xy -0.635 0.254) (xy -0.5334 0.254)
				(xy -0.5334 0.2794) (xy 0.508 0.2794) (xy 0.5334 0.2794)
			)
			(stroke
				(width 0)
				(type default)
			)
			(fill no)
			(layer "B.CrtYd")
		)
		(pad "1" smd rect
			(at -0.40005 0 90)
			(size 0.4572 0.508)
			(layers "B.Cu" "B.Mask" "B.Paste")
			(net "P1V05_NODE1")
		)
		(pad "2" smd rect
			(at 0.40005 0 90)
			(size 0.4572 0.508)
			(layers "B.Cu" "B.Mask" "B.Paste")
			(net "P1V05_VCCPLL_DDR3_NODE1")
		)
	)
	(footprint ""
		(layer "B.Cu")
		(at 138.79576 -187.872624 -90)
		(property "Reference" "C627"
			(at -4.565396 1.448308 270)
			(unlocked yes)
			(layer "B.SilkS")
			(effects
				(font
					(size 0.7874 0.5842)
					(thickness 0.1524)
				)
				(justify left mirror)
			)
		)
		(property "Value" ""
			(at 0 0 90)
			(layer "B.Fab")
			(effects
				(font
					(size 1.27 1.27)
				)
				(justify mirror)
			)
		)
		(duplicate_pad_numbers_are_jumpers no)
		(fp_line
			(start -0.7874 0.4064)
			(end 0.7874 0.4064)
			(stroke
				(width 0.1524)
				(type default)
			)
			(layer "B.SilkS")
		)
		(fp_line
			(start 0.7874 0.4064)
			(end 0.7874 -0.4064)
			(stroke
				(width 0.1524)
				(type default)
			)
			(layer "B.SilkS")
		)
		(fp_line
			(start 0 0.381)
			(end 0 -0.381)
			(stroke
				(width 0.1524)
				(type default)
			)
			(layer "B.SilkS")
		)
		(fp_line
			(start -0.7874 -0.4064)
			(end -0.7874 0.4064)
			(stroke
				(width 0.1524)
				(type default)
			)
			(layer "B.SilkS")
		)
		(fp_line
			(start 0.7874 -0.4064)
			(end -0.7874 -0.4064)
			(stroke
				(width 0.1524)
				(type default)
			)
			(layer "B.SilkS")
		)
		(fp_poly
			(pts
				(xy 0.5334 0.254) (xy 0.635 0.254) (xy 0.635 0.2286) (xy 0.635 -0.254) (xy 0.5334 -0.254) (xy 0.5334 -0.2794)
				(xy -0.5334 -0.2794) (xy -0.5334 -0.254) (xy -0.635 -0.254) (xy -0.635 0.254) (xy -0.5334 0.254)
				(xy -0.5334 0.2794) (xy 0.508 0.2794) (xy 0.5334 0.2794)
			)
			(stroke
				(width 0)
				(type default)
			)
			(fill no)
			(layer "B.CrtYd")
		)
		(pad "1" smd rect
			(at -0.40005 0 90)
			(size 0.4572 0.508)
			(layers "B.Cu" "B.Mask" "B.Paste")
			(net "T9_NODE2_EN_R")
		)
		(pad "2" smd rect
			(at 0.40005 0 90)
			(size 0.4572 0.508)
			(layers "B.Cu" "B.Mask" "B.Paste")
			(net "GND")
		)
	)
	(footprint ""
		(layer "B.Cu")
		(at 58.019188 -56.108854)
		(property "Reference" "R32"
			(at 3.14579 0.043688 0)
			(unlocked yes)
			(layer "B.SilkS")
			(effects
				(font
					(size 0.7874 0.5842)
					(thickness 0.1524)
				)
				(justify left mirror)
			)
		)
		(property "Value" ""
			(at 0 0 0)
			(layer "B.Fab")
			(effects
				(font
					(size 1.27 1.27)
				)
				(justify mirror)
			)
		)
		(duplicate_pad_numbers_are_jumpers no)
		(fp_line
			(start -0.7874 -0.4064)
			(end -0.7874 0.4064)
			(stroke
				(width 0.1524)
				(type default)
			)
			(layer "B.SilkS")
		)
		(fp_line
			(start -0.7874 0.4064)
			(end 0.7874 0.4064)
			(stroke
				(width 0.1524)
				(type default)
			)
			(layer "B.SilkS")
		)
		(fp_line
			(start 0.7874 -0.4064)
			(end -0.7874 -0.4064)
			(stroke
				(width 0.1524)
				(type default)
			)
			(layer "B.SilkS")
		)
		(fp_line
			(start 0.7874 0.4064)
			(end 0.7874 -0.4064)
			(stroke
				(width 0.1524)
				(type default)
			)
			(layer "B.SilkS")
		)
		(fp_poly
			(pts
				(xy 0.508 0.2794) (xy 0.508 0.2286) (xy 0.635 0.2286) (xy 0.635 -0.254) (xy 0.5334 -0.254) (xy 0.5334 -0.2794)
				(xy -0.5334 -0.2794) (xy -0.5334 -0.254) (xy -0.635 -0.254) (xy -0.635 0.254) (xy -0.5334 0.254)
				(xy -0.5334 0.2794)
			)
			(stroke
				(width 0)
				(type default)
			)
			(fill no)
			(layer "B.CrtYd")
		)
		(pad "1" smd rect
			(at -0.40005 0 180)
			(size 0.4572 0.508)
			(layers "B.Cu" "B.Mask" "B.Paste")
			(net "M_DDR3_NODE1_MON1P")
		)
		(pad "2" smd rect
			(at 0.40005 0 180)
			(size 0.4572 0.508)
			(layers "B.Cu" "B.Mask" "B.Paste")
			(net "M_DDR3_NODE1_MON1N")
		)
	)
	(footprint ""
		(layer "B.Cu")
		(at 137.550652 -135.84555 90)
		(property "Reference" "C879"
			(at -5.04825 -0.15875 270)
			(unlocked yes)
			(layer "B.SilkS")
			(effects
				(font
					(size 0.7874 0.5842)
					(thickness 0.1524)
				)
				(justify left mirror)
			)
		)
		(property "Value" ""
			(at 0 0 90)
			(layer "B.Fab")
			(effects
				(font
					(size 1.27 1.27)
				)
				(justify mirror)
			)
		)
		(duplicate_pad_numbers_are_jumpers no)
		(fp_line
			(start 0.7874 -0.4064)
			(end -0.7874 -0.4064)
			(stroke
				(width 0.1524)
				(type default)
			)
			(layer "B.SilkS")
		)
		(fp_line
			(start -0.7874 -0.4064)
			(end -0.7874 0.4064)
			(stroke
				(width 0.1524)
				(type default)
			)
			(layer "B.SilkS")
		)
		(fp_line
			(start 0 0.381)
			(end 0 -0.381)
			(stroke
				(width 0.1524)
				(type default)
			)
			(layer "B.SilkS")
		)
		(fp_line
			(start 0.7874 0.4064)
			(end 0.7874 -0.4064)
			(stroke
				(width 0.1524)
				(type default)
			)
			(layer "B.SilkS")
		)
		(fp_line
			(start -0.7874 0.4064)
			(end 0.7874 0.4064)
			(stroke
				(width 0.1524)
				(type default)
			)
			(layer "B.SilkS")
		)
		(fp_poly
			(pts
				(xy 0.5334 0.254) (xy 0.635 0.254) (xy 0.635 0.2286) (xy 0.635 -0.254) (xy 0.5334 -0.254) (xy 0.5334 -0.2794)
				(xy -0.5334 -0.2794) (xy -0.5334 -0.254) (xy -0.635 -0.254) (xy -0.635 0.254) (xy -0.5334 0.254)
				(xy -0.5334 0.2794) (xy 0.508 0.2794) (xy 0.5334 0.2794)
			)
			(stroke
				(width 0)
				(type default)
			)
			(fill no)
			(layer "B.CrtYd")
		)
		(pad "1" smd rect
			(at -0.40005 0 270)
			(size 0.4572 0.508)
			(layers "B.Cu" "B.Mask" "B.Paste")
			(net "P1V0_NODE1")
		)
		(pad "2" smd rect
			(at 0.40005 0 270)
			(size 0.4572 0.508)
			(layers "B.Cu" "B.Mask" "B.Paste")
			(net "GND")
		)
	)
	(footprint ""
		(layer "B.Cu")
		(at 144.909032 -37.694616)
		(property "Reference" "R1077"
			(at 1.24714 17.425924 0)
			(unlocked yes)
			(layer "B.SilkS")
			(effects
				(font
					(size 0.7874 0.5842)
					(thickness 0.1524)
				)
				(justify left mirror)
			)
		)
		(property "Value" ""
			(at 0 0 0)
			(layer "B.Fab")
			(effects
				(font
					(size 1.27 1.27)
				)
				(justify mirror)
			)
		)
		(duplicate_pad_numbers_are_jumpers no)
		(fp_line
			(start -0.7874 -0.4064)
			(end -0.7874 0.4064)
			(stroke
				(width 0.1524)
				(type default)
			)
			(layer "B.SilkS")
		)
		(fp_line
			(start -0.7874 0.4064)
			(end 0.7874 0.4064)
			(stroke
				(width 0.1524)
				(type default)
			)
			(layer "B.SilkS")
		)
		(fp_line
			(start 0.7874 -0.4064)
			(end -0.7874 -0.4064)
			(stroke
				(width 0.1524)
				(type default)
			)
			(layer "B.SilkS")
		)
		(fp_line
			(start 0.7874 0.4064)
			(end 0.7874 -0.4064)
			(stroke
				(width 0.1524)
				(type default)
			)
			(layer "B.SilkS")
		)
		(fp_poly
			(pts
				(xy 0.508 0.2794) (xy 0.508 0.2286) (xy 0.635 0.2286) (xy 0.635 -0.254) (xy 0.5334 -0.254) (xy 0.5334 -0.2794)
				(xy -0.5334 -0.2794) (xy -0.5334 -0.254) (xy -0.635 -0.254) (xy -0.635 0.254) (xy -0.5334 0.254)
				(xy -0.5334 0.2794)
			)
			(stroke
				(width 0)
				(type default)
			)
			(fill no)
			(layer "B.CrtYd")
		)
		(pad "1" smd rect
			(at -0.40005 0 180)
			(size 0.4572 0.508)
			(layers "B.Cu" "B.Mask" "B.Paste")
			(net "SIO_JTAG_CPLD2_TDI_R")
		)
		(pad "2" smd rect
			(at 0.40005 0 180)
			(size 0.4572 0.508)
			(layers "B.Cu" "B.Mask" "B.Paste")
			(net "P3V3_NODE1")
		)
	)
	(footprint ""
		(layer "B.Cu")
		(at 55.10276 -188.126624 90)
		(property "Reference" "R907"
			(at 4.276598 0.197104 270)
			(unlocked yes)
			(layer "B.SilkS")
			(effects
				(font
					(size 0.7874 0.5842)
					(thickness 0.1524)
				)
				(justify left mirror)
			)
		)
		(property "Value" ""
			(at 0 0 90)
			(layer "B.Fab")
			(effects
				(font
					(size 1.27 1.27)
				)
				(justify mirror)
			)
		)
		(duplicate_pad_numbers_are_jumpers no)
		(fp_line
			(start 0.7874 -0.4064)
			(end -0.7874 -0.4064)
			(stroke
				(width 0.1524)
				(type default)
			)
			(layer "B.SilkS")
		)
		(fp_line
			(start -0.7874 -0.4064)
			(end -0.7874 0.4064)
			(stroke
				(width 0.1524)
				(type default)
			)
			(layer "B.SilkS")
		)
		(fp_line
			(start 0.7874 0.4064)
			(end 0.7874 -0.4064)
			(stroke
				(width 0.1524)
				(type default)
			)
			(layer "B.SilkS")
		)
		(fp_line
			(start -0.7874 0.4064)
			(end 0.7874 0.4064)
			(stroke
				(width 0.1524)
				(type default)
			)
			(layer "B.SilkS")
		)
		(fp_poly
			(pts
				(xy 0.508 0.2794) (xy 0.508 0.2286) (xy 0.635 0.2286) (xy 0.635 -0.254) (xy 0.5334 -0.254) (xy 0.5334 -0.2794)
				(xy -0.5334 -0.2794) (xy -0.5334 -0.254) (xy -0.635 -0.254) (xy -0.635 0.254) (xy -0.5334 0.254)
				(xy -0.5334 0.2794)
			)
			(stroke
				(width 0)
				(type default)
			)
			(fill no)
			(layer "B.CrtYd")
		)
		(pad "1" smd rect
			(at -0.40005 0 270)
			(size 0.4572 0.508)
			(layers "B.Cu" "B.Mask" "B.Paste")
			(net "UART_T1_NODE1_RXD")
		)
		(pad "2" smd rect
			(at 0.40005 0 270)
			(size 0.4572 0.508)
			(layers "B.Cu" "B.Mask" "B.Paste")
			(net "UART_T1_NODE1_RXD_R")
		)
	)
	(footprint ""
		(layer "B.Cu")
		(at 48.758602 -152.128982 180)
		(property "Reference" "C405"
			(at 11.821922 5.554218 0)
			(unlocked yes)
			(layer "B.SilkS")
			(effects
				(font
					(size 0.7874 0.5842)
					(thickness 0.1524)
				)
				(justify left mirror)
			)
		)
		(property "Value" ""
			(at 0 0 0)
			(layer "B.Fab")
			(effects
				(font
					(size 1.27 1.27)
				)
				(justify mirror)
			)
		)
		(duplicate_pad_numbers_are_jumpers no)
		(fp_line
			(start 0.7874 0.4064)
			(end 0.7874 -0.4064)
			(stroke
				(width 0.1524)
				(type default)
			)
			(layer "B.SilkS")
		)
		(fp_line
			(start 0.7874 -0.4064)
			(end -0.7874 -0.4064)
			(stroke
				(width 0.1524)
				(type default)
			)
			(layer "B.SilkS")
		)
		(fp_line
			(start 0 0.381)
			(end 0 -0.381)
			(stroke
				(width 0.1524)
				(type default)
			)
			(layer "B.SilkS")
		)
		(fp_line
			(start -0.7874 0.4064)
			(end 0.7874 0.4064)
			(stroke
				(width 0.1524)
				(type default)
			)
			(layer "B.SilkS")
		)
		(fp_line
			(start -0.7874 -0.4064)
			(end -0.7874 0.4064)
			(stroke
				(width 0.1524)
				(type default)
			)
			(layer "B.SilkS")
		)
		(fp_poly
			(pts
				(xy 0.5334 0.254) (xy 0.635 0.254) (xy 0.635 0.2286) (xy 0.635 -0.254) (xy 0.5334 -0.254) (xy 0.5334 -0.2794)
				(xy -0.5334 -0.2794) (xy -0.5334 -0.254) (xy -0.635 -0.254) (xy -0.635 0.254) (xy -0.5334 0.254)
				(xy -0.5334 0.2794) (xy 0.508 0.2794) (xy 0.5334 0.2794)
			)
			(stroke
				(width 0)
				(type default)
			)
			(fill no)
			(layer "B.CrtYd")
		)
		(pad "1" smd rect
			(at -0.40005 0)
			(size 0.4572 0.508)
			(layers "B.Cu" "B.Mask" "B.Paste")
			(net "P1V9_LAN1")
		)
		(pad "2" smd rect
			(at 0.40005 0)
			(size 0.4572 0.508)
			(layers "B.Cu" "B.Mask" "B.Paste")
			(net "GND")
		)
	)
	(footprint ""
		(layer "B.Cu")
		(at 154.77363 -169.763948 90)
		(property "Reference" "C915"
			(at -4.011422 -0.368046 270)
			(unlocked yes)
			(layer "B.SilkS")
			(effects
				(font
					(size 0.7874 0.5842)
					(thickness 0.1524)
				)
				(justify left mirror)
			)
		)
		(property "Value" ""
			(at 0 0 90)
			(layer "B.Fab")
			(effects
				(font
					(size 1.27 1.27)
				)
				(justify mirror)
			)
		)
		(duplicate_pad_numbers_are_jumpers no)
		(fp_line
			(start 0.7874 -0.4064)
			(end -0.7874 -0.4064)
			(stroke
				(width 0.1524)
				(type default)
			)
			(layer "B.SilkS")
		)
		(fp_line
			(start -0.7874 -0.4064)
			(end -0.7874 0.4064)
			(stroke
				(width 0.1524)
				(type default)
			)
			(layer "B.SilkS")
		)
		(fp_line
			(start 0 0.381)
			(end 0 -0.381)
			(stroke
				(width 0.1524)
				(type default)
			)
			(layer "B.SilkS")
		)
		(fp_line
			(start 0.7874 0.4064)
			(end 0.7874 -0.4064)
			(stroke
				(width 0.1524)
				(type default)
			)
			(layer "B.SilkS")
		)
		(fp_line
			(start -0.7874 0.4064)
			(end 0.7874 0.4064)
			(stroke
				(width 0.1524)
				(type default)
			)
			(layer "B.SilkS")
		)
		(fp_poly
			(pts
				(xy 0.5334 0.254) (xy 0.635 0.254) (xy 0.635 0.2286) (xy 0.635 -0.254) (xy 0.5334 -0.254) (xy 0.5334 -0.2794)
				(xy -0.5334 -0.2794) (xy -0.5334 -0.254) (xy -0.635 -0.254) (xy -0.635 0.254) (xy -0.5334 0.254)
				(xy -0.5334 0.2794) (xy 0.508 0.2794) (xy 0.5334 0.2794)
			)
			(stroke
				(width 0)
				(type default)
			)
			(fill no)
			(layer "B.CrtYd")
		)
		(pad "1" smd rect
			(at -0.40005 0 270)
			(size 0.4572 0.508)
			(layers "B.Cu" "B.Mask" "B.Paste")
			(net "N54365827")
		)
		(pad "2" smd rect
			(at 0.40005 0 270)
			(size 0.4572 0.508)
			(layers "B.Cu" "B.Mask" "B.Paste")
			(net "N54365829")
		)
	)
	(footprint ""
		(layer "B.Cu")
		(at 147.104354 -178.784504 90)
		(property "Reference" "R744"
			(at 1.337818 -0.313944 270)
			(unlocked yes)
			(layer "B.SilkS")
			(effects
				(font
					(size 0.7874 0.5842)
					(thickness 0.1524)
				)
				(justify left mirror)
			)
		)
		(property "Value" ""
			(at 0 0 90)
			(layer "B.Fab")
			(effects
				(font
					(size 1.27 1.27)
				)
				(justify mirror)
			)
		)
		(duplicate_pad_numbers_are_jumpers no)
		(fp_line
			(start 0.7874 -0.4064)
			(end -0.7874 -0.4064)
			(stroke
				(width 0.1524)
				(type default)
			)
			(layer "B.SilkS")
		)
		(fp_line
			(start -0.7874 -0.4064)
			(end -0.7874 0.4064)
			(stroke
				(width 0.1524)
				(type default)
			)
			(layer "B.SilkS")
		)
		(fp_line
			(start 0.7874 0.4064)
			(end 0.7874 -0.4064)
			(stroke
				(width 0.1524)
				(type default)
			)
			(layer "B.SilkS")
		)
		(fp_line
			(start -0.7874 0.4064)
			(end 0.7874 0.4064)
			(stroke
				(width 0.1524)
				(type default)
			)
			(layer "B.SilkS")
		)
		(fp_poly
			(pts
				(xy 0.508 0.2794) (xy 0.508 0.2286) (xy 0.635 0.2286) (xy 0.635 -0.254) (xy 0.5334 -0.254) (xy 0.5334 -0.2794)
				(xy -0.5334 -0.2794) (xy -0.5334 -0.254) (xy -0.635 -0.254) (xy -0.635 0.254) (xy -0.5334 0.254)
				(xy -0.5334 0.2794)
			)
			(stroke
				(width 0)
				(type default)
			)
			(fill no)
			(layer "B.CrtYd")
		)
		(pad "1" smd rect
			(at -0.40005 0 270)
			(size 0.4572 0.508)
			(layers "B.Cu" "B.Mask" "B.Paste")
			(net "T11_NODE3_EN")
		)
		(pad "2" smd rect
			(at 0.40005 0 270)
			(size 0.4572 0.508)
			(layers "B.Cu" "B.Mask" "B.Paste")
			(net "P5V_NODE1")
		)
	)
	(footprint ""
		(layer "B.Cu")
		(at 61.965586 -138.166348)
		(property "Reference" "C244"
			(at -40.418004 52.882546 0)
			(unlocked yes)
			(layer "B.SilkS")
			(effects
				(font
					(size 0.7874 0.5842)
					(thickness 0.1524)
				)
				(justify left mirror)
			)
		)
		(property "Value" ""
			(at 0 0 0)
			(layer "B.Fab")
			(effects
				(font
					(size 1.27 1.27)
				)
				(justify mirror)
			)
		)
		(duplicate_pad_numbers_are_jumpers no)
		(fp_line
			(start -0.7874 -0.4064)
			(end -0.7874 0.4064)
			(stroke
				(width 0.1524)
				(type default)
			)
			(layer "B.SilkS")
		)
		(fp_line
			(start -0.7874 0.4064)
			(end 0.7874 0.4064)
			(stroke
				(width 0.1524)
				(type default)
			)
			(layer "B.SilkS")
		)
		(fp_line
			(start 0 0.381)
			(end 0 -0.381)
			(stroke
				(width 0.1524)
				(type default)
			)
			(layer "B.SilkS")
		)
		(fp_line
			(start 0.7874 -0.4064)
			(end -0.7874 -0.4064)
			(stroke
				(width 0.1524)
				(type default)
			)
			(layer "B.SilkS")
		)
		(fp_line
			(start 0.7874 0.4064)
			(end 0.7874 -0.4064)
			(stroke
				(width 0.1524)
				(type default)
			)
			(layer "B.SilkS")
		)
		(fp_poly
			(pts
				(xy 0.5334 0.254) (xy 0.635 0.254) (xy 0.635 0.2286) (xy 0.635 -0.254) (xy 0.5334 -0.254) (xy 0.5334 -0.2794)
				(xy -0.5334 -0.2794) (xy -0.5334 -0.254) (xy -0.635 -0.254) (xy -0.635 0.254) (xy -0.5334 0.254)
				(xy -0.5334 0.2794) (xy 0.508 0.2794) (xy 0.5334 0.2794)
			)
			(stroke
				(width 0)
				(type default)
			)
			(fill no)
			(layer "B.CrtYd")
		)
		(pad "1" smd rect
			(at -0.40005 0 180)
			(size 0.4572 0.508)
			(layers "B.Cu" "B.Mask" "B.Paste")
			(net "P3V3_NODE1")
		)
		(pad "2" smd rect
			(at 0.40005 0 180)
			(size 0.4572 0.508)
			(layers "B.Cu" "B.Mask" "B.Paste")
			(net "GND")
		)
	)
	(footprint ""
		(layer "B.Cu")
		(at 69.395086 -121.044462 90)
		(property "Reference" "R253"
			(at -7.37235 10.059162 270)
			(unlocked yes)
			(layer "B.SilkS")
			(effects
				(font
					(size 0.7874 0.5842)
					(thickness 0.1524)
				)
				(justify left mirror)
			)
		)
		(property "Value" ""
			(at 0 0 90)
			(layer "B.Fab")
			(effects
				(font
					(size 1.27 1.27)
				)
				(justify mirror)
			)
		)
		(duplicate_pad_numbers_are_jumpers no)
		(fp_line
			(start 0.7874 -0.4064)
			(end -0.7874 -0.4064)
			(stroke
				(width 0.1524)
				(type default)
			)
			(layer "B.SilkS")
		)
		(fp_line
			(start -0.7874 -0.4064)
			(end -0.7874 0.4064)
			(stroke
				(width 0.1524)
				(type default)
			)
			(layer "B.SilkS")
		)
		(fp_line
			(start 0.7874 0.4064)
			(end 0.7874 -0.4064)
			(stroke
				(width 0.1524)
				(type default)
			)
			(layer "B.SilkS")
		)
		(fp_line
			(start -0.7874 0.4064)
			(end 0.7874 0.4064)
			(stroke
				(width 0.1524)
				(type default)
			)
			(layer "B.SilkS")
		)
		(fp_poly
			(pts
				(xy 0.508 0.2794) (xy 0.508 0.2286) (xy 0.635 0.2286) (xy 0.635 -0.254) (xy 0.5334 -0.254) (xy 0.5334 -0.2794)
				(xy -0.5334 -0.2794) (xy -0.5334 -0.254) (xy -0.635 -0.254) (xy -0.635 0.254) (xy -0.5334 0.254)
				(xy -0.5334 0.2794)
			)
			(stroke
				(width 0)
				(type default)
			)
			(fill no)
			(layer "B.CrtYd")
		)
		(pad "1" smd rect
			(at -0.40005 0 270)
			(size 0.4572 0.508)
			(layers "B.Cu" "B.Mask" "B.Paste")
			(net "GND")
		)
		(pad "2" smd rect
			(at 0.40005 0 270)
			(size 0.4572 0.508)
			(layers "B.Cu" "B.Mask" "B.Paste")
			(net "RST_BMC_NODE1_PERST_L")
		)
	)
	(footprint ""
		(layer "B.Cu")
		(at 91.102434 -183.778398 180)
		(property "Reference" "R930"
			(at 2.352294 4.02082 0)
			(unlocked yes)
			(layer "B.SilkS")
			(effects
				(font
					(size 0.7874 0.5842)
					(thickness 0.1524)
				)
				(justify left mirror)
			)
		)
		(property "Value" ""
			(at 0 0 0)
			(layer "B.Fab")
			(effects
				(font
					(size 1.27 1.27)
				)
				(justify mirror)
			)
		)
		(duplicate_pad_numbers_are_jumpers no)
		(fp_line
			(start 0.7874 0.4064)
			(end 0.7874 -0.4064)
			(stroke
				(width 0.1524)
				(type default)
			)
			(layer "B.SilkS")
		)
		(fp_line
			(start 0.7874 -0.4064)
			(end -0.7874 -0.4064)
			(stroke
				(width 0.1524)
				(type default)
			)
			(layer "B.SilkS")
		)
		(fp_line
			(start -0.7874 0.4064)
			(end 0.7874 0.4064)
			(stroke
				(width 0.1524)
				(type default)
			)
			(layer "B.SilkS")
		)
		(fp_line
			(start -0.7874 -0.4064)
			(end -0.7874 0.4064)
			(stroke
				(width 0.1524)
				(type default)
			)
			(layer "B.SilkS")
		)
		(fp_poly
			(pts
				(xy 0.508 0.2794) (xy 0.508 0.2286) (xy 0.635 0.2286) (xy 0.635 -0.254) (xy 0.5334 -0.254) (xy 0.5334 -0.2794)
				(xy -0.5334 -0.2794) (xy -0.5334 -0.254) (xy -0.635 -0.254) (xy -0.635 0.254) (xy -0.5334 0.254)
				(xy -0.5334 0.2794)
			)
			(stroke
				(width 0)
				(type default)
			)
			(fill no)
			(layer "B.CrtYd")
		)
		(pad "1" smd rect
			(at -0.40005 0)
			(size 0.4572 0.508)
			(layers "B.Cu" "B.Mask" "B.Paste")
			(net "UART_T5_NODE4_TXD")
		)
		(pad "2" smd rect
			(at 0.40005 0)
			(size 0.4572 0.508)
			(layers "B.Cu" "B.Mask" "B.Paste")
			(net "UART_T5_NODE4_TXD_R")
		)
	)
	(footprint ""
		(layer "B.Cu")
		(at 171.180252 -98.59899 180)
		(property "Reference" "C368"
			(at -7.70509 0.042672 0)
			(unlocked yes)
			(layer "B.SilkS")
			(effects
				(font
					(size 0.7874 0.5842)
					(thickness 0.1524)
				)
				(justify left mirror)
			)
		)
		(property "Value" ""
			(at 0 0 0)
			(layer "B.Fab")
			(effects
				(font
					(size 1.27 1.27)
				)
				(justify mirror)
			)
		)
		(duplicate_pad_numbers_are_jumpers no)
		(fp_line
			(start 0.7874 0.4064)
			(end 0.7874 -0.4064)
			(stroke
				(width 0.1524)
				(type default)
			)
			(layer "B.SilkS")
		)
		(fp_line
			(start 0.7874 -0.4064)
			(end -0.7874 -0.4064)
			(stroke
				(width 0.1524)
				(type default)
			)
			(layer "B.SilkS")
		)
		(fp_line
			(start 0 0.381)
			(end 0 -0.381)
			(stroke
				(width 0.1524)
				(type default)
			)
			(layer "B.SilkS")
		)
		(fp_line
			(start -0.7874 0.4064)
			(end 0.7874 0.4064)
			(stroke
				(width 0.1524)
				(type default)
			)
			(layer "B.SilkS")
		)
		(fp_line
			(start -0.7874 -0.4064)
			(end -0.7874 0.4064)
			(stroke
				(width 0.1524)
				(type default)
			)
			(layer "B.SilkS")
		)
		(fp_poly
			(pts
				(xy 0.5334 0.254) (xy 0.635 0.254) (xy 0.635 0.2286) (xy 0.635 -0.254) (xy 0.5334 -0.254) (xy 0.5334 -0.2794)
				(xy -0.5334 -0.2794) (xy -0.5334 -0.254) (xy -0.635 -0.254) (xy -0.635 0.254) (xy -0.5334 0.254)
				(xy -0.5334 0.2794) (xy 0.508 0.2794) (xy 0.5334 0.2794)
			)
			(stroke
				(width 0)
				(type default)
			)
			(fill no)
			(layer "B.CrtYd")
		)
		(pad "1" smd rect
			(at -0.40005 0)
			(size 0.4572 0.508)
			(layers "B.Cu" "B.Mask" "B.Paste")
			(net "P1V05_NODE1")
		)
		(pad "2" smd rect
			(at 0.40005 0)
			(size 0.4572 0.508)
			(layers "B.Cu" "B.Mask" "B.Paste")
			(net "GND")
		)
	)
	(footprint ""
		(layer "B.Cu")
		(at 176.550828 -122.886724 90)
		(property "Reference" "C787"
			(at 2.881376 0.888492 270)
			(unlocked yes)
			(layer "B.SilkS")
			(effects
				(font
					(size 0.7874 0.5842)
					(thickness 0.1524)
				)
				(justify mirror)
			)
		)
		(property "Value" ""
			(at 0 0 90)
			(layer "B.Fab")
			(effects
				(font
					(size 1.27 1.27)
				)
				(justify mirror)
			)
		)
		(duplicate_pad_numbers_are_jumpers no)
		(fp_line
			(start 1.2954 -0.5842)
			(end -1.2954 -0.5842)
			(stroke
				(width 0.1524)
				(type default)
			)
			(layer "B.SilkS")
		)
		(fp_line
			(start 0 -0.5842)
			(end 0 0.5842)
			(stroke
				(width 0.1524)
				(type default)
			)
			(layer "B.SilkS")
		)
		(fp_line
			(start -1.2954 -0.5842)
			(end -1.2954 0.5842)
			(stroke
				(width 0.1524)
				(type default)
			)
			(layer "B.SilkS")
		)
		(fp_line
			(start 1.2954 0.5842)
			(end 1.2954 -0.5842)
			(stroke
				(width 0.1524)
				(type default)
			)
			(layer "B.SilkS")
		)
		(fp_line
			(start -1.2954 0.5842)
			(end 1.2954 0.5842)
			(stroke
				(width 0.1524)
				(type default)
			)
			(layer "B.SilkS")
		)
		(fp_poly
			(pts
				(xy -0.8636 -0.4572) (xy -0.8636 -0.3556) (xy -1.143 -0.3556) (xy -1.143 0.3556) (xy -0.8636 0.3556)
				(xy -0.8636 0.4572) (xy 0.8636 0.4572) (xy 0.8636 0.3556) (xy 1.143 0.3556) (xy 1.143 -0.3556) (xy 0.8636 -0.3556)
				(xy 0.8636 -0.4572)
			)
			(stroke
				(width 0)
				(type default)
			)
			(fill no)
			(layer "B.CrtYd")
		)
		(fp_line
			(start 0.884936 -0.504952)
			(end -0.884936 -0.504952)
			(stroke
				(width 0.1)
				(type default)
			)
			(layer "B.Fab")
		)
		(fp_line
			(start -0.884936 -0.504952)
			(end -0.884936 0.504952)
			(stroke
				(width 0.1)
				(type default)
			)
			(layer "B.Fab")
		)
		(fp_line
			(start 0.884936 0.504952)
			(end 0.884936 -0.504952)
			(stroke
				(width 0.1)
				(type default)
			)
			(layer "B.Fab")
		)
		(fp_line
			(start -0.884936 0.504952)
			(end 0.884936 0.504952)
			(stroke
				(width 0.1)
				(type default)
			)
			(layer "B.Fab")
		)
		(pad "1" smd rect
			(at -0.7366 0 180)
			(size 0.7112 0.8128)
			(layers "B.Cu" "B.Mask" "B.Paste")
			(net "P3V3_STB_NODE1")
		)
		(pad "2" smd rect
			(at 0.7366 0 180)
			(size 0.7112 0.8128)
			(layers "B.Cu" "B.Mask" "B.Paste")
			(net "GND")
		)
	)
	(footprint ""
		(layer "B.Cu")
		(at 80.272128 -77.946504)
		(property "Reference" "R118"
			(at 4.055872 0.292862 0)
			(unlocked yes)
			(layer "B.SilkS")
			(effects
				(font
					(size 0.7874 0.5842)
					(thickness 0.1524)
				)
				(justify left mirror)
			)
		)
		(property "Value" ""
			(at 0 0 0)
			(layer "B.Fab")
			(effects
				(font
					(size 1.27 1.27)
				)
				(justify mirror)
			)
		)
		(duplicate_pad_numbers_are_jumpers no)
		(fp_line
			(start -0.7874 -0.4064)
			(end -0.7874 0.4064)
			(stroke
				(width 0.1524)
				(type default)
			)
			(layer "B.SilkS")
		)
		(fp_line
			(start -0.7874 0.4064)
			(end 0.7874 0.4064)
			(stroke
				(width 0.1524)
				(type default)
			)
			(layer "B.SilkS")
		)
		(fp_line
			(start 0.7874 -0.4064)
			(end -0.7874 -0.4064)
			(stroke
				(width 0.1524)
				(type default)
			)
			(layer "B.SilkS")
		)
		(fp_line
			(start 0.7874 0.4064)
			(end 0.7874 -0.4064)
			(stroke
				(width 0.1524)
				(type default)
			)
			(layer "B.SilkS")
		)
		(fp_poly
			(pts
				(xy 0.508 0.2794) (xy 0.508 0.2286) (xy 0.635 0.2286) (xy 0.635 -0.254) (xy 0.5334 -0.254) (xy 0.5334 -0.2794)
				(xy -0.5334 -0.2794) (xy -0.5334 -0.254) (xy -0.635 -0.254) (xy -0.635 0.254) (xy -0.5334 0.254)
				(xy -0.5334 0.2794)
			)
			(stroke
				(width 0)
				(type default)
			)
			(fill no)
			(layer "B.CrtYd")
		)
		(pad "1" smd rect
			(at -0.40005 0 180)
			(size 0.4572 0.508)
			(layers "B.Cu" "B.Mask" "B.Paste")
			(net "SVID_CPU_NODE1_PVCCP_ALERT_R_L")
		)
		(pad "2" smd rect
			(at 0.40005 0 180)
			(size 0.4572 0.508)
			(layers "B.Cu" "B.Mask" "B.Paste")
			(net "SVID_CPU_NODE1_PVCCP_ALERT_L")
		)
	)
	(footprint ""
		(layer "B.Cu")
		(at 165.210998 -152.84323 180)
		(property "Reference" "C453"
			(at 1.075182 -0.208534 0)
			(unlocked yes)
			(layer "B.SilkS")
			(effects
				(font
					(size 0.7874 0.5842)
					(thickness 0.1524)
				)
				(justify left mirror)
			)
		)
		(property "Value" ""
			(at 0 0 0)
			(layer "B.Fab")
			(effects
				(font
					(size 1.27 1.27)
				)
				(justify mirror)
			)
		)
		(duplicate_pad_numbers_are_jumpers no)
		(fp_line
			(start 0.7874 0.4064)
			(end 0.7874 -0.4064)
			(stroke
				(width 0.1524)
				(type default)
			)
			(layer "B.SilkS")
		)
		(fp_line
			(start 0.7874 -0.4064)
			(end -0.7874 -0.4064)
			(stroke
				(width 0.1524)
				(type default)
			)
			(layer "B.SilkS")
		)
		(fp_line
			(start 0 0.381)
			(end 0 -0.381)
			(stroke
				(width 0.1524)
				(type default)
			)
			(layer "B.SilkS")
		)
		(fp_line
			(start -0.7874 0.4064)
			(end 0.7874 0.4064)
			(stroke
				(width 0.1524)
				(type default)
			)
			(layer "B.SilkS")
		)
		(fp_line
			(start -0.7874 -0.4064)
			(end -0.7874 0.4064)
			(stroke
				(width 0.1524)
				(type default)
			)
			(layer "B.SilkS")
		)
		(fp_poly
			(pts
				(xy 0.5334 0.254) (xy 0.635 0.254) (xy 0.635 0.2286) (xy 0.635 -0.254) (xy 0.5334 -0.254) (xy 0.5334 -0.2794)
				(xy -0.5334 -0.2794) (xy -0.5334 -0.254) (xy -0.635 -0.254) (xy -0.635 0.254) (xy -0.5334 0.254)
				(xy -0.5334 0.2794) (xy 0.508 0.2794) (xy 0.5334 0.2794)
			)
			(stroke
				(width 0)
				(type default)
			)
			(fill no)
			(layer "B.CrtYd")
		)
		(pad "1" smd rect
			(at -0.40005 0)
			(size 0.4572 0.508)
			(layers "B.Cu" "B.Mask" "B.Paste")
			(net "P1V9_LAN2")
		)
		(pad "2" smd rect
			(at 0.40005 0)
			(size 0.4572 0.508)
			(layers "B.Cu" "B.Mask" "B.Paste")
			(net "GND")
		)
	)
	(footprint ""
		(layer "B.Cu")
		(at 122.0978 -41.684702)
		(property "Reference" "R185"
			(at -2.808732 0.279146 0)
			(unlocked yes)
			(layer "B.SilkS")
			(effects
				(font
					(size 0.7874 0.5842)
					(thickness 0.1524)
				)
				(justify left mirror)
			)
		)
		(property "Value" ""
			(at 0 0 0)
			(layer "B.Fab")
			(effects
				(font
					(size 1.27 1.27)
				)
				(justify mirror)
			)
		)
		(duplicate_pad_numbers_are_jumpers no)
		(fp_line
			(start -0.7874 -0.406146)
			(end -0.7874 0.406146)
			(stroke
				(width 0.1524)
				(type default)
			)
			(layer "B.SilkS")
		)
		(fp_line
			(start -0.7874 0.406146)
			(end 0.7874 0.406146)
			(stroke
				(width 0.1524)
				(type default)
			)
			(layer "B.SilkS")
		)
		(fp_line
			(start 0.7874 -0.406146)
			(end -0.7874 -0.406146)
			(stroke
				(width 0.1524)
				(type default)
			)
			(layer "B.SilkS")
		)
		(fp_line
			(start 0.7874 0.406146)
			(end 0.7874 -0.406146)
			(stroke
				(width 0.1524)
				(type default)
			)
			(layer "B.SilkS")
		)
		(fp_poly
			(pts
				(xy 0.508 0.2794) (xy 0.508 0.2286) (xy 0.635 0.2286) (xy 0.635 -0.254) (xy 0.5334 -0.254) (xy 0.5334 -0.2794)
				(xy -0.5334 -0.2794) (xy -0.5334 -0.254) (xy -0.635 -0.254) (xy -0.635 0.254) (xy -0.5334 0.254)
				(xy -0.5334 0.2794)
			)
			(stroke
				(width 0)
				(type default)
			)
			(fill no)
			(layer "B.CrtYd")
		)
		(pad "1" smd rect
			(at -0.40005 0 180)
			(size 0.4572 0.508)
			(layers "B.Cu" "B.Mask" "B.Paste")
			(net "LPC_CPU_NODE1_LAD3")
		)
		(pad "2" smd rect
			(at 0.40005 0 180)
			(size 0.4572 0.508)
			(layers "B.Cu" "B.Mask" "B.Paste")
			(net "LPC_CPU_NODE1_LAD3_SIO")
		)
	)
	(footprint ""
		(layer "B.Cu")
		(at 77.07376 -188.126624 -90)
		(property "Reference" "C652"
			(at -4.151884 0.22098 270)
			(unlocked yes)
			(layer "B.SilkS")
			(effects
				(font
					(size 0.7874 0.5842)
					(thickness 0.1524)
				)
				(justify left mirror)
			)
		)
		(property "Value" ""
			(at 0 0 90)
			(layer "B.Fab")
			(effects
				(font
					(size 1.27 1.27)
				)
				(justify mirror)
			)
		)
		(duplicate_pad_numbers_are_jumpers no)
		(fp_line
			(start -0.7874 0.4064)
			(end 0.7874 0.4064)
			(stroke
				(width 0.1524)
				(type default)
			)
			(layer "B.SilkS")
		)
		(fp_line
			(start 0.7874 0.4064)
			(end 0.7874 -0.4064)
			(stroke
				(width 0.1524)
				(type default)
			)
			(layer "B.SilkS")
		)
		(fp_line
			(start 0 0.381)
			(end 0 -0.381)
			(stroke
				(width 0.1524)
				(type default)
			)
			(layer "B.SilkS")
		)
		(fp_line
			(start -0.7874 -0.4064)
			(end -0.7874 0.4064)
			(stroke
				(width 0.1524)
				(type default)
			)
			(layer "B.SilkS")
		)
		(fp_line
			(start 0.7874 -0.4064)
			(end -0.7874 -0.4064)
			(stroke
				(width 0.1524)
				(type default)
			)
			(layer "B.SilkS")
		)
		(fp_poly
			(pts
				(xy 0.5334 0.254) (xy 0.635 0.254) (xy 0.635 0.2286) (xy 0.635 -0.254) (xy 0.5334 -0.254) (xy 0.5334 -0.2794)
				(xy -0.5334 -0.2794) (xy -0.5334 -0.254) (xy -0.635 -0.254) (xy -0.635 0.254) (xy -0.5334 0.254)
				(xy -0.5334 0.2794) (xy 0.508 0.2794) (xy 0.5334 0.2794)
			)
			(stroke
				(width 0)
				(type default)
			)
			(fill no)
			(layer "B.CrtYd")
		)
		(pad "1" smd rect
			(at -0.40005 0 90)
			(size 0.4572 0.508)
			(layers "B.Cu" "B.Mask" "B.Paste")
			(net "T3_NODE3_EN_R")
		)
		(pad "2" smd rect
			(at 0.40005 0 90)
			(size 0.4572 0.508)
			(layers "B.Cu" "B.Mask" "B.Paste")
			(net "GND")
		)
	)
	(footprint ""
		(layer "B.Cu")
		(at 159.801814 -49.607978)
		(property "Reference" "C494"
			(at 1.435608 -2.73304 0)
			(unlocked yes)
			(layer "B.SilkS")
			(effects
				(font
					(size 0.7874 0.5842)
					(thickness 0.1524)
				)
				(justify left mirror)
			)
		)
		(property "Value" ""
			(at 0 0 0)
			(layer "B.Fab")
			(effects
				(font
					(size 1.27 1.27)
				)
				(justify mirror)
			)
		)
		(duplicate_pad_numbers_are_jumpers no)
		(fp_line
			(start -0.7874 -0.4064)
			(end -0.7874 0.4064)
			(stroke
				(width 0.1524)
				(type default)
			)
			(layer "B.SilkS")
		)
		(fp_line
			(start -0.7874 0.4064)
			(end 0.7874 0.4064)
			(stroke
				(width 0.1524)
				(type default)
			)
			(layer "B.SilkS")
		)
		(fp_line
			(start 0 0.381)
			(end 0 -0.381)
			(stroke
				(width 0.1524)
				(type default)
			)
			(layer "B.SilkS")
		)
		(fp_line
			(start 0.7874 -0.4064)
			(end -0.7874 -0.4064)
			(stroke
				(width 0.1524)
				(type default)
			)
			(layer "B.SilkS")
		)
		(fp_line
			(start 0.7874 0.4064)
			(end 0.7874 -0.4064)
			(stroke
				(width 0.1524)
				(type default)
			)
			(layer "B.SilkS")
		)
		(fp_poly
			(pts
				(xy 0.5334 0.254) (xy 0.635 0.254) (xy 0.635 0.2286) (xy 0.635 -0.254) (xy 0.5334 -0.254) (xy 0.5334 -0.2794)
				(xy -0.5334 -0.2794) (xy -0.5334 -0.254) (xy -0.635 -0.254) (xy -0.635 0.254) (xy -0.5334 0.254)
				(xy -0.5334 0.2794) (xy 0.508 0.2794) (xy 0.5334 0.2794)
			)
			(stroke
				(width 0)
				(type default)
			)
			(fill no)
			(layer "B.CrtYd")
		)
		(pad "1" smd rect
			(at -0.40005 0 180)
			(size 0.4572 0.508)
			(layers "B.Cu" "B.Mask" "B.Paste")
			(net "SATA_RX0_C_DN")
		)
		(pad "2" smd rect
			(at 0.40005 0 180)
			(size 0.4572 0.508)
			(layers "B.Cu" "B.Mask" "B.Paste")
			(net "SATA_A_NODE1_RX_N0")
		)
	)
	(footprint ""
		(layer "B.Cu")
		(at 135.196834 -35.343084)
		(property "Reference" "R1183"
			(at -5.415788 18.464784 0)
			(unlocked yes)
			(layer "B.SilkS")
			(effects
				(font
					(size 0.7874 0.5842)
					(thickness 0.1524)
				)
				(justify left mirror)
			)
		)
		(property "Value" ""
			(at 0 0 0)
			(layer "B.Fab")
			(effects
				(font
					(size 1.27 1.27)
				)
				(justify mirror)
			)
		)
		(duplicate_pad_numbers_are_jumpers no)
		(fp_line
			(start -0.7874 -0.4064)
			(end -0.7874 0.4064)
			(stroke
				(width 0.1524)
				(type default)
			)
			(layer "B.SilkS")
		)
		(fp_line
			(start -0.7874 0.4064)
			(end 0.7874 0.4064)
			(stroke
				(width 0.1524)
				(type default)
			)
			(layer "B.SilkS")
		)
		(fp_line
			(start 0.7874 -0.4064)
			(end -0.7874 -0.4064)
			(stroke
				(width 0.1524)
				(type default)
			)
			(layer "B.SilkS")
		)
		(fp_line
			(start 0.7874 0.4064)
			(end 0.7874 -0.4064)
			(stroke
				(width 0.1524)
				(type default)
			)
			(layer "B.SilkS")
		)
		(fp_poly
			(pts
				(xy 0.508 0.2794) (xy 0.508 0.2286) (xy 0.635 0.2286) (xy 0.635 -0.254) (xy 0.5334 -0.254) (xy 0.5334 -0.2794)
				(xy -0.5334 -0.2794) (xy -0.5334 -0.254) (xy -0.635 -0.254) (xy -0.635 0.254) (xy -0.5334 0.254)
				(xy -0.5334 0.2794)
			)
			(stroke
				(width 0)
				(type default)
			)
			(fill no)
			(layer "B.CrtYd")
		)
		(pad "1" smd rect
			(at -0.40005 0 180)
			(size 0.4572 0.508)
			(layers "B.Cu" "B.Mask" "B.Paste")
			(net "CPLD123_RSV2")
		)
		(pad "2" smd rect
			(at 0.40005 0 180)
			(size 0.4572 0.508)
			(layers "B.Cu" "B.Mask" "B.Paste")
			(net "SIO_CPLD_RSV2_R")
		)
	)
	(footprint ""
		(layer "B.Cu")
		(at 65.721992 -129.79146 -90)
		(property "Reference" "R328"
			(at 56.331866 41.181274 270)
			(unlocked yes)
			(layer "B.SilkS")
			(effects
				(font
					(size 0.7874 0.5842)
					(thickness 0.1524)
				)
				(justify left mirror)
			)
		)
		(property "Value" ""
			(at 0 0 90)
			(layer "B.Fab")
			(effects
				(font
					(size 1.27 1.27)
				)
				(justify mirror)
			)
		)
		(duplicate_pad_numbers_are_jumpers no)
		(fp_line
			(start -0.7874 0.4064)
			(end 0.7874 0.4064)
			(stroke
				(width 0.1524)
				(type default)
			)
			(layer "B.SilkS")
		)
		(fp_line
			(start 0.7874 0.4064)
			(end 0.7874 -0.4064)
			(stroke
				(width 0.1524)
				(type default)
			)
			(layer "B.SilkS")
		)
		(fp_line
			(start -0.7874 -0.4064)
			(end -0.7874 0.4064)
			(stroke
				(width 0.1524)
				(type default)
			)
			(layer "B.SilkS")
		)
		(fp_line
			(start 0.7874 -0.4064)
			(end -0.7874 -0.4064)
			(stroke
				(width 0.1524)
				(type default)
			)
			(layer "B.SilkS")
		)
		(fp_poly
			(pts
				(xy 0.508 0.2794) (xy 0.508 0.2286) (xy 0.635 0.2286) (xy 0.635 -0.254) (xy 0.5334 -0.254) (xy 0.5334 -0.2794)
				(xy -0.5334 -0.2794) (xy -0.5334 -0.254) (xy -0.635 -0.254) (xy -0.635 0.254) (xy -0.5334 0.254)
				(xy -0.5334 0.2794)
			)
			(stroke
				(width 0)
				(type default)
			)
			(fill no)
			(layer "B.CrtYd")
		)
		(pad "1" smd rect
			(at -0.40005 0 90)
			(size 0.4572 0.508)
			(layers "B.Cu" "B.Mask" "B.Paste")
			(net "P3V3_NODE1")
		)
		(pad "2" smd rect
			(at 0.40005 0 90)
			(size 0.4572 0.508)
			(layers "B.Cu" "B.Mask" "B.Paste")
			(net "BMC_ROMA12")
		)
	)
	(footprint ""
		(layer "B.Cu")
		(at 138.79576 -184.951624 90)
		(property "Reference" "R864"
			(at 4.357624 -2.004568 270)
			(unlocked yes)
			(layer "B.SilkS")
			(effects
				(font
					(size 0.7874 0.5842)
					(thickness 0.1524)
				)
				(justify left mirror)
			)
		)
		(property "Value" ""
			(at 0 0 90)
			(layer "B.Fab")
			(effects
				(font
					(size 1.27 1.27)
				)
				(justify mirror)
			)
		)
		(duplicate_pad_numbers_are_jumpers no)
		(fp_line
			(start 0.7874 -0.4064)
			(end -0.7874 -0.4064)
			(stroke
				(width 0.1524)
				(type default)
			)
			(layer "B.SilkS")
		)
		(fp_line
			(start -0.7874 -0.4064)
			(end -0.7874 0.4064)
			(stroke
				(width 0.1524)
				(type default)
			)
			(layer "B.SilkS")
		)
		(fp_line
			(start 0.7874 0.4064)
			(end 0.7874 -0.4064)
			(stroke
				(width 0.1524)
				(type default)
			)
			(layer "B.SilkS")
		)
		(fp_line
			(start -0.7874 0.4064)
			(end 0.7874 0.4064)
			(stroke
				(width 0.1524)
				(type default)
			)
			(layer "B.SilkS")
		)
		(fp_poly
			(pts
				(xy 0.508 0.2794) (xy 0.508 0.2286) (xy 0.635 0.2286) (xy 0.635 -0.254) (xy 0.5334 -0.254) (xy 0.5334 -0.2794)
				(xy -0.5334 -0.2794) (xy -0.5334 -0.254) (xy -0.635 -0.254) (xy -0.635 0.254) (xy -0.5334 0.254)
				(xy -0.5334 0.2794)
			)
			(stroke
				(width 0)
				(type default)
			)
			(fill no)
			(layer "B.CrtYd")
		)
		(pad "1" smd rect
			(at -0.40005 0 270)
			(size 0.4572 0.508)
			(layers "B.Cu" "B.Mask" "B.Paste")
			(net "T9_NODE2_EN")
		)
		(pad "2" smd rect
			(at 0.40005 0 270)
			(size 0.4572 0.508)
			(layers "B.Cu" "B.Mask" "B.Paste")
			(net "T9_NODE2_EN_R")
		)
	)
	(footprint ""
		(layer "B.Cu")
		(at 77.63256 -185.259218 90)
		(property "Reference" "R889"
			(at 3.766566 0.076454 270)
			(unlocked yes)
			(layer "B.SilkS")
			(effects
				(font
					(size 0.7874 0.5842)
					(thickness 0.1524)
				)
				(justify left mirror)
			)
		)
		(property "Value" ""
			(at 0 0 90)
			(layer "B.Fab")
			(effects
				(font
					(size 1.27 1.27)
				)
				(justify mirror)
			)
		)
		(duplicate_pad_numbers_are_jumpers no)
		(fp_line
			(start 0.7874 -0.4064)
			(end -0.7874 -0.4064)
			(stroke
				(width 0.1524)
				(type default)
			)
			(layer "B.SilkS")
		)
		(fp_line
			(start -0.7874 -0.4064)
			(end -0.7874 0.4064)
			(stroke
				(width 0.1524)
				(type default)
			)
			(layer "B.SilkS")
		)
		(fp_line
			(start 0.7874 0.4064)
			(end 0.7874 -0.4064)
			(stroke
				(width 0.1524)
				(type default)
			)
			(layer "B.SilkS")
		)
		(fp_line
			(start -0.7874 0.4064)
			(end 0.7874 0.4064)
			(stroke
				(width 0.1524)
				(type default)
			)
			(layer "B.SilkS")
		)
		(fp_poly
			(pts
				(xy 0.508 0.2794) (xy 0.508 0.2286) (xy 0.635 0.2286) (xy 0.635 -0.254) (xy 0.5334 -0.254) (xy 0.5334 -0.2794)
				(xy -0.5334 -0.2794) (xy -0.5334 -0.254) (xy -0.635 -0.254) (xy -0.635 0.254) (xy -0.5334 0.254)
				(xy -0.5334 0.2794)
			)
			(stroke
				(width 0)
				(type default)
			)
			(fill no)
			(layer "B.CrtYd")
		)
		(pad "1" smd rect
			(at -0.40005 0 270)
			(size 0.4572 0.508)
			(layers "B.Cu" "B.Mask" "B.Paste")
			(net "T3_NODE3_EN")
		)
		(pad "2" smd rect
			(at 0.40005 0 270)
			(size 0.4572 0.508)
			(layers "B.Cu" "B.Mask" "B.Paste")
			(net "T3_NODE3_EN_R")
		)
	)
	(footprint ""
		(layer "B.Cu")
		(at 105.191814 -104.85882)
		(property "Reference" "PC116"
			(at -3.119374 -0.397002 0)
			(unlocked yes)
			(layer "B.SilkS")
			(effects
				(font
					(size 0.7874 0.5842)
					(thickness 0.1524)
				)
				(justify left mirror)
			)
		)
		(property "Value" ""
			(at 0 0 0)
			(layer "B.Fab")
			(effects
				(font
					(size 1.27 1.27)
				)
				(justify mirror)
			)
		)
		(duplicate_pad_numbers_are_jumpers no)
		(fp_line
			(start -1.905 -0.8636)
			(end -1.905 0.8636)
			(stroke
				(width 0.1524)
				(type default)
			)
			(layer "B.SilkS")
		)
		(fp_line
			(start -1.905 0.8636)
			(end 1.905 0.8636)
			(stroke
				(width 0.1524)
				(type default)
			)
			(layer "B.SilkS")
		)
		(fp_line
			(start 0 0.8382)
			(end 0 -0.8382)
			(stroke
				(width 0.1524)
				(type default)
			)
			(layer "B.SilkS")
		)
		(fp_line
			(start 1.905 -0.8636)
			(end -1.905 -0.8636)
			(stroke
				(width 0.1524)
				(type default)
			)
			(layer "B.SilkS")
		)
		(fp_line
			(start 1.905 0.8636)
			(end 1.905 -0.8636)
			(stroke
				(width 0.1524)
				(type default)
			)
			(layer "B.SilkS")
		)
		(fp_rect
			(start 1.524 0.7366)
			(end -1.524 -0.7366)
			(stroke
				(width 0)
				(type default)
			)
			(fill no)
			(layer "B.CrtYd")
		)
		(pad "1" smd rect
			(at -0.94996 0 180)
			(size 1.1176 1.3716)
			(layers "B.Cu" "B.Mask" "B.Paste")
			(net "GND")
		)
		(pad "2" smd rect
			(at 0.94996 0 180)
			(size 1.1176 1.3716)
			(layers "B.Cu" "B.Mask" "B.Paste")
			(net "PV_VCCP_NODE1")
		)
	)
	(footprint ""
		(layer "B.Cu")
		(at 74.906886 -148.476462 90)
		(property "Reference" "R293"
			(at -1.530858 1.004824 270)
			(unlocked yes)
			(layer "B.SilkS")
			(effects
				(font
					(size 0.7874 0.5842)
					(thickness 0.1524)
				)
				(justify left mirror)
			)
		)
		(property "Value" ""
			(at 0 0 90)
			(layer "B.Fab")
			(effects
				(font
					(size 1.27 1.27)
				)
				(justify mirror)
			)
		)
		(duplicate_pad_numbers_are_jumpers no)
		(fp_line
			(start 0.7874 -0.4064)
			(end -0.7874 -0.4064)
			(stroke
				(width 0.1524)
				(type default)
			)
			(layer "B.SilkS")
		)
		(fp_line
			(start -0.7874 -0.4064)
			(end -0.7874 0.4064)
			(stroke
				(width 0.1524)
				(type default)
			)
			(layer "B.SilkS")
		)
		(fp_line
			(start 0.7874 0.4064)
			(end 0.7874 -0.4064)
			(stroke
				(width 0.1524)
				(type default)
			)
			(layer "B.SilkS")
		)
		(fp_line
			(start -0.7874 0.4064)
			(end 0.7874 0.4064)
			(stroke
				(width 0.1524)
				(type default)
			)
			(layer "B.SilkS")
		)
		(fp_poly
			(pts
				(xy 0.508 0.2794) (xy 0.508 0.2286) (xy 0.635 0.2286) (xy 0.635 -0.254) (xy 0.5334 -0.254) (xy 0.5334 -0.2794)
				(xy -0.5334 -0.2794) (xy -0.5334 -0.254) (xy -0.635 -0.254) (xy -0.635 0.254) (xy -0.5334 0.254)
				(xy -0.5334 0.2794)
			)
			(stroke
				(width 0)
				(type default)
			)
			(fill no)
			(layer "B.CrtYd")
		)
		(pad "1" smd rect
			(at -0.40005 0 270)
			(size 0.4572 0.508)
			(layers "B.Cu" "B.Mask" "B.Paste")
			(net "N20822523")
		)
		(pad "2" smd rect
			(at 0.40005 0 270)
			(size 0.4572 0.508)
			(layers "B.Cu" "B.Mask" "B.Paste")
			(net "GND")
		)
	)
	(footprint ""
		(layer "B.Cu")
		(at 159.801814 -50.623978)
		(property "Reference" "C492"
			(at 1.435608 -2.73304 0)
			(unlocked yes)
			(layer "B.SilkS")
			(effects
				(font
					(size 0.7874 0.5842)
					(thickness 0.1524)
				)
				(justify left mirror)
			)
		)
		(property "Value" ""
			(at 0 0 0)
			(layer "B.Fab")
			(effects
				(font
					(size 1.27 1.27)
				)
				(justify mirror)
			)
		)
		(duplicate_pad_numbers_are_jumpers no)
		(fp_line
			(start -0.7874 -0.4064)
			(end -0.7874 0.4064)
			(stroke
				(width 0.1524)
				(type default)
			)
			(layer "B.SilkS")
		)
		(fp_line
			(start -0.7874 0.4064)
			(end 0.7874 0.4064)
			(stroke
				(width 0.1524)
				(type default)
			)
			(layer "B.SilkS")
		)
		(fp_line
			(start 0 0.381)
			(end 0 -0.381)
			(stroke
				(width 0.1524)
				(type default)
			)
			(layer "B.SilkS")
		)
		(fp_line
			(start 0.7874 -0.4064)
			(end -0.7874 -0.4064)
			(stroke
				(width 0.1524)
				(type default)
			)
			(layer "B.SilkS")
		)
		(fp_line
			(start 0.7874 0.4064)
			(end 0.7874 -0.4064)
			(stroke
				(width 0.1524)
				(type default)
			)
			(layer "B.SilkS")
		)
		(fp_poly
			(pts
				(xy 0.5334 0.254) (xy 0.635 0.254) (xy 0.635 0.2286) (xy 0.635 -0.254) (xy 0.5334 -0.254) (xy 0.5334 -0.2794)
				(xy -0.5334 -0.2794) (xy -0.5334 -0.254) (xy -0.635 -0.254) (xy -0.635 0.254) (xy -0.5334 0.254)
				(xy -0.5334 0.2794) (xy 0.508 0.2794) (xy 0.5334 0.2794)
			)
			(stroke
				(width 0)
				(type default)
			)
			(fill no)
			(layer "B.CrtYd")
		)
		(pad "1" smd rect
			(at -0.40005 0 180)
			(size 0.4572 0.508)
			(layers "B.Cu" "B.Mask" "B.Paste")
			(net "SATA_RX0_C_DP")
		)
		(pad "2" smd rect
			(at 0.40005 0 180)
			(size 0.4572 0.508)
			(layers "B.Cu" "B.Mask" "B.Paste")
			(net "SATA_A_NODE1_RX_P0")
		)
	)
	(footprint ""
		(layer "B.Cu")
		(at 58.019188 -55.092854)
		(property "Reference" "R33"
			(at 3.14579 0.043688 0)
			(unlocked yes)
			(layer "B.SilkS")
			(effects
				(font
					(size 0.7874 0.5842)
					(thickness 0.1524)
				)
				(justify left mirror)
			)
		)
		(property "Value" ""
			(at 0 0 0)
			(layer "B.Fab")
			(effects
				(font
					(size 1.27 1.27)
				)
				(justify mirror)
			)
		)
		(duplicate_pad_numbers_are_jumpers no)
		(fp_line
			(start -0.7874 -0.4064)
			(end -0.7874 0.4064)
			(stroke
				(width 0.1524)
				(type default)
			)
			(layer "B.SilkS")
		)
		(fp_line
			(start -0.7874 0.4064)
			(end 0.7874 0.4064)
			(stroke
				(width 0.1524)
				(type default)
			)
			(layer "B.SilkS")
		)
		(fp_line
			(start 0.7874 -0.4064)
			(end -0.7874 -0.4064)
			(stroke
				(width 0.1524)
				(type default)
			)
			(layer "B.SilkS")
		)
		(fp_line
			(start 0.7874 0.4064)
			(end 0.7874 -0.4064)
			(stroke
				(width 0.1524)
				(type default)
			)
			(layer "B.SilkS")
		)
		(fp_poly
			(pts
				(xy 0.508 0.2794) (xy 0.508 0.2286) (xy 0.635 0.2286) (xy 0.635 -0.254) (xy 0.5334 -0.254) (xy 0.5334 -0.2794)
				(xy -0.5334 -0.2794) (xy -0.5334 -0.254) (xy -0.635 -0.254) (xy -0.635 0.254) (xy -0.5334 0.254)
				(xy -0.5334 0.2794)
			)
			(stroke
				(width 0)
				(type default)
			)
			(fill no)
			(layer "B.CrtYd")
		)
		(pad "1" smd rect
			(at -0.40005 0 180)
			(size 0.4572 0.508)
			(layers "B.Cu" "B.Mask" "B.Paste")
			(net "M_DDR3_NODE1_MON1P")
		)
		(pad "2" smd rect
			(at 0.40005 0 180)
			(size 0.4572 0.508)
			(layers "B.Cu" "B.Mask" "B.Paste")
			(net "M_DDR3_NODE1_MON1N")
		)
	)
	(footprint ""
		(layer "B.Cu")
		(at 156.123894 -177.13833 180)
		(property "Reference" "R1306"
			(at -2.20345 2.11074 0)
			(unlocked yes)
			(layer "B.SilkS")
			(effects
				(font
					(size 0.7874 0.5842)
					(thickness 0.1524)
				)
				(justify left mirror)
			)
		)
		(property "Value" ""
			(at 0 0 0)
			(layer "B.Fab")
			(effects
				(font
					(size 1.27 1.27)
				)
				(justify mirror)
			)
		)
		(duplicate_pad_numbers_are_jumpers no)
		(fp_line
			(start 0.7874 0.4064)
			(end 0.7874 -0.4064)
			(stroke
				(width 0.1524)
				(type default)
			)
			(layer "B.SilkS")
		)
		(fp_line
			(start 0.7874 -0.4064)
			(end -0.7874 -0.4064)
			(stroke
				(width 0.1524)
				(type default)
			)
			(layer "B.SilkS")
		)
		(fp_line
			(start -0.7874 0.4064)
			(end 0.7874 0.4064)
			(stroke
				(width 0.1524)
				(type default)
			)
			(layer "B.SilkS")
		)
		(fp_line
			(start -0.7874 -0.4064)
			(end -0.7874 0.4064)
			(stroke
				(width 0.1524)
				(type default)
			)
			(layer "B.SilkS")
		)
		(fp_poly
			(pts
				(xy 0.508 0.2794) (xy 0.508 0.2286) (xy 0.635 0.2286) (xy 0.635 -0.254) (xy 0.5334 -0.254) (xy 0.5334 -0.2794)
				(xy -0.5334 -0.2794) (xy -0.5334 -0.254) (xy -0.635 -0.254) (xy -0.635 0.254) (xy -0.5334 0.254)
				(xy -0.5334 0.2794)
			)
			(stroke
				(width 0)
				(type default)
			)
			(fill no)
			(layer "B.CrtYd")
		)
		(pad "1" smd rect
			(at -0.40005 0)
			(size 0.4572 0.508)
			(layers "B.Cu" "B.Mask" "B.Paste")
			(net "GND")
		)
		(pad "2" smd rect
			(at 0.40005 0)
			(size 0.4572 0.508)
			(layers "B.Cu" "B.Mask" "B.Paste")
			(net "N54365764")
		)
	)
	(footprint ""
		(layer "B.Cu")
		(at 145.65376 -184.951624 90)
		(property "Reference" "R966"
			(at 4.357624 -2.55905 270)
			(unlocked yes)
			(layer "B.SilkS")
			(effects
				(font
					(size 0.7874 0.5842)
					(thickness 0.1524)
				)
				(justify left mirror)
			)
		)
		(property "Value" ""
			(at 0 0 90)
			(layer "B.Fab")
			(effects
				(font
					(size 1.27 1.27)
				)
				(justify mirror)
			)
		)
		(duplicate_pad_numbers_are_jumpers no)
		(fp_line
			(start 0.7874 -0.4064)
			(end -0.7874 -0.4064)
			(stroke
				(width 0.1524)
				(type default)
			)
			(layer "B.SilkS")
		)
		(fp_line
			(start -0.7874 -0.4064)
			(end -0.7874 0.4064)
			(stroke
				(width 0.1524)
				(type default)
			)
			(layer "B.SilkS")
		)
		(fp_line
			(start 0.7874 0.4064)
			(end 0.7874 -0.4064)
			(stroke
				(width 0.1524)
				(type default)
			)
			(layer "B.SilkS")
		)
		(fp_line
			(start -0.7874 0.4064)
			(end 0.7874 0.4064)
			(stroke
				(width 0.1524)
				(type default)
			)
			(layer "B.SilkS")
		)
		(fp_poly
			(pts
				(xy 0.508 0.2794) (xy 0.508 0.2286) (xy 0.635 0.2286) (xy 0.635 -0.254) (xy 0.5334 -0.254) (xy 0.5334 -0.2794)
				(xy -0.5334 -0.2794) (xy -0.5334 -0.254) (xy -0.635 -0.254) (xy -0.635 0.254) (xy -0.5334 0.254)
				(xy -0.5334 0.2794)
			)
			(stroke
				(width 0)
				(type default)
			)
			(fill no)
			(layer "B.CrtYd")
		)
		(pad "1" smd rect
			(at -0.40005 0 270)
			(size 0.4572 0.508)
			(layers "B.Cu" "B.Mask" "B.Paste")
			(net "UART_T11_NODE2_TXD")
		)
		(pad "2" smd rect
			(at 0.40005 0 270)
			(size 0.4572 0.508)
			(layers "B.Cu" "B.Mask" "B.Paste")
			(net "UART_T11_NODE2_TXD_R")
		)
	)
	(footprint ""
		(layer "B.Cu")
		(at 70.31355 -92.822268 90)
		(property "Reference" "R85"
			(at -1.309116 2.74828 270)
			(unlocked yes)
			(layer "B.SilkS")
			(effects
				(font
					(size 0.7874 0.5842)
					(thickness 0.1524)
				)
				(justify left mirror)
			)
		)
		(property "Value" ""
			(at 0 0 90)
			(layer "B.Fab")
			(effects
				(font
					(size 1.27 1.27)
				)
				(justify mirror)
			)
		)
		(duplicate_pad_numbers_are_jumpers no)
		(fp_line
			(start 0.7874 -0.4064)
			(end -0.7874 -0.4064)
			(stroke
				(width 0.1524)
				(type default)
			)
			(layer "B.SilkS")
		)
		(fp_line
			(start -0.7874 -0.4064)
			(end -0.7874 0.4064)
			(stroke
				(width 0.1524)
				(type default)
			)
			(layer "B.SilkS")
		)
		(fp_line
			(start 0.7874 0.4064)
			(end 0.7874 -0.4064)
			(stroke
				(width 0.1524)
				(type default)
			)
			(layer "B.SilkS")
		)
		(fp_line
			(start -0.7874 0.4064)
			(end 0.7874 0.4064)
			(stroke
				(width 0.1524)
				(type default)
			)
			(layer "B.SilkS")
		)
		(fp_poly
			(pts
				(xy 0.508 0.2794) (xy 0.508 0.2286) (xy 0.635 0.2286) (xy 0.635 -0.254) (xy 0.5334 -0.254) (xy 0.5334 -0.2794)
				(xy -0.5334 -0.2794) (xy -0.5334 -0.254) (xy -0.635 -0.254) (xy -0.635 0.254) (xy -0.5334 0.254)
				(xy -0.5334 0.2794)
			)
			(stroke
				(width 0)
				(type default)
			)
			(fill no)
			(layer "B.CrtYd")
		)
		(pad "1" smd rect
			(at -0.40005 0 270)
			(size 0.4572 0.508)
			(layers "B.Cu" "B.Mask" "B.Paste")
			(net "H_CPU_NODE1_ERR2")
		)
		(pad "2" smd rect
			(at 0.40005 0 270)
			(size 0.4572 0.508)
			(layers "B.Cu" "B.Mask" "B.Paste")
			(net "H_CPU_NODE1_ERR2_R")
		)
	)
	(footprint ""
		(layer "B.Cu")
		(at 63.10376 -185.205624 90)
		(property "Reference" "R868"
			(at 4.15163 0.159512 270)
			(unlocked yes)
			(layer "B.SilkS")
			(effects
				(font
					(size 0.7874 0.5842)
					(thickness 0.1524)
				)
				(justify left mirror)
			)
		)
		(property "Value" ""
			(at 0 0 90)
			(layer "B.Fab")
			(effects
				(font
					(size 1.27 1.27)
				)
				(justify mirror)
			)
		)
		(duplicate_pad_numbers_are_jumpers no)
		(fp_line
			(start 0.7874 -0.406146)
			(end -0.7874 -0.406146)
			(stroke
				(width 0.1524)
				(type default)
			)
			(layer "B.SilkS")
		)
		(fp_line
			(start -0.7874 -0.406146)
			(end -0.7874 0.406146)
			(stroke
				(width 0.1524)
				(type default)
			)
			(layer "B.SilkS")
		)
		(fp_line
			(start 0.7874 0.406146)
			(end 0.7874 -0.406146)
			(stroke
				(width 0.1524)
				(type default)
			)
			(layer "B.SilkS")
		)
		(fp_line
			(start -0.7874 0.406146)
			(end 0.7874 0.406146)
			(stroke
				(width 0.1524)
				(type default)
			)
			(layer "B.SilkS")
		)
		(fp_poly
			(pts
				(xy 0.508 0.2794) (xy 0.508 0.2286) (xy 0.635 0.2286) (xy 0.635 -0.254) (xy 0.5334 -0.254) (xy 0.5334 -0.2794)
				(xy -0.5334 -0.2794) (xy -0.5334 -0.254) (xy -0.635 -0.254) (xy -0.635 0.254) (xy -0.5334 0.254)
				(xy -0.5334 0.2794)
			)
			(stroke
				(width 0)
				(type default)
			)
			(fill no)
			(layer "B.CrtYd")
		)
		(pad "1" smd rect
			(at -0.40005 0 270)
			(size 0.4572 0.508)
			(layers "B.Cu" "B.Mask" "B.Paste")
			(net "T1_NODE4_EN")
		)
		(pad "2" smd rect
			(at 0.40005 0 270)
			(size 0.4572 0.508)
			(layers "B.Cu" "B.Mask" "B.Paste")
			(net "T1_NODE4_EN_R")
		)
	)
	(footprint ""
		(layer "B.Cu")
		(at 121.40184 -144.956276 180)
		(property "Reference" "C185"
			(at 1.136396 -0.943864 0)
			(unlocked yes)
			(layer "B.SilkS")
			(effects
				(font
					(size 0.7874 0.5842)
					(thickness 0.1524)
				)
				(justify left mirror)
			)
		)
		(property "Value" ""
			(at 0 0 0)
			(layer "B.Fab")
			(effects
				(font
					(size 1.27 1.27)
				)
				(justify mirror)
			)
		)
		(duplicate_pad_numbers_are_jumpers no)
		(fp_line
			(start 0.7874 0.406146)
			(end 0.7874 -0.406146)
			(stroke
				(width 0.1524)
				(type default)
			)
			(layer "B.SilkS")
		)
		(fp_line
			(start 0.7874 -0.406146)
			(end -0.7874 -0.406146)
			(stroke
				(width 0.1524)
				(type default)
			)
			(layer "B.SilkS")
		)
		(fp_line
			(start 0 0.381)
			(end 0 -0.381)
			(stroke
				(width 0.1524)
				(type default)
			)
			(layer "B.SilkS")
		)
		(fp_line
			(start -0.7874 0.406146)
			(end 0.7874 0.406146)
			(stroke
				(width 0.1524)
				(type default)
			)
			(layer "B.SilkS")
		)
		(fp_line
			(start -0.7874 -0.406146)
			(end -0.7874 0.406146)
			(stroke
				(width 0.1524)
				(type default)
			)
			(layer "B.SilkS")
		)
		(fp_poly
			(pts
				(xy 0.5334 0.254) (xy 0.635 0.254) (xy 0.635 0.2286) (xy 0.635 -0.254) (xy 0.5334 -0.254) (xy 0.5334 -0.2794)
				(xy -0.5334 -0.2794) (xy -0.5334 -0.254) (xy -0.635 -0.254) (xy -0.635 0.254) (xy -0.5334 0.254)
				(xy -0.5334 0.2794) (xy 0.508 0.2794) (xy 0.5334 0.2794)
			)
			(stroke
				(width 0)
				(type default)
			)
			(fill no)
			(layer "B.CrtYd")
		)
		(pad "1" smd rect
			(at -0.40005 0)
			(size 0.4572 0.508)
			(layers "B.Cu" "B.Mask" "B.Paste")
			(net "P2E_CPU_PCIE_SW_NODE1_RX_C_DP")
		)
		(pad "2" smd rect
			(at 0.40005 0)
			(size 0.4572 0.508)
			(layers "B.Cu" "B.Mask" "B.Paste")
			(net "P2E_CPU_PCIE_SW_NODE1_RX_DP")
		)
	)
	(footprint ""
		(layer "B.Cu")
		(at 90.81262 -166.910512)
		(property "Reference" "R785"
			(at 24.774144 20.136104 0)
			(unlocked yes)
			(layer "B.SilkS")
			(effects
				(font
					(size 0.7874 0.5842)
					(thickness 0.1524)
				)
				(justify left mirror)
			)
		)
		(property "Value" ""
			(at 0 0 0)
			(layer "B.Fab")
			(effects
				(font
					(size 1.27 1.27)
				)
				(justify mirror)
			)
		)
		(duplicate_pad_numbers_are_jumpers no)
		(fp_line
			(start -0.7874 -0.4064)
			(end -0.7874 0.4064)
			(stroke
				(width 0.1524)
				(type default)
			)
			(layer "B.SilkS")
		)
		(fp_line
			(start -0.7874 0.4064)
			(end 0.7874 0.4064)
			(stroke
				(width 0.1524)
				(type default)
			)
			(layer "B.SilkS")
		)
		(fp_line
			(start 0.7874 -0.4064)
			(end -0.7874 -0.4064)
			(stroke
				(width 0.1524)
				(type default)
			)
			(layer "B.SilkS")
		)
		(fp_line
			(start 0.7874 0.4064)
			(end 0.7874 -0.4064)
			(stroke
				(width 0.1524)
				(type default)
			)
			(layer "B.SilkS")
		)
		(fp_poly
			(pts
				(xy 0.508 0.2794) (xy 0.508 0.2286) (xy 0.635 0.2286) (xy 0.635 -0.254) (xy 0.5334 -0.254) (xy 0.5334 -0.2794)
				(xy -0.5334 -0.2794) (xy -0.5334 -0.254) (xy -0.635 -0.254) (xy -0.635 0.254) (xy -0.5334 0.254)
				(xy -0.5334 0.2794)
			)
			(stroke
				(width 0)
				(type default)
			)
			(fill no)
			(layer "B.CrtYd")
		)
		(pad "1" smd rect
			(at -0.40005 0 180)
			(size 0.4572 0.508)
			(layers "B.Cu" "B.Mask" "B.Paste")
			(net "UART_SW_S1_N")
		)
		(pad "2" smd rect
			(at 0.40005 0 180)
			(size 0.4572 0.508)
			(layers "B.Cu" "B.Mask" "B.Paste")
			(net "P3V3_NODE1")
		)
	)
	(footprint ""
		(layer "B.Cu")
		(at 55.552086 -125.819662 -90)
		(property "Reference" "L15"
			(at 53.329586 42.553636 270)
			(unlocked yes)
			(layer "B.SilkS")
			(effects
				(font
					(size 0.7874 0.5842)
					(thickness 0.1524)
				)
				(justify mirror)
			)
		)
		(property "Value" ""
			(at 0 0 90)
			(layer "B.Fab")
			(effects
				(font
					(size 1.27 1.27)
				)
				(justify mirror)
			)
		)
		(duplicate_pad_numbers_are_jumpers no)
		(fp_line
			(start -1.2954 0.635)
			(end 1.2954 0.635)
			(stroke
				(width 0.1524)
				(type default)
			)
			(layer "B.SilkS")
		)
		(fp_line
			(start -0.127 -0.5842)
			(end -0.127 0.5842)
			(stroke
				(width 0.1524)
				(type default)
			)
			(layer "B.SilkS")
		)
		(fp_line
			(start 0.127 -0.5842)
			(end 0.127 0.5842)
			(stroke
				(width 0.1524)
				(type default)
			)
			(layer "B.SilkS")
		)
		(fp_line
			(start -1.2954 -0.635)
			(end -1.2954 0.635)
			(stroke
				(width 0.1524)
				(type default)
			)
			(layer "B.SilkS")
		)
		(fp_line
			(start 1.2954 -0.635)
			(end 1.2954 0.635)
			(stroke
				(width 0.1524)
				(type default)
			)
			(layer "B.SilkS")
		)
		(fp_line
			(start 1.2954 -0.635)
			(end -1.2954 -0.635)
			(stroke
				(width 0.1524)
				(type default)
			)
			(layer "B.SilkS")
		)
		(fp_poly
			(pts
				(xy 0.9144 0.508) (xy 0.9144 0.3556) (xy 1.143 0.3556) (xy 1.143 -0.3556) (xy 0.9144 -0.3556) (xy 0.9144 -0.508)
				(xy -0.9144 -0.508) (xy -0.9144 -0.3556) (xy -1.143 -0.3556) (xy -1.143 0.3556) (xy -0.9144 0.3556)
				(xy -0.9144 0.508)
			)
			(stroke
				(width 0)
				(type default)
			)
			(fill no)
			(layer "B.CrtYd")
		)
		(pad "1" smd rect
			(at -0.7366 0)
			(size 0.7112 0.8128)
			(layers "B.Cu" "B.Mask" "B.Paste")
			(net "BMC_NODE1_MPLLAV33")
		)
		(pad "2" smd rect
			(at 0.7366 0)
			(size 0.7112 0.8128)
			(layers "B.Cu" "B.Mask" "B.Paste")
			(net "P3V3_NODE1")
		)
	)
	(footprint ""
		(layer "B.Cu")
		(at 90.81262 -163.87445)
		(property "Reference" "R780"
			(at 24.774144 20.136104 0)
			(unlocked yes)
			(layer "B.SilkS")
			(effects
				(font
					(size 0.7874 0.5842)
					(thickness 0.1524)
				)
				(justify left mirror)
			)
		)
		(property "Value" ""
			(at 0 0 0)
			(layer "B.Fab")
			(effects
				(font
					(size 1.27 1.27)
				)
				(justify mirror)
			)
		)
		(duplicate_pad_numbers_are_jumpers no)
		(fp_line
			(start -0.7874 -0.4064)
			(end -0.7874 0.4064)
			(stroke
				(width 0.1524)
				(type default)
			)
			(layer "B.SilkS")
		)
		(fp_line
			(start -0.7874 0.4064)
			(end 0.7874 0.4064)
			(stroke
				(width 0.1524)
				(type default)
			)
			(layer "B.SilkS")
		)
		(fp_line
			(start 0.7874 -0.4064)
			(end -0.7874 -0.4064)
			(stroke
				(width 0.1524)
				(type default)
			)
			(layer "B.SilkS")
		)
		(fp_line
			(start 0.7874 0.4064)
			(end 0.7874 -0.4064)
			(stroke
				(width 0.1524)
				(type default)
			)
			(layer "B.SilkS")
		)
		(fp_poly
			(pts
				(xy 0.508 0.2794) (xy 0.508 0.2286) (xy 0.635 0.2286) (xy 0.635 -0.254) (xy 0.5334 -0.254) (xy 0.5334 -0.2794)
				(xy -0.5334 -0.2794) (xy -0.5334 -0.254) (xy -0.635 -0.254) (xy -0.635 0.254) (xy -0.5334 0.254)
				(xy -0.5334 0.2794)
			)
			(stroke
				(width 0)
				(type default)
			)
			(fill no)
			(layer "B.CrtYd")
		)
		(pad "1" smd rect
			(at -0.40005 0 180)
			(size 0.4572 0.508)
			(layers "B.Cu" "B.Mask" "B.Paste")
			(net "I2C_SDC_SDA")
		)
		(pad "2" smd rect
			(at 0.40005 0 180)
			(size 0.4572 0.508)
			(layers "B.Cu" "B.Mask" "B.Paste")
			(net "P3V3_NODE1")
		)
	)
	(footprint ""
		(layer "B.Cu")
		(at 137.1854 -54.8894)
		(property "Reference" "C598"
			(at 1.7272 -1.82753 0)
			(unlocked yes)
			(layer "B.SilkS")
			(effects
				(font
					(size 0.7874 0.5842)
					(thickness 0.1524)
				)
				(justify left mirror)
			)
		)
		(property "Value" ""
			(at 0 0 0)
			(layer "B.Fab")
			(effects
				(font
					(size 1.27 1.27)
				)
				(justify mirror)
			)
		)
		(duplicate_pad_numbers_are_jumpers no)
		(fp_line
			(start -0.7874 -0.4064)
			(end -0.7874 0.4064)
			(stroke
				(width 0.1524)
				(type default)
			)
			(layer "B.SilkS")
		)
		(fp_line
			(start -0.7874 0.4064)
			(end 0.7874 0.4064)
			(stroke
				(width 0.1524)
				(type default)
			)
			(layer "B.SilkS")
		)
		(fp_line
			(start 0 0.381)
			(end 0 -0.381)
			(stroke
				(width 0.1524)
				(type default)
			)
			(layer "B.SilkS")
		)
		(fp_line
			(start 0.7874 -0.4064)
			(end -0.7874 -0.4064)
			(stroke
				(width 0.1524)
				(type default)
			)
			(layer "B.SilkS")
		)
		(fp_line
			(start 0.7874 0.4064)
			(end 0.7874 -0.4064)
			(stroke
				(width 0.1524)
				(type default)
			)
			(layer "B.SilkS")
		)
		(fp_poly
			(pts
				(xy 0.5334 0.254) (xy 0.635 0.254) (xy 0.635 0.2286) (xy 0.635 -0.254) (xy 0.5334 -0.254) (xy 0.5334 -0.2794)
				(xy -0.5334 -0.2794) (xy -0.5334 -0.254) (xy -0.635 -0.254) (xy -0.635 0.254) (xy -0.5334 0.254)
				(xy -0.5334 0.2794) (xy 0.508 0.2794) (xy 0.5334 0.2794)
			)
			(stroke
				(width 0)
				(type default)
			)
			(fill no)
			(layer "B.CrtYd")
		)
		(pad "1" smd rect
			(at -0.40005 0 180)
			(size 0.4572 0.508)
			(layers "B.Cu" "B.Mask" "B.Paste")
			(net "P3V3_NODE1")
		)
		(pad "2" smd rect
			(at 0.40005 0 180)
			(size 0.4572 0.508)
			(layers "B.Cu" "B.Mask" "B.Paste")
			(net "GND")
		)
	)
	(footprint ""
		(layer "B.Cu")
		(at 43.82262 -159.16529 -90)
		(property "Reference" "C425"
			(at -7.08787 6.84276 270)
			(unlocked yes)
			(layer "B.SilkS")
			(effects
				(font
					(size 0.7874 0.5842)
					(thickness 0.1524)
				)
				(justify left mirror)
			)
		)
		(property "Value" ""
			(at 0 0 90)
			(layer "B.Fab")
			(effects
				(font
					(size 1.27 1.27)
				)
				(justify mirror)
			)
		)
		(duplicate_pad_numbers_are_jumpers no)
		(fp_line
			(start -0.7874 0.4064)
			(end 0.7874 0.4064)
			(stroke
				(width 0.1524)
				(type default)
			)
			(layer "B.SilkS")
		)
		(fp_line
			(start 0.7874 0.4064)
			(end 0.7874 -0.4064)
			(stroke
				(width 0.1524)
				(type default)
			)
			(layer "B.SilkS")
		)
		(fp_line
			(start 0 0.381)
			(end 0 -0.381)
			(stroke
				(width 0.1524)
				(type default)
			)
			(layer "B.SilkS")
		)
		(fp_line
			(start -0.7874 -0.4064)
			(end -0.7874 0.4064)
			(stroke
				(width 0.1524)
				(type default)
			)
			(layer "B.SilkS")
		)
		(fp_line
			(start 0.7874 -0.4064)
			(end -0.7874 -0.4064)
			(stroke
				(width 0.1524)
				(type default)
			)
			(layer "B.SilkS")
		)
		(fp_poly
			(pts
				(xy 0.5334 0.254) (xy 0.635 0.254) (xy 0.635 0.2286) (xy 0.635 -0.254) (xy 0.5334 -0.254) (xy 0.5334 -0.2794)
				(xy -0.5334 -0.2794) (xy -0.5334 -0.254) (xy -0.635 -0.254) (xy -0.635 0.254) (xy -0.5334 0.254)
				(xy -0.5334 0.2794) (xy 0.508 0.2794) (xy 0.5334 0.2794)
			)
			(stroke
				(width 0)
				(type default)
			)
			(fill no)
			(layer "B.CrtYd")
		)
		(pad "1" smd rect
			(at -0.40005 0 90)
			(size 0.4572 0.508)
			(layers "B.Cu" "B.Mask" "B.Paste")
			(net "P1V9_LAN1")
		)
		(pad "2" smd rect
			(at 0.40005 0 90)
			(size 0.4572 0.508)
			(layers "B.Cu" "B.Mask" "B.Paste")
			(net "GND")
		)
	)
	(footprint ""
		(layer "B.Cu")
		(at 62.537086 -140.246862 90)
		(property "Reference" "C294"
			(at -54.2163 -41.487852 270)
			(unlocked yes)
			(layer "B.SilkS")
			(effects
				(font
					(size 0.7874 0.5842)
					(thickness 0.1524)
				)
				(justify left mirror)
			)
		)
		(property "Value" ""
			(at 0 0 90)
			(layer "B.Fab")
			(effects
				(font
					(size 1.27 1.27)
				)
				(justify mirror)
			)
		)
		(duplicate_pad_numbers_are_jumpers no)
		(fp_line
			(start 0.7874 -0.4064)
			(end -0.7874 -0.4064)
			(stroke
				(width 0.1524)
				(type default)
			)
			(layer "B.SilkS")
		)
		(fp_line
			(start -0.7874 -0.4064)
			(end -0.7874 0.4064)
			(stroke
				(width 0.1524)
				(type default)
			)
			(layer "B.SilkS")
		)
		(fp_line
			(start 0 0.381)
			(end 0 -0.381)
			(stroke
				(width 0.1524)
				(type default)
			)
			(layer "B.SilkS")
		)
		(fp_line
			(start 0.7874 0.4064)
			(end 0.7874 -0.4064)
			(stroke
				(width 0.1524)
				(type default)
			)
			(layer "B.SilkS")
		)
		(fp_line
			(start -0.7874 0.4064)
			(end 0.7874 0.4064)
			(stroke
				(width 0.1524)
				(type default)
			)
			(layer "B.SilkS")
		)
		(fp_poly
			(pts
				(xy 0.5334 0.254) (xy 0.635 0.254) (xy 0.635 0.2286) (xy 0.635 -0.254) (xy 0.5334 -0.254) (xy 0.5334 -0.2794)
				(xy -0.5334 -0.2794) (xy -0.5334 -0.254) (xy -0.635 -0.254) (xy -0.635 0.254) (xy -0.5334 0.254)
				(xy -0.5334 0.2794) (xy 0.508 0.2794) (xy 0.5334 0.2794)
			)
			(stroke
				(width 0)
				(type default)
			)
			(fill no)
			(layer "B.CrtYd")
		)
		(pad "1" smd rect
			(at -0.40005 0 270)
			(size 0.4572 0.508)
			(layers "B.Cu" "B.Mask" "B.Paste")
			(net "P1V26_BMC_NODE1")
		)
		(pad "2" smd rect
			(at 0.40005 0 270)
			(size 0.4572 0.508)
			(layers "B.Cu" "B.Mask" "B.Paste")
			(net "GND")
		)
	)
	(footprint ""
		(layer "B.Cu")
		(at 68.48475 -25.873456 -90)
		(property "Reference" "C170"
			(at 0.370332 -1.06426 270)
			(unlocked yes)
			(layer "B.SilkS")
			(effects
				(font
					(size 0.7874 0.5842)
					(thickness 0.1524)
				)
				(justify left mirror)
			)
		)
		(property "Value" ""
			(at 0 0 90)
			(layer "B.Fab")
			(effects
				(font
					(size 1.27 1.27)
				)
				(justify mirror)
			)
		)
		(duplicate_pad_numbers_are_jumpers no)
		(fp_line
			(start -0.7874 0.4064)
			(end 0.7874 0.4064)
			(stroke
				(width 0.1524)
				(type default)
			)
			(layer "B.SilkS")
		)
		(fp_line
			(start 0.7874 0.4064)
			(end 0.7874 -0.4064)
			(stroke
				(width 0.1524)
				(type default)
			)
			(layer "B.SilkS")
		)
		(fp_line
			(start 0 0.381)
			(end 0 -0.381)
			(stroke
				(width 0.1524)
				(type default)
			)
			(layer "B.SilkS")
		)
		(fp_line
			(start -0.7874 -0.4064)
			(end -0.7874 0.4064)
			(stroke
				(width 0.1524)
				(type default)
			)
			(layer "B.SilkS")
		)
		(fp_line
			(start 0.7874 -0.4064)
			(end -0.7874 -0.4064)
			(stroke
				(width 0.1524)
				(type default)
			)
			(layer "B.SilkS")
		)
		(fp_poly
			(pts
				(xy 0.5334 0.254) (xy 0.635 0.254) (xy 0.635 0.2286) (xy 0.635 -0.254) (xy 0.5334 -0.254) (xy 0.5334 -0.2794)
				(xy -0.5334 -0.2794) (xy -0.5334 -0.254) (xy -0.635 -0.254) (xy -0.635 0.254) (xy -0.5334 0.254)
				(xy -0.5334 0.2794) (xy 0.508 0.2794) (xy 0.5334 0.2794)
			)
			(stroke
				(width 0)
				(type default)
			)
			(fill no)
			(layer "B.CrtYd")
		)
		(pad "1" smd rect
			(at -0.40005 0 90)
			(size 0.4572 0.508)
			(layers "B.Cu" "B.Mask" "B.Paste")
			(net "PV_VDDR_NODE1")
		)
		(pad "2" smd rect
			(at 0.40005 0 90)
			(size 0.4572 0.508)
			(layers "B.Cu" "B.Mask" "B.Paste")
			(net "GND")
		)
	)
	(footprint ""
		(layer "B.Cu")
		(at 61.326522 -130.924046)
		(property "Reference" "C268"
			(at -40.553132 52.957984 0)
			(unlocked yes)
			(layer "B.SilkS")
			(effects
				(font
					(size 0.7874 0.5842)
					(thickness 0.1524)
				)
				(justify left mirror)
			)
		)
		(property "Value" ""
			(at 0 0 0)
			(layer "B.Fab")
			(effects
				(font
					(size 1.27 1.27)
				)
				(justify mirror)
			)
		)
		(duplicate_pad_numbers_are_jumpers no)
		(fp_line
			(start -0.7874 -0.4064)
			(end -0.7874 0.4064)
			(stroke
				(width 0.1524)
				(type default)
			)
			(layer "B.SilkS")
		)
		(fp_line
			(start -0.7874 0.4064)
			(end 0.7874 0.4064)
			(stroke
				(width 0.1524)
				(type default)
			)
			(layer "B.SilkS")
		)
		(fp_line
			(start 0 0.381)
			(end 0 -0.381)
			(stroke
				(width 0.1524)
				(type default)
			)
			(layer "B.SilkS")
		)
		(fp_line
			(start 0.7874 -0.4064)
			(end -0.7874 -0.4064)
			(stroke
				(width 0.1524)
				(type default)
			)
			(layer "B.SilkS")
		)
		(fp_line
			(start 0.7874 0.4064)
			(end 0.7874 -0.4064)
			(stroke
				(width 0.1524)
				(type default)
			)
			(layer "B.SilkS")
		)
		(fp_poly
			(pts
				(xy 0.5334 0.254) (xy 0.635 0.254) (xy 0.635 0.2286) (xy 0.635 -0.254) (xy 0.5334 -0.254) (xy 0.5334 -0.2794)
				(xy -0.5334 -0.2794) (xy -0.5334 -0.254) (xy -0.635 -0.254) (xy -0.635 0.254) (xy -0.5334 0.254)
				(xy -0.5334 0.2794) (xy 0.508 0.2794) (xy 0.5334 0.2794)
			)
			(stroke
				(width 0)
				(type default)
			)
			(fill no)
			(layer "B.CrtYd")
		)
		(pad "1" smd rect
			(at -0.40005 0 180)
			(size 0.4572 0.508)
			(layers "B.Cu" "B.Mask" "B.Paste")
			(net "BMC_NODE1_HPLLAV33")
		)
		(pad "2" smd rect
			(at 0.40005 0 180)
			(size 0.4572 0.508)
			(layers "B.Cu" "B.Mask" "B.Paste")
			(net "GND")
		)
	)
	(footprint ""
		(layer "B.Cu")
		(at 131.784852 -135.87095 -90)
		(property "Reference" "C893"
			(at 5.07365 -0.25781 270)
			(unlocked yes)
			(layer "B.SilkS")
			(effects
				(font
					(size 0.7874 0.5842)
					(thickness 0.1524)
				)
				(justify left mirror)
			)
		)
		(property "Value" ""
			(at 0 0 90)
			(layer "B.Fab")
			(effects
				(font
					(size 1.27 1.27)
				)
				(justify mirror)
			)
		)
		(duplicate_pad_numbers_are_jumpers no)
		(fp_line
			(start -0.7874 0.4064)
			(end 0.7874 0.4064)
			(stroke
				(width 0.1524)
				(type default)
			)
			(layer "B.SilkS")
		)
		(fp_line
			(start 0.7874 0.4064)
			(end 0.7874 -0.4064)
			(stroke
				(width 0.1524)
				(type default)
			)
			(layer "B.SilkS")
		)
		(fp_line
			(start 0 0.381)
			(end 0 -0.381)
			(stroke
				(width 0.1524)
				(type default)
			)
			(layer "B.SilkS")
		)
		(fp_line
			(start -0.7874 -0.4064)
			(end -0.7874 0.4064)
			(stroke
				(width 0.1524)
				(type default)
			)
			(layer "B.SilkS")
		)
		(fp_line
			(start 0.7874 -0.4064)
			(end -0.7874 -0.4064)
			(stroke
				(width 0.1524)
				(type default)
			)
			(layer "B.SilkS")
		)
		(fp_poly
			(pts
				(xy 0.5334 0.254) (xy 0.635 0.254) (xy 0.635 0.2286) (xy 0.635 -0.254) (xy 0.5334 -0.254) (xy 0.5334 -0.2794)
				(xy -0.5334 -0.2794) (xy -0.5334 -0.254) (xy -0.635 -0.254) (xy -0.635 0.254) (xy -0.5334 0.254)
				(xy -0.5334 0.2794) (xy 0.508 0.2794) (xy 0.5334 0.2794)
			)
			(stroke
				(width 0)
				(type default)
			)
			(fill no)
			(layer "B.CrtYd")
		)
		(pad "1" smd rect
			(at -0.40005 0 90)
			(size 0.4572 0.508)
			(layers "B.Cu" "B.Mask" "B.Paste")
			(net "P1V538_BMC_NODE1")
		)
		(pad "2" smd rect
			(at 0.40005 0 90)
			(size 0.4572 0.508)
			(layers "B.Cu" "B.Mask" "B.Paste")
			(net "GND")
		)
	)
	(footprint ""
		(layer "B.Cu")
		(at 61.766196 -96.824038)
		(property "Reference" "R63"
			(at -4.06654 -7.642352 0)
			(unlocked yes)
			(layer "B.SilkS")
			(effects
				(font
					(size 0.7874 0.5842)
					(thickness 0.1524)
				)
				(justify left mirror)
			)
		)
		(property "Value" ""
			(at 0 0 0)
			(layer "B.Fab")
			(effects
				(font
					(size 1.27 1.27)
				)
				(justify mirror)
			)
		)
		(duplicate_pad_numbers_are_jumpers no)
		(fp_line
			(start -0.7874 -0.4064)
			(end -0.7874 0.4064)
			(stroke
				(width 0.1524)
				(type default)
			)
			(layer "B.SilkS")
		)
		(fp_line
			(start -0.7874 0.4064)
			(end 0.7874 0.4064)
			(stroke
				(width 0.1524)
				(type default)
			)
			(layer "B.SilkS")
		)
		(fp_line
			(start 0.7874 -0.4064)
			(end -0.7874 -0.4064)
			(stroke
				(width 0.1524)
				(type default)
			)
			(layer "B.SilkS")
		)
		(fp_line
			(start 0.7874 0.4064)
			(end 0.7874 -0.4064)
			(stroke
				(width 0.1524)
				(type default)
			)
			(layer "B.SilkS")
		)
		(fp_poly
			(pts
				(xy 0.508 0.2794) (xy 0.508 0.2286) (xy 0.635 0.2286) (xy 0.635 -0.254) (xy 0.5334 -0.254) (xy 0.5334 -0.2794)
				(xy -0.5334 -0.2794) (xy -0.5334 -0.254) (xy -0.635 -0.254) (xy -0.635 0.254) (xy -0.5334 0.254)
				(xy -0.5334 0.2794)
			)
			(stroke
				(width 0)
				(type default)
			)
			(fill no)
			(layer "B.CrtYd")
		)
		(pad "1" smd rect
			(at -0.40005 0 180)
			(size 0.4572 0.508)
			(layers "B.Cu" "B.Mask" "B.Paste")
			(net "LPC_CPU_NODE1_LAD0")
		)
		(pad "2" smd rect
			(at 0.40005 0 180)
			(size 0.4572 0.508)
			(layers "B.Cu" "B.Mask" "B.Paste")
			(net "LPC_CPU_NODE1_LAD0_R")
		)
	)
	(footprint ""
		(layer "B.Cu")
		(at 138.627866 -104.55148 180)
		(property "Reference" "R1"
			(at -0.609346 1.29413 0)
			(unlocked yes)
			(layer "B.SilkS")
			(effects
				(font
					(size 0.7874 0.5842)
					(thickness 0.1524)
				)
				(justify mirror)
			)
		)
		(property "Value" ""
			(at 0 0 0)
			(layer "B.Fab")
			(effects
				(font
					(size 1.27 1.27)
				)
				(justify mirror)
			)
		)
		(duplicate_pad_numbers_are_jumpers no)
		(fp_line
			(start 1.2954 0.5842)
			(end 1.2954 -0.5842)
			(stroke
				(width 0.1524)
				(type default)
			)
			(layer "B.SilkS")
		)
		(fp_line
			(start 1.2954 -0.5842)
			(end -1.2954 -0.5842)
			(stroke
				(width 0.1524)
				(type default)
			)
			(layer "B.SilkS")
		)
		(fp_line
			(start -1.2954 0.5842)
			(end 1.2954 0.5842)
			(stroke
				(width 0.1524)
				(type default)
			)
			(layer "B.SilkS")
		)
		(fp_line
			(start -1.2954 -0.5842)
			(end -1.2954 0.5842)
			(stroke
				(width 0.1524)
				(type default)
			)
			(layer "B.SilkS")
		)
		(fp_poly
			(pts
				(xy -1.143 -0.3556) (xy -1.143 0.3556) (xy -0.8636 0.3556) (xy -0.8636 0.4572) (xy 0.8636 0.4572)
				(xy 0.8636 0.4318) (xy 0.8636 0.3556) (xy 1.143 0.3556) (xy 1.143 -0.3556) (xy 0.8636 -0.3556) (xy 0.8636 -0.4572)
				(xy -0.8636 -0.4572) (xy -0.8636 -0.3556)
			)
			(stroke
				(width 0)
				(type default)
			)
			(fill no)
			(layer "B.CrtYd")
		)
		(pad "1" smd rect
			(at -0.7366 0 270)
			(size 0.7112 0.8128)
			(layers "B.Cu" "B.Mask" "B.Paste")
			(net "P3V3_NODE1")
		)
		(pad "2" smd rect
			(at 0.7366 0 270)
			(size 0.7112 0.8128)
			(layers "B.Cu" "B.Mask" "B.Paste")
			(net "P3V3_CLK_NODE1_R")
		)
	)
	(footprint ""
		(layer "B.Cu")
		(at 180.16093 -118.90502)
		(property "Reference" "C782"
			(at 2.877566 -0.147066 0)
			(unlocked yes)
			(layer "B.SilkS")
			(effects
				(font
					(size 0.7874 0.5842)
					(thickness 0.1524)
				)
				(justify mirror)
			)
		)
		(property "Value" ""
			(at 0 0 0)
			(layer "B.Fab")
			(effects
				(font
					(size 1.27 1.27)
				)
				(justify mirror)
			)
		)
		(duplicate_pad_numbers_are_jumpers no)
		(fp_line
			(start -1.2954 -0.5842)
			(end -1.2954 0.5842)
			(stroke
				(width 0.1524)
				(type default)
			)
			(layer "B.SilkS")
		)
		(fp_line
			(start -1.2954 0.5842)
			(end 1.2954 0.5842)
			(stroke
				(width 0.1524)
				(type default)
			)
			(layer "B.SilkS")
		)
		(fp_line
			(start 0 -0.5842)
			(end 0 0.5842)
			(stroke
				(width 0.1524)
				(type default)
			)
			(layer "B.SilkS")
		)
		(fp_line
			(start 1.2954 -0.5842)
			(end -1.2954 -0.5842)
			(stroke
				(width 0.1524)
				(type default)
			)
			(layer "B.SilkS")
		)
		(fp_line
			(start 1.2954 0.5842)
			(end 1.2954 -0.5842)
			(stroke
				(width 0.1524)
				(type default)
			)
			(layer "B.SilkS")
		)
		(fp_poly
			(pts
				(xy -0.8636 -0.4572) (xy -0.8636 -0.3556) (xy -1.143 -0.3556) (xy -1.143 0.3556) (xy -0.8636 0.3556)
				(xy -0.8636 0.4572) (xy 0.8636 0.4572) (xy 0.8636 0.3556) (xy 1.143 0.3556) (xy 1.143 -0.3556) (xy 0.8636 -0.3556)
				(xy 0.8636 -0.4572)
			)
			(stroke
				(width 0)
				(type default)
			)
			(fill no)
			(layer "B.CrtYd")
		)
		(fp_line
			(start -0.884936 -0.504952)
			(end -0.884936 0.504952)
			(stroke
				(width 0.1)
				(type default)
			)
			(layer "B.Fab")
		)
		(fp_line
			(start -0.884936 0.504952)
			(end 0.884936 0.504952)
			(stroke
				(width 0.1)
				(type default)
			)
			(layer "B.Fab")
		)
		(fp_line
			(start 0.884936 -0.504952)
			(end -0.884936 -0.504952)
			(stroke
				(width 0.1)
				(type default)
			)
			(layer "B.Fab")
		)
		(fp_line
			(start 0.884936 0.504952)
			(end 0.884936 -0.504952)
			(stroke
				(width 0.1)
				(type default)
			)
			(layer "B.Fab")
		)
		(pad "1" smd rect
			(at -0.7366 0 90)
			(size 0.7112 0.8128)
			(layers "B.Cu" "B.Mask" "B.Paste")
			(net "P3V3_STB_NODE1")
		)
		(pad "2" smd rect
			(at 0.7366 0 90)
			(size 0.7112 0.8128)
			(layers "B.Cu" "B.Mask" "B.Paste")
			(net "GND")
		)
	)
	(footprint ""
		(layer "B.Cu")
		(at 91.47302 -72.216518)
		(property "Reference" "R165"
			(at 4.07797 0.606044 0)
			(unlocked yes)
			(layer "B.SilkS")
			(effects
				(font
					(size 0.7874 0.5842)
					(thickness 0.1524)
				)
				(justify left mirror)
			)
		)
		(property "Value" ""
			(at 0 0 0)
			(layer "B.Fab")
			(effects
				(font
					(size 1.27 1.27)
				)
				(justify mirror)
			)
		)
		(duplicate_pad_numbers_are_jumpers no)
		(fp_line
			(start -0.7874 -0.4064)
			(end -0.7874 0.4064)
			(stroke
				(width 0.1524)
				(type default)
			)
			(layer "B.SilkS")
		)
		(fp_line
			(start -0.7874 0.4064)
			(end 0.7874 0.4064)
			(stroke
				(width 0.1524)
				(type default)
			)
			(layer "B.SilkS")
		)
		(fp_line
			(start 0.7874 -0.4064)
			(end -0.7874 -0.4064)
			(stroke
				(width 0.1524)
				(type default)
			)
			(layer "B.SilkS")
		)
		(fp_line
			(start 0.7874 0.4064)
			(end 0.7874 -0.4064)
			(stroke
				(width 0.1524)
				(type default)
			)
			(layer "B.SilkS")
		)
		(fp_poly
			(pts
				(xy 0.508 0.2794) (xy 0.508 0.2286) (xy 0.635 0.2286) (xy 0.635 -0.254) (xy 0.5334 -0.254) (xy 0.5334 -0.2794)
				(xy -0.5334 -0.2794) (xy -0.5334 -0.254) (xy -0.635 -0.254) (xy -0.635 0.254) (xy -0.5334 0.254)
				(xy -0.5334 0.2794)
			)
			(stroke
				(width 0)
				(type default)
			)
			(fill no)
			(layer "B.CrtYd")
		)
		(pad "1" smd rect
			(at -0.40005 0 180)
			(size 0.4572 0.508)
			(layers "B.Cu" "B.Mask" "B.Paste")
			(net "PD_CPU_NODE1_PUNIT_ST_ADDR0")
		)
		(pad "2" smd rect
			(at 0.40005 0 180)
			(size 0.4572 0.508)
			(layers "B.Cu" "B.Mask" "B.Paste")
			(net "P1V05_SUS_NODE1")
		)
	)
	(footprint ""
		(layer "B.Cu")
		(at 70.50786 -147.25269 180)
		(property "Reference" "PJ19"
			(at 0.933958 -0.877824 270)
			(unlocked yes)
			(layer "B.SilkS")
			(effects
				(font
					(size 0.7874 0.5842)
					(thickness 0.1524)
				)
				(justify left mirror)
			)
		)
		(property "Value" ""
			(at 0 0 0)
			(layer "B.Fab")
			(effects
				(font
					(size 1.27 1.27)
				)
				(justify mirror)
			)
		)
		(duplicate_pad_numbers_are_jumpers no)
		(fp_poly
			(pts
				(xy -0.2794 0.907796) (xy -0.254 0.907796) (xy -0.254 1.0414) (xy 0.254 1.0414) (xy 0.254 1.034796)
				(xy 0.254 0.933196) (xy 0.2794 0.933196) (xy 0.2794 -0.133604) (xy 0.254 -0.133604) (xy 0.254 -0.235204)
				(xy -0.254 -0.235204) (xy -0.254 -0.133604) (xy -0.2794 -0.133604)
			)
			(stroke
				(width 0)
				(type default)
			)
			(fill no)
			(layer "B.CrtYd")
		)
		(pad "1" smd custom
			(at 0 -0.000254)
			(size 0.127 0.127)
			(layers "B.Cu" "B.Mask" "B.Paste")
			(net "BMC_DEBUG_TXD")
			(options
				(clearance outline)
				(anchor circle)
			)
			(primitives
				(gr_poly
					(pts
						(xy -0.127 -0.508) (xy -0.127 0.0508) (xy -0.254 0.0508) (xy -0.254 0.508) (xy 0.254 0.508) (xy 0.254 0.0508)
						(xy 0.127 0.0508) (xy 0.127 -0.508)
					)
					(width 0)
					(fill yes)
				)
			)
		)
		(pad "2" smd rect
			(at 0 0.799846 270)
			(size 0.4572 0.508)
			(layers "B.Cu" "B.Mask" "B.Paste")
			(net "Net_467")
		)
		(zone
			(layer "B.Cu")
			(hatch none 0.5)
			(connect_pads
				(clearance 0)
			)
			(min_thickness 0.25)
			(keepout
				(tracks allowed)
				(vias not_allowed)
				(pads allowed)
				(copperpour not_allowed)
				(footprints allowed)
			)
			(placement
				(enabled no)
				(sheetname "")
			)
			(fill
				(thermal_gap 0.5)
				(thermal_bridge_width 0.5)
				(island_removal_mode 0)
			)
			(polygon
				(pts
					(xy 70.20306 -148.338286) (xy 70.81266 -148.338286) (xy 70.81266 -146.966686) (xy 70.20306 -146.966686)
				)
			)
		)
	)
	(footprint ""
		(layer "B.Cu")
		(at 118.184422 -123.297442 -90)
		(property "Reference" "PC93"
			(at -3.082036 0.88138 270)
			(unlocked yes)
			(layer "B.SilkS")
			(effects
				(font
					(size 0.7874 0.5842)
					(thickness 0.1524)
				)
				(justify left mirror)
			)
		)
		(property "Value" ""
			(at 0 0 90)
			(layer "B.Fab")
			(effects
				(font
					(size 1.27 1.27)
				)
				(justify mirror)
			)
		)
		(duplicate_pad_numbers_are_jumpers no)
		(fp_line
			(start -2.2098 0.9398)
			(end 2.2098 0.9398)
			(stroke
				(width 0.1524)
				(type default)
			)
			(layer "B.SilkS")
		)
		(fp_line
			(start 2.2098 0.9398)
			(end 2.2098 -0.9398)
			(stroke
				(width 0.1524)
				(type default)
			)
			(layer "B.SilkS")
		)
		(fp_line
			(start -2.2098 -0.9398)
			(end -2.2098 0.9398)
			(stroke
				(width 0.1524)
				(type default)
			)
			(layer "B.SilkS")
		)
		(fp_line
			(start 0 -0.9398)
			(end 0 0.9398)
			(stroke
				(width 0.1524)
				(type default)
			)
			(layer "B.SilkS")
		)
		(fp_line
			(start 2.2098 -0.9398)
			(end -2.2098 -0.9398)
			(stroke
				(width 0.1524)
				(type default)
			)
			(layer "B.SilkS")
		)
		(fp_poly
			(pts
				(xy 1.6764 0.889) (xy 1.6764 0.7874) (xy 2.0574 0.7874) (xy 2.0574 -0.7874) (xy 1.6764 -0.7874)
				(xy 1.6764 -0.9398) (xy -1.6764 -0.9398) (xy -1.6764 -0.7874) (xy -2.0574 -0.7874) (xy -2.0574 0.7874)
				(xy -1.6764 0.7874) (xy -1.6764 0.9398) (xy 1.6764 0.9398)
			)
			(stroke
				(width 0)
				(type default)
			)
			(fill no)
			(layer "B.CrtYd")
		)
		(fp_line
			(start -1.700022 0.899922)
			(end 1.700022 0.899922)
			(stroke
				(width 0.1)
				(type default)
			)
			(layer "B.Fab")
		)
		(fp_line
			(start 1.700022 0.899922)
			(end 1.700022 -0.899922)
			(stroke
				(width 0.1)
				(type default)
			)
			(layer "B.Fab")
		)
		(fp_line
			(start -1.700022 -0.899922)
			(end -1.700022 0.899922)
			(stroke
				(width 0.1)
				(type default)
			)
			(layer "B.Fab")
		)
		(fp_line
			(start 1.700022 -0.899922)
			(end -1.700022 -0.899922)
			(stroke
				(width 0.1)
				(type default)
			)
			(layer "B.Fab")
		)
		(pad "1" smd rect
			(at -1.4732 0 90)
			(size 1.1684 1.5748)
			(layers "B.Cu" "B.Mask" "B.Paste")
			(net "SW_VR_PVCCP_NODE1_VIN_FLT")
		)
		(pad "2" smd rect
			(at 1.4732 0 90)
			(size 1.1684 1.5748)
			(layers "B.Cu" "B.Mask" "B.Paste")
			(net "GND")
		)
	)
	(footprint ""
		(layer "B.Cu")
		(at 74.123296 -21.14296 90)
		(property "Reference" "C171"
			(at -5.852668 -0.810006 270)
			(unlocked yes)
			(layer "B.SilkS")
			(effects
				(font
					(size 0.7874 0.5842)
					(thickness 0.1524)
				)
				(justify left mirror)
			)
		)
		(property "Value" ""
			(at 0 0 90)
			(layer "B.Fab")
			(effects
				(font
					(size 1.27 1.27)
				)
				(justify mirror)
			)
		)
		(duplicate_pad_numbers_are_jumpers no)
		(fp_line
			(start 0.7874 -0.4064)
			(end -0.7874 -0.4064)
			(stroke
				(width 0.1524)
				(type default)
			)
			(layer "B.SilkS")
		)
		(fp_line
			(start -0.7874 -0.4064)
			(end -0.7874 0.4064)
			(stroke
				(width 0.1524)
				(type default)
			)
			(layer "B.SilkS")
		)
		(fp_line
			(start 0 0.381)
			(end 0 -0.381)
			(stroke
				(width 0.1524)
				(type default)
			)
			(layer "B.SilkS")
		)
		(fp_line
			(start 0.7874 0.4064)
			(end 0.7874 -0.4064)
			(stroke
				(width 0.1524)
				(type default)
			)
			(layer "B.SilkS")
		)
		(fp_line
			(start -0.7874 0.4064)
			(end 0.7874 0.4064)
			(stroke
				(width 0.1524)
				(type default)
			)
			(layer "B.SilkS")
		)
		(fp_poly
			(pts
				(xy 0.5334 0.254) (xy 0.635 0.254) (xy 0.635 0.2286) (xy 0.635 -0.254) (xy 0.5334 -0.254) (xy 0.5334 -0.2794)
				(xy -0.5334 -0.2794) (xy -0.5334 -0.254) (xy -0.635 -0.254) (xy -0.635 0.254) (xy -0.5334 0.254)
				(xy -0.5334 0.2794) (xy 0.508 0.2794) (xy 0.5334 0.2794)
			)
			(stroke
				(width 0)
				(type default)
			)
			(fill no)
			(layer "B.CrtYd")
		)
		(pad "1" smd rect
			(at -0.40005 0 270)
			(size 0.4572 0.508)
			(layers "B.Cu" "B.Mask" "B.Paste")
			(net "PV_VDDR_NODE1")
		)
		(pad "2" smd rect
			(at 0.40005 0 270)
			(size 0.4572 0.508)
			(layers "B.Cu" "B.Mask" "B.Paste")
			(net "GND")
		)
	)
	(footprint ""
		(layer "B.Cu")
		(at 132.41528 -43.7134 -90)
		(property "Reference" "R1329"
			(at 2.8194 -0.93345 270)
			(unlocked yes)
			(layer "B.SilkS")
			(effects
				(font
					(size 0.7874 0.5842)
					(thickness 0.1524)
				)
				(justify left mirror)
			)
		)
		(property "Value" ""
			(at 0 0 90)
			(layer "B.Fab")
			(effects
				(font
					(size 1.27 1.27)
				)
				(justify mirror)
			)
		)
		(duplicate_pad_numbers_are_jumpers no)
		(fp_line
			(start -0.7874 0.4064)
			(end 0.7874 0.4064)
			(stroke
				(width 0.1524)
				(type default)
			)
			(layer "B.SilkS")
		)
		(fp_line
			(start 0.7874 0.4064)
			(end 0.7874 -0.4064)
			(stroke
				(width 0.1524)
				(type default)
			)
			(layer "B.SilkS")
		)
		(fp_line
			(start -0.7874 -0.4064)
			(end -0.7874 0.4064)
			(stroke
				(width 0.1524)
				(type default)
			)
			(layer "B.SilkS")
		)
		(fp_line
			(start 0.7874 -0.4064)
			(end -0.7874 -0.4064)
			(stroke
				(width 0.1524)
				(type default)
			)
			(layer "B.SilkS")
		)
		(fp_poly
			(pts
				(xy 0.508 0.2794) (xy 0.508 0.2286) (xy 0.635 0.2286) (xy 0.635 -0.254) (xy 0.5334 -0.254) (xy 0.5334 -0.2794)
				(xy -0.5334 -0.2794) (xy -0.5334 -0.254) (xy -0.635 -0.254) (xy -0.635 0.254) (xy -0.5334 0.254)
				(xy -0.5334 0.2794)
			)
			(stroke
				(width 0)
				(type default)
			)
			(fill no)
			(layer "B.CrtYd")
		)
		(pad "1" smd rect
			(at -0.40005 0 90)
			(size 0.4572 0.508)
			(layers "B.Cu" "B.Mask" "B.Paste")
			(net "UART_RI_P4_N")
		)
		(pad "2" smd rect
			(at 0.40005 0 90)
			(size 0.4572 0.508)
			(layers "B.Cu" "B.Mask" "B.Paste")
			(net "P3V3_NODE1")
		)
	)
	(footprint ""
		(layer "B.Cu")
		(at 90.81262 -168.942512 180)
		(property "Reference" "C568"
			(at -24.86914 -19.97075 0)
			(unlocked yes)
			(layer "B.SilkS")
			(effects
				(font
					(size 0.7874 0.5842)
					(thickness 0.1524)
				)
				(justify left mirror)
			)
		)
		(property "Value" ""
			(at 0 0 0)
			(layer "B.Fab")
			(effects
				(font
					(size 1.27 1.27)
				)
				(justify mirror)
			)
		)
		(duplicate_pad_numbers_are_jumpers no)
		(fp_line
			(start 0.7874 0.4064)
			(end 0.7874 -0.4064)
			(stroke
				(width 0.1524)
				(type default)
			)
			(layer "B.SilkS")
		)
		(fp_line
			(start 0.7874 -0.4064)
			(end -0.7874 -0.4064)
			(stroke
				(width 0.1524)
				(type default)
			)
			(layer "B.SilkS")
		)
		(fp_line
			(start 0 0.381)
			(end 0 -0.381)
			(stroke
				(width 0.1524)
				(type default)
			)
			(layer "B.SilkS")
		)
		(fp_line
			(start -0.7874 0.4064)
			(end 0.7874 0.4064)
			(stroke
				(width 0.1524)
				(type default)
			)
			(layer "B.SilkS")
		)
		(fp_line
			(start -0.7874 -0.4064)
			(end -0.7874 0.4064)
			(stroke
				(width 0.1524)
				(type default)
			)
			(layer "B.SilkS")
		)
		(fp_poly
			(pts
				(xy 0.5334 0.254) (xy 0.635 0.254) (xy 0.635 0.2286) (xy 0.635 -0.254) (xy 0.5334 -0.254) (xy 0.5334 -0.2794)
				(xy -0.5334 -0.2794) (xy -0.5334 -0.254) (xy -0.635 -0.254) (xy -0.635 0.254) (xy -0.5334 0.254)
				(xy -0.5334 0.2794) (xy 0.508 0.2794) (xy 0.5334 0.2794)
			)
			(stroke
				(width 0)
				(type default)
			)
			(fill no)
			(layer "B.CrtYd")
		)
		(pad "1" smd rect
			(at -0.40005 0)
			(size 0.4572 0.508)
			(layers "B.Cu" "B.Mask" "B.Paste")
			(net "GND")
		)
		(pad "2" smd rect
			(at 0.40005 0)
			(size 0.4572 0.508)
			(layers "B.Cu" "B.Mask" "B.Paste")
			(net "P3V3_NODE1")
		)
	)
	(footprint ""
		(layer "B.Cu")
		(at 137.970006 -35.41141)
		(property "Reference" "R1184"
			(at -4.172458 18.515838 0)
			(unlocked yes)
			(layer "B.SilkS")
			(effects
				(font
					(size 0.7874 0.5842)
					(thickness 0.1524)
				)
				(justify left mirror)
			)
		)
		(property "Value" ""
			(at 0 0 0)
			(layer "B.Fab")
			(effects
				(font
					(size 1.27 1.27)
				)
				(justify mirror)
			)
		)
		(duplicate_pad_numbers_are_jumpers no)
		(fp_line
			(start -0.7874 -0.4064)
			(end -0.7874 0.4064)
			(stroke
				(width 0.1524)
				(type default)
			)
			(layer "B.SilkS")
		)
		(fp_line
			(start -0.7874 0.4064)
			(end 0.7874 0.4064)
			(stroke
				(width 0.1524)
				(type default)
			)
			(layer "B.SilkS")
		)
		(fp_line
			(start 0.7874 -0.4064)
			(end -0.7874 -0.4064)
			(stroke
				(width 0.1524)
				(type default)
			)
			(layer "B.SilkS")
		)
		(fp_line
			(start 0.7874 0.4064)
			(end 0.7874 -0.4064)
			(stroke
				(width 0.1524)
				(type default)
			)
			(layer "B.SilkS")
		)
		(fp_poly
			(pts
				(xy 0.508 0.2794) (xy 0.508 0.2286) (xy 0.635 0.2286) (xy 0.635 -0.254) (xy 0.5334 -0.254) (xy 0.5334 -0.2794)
				(xy -0.5334 -0.2794) (xy -0.5334 -0.254) (xy -0.635 -0.254) (xy -0.635 0.254) (xy -0.5334 0.254)
				(xy -0.5334 0.2794)
			)
			(stroke
				(width 0)
				(type default)
			)
			(fill no)
			(layer "B.CrtYd")
		)
		(pad "1" smd rect
			(at -0.40005 0 180)
			(size 0.4572 0.508)
			(layers "B.Cu" "B.Mask" "B.Paste")
			(net "SIO_CPLD_RSV2_R")
		)
		(pad "2" smd rect
			(at 0.40005 0 180)
			(size 0.4572 0.508)
			(layers "B.Cu" "B.Mask" "B.Paste")
			(net "GND")
		)
	)
	(footprint ""
		(layer "B.Cu")
		(at 50.273966 -84.077556 180)
		(property "Reference" "R148"
			(at 13.842746 -30.57652 0)
			(unlocked yes)
			(layer "B.SilkS")
			(effects
				(font
					(size 0.7874 0.5842)
					(thickness 0.1524)
				)
				(justify left mirror)
			)
		)
		(property "Value" ""
			(at 0 0 0)
			(layer "B.Fab")
			(effects
				(font
					(size 1.27 1.27)
				)
				(justify mirror)
			)
		)
		(duplicate_pad_numbers_are_jumpers no)
		(fp_line
			(start 0.7874 0.4064)
			(end 0.7874 -0.4064)
			(stroke
				(width 0.1524)
				(type default)
			)
			(layer "B.SilkS")
		)
		(fp_line
			(start 0.7874 -0.4064)
			(end -0.7874 -0.4064)
			(stroke
				(width 0.1524)
				(type default)
			)
			(layer "B.SilkS")
		)
		(fp_line
			(start -0.7874 0.4064)
			(end 0.7874 0.4064)
			(stroke
				(width 0.1524)
				(type default)
			)
			(layer "B.SilkS")
		)
		(fp_line
			(start -0.7874 -0.4064)
			(end -0.7874 0.4064)
			(stroke
				(width 0.1524)
				(type default)
			)
			(layer "B.SilkS")
		)
		(fp_poly
			(pts
				(xy 0.508 0.2794) (xy 0.508 0.2286) (xy 0.635 0.2286) (xy 0.635 -0.254) (xy 0.5334 -0.254) (xy 0.5334 -0.2794)
				(xy -0.5334 -0.2794) (xy -0.5334 -0.254) (xy -0.635 -0.254) (xy -0.635 0.254) (xy -0.5334 0.254)
				(xy -0.5334 0.2794)
			)
			(stroke
				(width 0)
				(type default)
			)
			(fill no)
			(layer "B.CrtYd")
		)
		(pad "1" smd rect
			(at -0.40005 0)
			(size 0.4572 0.508)
			(layers "B.Cu" "B.Mask" "B.Paste")
			(net "P1V5_NODE1")
		)
		(pad "2" smd rect
			(at 0.40005 0)
			(size 0.4572 0.508)
			(layers "B.Cu" "B.Mask" "B.Paste")
			(net "P1V5_NODE1_AA21")
		)
	)
	(footprint ""
		(layer "B.Cu")
		(at 154.620214 -64.971422 -90)
		(property "Reference" "C343"
			(at 2.01422 -5.839714 270)
			(unlocked yes)
			(layer "B.SilkS")
			(effects
				(font
					(size 0.7874 0.5842)
					(thickness 0.1524)
				)
				(justify left mirror)
			)
		)
		(property "Value" ""
			(at 0 0 90)
			(layer "B.Fab")
			(effects
				(font
					(size 1.27 1.27)
				)
				(justify mirror)
			)
		)
		(duplicate_pad_numbers_are_jumpers no)
		(fp_line
			(start -0.7874 0.4064)
			(end 0.7874 0.4064)
			(stroke
				(width 0.1524)
				(type default)
			)
			(layer "B.SilkS")
		)
		(fp_line
			(start 0.7874 0.4064)
			(end 0.7874 -0.4064)
			(stroke
				(width 0.1524)
				(type default)
			)
			(layer "B.SilkS")
		)
		(fp_line
			(start 0 0.381)
			(end 0 -0.381)
			(stroke
				(width 0.1524)
				(type default)
			)
			(layer "B.SilkS")
		)
		(fp_line
			(start -0.7874 -0.4064)
			(end -0.7874 0.4064)
			(stroke
				(width 0.1524)
				(type default)
			)
			(layer "B.SilkS")
		)
		(fp_line
			(start 0.7874 -0.4064)
			(end -0.7874 -0.4064)
			(stroke
				(width 0.1524)
				(type default)
			)
			(layer "B.SilkS")
		)
		(fp_poly
			(pts
				(xy 0.5334 0.254) (xy 0.635 0.254) (xy 0.635 0.2286) (xy 0.635 -0.254) (xy 0.5334 -0.254) (xy 0.5334 -0.2794)
				(xy -0.5334 -0.2794) (xy -0.5334 -0.254) (xy -0.635 -0.254) (xy -0.635 0.254) (xy -0.5334 0.254)
				(xy -0.5334 0.2794) (xy 0.508 0.2794) (xy 0.5334 0.2794)
			)
			(stroke
				(width 0)
				(type default)
			)
			(fill no)
			(layer "B.CrtYd")
		)
		(pad "1" smd rect
			(at -0.40005 0 90)
			(size 0.4572 0.508)
			(layers "B.Cu" "B.Mask" "B.Paste")
			(net "P1V8_SATA_VAA2_0_NODE1")
		)
		(pad "2" smd rect
			(at 0.40005 0 90)
			(size 0.4572 0.508)
			(layers "B.Cu" "B.Mask" "B.Paste")
			(net "GND")
		)
	)
	(footprint ""
		(layer "B.Cu")
		(at 128.912112 -144.83461 90)
		(property "Reference" "C931"
			(at 0.07112 2.44983 270)
			(unlocked yes)
			(layer "B.SilkS")
			(effects
				(font
					(size 0.7874 0.5842)
					(thickness 0.1524)
				)
				(justify left mirror)
			)
		)
		(property "Value" ""
			(at 0 0 90)
			(layer "B.Fab")
			(effects
				(font
					(size 1.27 1.27)
				)
				(justify mirror)
			)
		)
		(duplicate_pad_numbers_are_jumpers no)
		(fp_line
			(start 0.7874 -0.4064)
			(end -0.7874 -0.4064)
			(stroke
				(width 0.1524)
				(type default)
			)
			(layer "B.SilkS")
		)
		(fp_line
			(start -0.7874 -0.4064)
			(end -0.7874 0.4064)
			(stroke
				(width 0.1524)
				(type default)
			)
			(layer "B.SilkS")
		)
		(fp_line
			(start 0 0.381)
			(end 0 -0.381)
			(stroke
				(width 0.1524)
				(type default)
			)
			(layer "B.SilkS")
		)
		(fp_line
			(start 0.7874 0.4064)
			(end 0.7874 -0.4064)
			(stroke
				(width 0.1524)
				(type default)
			)
			(layer "B.SilkS")
		)
		(fp_line
			(start -0.7874 0.4064)
			(end 0.7874 0.4064)
			(stroke
				(width 0.1524)
				(type default)
			)
			(layer "B.SilkS")
		)
		(fp_poly
			(pts
				(xy 0.5334 0.254) (xy 0.635 0.254) (xy 0.635 0.2286) (xy 0.635 -0.254) (xy 0.5334 -0.254) (xy 0.5334 -0.2794)
				(xy -0.5334 -0.2794) (xy -0.5334 -0.254) (xy -0.635 -0.254) (xy -0.635 0.254) (xy -0.5334 0.254)
				(xy -0.5334 0.2794) (xy 0.508 0.2794) (xy 0.5334 0.2794)
			)
			(stroke
				(width 0)
				(type default)
			)
			(fill no)
			(layer "B.CrtYd")
		)
		(pad "1" smd rect
			(at -0.40005 0 270)
			(size 0.4572 0.508)
			(layers "B.Cu" "B.Mask" "B.Paste")
			(net "P1V0_PCI_SW_A")
		)
		(pad "2" smd rect
			(at 0.40005 0 270)
			(size 0.4572 0.508)
			(layers "B.Cu" "B.Mask" "B.Paste")
			(net "GND")
		)
	)
	(footprint ""
		(layer "B.Cu")
		(at 105.191814 -112.98682)
		(property "Reference" "PC112"
			(at -3.119374 0.182118 0)
			(unlocked yes)
			(layer "B.SilkS")
			(effects
				(font
					(size 0.7874 0.5842)
					(thickness 0.1524)
				)
				(justify left mirror)
			)
		)
		(property "Value" ""
			(at 0 0 0)
			(layer "B.Fab")
			(effects
				(font
					(size 1.27 1.27)
				)
				(justify mirror)
			)
		)
		(duplicate_pad_numbers_are_jumpers no)
		(fp_line
			(start -1.905 -0.8636)
			(end -1.905 0.8636)
			(stroke
				(width 0.1524)
				(type default)
			)
			(layer "B.SilkS")
		)
		(fp_line
			(start -1.905 0.8636)
			(end 1.905 0.8636)
			(stroke
				(width 0.1524)
				(type default)
			)
			(layer "B.SilkS")
		)
		(fp_line
			(start 0 0.8382)
			(end 0 -0.8382)
			(stroke
				(width 0.1524)
				(type default)
			)
			(layer "B.SilkS")
		)
		(fp_line
			(start 1.905 -0.8636)
			(end -1.905 -0.8636)
			(stroke
				(width 0.1524)
				(type default)
			)
			(layer "B.SilkS")
		)
		(fp_line
			(start 1.905 0.8636)
			(end 1.905 -0.8636)
			(stroke
				(width 0.1524)
				(type default)
			)
			(layer "B.SilkS")
		)
		(fp_rect
			(start 1.524 0.7366)
			(end -1.524 -0.7366)
			(stroke
				(width 0)
				(type default)
			)
			(fill no)
			(layer "B.CrtYd")
		)
		(pad "1" smd rect
			(at -0.94996 0 180)
			(size 1.1176 1.3716)
			(layers "B.Cu" "B.Mask" "B.Paste")
			(net "GND")
		)
		(pad "2" smd rect
			(at 0.94996 0 180)
			(size 1.1176 1.3716)
			(layers "B.Cu" "B.Mask" "B.Paste")
			(net "PV_VCCP_NODE1")
		)
	)
	(footprint ""
		(layer "B.Cu")
		(at 110.686342 -67.025012 90)
		(property "Reference" "R224"
			(at 1.025652 -0.039116 270)
			(unlocked yes)
			(layer "B.SilkS")
			(effects
				(font
					(size 0.7874 0.5842)
					(thickness 0.1524)
				)
				(justify left mirror)
			)
		)
		(property "Value" ""
			(at 0 0 90)
			(layer "B.Fab")
			(effects
				(font
					(size 1.27 1.27)
				)
				(justify mirror)
			)
		)
		(duplicate_pad_numbers_are_jumpers no)
		(fp_line
			(start 0.7874 -0.4064)
			(end -0.7874 -0.4064)
			(stroke
				(width 0.1524)
				(type default)
			)
			(layer "B.SilkS")
		)
		(fp_line
			(start -0.7874 -0.4064)
			(end -0.7874 0.4064)
			(stroke
				(width 0.1524)
				(type default)
			)
			(layer "B.SilkS")
		)
		(fp_line
			(start 0.7874 0.4064)
			(end 0.7874 -0.4064)
			(stroke
				(width 0.1524)
				(type default)
			)
			(layer "B.SilkS")
		)
		(fp_line
			(start -0.7874 0.4064)
			(end 0.7874 0.4064)
			(stroke
				(width 0.1524)
				(type default)
			)
			(layer "B.SilkS")
		)
		(fp_poly
			(pts
				(xy 0.508 0.2794) (xy 0.508 0.2286) (xy 0.635 0.2286) (xy 0.635 -0.254) (xy 0.5334 -0.254) (xy 0.5334 -0.2794)
				(xy -0.5334 -0.2794) (xy -0.5334 -0.254) (xy -0.635 -0.254) (xy -0.635 0.254) (xy -0.5334 0.254)
				(xy -0.5334 0.2794)
			)
			(stroke
				(width 0)
				(type default)
			)
			(fill no)
			(layer "B.CrtYd")
		)
		(pad "1" smd rect
			(at -0.40005 0 270)
			(size 0.4572 0.508)
			(layers "B.Cu" "B.Mask" "B.Paste")
			(net "P1V05_STB_NODE1_XDP_A")
		)
		(pad "2" smd rect
			(at 0.40005 0 270)
			(size 0.4572 0.508)
			(layers "B.Cu" "B.Mask" "B.Paste")
			(net "P1V05_NODE1")
		)
	)
	(footprint ""
		(layer "B.Cu")
		(at 144.747996 -59.96813 90)
		(property "Reference" "C354"
			(at 1.168908 -0.368046 270)
			(unlocked yes)
			(layer "B.SilkS")
			(effects
				(font
					(size 0.7874 0.5842)
					(thickness 0.1524)
				)
				(justify left mirror)
			)
		)
		(property "Value" ""
			(at 0 0 90)
			(layer "B.Fab")
			(effects
				(font
					(size 1.27 1.27)
				)
				(justify mirror)
			)
		)
		(duplicate_pad_numbers_are_jumpers no)
		(fp_line
			(start 0.7874 -0.4064)
			(end -0.7874 -0.4064)
			(stroke
				(width 0.1524)
				(type default)
			)
			(layer "B.SilkS")
		)
		(fp_line
			(start -0.7874 -0.4064)
			(end -0.7874 0.4064)
			(stroke
				(width 0.1524)
				(type default)
			)
			(layer "B.SilkS")
		)
		(fp_line
			(start 0 0.381)
			(end 0 -0.381)
			(stroke
				(width 0.1524)
				(type default)
			)
			(layer "B.SilkS")
		)
		(fp_line
			(start 0.7874 0.4064)
			(end 0.7874 -0.4064)
			(stroke
				(width 0.1524)
				(type default)
			)
			(layer "B.SilkS")
		)
		(fp_line
			(start -0.7874 0.4064)
			(end 0.7874 0.4064)
			(stroke
				(width 0.1524)
				(type default)
			)
			(layer "B.SilkS")
		)
		(fp_poly
			(pts
				(xy 0.5334 0.254) (xy 0.635 0.254) (xy 0.635 0.2286) (xy 0.635 -0.254) (xy 0.5334 -0.254) (xy 0.5334 -0.2794)
				(xy -0.5334 -0.2794) (xy -0.5334 -0.254) (xy -0.635 -0.254) (xy -0.635 0.254) (xy -0.5334 0.254)
				(xy -0.5334 0.2794) (xy 0.508 0.2794) (xy 0.5334 0.2794)
			)
			(stroke
				(width 0)
				(type default)
			)
			(fill no)
			(layer "B.CrtYd")
		)
		(pad "1" smd rect
			(at -0.40005 0 270)
			(size 0.4572 0.508)
			(layers "B.Cu" "B.Mask" "B.Paste")
			(net "P3V3_NODE1")
		)
		(pad "2" smd rect
			(at 0.40005 0 270)
			(size 0.4572 0.508)
			(layers "B.Cu" "B.Mask" "B.Paste")
			(net "GND")
		)
	)
	(footprint ""
		(layer "B.Cu")
		(at 84.82076 -173.394624 -90)
		(property "Reference" "U62"
			(at 22.479254 -27.045412 0)
			(unlocked yes)
			(layer "B.SilkS")
			(effects
				(font
					(size 0.7874 0.5842)
					(thickness 0.1524)
				)
				(justify left mirror)
			)
		)
		(property "Value" ""
			(at 0 0 90)
			(layer "B.Fab")
			(effects
				(font
					(size 1.27 1.27)
				)
				(justify mirror)
			)
		)
		(duplicate_pad_numbers_are_jumpers no)
		(fp_line
			(start -3.9624 2.0066)
			(end 3.9624 2.0066)
			(stroke
				(width 0.1524)
				(type default)
			)
			(layer "B.SilkS")
		)
		(fp_line
			(start 3.9624 2.0066)
			(end 3.9624 0.5842)
			(stroke
				(width 0.1524)
				(type default)
			)
			(layer "B.SilkS")
		)
		(fp_line
			(start 3.9624 0.5842)
			(end 3.3782 0)
			(stroke
				(width 0.1524)
				(type default)
			)
			(layer "B.SilkS")
		)
		(fp_line
			(start 3.3782 0)
			(end 3.9624 -0.5842)
			(stroke
				(width 0.1524)
				(type default)
			)
			(layer "B.SilkS")
		)
		(fp_line
			(start 3.9624 -0.5842)
			(end 3.9624 -2.0066)
			(stroke
				(width 0.1524)
				(type default)
			)
			(layer "B.SilkS")
		)
		(fp_line
			(start -3.9624 -2.0066)
			(end -3.9624 2.0066)
			(stroke
				(width 0.1524)
				(type default)
			)
			(layer "B.SilkS")
		)
		(fp_line
			(start 3.9624 -2.0066)
			(end -3.9624 -2.0066)
			(stroke
				(width 0.1524)
				(type default)
			)
			(layer "B.SilkS")
		)
		(fp_circle
			(center 3.429 1.524)
			(end 3.429 1.27)
			(stroke
				(width 0.1524)
				(type default)
			)
			(fill no)
			(layer "B.SilkS")
		)
		(fp_poly
			(pts
				(xy 3.962654 3.6703) (xy 3.974846 -3.6703) (xy -3.9624 -3.6703) (xy -3.9624 3.6703)
			)
			(stroke
				(width 0)
				(type default)
			)
			(fill no)
			(layer "B.CrtYd")
		)
		(pad "1" smd rect
			(at 3.57505 2.921 90)
			(size 0.3556 1.4986)
			(layers "B.Cu" "B.Mask" "B.Paste")
			(net "N21699285")
		)
		(pad "2" smd rect
			(at 2.925064 2.921 90)
			(size 0.3556 1.4986)
			(layers "B.Cu" "B.Mask" "B.Paste")
			(net "N21700927")
		)
		(pad "3" smd rect
			(at 2.275078 2.921 90)
			(size 0.3556 1.4986)
			(layers "B.Cu" "B.Mask" "B.Paste")
			(net "N21700927")
		)
		(pad "4" smd rect
			(at 1.625092 2.921 90)
			(size 0.3556 1.4986)
			(layers "B.Cu" "B.Mask" "B.Paste")
			(net "T1_NODE1_EN")
		)
		(pad "5" smd rect
			(at 0.975106 2.921 90)
			(size 0.3556 1.4986)
			(layers "B.Cu" "B.Mask" "B.Paste")
			(net "T1_NODE2_EN")
		)
		(pad "6" smd rect
			(at 0.32512 2.921 90)
			(size 0.3556 1.4986)
			(layers "B.Cu" "B.Mask" "B.Paste")
			(net "T1_NODE3_EN")
		)
		(pad "7" smd rect
			(at -0.32512 2.921 90)
			(size 0.3556 1.4986)
			(layers "B.Cu" "B.Mask" "B.Paste")
			(net "T1_NODE4_EN")
		)
		(pad "8" smd rect
			(at -0.975106 2.921 90)
			(size 0.3556 1.4986)
			(layers "B.Cu" "B.Mask" "B.Paste")
			(net "T2_NODE1_EN")
		)
		(pad "9" smd rect
			(at -1.625092 2.921 90)
			(size 0.3556 1.4986)
			(layers "B.Cu" "B.Mask" "B.Paste")
			(net "T2_NODE2_EN")
		)
		(pad "10" smd rect
			(at -2.275078 2.921 90)
			(size 0.3556 1.4986)
			(layers "B.Cu" "B.Mask" "B.Paste")
			(net "T2_NODE3_EN")
		)
		(pad "11" smd rect
			(at -2.925064 2.921 90)
			(size 0.3556 1.4986)
			(layers "B.Cu" "B.Mask" "B.Paste")
			(net "T2_NODE4_EN")
		)
		(pad "12" smd rect
			(at -3.57505 2.921 90)
			(size 0.3556 1.4986)
			(layers "B.Cu" "B.Mask" "B.Paste")
			(net "GND")
		)
		(pad "13" smd rect
			(at -3.57505 -2.921 90)
			(size 0.3556 1.4986)
			(layers "B.Cu" "B.Mask" "B.Paste")
			(net "T3_NODE1_EN")
		)
		(pad "14" smd rect
			(at -2.925064 -2.921 90)
			(size 0.3556 1.4986)
			(layers "B.Cu" "B.Mask" "B.Paste")
			(net "T3_NODE2_EN")
		)
		(pad "15" smd rect
			(at -2.275078 -2.921 90)
			(size 0.3556 1.4986)
			(layers "B.Cu" "B.Mask" "B.Paste")
			(net "T3_NODE3_EN")
		)
		(pad "16" smd rect
			(at -1.625092 -2.921 90)
			(size 0.3556 1.4986)
			(layers "B.Cu" "B.Mask" "B.Paste")
			(net "T3_NODE4_EN")
		)
		(pad "17" smd rect
			(at -0.975106 -2.921 90)
			(size 0.3556 1.4986)
			(layers "B.Cu" "B.Mask" "B.Paste")
			(net "T4_NODE1_EN")
		)
		(pad "18" smd rect
			(at -0.32512 -2.921 90)
			(size 0.3556 1.4986)
			(layers "B.Cu" "B.Mask" "B.Paste")
			(net "T4_NODE2_EN")
		)
		(pad "19" smd rect
			(at 0.32512 -2.921 90)
			(size 0.3556 1.4986)
			(layers "B.Cu" "B.Mask" "B.Paste")
			(net "T4_NODE3_EN")
		)
		(pad "20" smd rect
			(at 0.975106 -2.921 90)
			(size 0.3556 1.4986)
			(layers "B.Cu" "B.Mask" "B.Paste")
			(net "T4_NODE4_EN")
		)
		(pad "21" smd rect
			(at 1.625092 -2.921 90)
			(size 0.3556 1.4986)
			(layers "B.Cu" "B.Mask" "B.Paste")
			(net "N21700927")
		)
		(pad "22" smd rect
			(at 2.275078 -2.921 90)
			(size 0.3556 1.4986)
			(layers "B.Cu" "B.Mask" "B.Paste")
			(net "I2C_COM3_SCL")
		)
		(pad "23" smd rect
			(at 2.925064 -2.921 90)
			(size 0.3556 1.4986)
			(layers "B.Cu" "B.Mask" "B.Paste")
			(net "I2C_COM3_SDA")
		)
		(pad "24" smd rect
			(at 3.57505 -2.921 90)
			(size 0.3556 1.4986)
			(layers "B.Cu" "B.Mask" "B.Paste")
			(net "P3V3_NODE1")
		)
	)
	(footprint ""
		(layer "B.Cu")
		(at 49.64176 -179.871624)
		(property "Reference" "C569"
			(at -1.279652 -0.008128 0)
			(unlocked yes)
			(layer "B.SilkS")
			(effects
				(font
					(size 0.7874 0.5842)
					(thickness 0.1524)
				)
				(justify left mirror)
			)
		)
		(property "Value" ""
			(at 0 0 0)
			(layer "B.Fab")
			(effects
				(font
					(size 1.27 1.27)
				)
				(justify mirror)
			)
		)
		(duplicate_pad_numbers_are_jumpers no)
		(fp_line
			(start -0.7874 -0.4064)
			(end -0.7874 0.4064)
			(stroke
				(width 0.1524)
				(type default)
			)
			(layer "B.SilkS")
		)
		(fp_line
			(start -0.7874 0.4064)
			(end 0.7874 0.4064)
			(stroke
				(width 0.1524)
				(type default)
			)
			(layer "B.SilkS")
		)
		(fp_line
			(start 0 0.381)
			(end 0 -0.381)
			(stroke
				(width 0.1524)
				(type default)
			)
			(layer "B.SilkS")
		)
		(fp_line
			(start 0.7874 -0.4064)
			(end -0.7874 -0.4064)
			(stroke
				(width 0.1524)
				(type default)
			)
			(layer "B.SilkS")
		)
		(fp_line
			(start 0.7874 0.4064)
			(end 0.7874 -0.4064)
			(stroke
				(width 0.1524)
				(type default)
			)
			(layer "B.SilkS")
		)
		(fp_poly
			(pts
				(xy 0.5334 0.254) (xy 0.635 0.254) (xy 0.635 0.2286) (xy 0.635 -0.254) (xy 0.5334 -0.254) (xy 0.5334 -0.2794)
				(xy -0.5334 -0.2794) (xy -0.5334 -0.254) (xy -0.635 -0.254) (xy -0.635 0.254) (xy -0.5334 0.254)
				(xy -0.5334 0.2794) (xy 0.508 0.2794) (xy 0.5334 0.2794)
			)
			(stroke
				(width 0)
				(type default)
			)
			(fill no)
			(layer "B.CrtYd")
		)
		(pad "1" smd rect
			(at -0.40005 0 180)
			(size 0.4572 0.508)
			(layers "B.Cu" "B.Mask" "B.Paste")
			(net "GND")
		)
		(pad "2" smd rect
			(at 0.40005 0 180)
			(size 0.4572 0.508)
			(layers "B.Cu" "B.Mask" "B.Paste")
			(net "P3V3_NODE1")
		)
	)
	(footprint ""
		(layer "B.Cu")
		(at 83.58886 -79.213456)
		(property "Reference" "R127"
			(at 0.816864 -1.071626 0)
			(unlocked yes)
			(layer "B.SilkS")
			(effects
				(font
					(size 0.7874 0.5842)
					(thickness 0.1524)
				)
				(justify left mirror)
			)
		)
		(property "Value" ""
			(at 0 0 0)
			(layer "B.Fab")
			(effects
				(font
					(size 1.27 1.27)
				)
				(justify mirror)
			)
		)
		(duplicate_pad_numbers_are_jumpers no)
		(fp_line
			(start -0.7874 -0.4064)
			(end -0.7874 0.4064)
			(stroke
				(width 0.1524)
				(type default)
			)
			(layer "B.SilkS")
		)
		(fp_line
			(start -0.7874 0.4064)
			(end 0.7874 0.4064)
			(stroke
				(width 0.1524)
				(type default)
			)
			(layer "B.SilkS")
		)
		(fp_line
			(start 0.7874 -0.4064)
			(end -0.7874 -0.4064)
			(stroke
				(width 0.1524)
				(type default)
			)
			(layer "B.SilkS")
		)
		(fp_line
			(start 0.7874 0.4064)
			(end 0.7874 -0.4064)
			(stroke
				(width 0.1524)
				(type default)
			)
			(layer "B.SilkS")
		)
		(fp_poly
			(pts
				(xy 0.508 0.2794) (xy 0.508 0.2286) (xy 0.635 0.2286) (xy 0.635 -0.254) (xy 0.5334 -0.254) (xy 0.5334 -0.2794)
				(xy -0.5334 -0.2794) (xy -0.5334 -0.254) (xy -0.635 -0.254) (xy -0.635 0.254) (xy -0.5334 0.254)
				(xy -0.5334 0.2794)
			)
			(stroke
				(width 0)
				(type default)
			)
			(fill no)
			(layer "B.CrtYd")
		)
		(pad "1" smd rect
			(at -0.40005 0 180)
			(size 0.4572 0.508)
			(layers "B.Cu" "B.Mask" "B.Paste")
			(net "SVID_CPU_NODE1_PVCCP_DAT")
		)
		(pad "2" smd rect
			(at 0.40005 0 180)
			(size 0.4572 0.508)
			(layers "B.Cu" "B.Mask" "B.Paste")
			(net "P1V05_NODE1")
		)
	)
	(footprint ""
		(layer "B.Cu")
		(at 67.67576 -188.126624 -90)
		(property "Reference" "C692"
			(at -4.308602 0.378206 270)
			(unlocked yes)
			(layer "B.SilkS")
			(effects
				(font
					(size 0.7874 0.5842)
					(thickness 0.1524)
				)
				(justify left mirror)
			)
		)
		(property "Value" ""
			(at 0 0 90)
			(layer "B.Fab")
			(effects
				(font
					(size 1.27 1.27)
				)
				(justify mirror)
			)
		)
		(duplicate_pad_numbers_are_jumpers no)
		(fp_line
			(start -0.7874 0.4064)
			(end 0.7874 0.4064)
			(stroke
				(width 0.1524)
				(type default)
			)
			(layer "B.SilkS")
		)
		(fp_line
			(start 0.7874 0.4064)
			(end 0.7874 -0.4064)
			(stroke
				(width 0.1524)
				(type default)
			)
			(layer "B.SilkS")
		)
		(fp_line
			(start 0 0.381)
			(end 0 -0.381)
			(stroke
				(width 0.1524)
				(type default)
			)
			(layer "B.SilkS")
		)
		(fp_line
			(start -0.7874 -0.4064)
			(end -0.7874 0.4064)
			(stroke
				(width 0.1524)
				(type default)
			)
			(layer "B.SilkS")
		)
		(fp_line
			(start 0.7874 -0.4064)
			(end -0.7874 -0.4064)
			(stroke
				(width 0.1524)
				(type default)
			)
			(layer "B.SilkS")
		)
		(fp_poly
			(pts
				(xy 0.5334 0.254) (xy 0.635 0.254) (xy 0.635 0.2286) (xy 0.635 -0.254) (xy 0.5334 -0.254) (xy 0.5334 -0.2794)
				(xy -0.5334 -0.2794) (xy -0.5334 -0.254) (xy -0.635 -0.254) (xy -0.635 0.254) (xy -0.5334 0.254)
				(xy -0.5334 0.2794) (xy 0.508 0.2794) (xy 0.5334 0.2794)
			)
			(stroke
				(width 0)
				(type default)
			)
			(fill no)
			(layer "B.CrtYd")
		)
		(pad "1" smd rect
			(at -0.40005 0 90)
			(size 0.4572 0.508)
			(layers "B.Cu" "B.Mask" "B.Paste")
			(net "UART_T3_NODE4_TXD_R")
		)
		(pad "2" smd rect
			(at 0.40005 0 90)
			(size 0.4572 0.508)
			(layers "B.Cu" "B.Mask" "B.Paste")
			(net "GND")
		)
	)
	(footprint ""
		(layer "B.Cu")
		(at 140.760196 -65.55613)
		(property "Reference" "C342"
			(at 1.533652 -1.064006 0)
			(unlocked yes)
			(layer "B.SilkS")
			(effects
				(font
					(size 0.7874 0.5842)
					(thickness 0.1524)
				)
				(justify left mirror)
			)
		)
		(property "Value" ""
			(at 0 0 0)
			(layer "B.Fab")
			(effects
				(font
					(size 1.27 1.27)
				)
				(justify mirror)
			)
		)
		(duplicate_pad_numbers_are_jumpers no)
		(fp_line
			(start -0.7874 -0.4064)
			(end -0.7874 0.4064)
			(stroke
				(width 0.1524)
				(type default)
			)
			(layer "B.SilkS")
		)
		(fp_line
			(start -0.7874 0.4064)
			(end 0.7874 0.4064)
			(stroke
				(width 0.1524)
				(type default)
			)
			(layer "B.SilkS")
		)
		(fp_line
			(start 0 0.381)
			(end 0 -0.381)
			(stroke
				(width 0.1524)
				(type default)
			)
			(layer "B.SilkS")
		)
		(fp_line
			(start 0.7874 -0.4064)
			(end -0.7874 -0.4064)
			(stroke
				(width 0.1524)
				(type default)
			)
			(layer "B.SilkS")
		)
		(fp_line
			(start 0.7874 0.4064)
			(end 0.7874 -0.4064)
			(stroke
				(width 0.1524)
				(type default)
			)
			(layer "B.SilkS")
		)
		(fp_poly
			(pts
				(xy 0.5334 0.254) (xy 0.635 0.254) (xy 0.635 0.2286) (xy 0.635 -0.254) (xy 0.5334 -0.254) (xy 0.5334 -0.2794)
				(xy -0.5334 -0.2794) (xy -0.5334 -0.254) (xy -0.635 -0.254) (xy -0.635 0.254) (xy -0.5334 0.254)
				(xy -0.5334 0.2794) (xy 0.508 0.2794) (xy 0.5334 0.2794)
			)
			(stroke
				(width 0)
				(type default)
			)
			(fill no)
			(layer "B.CrtYd")
		)
		(pad "1" smd rect
			(at -0.40005 0 180)
			(size 0.4572 0.508)
			(layers "B.Cu" "B.Mask" "B.Paste")
			(net "P1V0_SATA")
		)
		(pad "2" smd rect
			(at 0.40005 0 180)
			(size 0.4572 0.508)
			(layers "B.Cu" "B.Mask" "B.Paste")
			(net "GND")
		)
	)
	(footprint ""
		(layer "B.Cu")
		(at 110.70717 -182.658512 180)
		(property "Reference" "R970"
			(at 21.496528 -32.262826 0)
			(unlocked yes)
			(layer "B.SilkS")
			(effects
				(font
					(size 0.7874 0.5842)
					(thickness 0.1524)
				)
				(justify left mirror)
			)
		)
		(property "Value" ""
			(at 0 0 0)
			(layer "B.Fab")
			(effects
				(font
					(size 1.27 1.27)
				)
				(justify mirror)
			)
		)
		(duplicate_pad_numbers_are_jumpers no)
		(fp_line
			(start 0.7874 0.4064)
			(end 0.7874 -0.4064)
			(stroke
				(width 0.1524)
				(type default)
			)
			(layer "B.SilkS")
		)
		(fp_line
			(start 0.7874 -0.4064)
			(end -0.7874 -0.4064)
			(stroke
				(width 0.1524)
				(type default)
			)
			(layer "B.SilkS")
		)
		(fp_line
			(start -0.7874 0.4064)
			(end 0.7874 0.4064)
			(stroke
				(width 0.1524)
				(type default)
			)
			(layer "B.SilkS")
		)
		(fp_line
			(start -0.7874 -0.4064)
			(end -0.7874 0.4064)
			(stroke
				(width 0.1524)
				(type default)
			)
			(layer "B.SilkS")
		)
		(fp_poly
			(pts
				(xy 0.508 0.2794) (xy 0.508 0.2286) (xy 0.635 0.2286) (xy 0.635 -0.254) (xy 0.5334 -0.254) (xy 0.5334 -0.2794)
				(xy -0.5334 -0.2794) (xy -0.5334 -0.254) (xy -0.635 -0.254) (xy -0.635 0.254) (xy -0.5334 0.254)
				(xy -0.5334 0.2794)
			)
			(stroke
				(width 0)
				(type default)
			)
			(fill no)
			(layer "B.CrtYd")
		)
		(pad "1" smd rect
			(at -0.40005 0)
			(size 0.4572 0.508)
			(layers "B.Cu" "B.Mask" "B.Paste")
			(net "UART_T7_NODE3_TXD")
		)
		(pad "2" smd rect
			(at 0.40005 0)
			(size 0.4572 0.508)
			(layers "B.Cu" "B.Mask" "B.Paste")
			(net "UART_T7_NODE3_TXD_R")
		)
	)
	(footprint ""
		(layer "B.Cu")
		(at 63.922656 -143.802862)
		(property "Reference" "C257"
			(at 4.321556 0.176276 0)
			(unlocked yes)
			(layer "B.SilkS")
			(effects
				(font
					(size 0.7874 0.5842)
					(thickness 0.1524)
				)
				(justify left mirror)
			)
		)
		(property "Value" ""
			(at 0 0 0)
			(layer "B.Fab")
			(effects
				(font
					(size 1.27 1.27)
				)
				(justify mirror)
			)
		)
		(duplicate_pad_numbers_are_jumpers no)
		(fp_line
			(start -0.7874 -0.4064)
			(end -0.7874 0.4064)
			(stroke
				(width 0.1524)
				(type default)
			)
			(layer "B.SilkS")
		)
		(fp_line
			(start -0.7874 0.4064)
			(end 0.7874 0.4064)
			(stroke
				(width 0.1524)
				(type default)
			)
			(layer "B.SilkS")
		)
		(fp_line
			(start 0 0.381)
			(end 0 -0.381)
			(stroke
				(width 0.1524)
				(type default)
			)
			(layer "B.SilkS")
		)
		(fp_line
			(start 0.7874 -0.4064)
			(end -0.7874 -0.4064)
			(stroke
				(width 0.1524)
				(type default)
			)
			(layer "B.SilkS")
		)
		(fp_line
			(start 0.7874 0.4064)
			(end 0.7874 -0.4064)
			(stroke
				(width 0.1524)
				(type default)
			)
			(layer "B.SilkS")
		)
		(fp_poly
			(pts
				(xy 0.5334 0.254) (xy 0.635 0.254) (xy 0.635 0.2286) (xy 0.635 -0.254) (xy 0.5334 -0.254) (xy 0.5334 -0.2794)
				(xy -0.5334 -0.2794) (xy -0.5334 -0.254) (xy -0.635 -0.254) (xy -0.635 0.254) (xy -0.5334 0.254)
				(xy -0.5334 0.2794) (xy 0.508 0.2794) (xy 0.5334 0.2794)
			)
			(stroke
				(width 0)
				(type default)
			)
			(fill no)
			(layer "B.CrtYd")
		)
		(pad "1" smd rect
			(at -0.40005 0 180)
			(size 0.4572 0.508)
			(layers "B.Cu" "B.Mask" "B.Paste")
			(net "BMC_NODE1_ADCAV33")
		)
		(pad "2" smd rect
			(at 0.40005 0 180)
			(size 0.4572 0.508)
			(layers "B.Cu" "B.Mask" "B.Paste")
			(net "GND")
		)
	)
	(footprint ""
		(layer "B.Cu")
		(at 135.407908 -122.841258 180)
		(property "Reference" "R5"
			(at -2.329688 -0.027178 0)
			(unlocked yes)
			(layer "B.SilkS")
			(effects
				(font
					(size 0.7874 0.5842)
					(thickness 0.1524)
				)
				(justify left mirror)
			)
		)
		(property "Value" ""
			(at 0 0 0)
			(layer "B.Fab")
			(effects
				(font
					(size 1.27 1.27)
				)
				(justify mirror)
			)
		)
		(duplicate_pad_numbers_are_jumpers no)
		(fp_line
			(start 0.7874 0.4064)
			(end 0.7874 -0.4064)
			(stroke
				(width 0.1524)
				(type default)
			)
			(layer "B.SilkS")
		)
		(fp_line
			(start 0.7874 -0.4064)
			(end -0.7874 -0.4064)
			(stroke
				(width 0.1524)
				(type default)
			)
			(layer "B.SilkS")
		)
		(fp_line
			(start -0.7874 0.4064)
			(end 0.7874 0.4064)
			(stroke
				(width 0.1524)
				(type default)
			)
			(layer "B.SilkS")
		)
		(fp_line
			(start -0.7874 -0.4064)
			(end -0.7874 0.4064)
			(stroke
				(width 0.1524)
				(type default)
			)
			(layer "B.SilkS")
		)
		(fp_poly
			(pts
				(xy 0.508 0.2794) (xy 0.508 0.2286) (xy 0.635 0.2286) (xy 0.635 -0.254) (xy 0.5334 -0.254) (xy 0.5334 -0.2794)
				(xy -0.5334 -0.2794) (xy -0.5334 -0.254) (xy -0.635 -0.254) (xy -0.635 0.254) (xy -0.5334 0.254)
				(xy -0.5334 0.2794)
			)
			(stroke
				(width 0)
				(type default)
			)
			(fill no)
			(layer "B.CrtYd")
		)
		(pad "1" smd rect
			(at -0.40005 0)
			(size 0.4572 0.508)
			(layers "B.Cu" "B.Mask" "B.Paste")
			(net "P3V3_CLK_NODE1")
		)
		(pad "2" smd rect
			(at 0.40005 0)
			(size 0.4572 0.508)
			(layers "B.Cu" "B.Mask" "B.Paste")
			(net "PCI_STP_NODE1")
		)
	)
	(footprint ""
		(layer "B.Cu")
		(at 73.00976 -188.126624 90)
		(property "Reference" "R914"
			(at 4.318254 -0.320802 270)
			(unlocked yes)
			(layer "B.SilkS")
			(effects
				(font
					(size 0.7874 0.5842)
					(thickness 0.1524)
				)
				(justify left mirror)
			)
		)
		(property "Value" ""
			(at 0 0 90)
			(layer "B.Fab")
			(effects
				(font
					(size 1.27 1.27)
				)
				(justify mirror)
			)
		)
		(duplicate_pad_numbers_are_jumpers no)
		(fp_line
			(start 0.7874 -0.4064)
			(end -0.7874 -0.4064)
			(stroke
				(width 0.1524)
				(type default)
			)
			(layer "B.SilkS")
		)
		(fp_line
			(start -0.7874 -0.4064)
			(end -0.7874 0.4064)
			(stroke
				(width 0.1524)
				(type default)
			)
			(layer "B.SilkS")
		)
		(fp_line
			(start 0.7874 0.4064)
			(end 0.7874 -0.4064)
			(stroke
				(width 0.1524)
				(type default)
			)
			(layer "B.SilkS")
		)
		(fp_line
			(start -0.7874 0.4064)
			(end 0.7874 0.4064)
			(stroke
				(width 0.1524)
				(type default)
			)
			(layer "B.SilkS")
		)
		(fp_poly
			(pts
				(xy 0.508 0.2794) (xy 0.508 0.2286) (xy 0.635 0.2286) (xy 0.635 -0.254) (xy 0.5334 -0.254) (xy 0.5334 -0.2794)
				(xy -0.5334 -0.2794) (xy -0.5334 -0.254) (xy -0.635 -0.254) (xy -0.635 0.254) (xy -0.5334 0.254)
				(xy -0.5334 0.2794)
			)
			(stroke
				(width 0)
				(type default)
			)
			(fill no)
			(layer "B.CrtYd")
		)
		(pad "1" smd rect
			(at -0.40005 0 270)
			(size 0.4572 0.508)
			(layers "B.Cu" "B.Mask" "B.Paste")
			(net "UART_T3_NODE2_RXD")
		)
		(pad "2" smd rect
			(at 0.40005 0 270)
			(size 0.4572 0.508)
			(layers "B.Cu" "B.Mask" "B.Paste")
			(net "UART_T3_NODE2_RXD_R")
		)
	)
	(footprint ""
		(layer "B.Cu")
		(at 58.279538 -80.420718)
		(property "Reference" "C46"
			(at -13.440918 30.936184 0)
			(unlocked yes)
			(layer "B.SilkS")
			(effects
				(font
					(size 0.7874 0.5842)
					(thickness 0.1524)
				)
				(justify left mirror)
			)
		)
		(property "Value" ""
			(at 0 0 0)
			(layer "B.Fab")
			(effects
				(font
					(size 1.27 1.27)
				)
				(justify mirror)
			)
		)
		(duplicate_pad_numbers_are_jumpers no)
		(fp_line
			(start -0.7874 -0.4064)
			(end -0.7874 0.4064)
			(stroke
				(width 0.1524)
				(type default)
			)
			(layer "B.SilkS")
		)
		(fp_line
			(start -0.7874 0.4064)
			(end 0.7874 0.4064)
			(stroke
				(width 0.1524)
				(type default)
			)
			(layer "B.SilkS")
		)
		(fp_line
			(start 0 0.381)
			(end 0 -0.381)
			(stroke
				(width 0.1524)
				(type default)
			)
			(layer "B.SilkS")
		)
		(fp_line
			(start 0.7874 -0.4064)
			(end -0.7874 -0.4064)
			(stroke
				(width 0.1524)
				(type default)
			)
			(layer "B.SilkS")
		)
		(fp_line
			(start 0.7874 0.4064)
			(end 0.7874 -0.4064)
			(stroke
				(width 0.1524)
				(type default)
			)
			(layer "B.SilkS")
		)
		(fp_poly
			(pts
				(xy 0.5334 0.254) (xy 0.635 0.254) (xy 0.635 0.2286) (xy 0.635 -0.254) (xy 0.5334 -0.254) (xy 0.5334 -0.2794)
				(xy -0.5334 -0.2794) (xy -0.5334 -0.254) (xy -0.635 -0.254) (xy -0.635 0.254) (xy -0.5334 0.254)
				(xy -0.5334 0.2794) (xy 0.508 0.2794) (xy 0.5334 0.2794)
			)
			(stroke
				(width 0)
				(type default)
			)
			(fill no)
			(layer "B.CrtYd")
		)
		(pad "1" smd rect
			(at -0.40005 0 180)
			(size 0.4572 0.508)
			(layers "B.Cu" "B.Mask" "B.Paste")
			(net "P1V05_NODE1")
		)
		(pad "2" smd rect
			(at 0.40005 0 180)
			(size 0.4572 0.508)
			(layers "B.Cu" "B.Mask" "B.Paste")
			(net "GND")
		)
	)
	(footprint ""
		(layer "B.Cu")
		(at 138.541252 -135.84555 -90)
		(property "Reference" "C870"
			(at 5.04825 0.03937 270)
			(unlocked yes)
			(layer "B.SilkS")
			(effects
				(font
					(size 0.7874 0.5842)
					(thickness 0.1524)
				)
				(justify left mirror)
			)
		)
		(property "Value" ""
			(at 0 0 90)
			(layer "B.Fab")
			(effects
				(font
					(size 1.27 1.27)
				)
				(justify mirror)
			)
		)
		(duplicate_pad_numbers_are_jumpers no)
		(fp_line
			(start -0.7874 0.4064)
			(end 0.7874 0.4064)
			(stroke
				(width 0.1524)
				(type default)
			)
			(layer "B.SilkS")
		)
		(fp_line
			(start 0.7874 0.4064)
			(end 0.7874 -0.4064)
			(stroke
				(width 0.1524)
				(type default)
			)
			(layer "B.SilkS")
		)
		(fp_line
			(start 0 0.381)
			(end 0 -0.381)
			(stroke
				(width 0.1524)
				(type default)
			)
			(layer "B.SilkS")
		)
		(fp_line
			(start -0.7874 -0.4064)
			(end -0.7874 0.4064)
			(stroke
				(width 0.1524)
				(type default)
			)
			(layer "B.SilkS")
		)
		(fp_line
			(start 0.7874 -0.4064)
			(end -0.7874 -0.4064)
			(stroke
				(width 0.1524)
				(type default)
			)
			(layer "B.SilkS")
		)
		(fp_poly
			(pts
				(xy 0.5334 0.254) (xy 0.635 0.254) (xy 0.635 0.2286) (xy 0.635 -0.254) (xy 0.5334 -0.254) (xy 0.5334 -0.2794)
				(xy -0.5334 -0.2794) (xy -0.5334 -0.254) (xy -0.635 -0.254) (xy -0.635 0.254) (xy -0.5334 0.254)
				(xy -0.5334 0.2794) (xy 0.508 0.2794) (xy 0.5334 0.2794)
			)
			(stroke
				(width 0)
				(type default)
			)
			(fill no)
			(layer "B.CrtYd")
		)
		(pad "1" smd rect
			(at -0.40005 0 90)
			(size 0.4572 0.508)
			(layers "B.Cu" "B.Mask" "B.Paste")
			(net "P3V3_NODE1")
		)
		(pad "2" smd rect
			(at 0.40005 0 90)
			(size 0.4572 0.508)
			(layers "B.Cu" "B.Mask" "B.Paste")
			(net "GND")
		)
	)
	(footprint ""
		(layer "B.Cu")
		(at 51.67376 -188.126624 -90)
		(property "Reference" "R854"
			(at -4.339082 -0.298704 270)
			(unlocked yes)
			(layer "B.SilkS")
			(effects
				(font
					(size 0.7874 0.5842)
					(thickness 0.1524)
				)
				(justify left mirror)
			)
		)
		(property "Value" ""
			(at 0 0 90)
			(layer "B.Fab")
			(effects
				(font
					(size 1.27 1.27)
				)
				(justify mirror)
			)
		)
		(duplicate_pad_numbers_are_jumpers no)
		(fp_line
			(start -0.7874 0.4064)
			(end 0.7874 0.4064)
			(stroke
				(width 0.1524)
				(type default)
			)
			(layer "B.SilkS")
		)
		(fp_line
			(start 0.7874 0.4064)
			(end 0.7874 -0.4064)
			(stroke
				(width 0.1524)
				(type default)
			)
			(layer "B.SilkS")
		)
		(fp_line
			(start -0.7874 -0.4064)
			(end -0.7874 0.4064)
			(stroke
				(width 0.1524)
				(type default)
			)
			(layer "B.SilkS")
		)
		(fp_line
			(start 0.7874 -0.4064)
			(end -0.7874 -0.4064)
			(stroke
				(width 0.1524)
				(type default)
			)
			(layer "B.SilkS")
		)
		(fp_poly
			(pts
				(xy 0.508 0.2794) (xy 0.508 0.2286) (xy 0.635 0.2286) (xy 0.635 -0.254) (xy 0.5334 -0.254) (xy 0.5334 -0.2794)
				(xy -0.5334 -0.2794) (xy -0.5334 -0.254) (xy -0.635 -0.254) (xy -0.635 0.254) (xy -0.5334 0.254)
				(xy -0.5334 0.2794)
			)
			(stroke
				(width 0)
				(type default)
			)
			(fill no)
			(layer "B.CrtYd")
		)
		(pad "1" smd rect
			(at -0.40005 0 90)
			(size 0.4572 0.508)
			(layers "B.Cu" "B.Mask" "B.Paste")
			(net "PSU2_DC_OK_R")
		)
		(pad "2" smd rect
			(at 0.40005 0 90)
			(size 0.4572 0.508)
			(layers "B.Cu" "B.Mask" "B.Paste")
			(net "GND")
		)
	)
	(footprint ""
		(layer "B.Cu")
		(at 123.70816 -172.378624 180)
		(property "Reference" "C570"
			(at 28.598876 -31.561024 0)
			(unlocked yes)
			(layer "B.SilkS")
			(effects
				(font
					(size 0.7874 0.5842)
					(thickness 0.1524)
				)
				(justify left mirror)
			)
		)
		(property "Value" ""
			(at 0 0 0)
			(layer "B.Fab")
			(effects
				(font
					(size 1.27 1.27)
				)
				(justify mirror)
			)
		)
		(duplicate_pad_numbers_are_jumpers no)
		(fp_line
			(start 0.7874 0.4064)
			(end 0.7874 -0.4064)
			(stroke
				(width 0.1524)
				(type default)
			)
			(layer "B.SilkS")
		)
		(fp_line
			(start 0.7874 -0.4064)
			(end -0.7874 -0.4064)
			(stroke
				(width 0.1524)
				(type default)
			)
			(layer "B.SilkS")
		)
		(fp_line
			(start 0 0.381)
			(end 0 -0.381)
			(stroke
				(width 0.1524)
				(type default)
			)
			(layer "B.SilkS")
		)
		(fp_line
			(start -0.7874 0.4064)
			(end 0.7874 0.4064)
			(stroke
				(width 0.1524)
				(type default)
			)
			(layer "B.SilkS")
		)
		(fp_line
			(start -0.7874 -0.4064)
			(end -0.7874 0.4064)
			(stroke
				(width 0.1524)
				(type default)
			)
			(layer "B.SilkS")
		)
		(fp_poly
			(pts
				(xy 0.5334 0.254) (xy 0.635 0.254) (xy 0.635 0.2286) (xy 0.635 -0.254) (xy 0.5334 -0.254) (xy 0.5334 -0.2794)
				(xy -0.5334 -0.2794) (xy -0.5334 -0.254) (xy -0.635 -0.254) (xy -0.635 0.254) (xy -0.5334 0.254)
				(xy -0.5334 0.2794) (xy 0.508 0.2794) (xy 0.5334 0.2794)
			)
			(stroke
				(width 0)
				(type default)
			)
			(fill no)
			(layer "B.CrtYd")
		)
		(pad "1" smd rect
			(at -0.40005 0)
			(size 0.4572 0.508)
			(layers "B.Cu" "B.Mask" "B.Paste")
			(net "GND")
		)
		(pad "2" smd rect
			(at 0.40005 0)
			(size 0.4572 0.508)
			(layers "B.Cu" "B.Mask" "B.Paste")
			(net "P3V3_NODE1")
		)
	)
	(footprint ""
		(layer "B.Cu")
		(at 125.892052 -145.21815 180)
		(property "Reference" "C880"
			(at 3.260598 3.302254 0)
			(unlocked yes)
			(layer "B.SilkS")
			(effects
				(font
					(size 0.7874 0.5842)
					(thickness 0.1524)
				)
				(justify left mirror)
			)
		)
		(property "Value" ""
			(at 0 0 0)
			(layer "B.Fab")
			(effects
				(font
					(size 1.27 1.27)
				)
				(justify mirror)
			)
		)
		(duplicate_pad_numbers_are_jumpers no)
		(fp_line
			(start 0.7874 0.4064)
			(end 0.7874 -0.4064)
			(stroke
				(width 0.1524)
				(type default)
			)
			(layer "B.SilkS")
		)
		(fp_line
			(start 0.7874 -0.4064)
			(end -0.7874 -0.4064)
			(stroke
				(width 0.1524)
				(type default)
			)
			(layer "B.SilkS")
		)
		(fp_line
			(start 0 0.381)
			(end 0 -0.381)
			(stroke
				(width 0.1524)
				(type default)
			)
			(layer "B.SilkS")
		)
		(fp_line
			(start -0.7874 0.4064)
			(end 0.7874 0.4064)
			(stroke
				(width 0.1524)
				(type default)
			)
			(layer "B.SilkS")
		)
		(fp_line
			(start -0.7874 -0.4064)
			(end -0.7874 0.4064)
			(stroke
				(width 0.1524)
				(type default)
			)
			(layer "B.SilkS")
		)
		(fp_poly
			(pts
				(xy 0.5334 0.254) (xy 0.635 0.254) (xy 0.635 0.2286) (xy 0.635 -0.254) (xy 0.5334 -0.254) (xy 0.5334 -0.2794)
				(xy -0.5334 -0.2794) (xy -0.5334 -0.254) (xy -0.635 -0.254) (xy -0.635 0.254) (xy -0.5334 0.254)
				(xy -0.5334 0.2794) (xy 0.508 0.2794) (xy 0.5334 0.2794)
			)
			(stroke
				(width 0)
				(type default)
			)
			(fill no)
			(layer "B.CrtYd")
		)
		(pad "1" smd rect
			(at -0.40005 0)
			(size 0.4572 0.508)
			(layers "B.Cu" "B.Mask" "B.Paste")
			(net "P1V0_NODE1")
		)
		(pad "2" smd rect
			(at 0.40005 0)
			(size 0.4572 0.508)
			(layers "B.Cu" "B.Mask" "B.Paste")
			(net "GND")
		)
	)
	(footprint ""
		(layer "B.Cu")
		(at 155.05176 -187.872624 -90)
		(property "Reference" "C648"
			(at -4.565396 3.650742 270)
			(unlocked yes)
			(layer "B.SilkS")
			(effects
				(font
					(size 0.7874 0.5842)
					(thickness 0.1524)
				)
				(justify left mirror)
			)
		)
		(property "Value" ""
			(at 0 0 90)
			(layer "B.Fab")
			(effects
				(font
					(size 1.27 1.27)
				)
				(justify mirror)
			)
		)
		(duplicate_pad_numbers_are_jumpers no)
		(fp_line
			(start -0.7874 0.4064)
			(end 0.7874 0.4064)
			(stroke
				(width 0.1524)
				(type default)
			)
			(layer "B.SilkS")
		)
		(fp_line
			(start 0.7874 0.4064)
			(end 0.7874 -0.4064)
			(stroke
				(width 0.1524)
				(type default)
			)
			(layer "B.SilkS")
		)
		(fp_line
			(start 0 0.381)
			(end 0 -0.381)
			(stroke
				(width 0.1524)
				(type default)
			)
			(layer "B.SilkS")
		)
		(fp_line
			(start -0.7874 -0.4064)
			(end -0.7874 0.4064)
			(stroke
				(width 0.1524)
				(type default)
			)
			(layer "B.SilkS")
		)
		(fp_line
			(start 0.7874 -0.4064)
			(end -0.7874 -0.4064)
			(stroke
				(width 0.1524)
				(type default)
			)
			(layer "B.SilkS")
		)
		(fp_poly
			(pts
				(xy 0.5334 0.254) (xy 0.635 0.254) (xy 0.635 0.2286) (xy 0.635 -0.254) (xy 0.5334 -0.254) (xy 0.5334 -0.2794)
				(xy -0.5334 -0.2794) (xy -0.5334 -0.254) (xy -0.635 -0.254) (xy -0.635 0.254) (xy -0.5334 0.254)
				(xy -0.5334 0.2794) (xy 0.508 0.2794) (xy 0.5334 0.2794)
			)
			(stroke
				(width 0)
				(type default)
			)
			(fill no)
			(layer "B.CrtYd")
		)
		(pad "1" smd rect
			(at -0.40005 0 90)
			(size 0.4572 0.508)
			(layers "B.Cu" "B.Mask" "B.Paste")
			(net "T11_NODE1_EN_R")
		)
		(pad "2" smd rect
			(at 0.40005 0 90)
			(size 0.4572 0.508)
			(layers "B.Cu" "B.Mask" "B.Paste")
			(net "GND")
		)
	)
	(footprint ""
		(layer "B.Cu")
		(at 66.581528 -62.855856 -90)
		(property "Reference" "C114"
			(at 5.118862 -0.922782 270)
			(unlocked yes)
			(layer "B.SilkS")
			(effects
				(font
					(size 0.7874 0.5842)
					(thickness 0.1524)
				)
				(justify left mirror)
			)
		)
		(property "Value" ""
			(at 0 0 90)
			(layer "B.Fab")
			(effects
				(font
					(size 1.27 1.27)
				)
				(justify mirror)
			)
		)
		(duplicate_pad_numbers_are_jumpers no)
		(fp_line
			(start -0.7874 0.4064)
			(end 0.7874 0.4064)
			(stroke
				(width 0.1524)
				(type default)
			)
			(layer "B.SilkS")
		)
		(fp_line
			(start 0.7874 0.4064)
			(end 0.7874 -0.4064)
			(stroke
				(width 0.1524)
				(type default)
			)
			(layer "B.SilkS")
		)
		(fp_line
			(start 0 0.381)
			(end 0 -0.381)
			(stroke
				(width 0.1524)
				(type default)
			)
			(layer "B.SilkS")
		)
		(fp_line
			(start -0.7874 -0.4064)
			(end -0.7874 0.4064)
			(stroke
				(width 0.1524)
				(type default)
			)
			(layer "B.SilkS")
		)
		(fp_line
			(start 0.7874 -0.4064)
			(end -0.7874 -0.4064)
			(stroke
				(width 0.1524)
				(type default)
			)
			(layer "B.SilkS")
		)
		(fp_poly
			(pts
				(xy 0.5334 0.254) (xy 0.635 0.254) (xy 0.635 0.2286) (xy 0.635 -0.254) (xy 0.5334 -0.254) (xy 0.5334 -0.2794)
				(xy -0.5334 -0.2794) (xy -0.5334 -0.254) (xy -0.635 -0.254) (xy -0.635 0.254) (xy -0.5334 0.254)
				(xy -0.5334 0.2794) (xy 0.508 0.2794) (xy 0.5334 0.2794)
			)
			(stroke
				(width 0)
				(type default)
			)
			(fill no)
			(layer "B.CrtYd")
		)
		(pad "1" smd rect
			(at -0.40005 0 90)
			(size 0.4572 0.508)
			(layers "B.Cu" "B.Mask" "B.Paste")
			(net "PV_VDDR_NODE1")
		)
		(pad "2" smd rect
			(at 0.40005 0 90)
			(size 0.4572 0.508)
			(layers "B.Cu" "B.Mask" "B.Paste")
			(net "GND")
		)
	)
	(footprint ""
		(layer "B.Cu")
		(at 55.038498 -96.696784 90)
		(property "Reference" "R53"
			(at 6.405118 -4.364228 270)
			(unlocked yes)
			(layer "B.SilkS")
			(effects
				(font
					(size 0.7874 0.5842)
					(thickness 0.1524)
				)
				(justify left mirror)
			)
		)
		(property "Value" ""
			(at 0 0 90)
			(layer "B.Fab")
			(effects
				(font
					(size 1.27 1.27)
				)
				(justify mirror)
			)
		)
		(duplicate_pad_numbers_are_jumpers no)
		(fp_line
			(start 0.7874 -0.4064)
			(end -0.7874 -0.4064)
			(stroke
				(width 0.1524)
				(type default)
			)
			(layer "B.SilkS")
		)
		(fp_line
			(start -0.7874 -0.4064)
			(end -0.7874 0.4064)
			(stroke
				(width 0.1524)
				(type default)
			)
			(layer "B.SilkS")
		)
		(fp_line
			(start 0.7874 0.4064)
			(end 0.7874 -0.4064)
			(stroke
				(width 0.1524)
				(type default)
			)
			(layer "B.SilkS")
		)
		(fp_line
			(start -0.7874 0.4064)
			(end 0.7874 0.4064)
			(stroke
				(width 0.1524)
				(type default)
			)
			(layer "B.SilkS")
		)
		(fp_poly
			(pts
				(xy 0.508 0.2794) (xy 0.508 0.2286) (xy 0.635 0.2286) (xy 0.635 -0.254) (xy 0.5334 -0.254) (xy 0.5334 -0.2794)
				(xy -0.5334 -0.2794) (xy -0.5334 -0.254) (xy -0.635 -0.254) (xy -0.635 0.254) (xy -0.5334 0.254)
				(xy -0.5334 0.2794)
			)
			(stroke
				(width 0)
				(type default)
			)
			(fill no)
			(layer "B.CrtYd")
		)
		(pad "1" smd rect
			(at -0.40005 0 270)
			(size 0.4572 0.508)
			(layers "B.Cu" "B.Mask" "B.Paste")
			(net "PU_CPU_NODE1_DFX_GPIO_GRP1_3")
		)
		(pad "2" smd rect
			(at 0.40005 0 270)
			(size 0.4572 0.508)
			(layers "B.Cu" "B.Mask" "B.Paste")
			(net "P1V8_NODE1")
		)
	)
	(footprint ""
		(layer "B.Cu")
		(at 122.0978 -43.716702)
		(property "Reference" "R183"
			(at -2.808732 0.03429 0)
			(unlocked yes)
			(layer "B.SilkS")
			(effects
				(font
					(size 0.7874 0.5842)
					(thickness 0.1524)
				)
				(justify left mirror)
			)
		)
		(property "Value" ""
			(at 0 0 0)
			(layer "B.Fab")
			(effects
				(font
					(size 1.27 1.27)
				)
				(justify mirror)
			)
		)
		(duplicate_pad_numbers_are_jumpers no)
		(fp_line
			(start -0.7874 -0.4064)
			(end -0.7874 0.4064)
			(stroke
				(width 0.1524)
				(type default)
			)
			(layer "B.SilkS")
		)
		(fp_line
			(start -0.7874 0.4064)
			(end 0.7874 0.4064)
			(stroke
				(width 0.1524)
				(type default)
			)
			(layer "B.SilkS")
		)
		(fp_line
			(start 0.7874 -0.4064)
			(end -0.7874 -0.4064)
			(stroke
				(width 0.1524)
				(type default)
			)
			(layer "B.SilkS")
		)
		(fp_line
			(start 0.7874 0.4064)
			(end 0.7874 -0.4064)
			(stroke
				(width 0.1524)
				(type default)
			)
			(layer "B.SilkS")
		)
		(fp_poly
			(pts
				(xy 0.508 0.2794) (xy 0.508 0.2286) (xy 0.635 0.2286) (xy 0.635 -0.254) (xy 0.5334 -0.254) (xy 0.5334 -0.2794)
				(xy -0.5334 -0.2794) (xy -0.5334 -0.254) (xy -0.635 -0.254) (xy -0.635 0.254) (xy -0.5334 0.254)
				(xy -0.5334 0.2794)
			)
			(stroke
				(width 0)
				(type default)
			)
			(fill no)
			(layer "B.CrtYd")
		)
		(pad "1" smd rect
			(at -0.40005 0 180)
			(size 0.4572 0.508)
			(layers "B.Cu" "B.Mask" "B.Paste")
			(net "LPC_CPU_NODE1_LAD1")
		)
		(pad "2" smd rect
			(at 0.40005 0 180)
			(size 0.4572 0.508)
			(layers "B.Cu" "B.Mask" "B.Paste")
			(net "LPC_CPU_NODE1_LAD1_SIO")
		)
	)
	(footprint ""
		(layer "B.Cu")
		(at 75.0062 -31.72714 180)
		(property "Reference" "C144"
			(at -1.788922 -2.09804 0)
			(unlocked yes)
			(layer "B.SilkS")
			(effects
				(font
					(size 0.7874 0.5842)
					(thickness 0.1524)
				)
				(justify left mirror)
			)
		)
		(property "Value" ""
			(at 0 0 0)
			(layer "B.Fab")
			(effects
				(font
					(size 1.27 1.27)
				)
				(justify mirror)
			)
		)
		(duplicate_pad_numbers_are_jumpers no)
		(fp_line
			(start 0.7874 0.4064)
			(end 0.7874 -0.4064)
			(stroke
				(width 0.1524)
				(type default)
			)
			(layer "B.SilkS")
		)
		(fp_line
			(start 0.7874 -0.4064)
			(end -0.7874 -0.4064)
			(stroke
				(width 0.1524)
				(type default)
			)
			(layer "B.SilkS")
		)
		(fp_line
			(start 0 0.381)
			(end 0 -0.381)
			(stroke
				(width 0.1524)
				(type default)
			)
			(layer "B.SilkS")
		)
		(fp_line
			(start -0.7874 0.4064)
			(end 0.7874 0.4064)
			(stroke
				(width 0.1524)
				(type default)
			)
			(layer "B.SilkS")
		)
		(fp_line
			(start -0.7874 -0.4064)
			(end -0.7874 0.4064)
			(stroke
				(width 0.1524)
				(type default)
			)
			(layer "B.SilkS")
		)
		(fp_poly
			(pts
				(xy 0.5334 0.254) (xy 0.635 0.254) (xy 0.635 0.2286) (xy 0.635 -0.254) (xy 0.5334 -0.254) (xy 0.5334 -0.2794)
				(xy -0.5334 -0.2794) (xy -0.5334 -0.254) (xy -0.635 -0.254) (xy -0.635 0.254) (xy -0.5334 0.254)
				(xy -0.5334 0.2794) (xy 0.508 0.2794) (xy 0.5334 0.2794)
			)
			(stroke
				(width 0)
				(type default)
			)
			(fill no)
			(layer "B.CrtYd")
		)
		(pad "1" smd rect
			(at -0.40005 0)
			(size 0.4572 0.508)
			(layers "B.Cu" "B.Mask" "B.Paste")
			(net "PV_VDDR_NODE1")
		)
		(pad "2" smd rect
			(at 0.40005 0)
			(size 0.4572 0.508)
			(layers "B.Cu" "B.Mask" "B.Paste")
			(net "GND")
		)
	)
	(footprint ""
		(layer "B.Cu")
		(at 53.95976 -188.126624 -90)
		(property "Reference" "C673"
			(at -4.276598 -0.103124 270)
			(unlocked yes)
			(layer "B.SilkS")
			(effects
				(font
					(size 0.7874 0.5842)
					(thickness 0.1524)
				)
				(justify left mirror)
			)
		)
		(property "Value" ""
			(at 0 0 90)
			(layer "B.Fab")
			(effects
				(font
					(size 1.27 1.27)
				)
				(justify mirror)
			)
		)
		(duplicate_pad_numbers_are_jumpers no)
		(fp_line
			(start -0.7874 0.4064)
			(end 0.7874 0.4064)
			(stroke
				(width 0.1524)
				(type default)
			)
			(layer "B.SilkS")
		)
		(fp_line
			(start 0.7874 0.4064)
			(end 0.7874 -0.4064)
			(stroke
				(width 0.1524)
				(type default)
			)
			(layer "B.SilkS")
		)
		(fp_line
			(start 0 0.381)
			(end 0 -0.381)
			(stroke
				(width 0.1524)
				(type default)
			)
			(layer "B.SilkS")
		)
		(fp_line
			(start -0.7874 -0.4064)
			(end -0.7874 0.4064)
			(stroke
				(width 0.1524)
				(type default)
			)
			(layer "B.SilkS")
		)
		(fp_line
			(start 0.7874 -0.4064)
			(end -0.7874 -0.4064)
			(stroke
				(width 0.1524)
				(type default)
			)
			(layer "B.SilkS")
		)
		(fp_poly
			(pts
				(xy 0.5334 0.254) (xy 0.635 0.254) (xy 0.635 0.2286) (xy 0.635 -0.254) (xy 0.5334 -0.254) (xy 0.5334 -0.2794)
				(xy -0.5334 -0.2794) (xy -0.5334 -0.254) (xy -0.635 -0.254) (xy -0.635 0.254) (xy -0.5334 0.254)
				(xy -0.5334 0.2794) (xy 0.508 0.2794) (xy 0.5334 0.2794)
			)
			(stroke
				(width 0)
				(type default)
			)
			(fill no)
			(layer "B.CrtYd")
		)
		(pad "1" smd rect
			(at -0.40005 0 90)
			(size 0.4572 0.508)
			(layers "B.Cu" "B.Mask" "B.Paste")
			(net "UART_T1_NODE1_TXD_R")
		)
		(pad "2" smd rect
			(at 0.40005 0 90)
			(size 0.4572 0.508)
			(layers "B.Cu" "B.Mask" "B.Paste")
			(net "GND")
		)
	)
	(footprint ""
		(layer "B.Cu")
		(at 37.92474 -145.56867)
		(property "Reference" "R551"
			(at -2.549652 0.339852 0)
			(unlocked yes)
			(layer "B.SilkS")
			(effects
				(font
					(size 0.7874 0.5842)
					(thickness 0.1524)
				)
				(justify left mirror)
			)
		)
		(property "Value" ""
			(at 0 0 0)
			(layer "B.Fab")
			(effects
				(font
					(size 1.27 1.27)
				)
				(justify mirror)
			)
		)
		(duplicate_pad_numbers_are_jumpers no)
		(fp_line
			(start -0.7874 -0.4064)
			(end -0.7874 0.4064)
			(stroke
				(width 0.1524)
				(type default)
			)
			(layer "B.SilkS")
		)
		(fp_line
			(start -0.7874 0.4064)
			(end 0.7874 0.4064)
			(stroke
				(width 0.1524)
				(type default)
			)
			(layer "B.SilkS")
		)
		(fp_line
			(start 0.7874 -0.4064)
			(end -0.7874 -0.4064)
			(stroke
				(width 0.1524)
				(type default)
			)
			(layer "B.SilkS")
		)
		(fp_line
			(start 0.7874 0.4064)
			(end 0.7874 -0.4064)
			(stroke
				(width 0.1524)
				(type default)
			)
			(layer "B.SilkS")
		)
		(fp_poly
			(pts
				(xy 0.508 0.2794) (xy 0.508 0.2286) (xy 0.635 0.2286) (xy 0.635 -0.254) (xy 0.5334 -0.254) (xy 0.5334 -0.2794)
				(xy -0.5334 -0.2794) (xy -0.5334 -0.254) (xy -0.635 -0.254) (xy -0.635 0.254) (xy -0.5334 0.254)
				(xy -0.5334 0.2794)
			)
			(stroke
				(width 0)
				(type default)
			)
			(fill no)
			(layer "B.CrtYd")
		)
		(pad "1" smd rect
			(at -0.40005 0 180)
			(size 0.4572 0.508)
			(layers "B.Cu" "B.Mask" "B.Paste")
			(net "P3V3_NODE1")
		)
		(pad "2" smd rect
			(at 0.40005 0 180)
			(size 0.4572 0.508)
			(layers "B.Cu" "B.Mask" "B.Paste")
			(net "LAN1_DIS_REG10")
		)
	)
	(footprint ""
		(layer "B.Cu")
		(at 60.057538 -82.325718)
		(property "Reference" "C40"
			(at -13.458698 30.852872 0)
			(unlocked yes)
			(layer "B.SilkS")
			(effects
				(font
					(size 0.7874 0.5842)
					(thickness 0.1524)
				)
				(justify left mirror)
			)
		)
		(property "Value" ""
			(at 0 0 0)
			(layer "B.Fab")
			(effects
				(font
					(size 1.27 1.27)
				)
				(justify mirror)
			)
		)
		(duplicate_pad_numbers_are_jumpers no)
		(fp_line
			(start -0.7874 -0.4064)
			(end -0.7874 0.4064)
			(stroke
				(width 0.1524)
				(type default)
			)
			(layer "B.SilkS")
		)
		(fp_line
			(start -0.7874 0.4064)
			(end 0.7874 0.4064)
			(stroke
				(width 0.1524)
				(type default)
			)
			(layer "B.SilkS")
		)
		(fp_line
			(start 0 0.381)
			(end 0 -0.381)
			(stroke
				(width 0.1524)
				(type default)
			)
			(layer "B.SilkS")
		)
		(fp_line
			(start 0.7874 -0.4064)
			(end -0.7874 -0.4064)
			(stroke
				(width 0.1524)
				(type default)
			)
			(layer "B.SilkS")
		)
		(fp_line
			(start 0.7874 0.4064)
			(end 0.7874 -0.4064)
			(stroke
				(width 0.1524)
				(type default)
			)
			(layer "B.SilkS")
		)
		(fp_poly
			(pts
				(xy 0.5334 0.254) (xy 0.635 0.254) (xy 0.635 0.2286) (xy 0.635 -0.254) (xy 0.5334 -0.254) (xy 0.5334 -0.2794)
				(xy -0.5334 -0.2794) (xy -0.5334 -0.254) (xy -0.635 -0.254) (xy -0.635 0.254) (xy -0.5334 0.254)
				(xy -0.5334 0.2794) (xy 0.508 0.2794) (xy 0.5334 0.2794)
			)
			(stroke
				(width 0)
				(type default)
			)
			(fill no)
			(layer "B.CrtYd")
		)
		(pad "1" smd rect
			(at -0.40005 0 180)
			(size 0.4572 0.508)
			(layers "B.Cu" "B.Mask" "B.Paste")
			(net "P3V3_NODE1")
		)
		(pad "2" smd rect
			(at 0.40005 0 180)
			(size 0.4572 0.508)
			(layers "B.Cu" "B.Mask" "B.Paste")
			(net "GND")
		)
	)
	(footprint ""
		(layer "B.Cu")
		(at 174.616872 -159.346138 -90)
		(property "Reference" "C523"
			(at -2.561844 0.00762 270)
			(unlocked yes)
			(layer "B.SilkS")
			(effects
				(font
					(size 0.7874 0.5842)
					(thickness 0.1524)
				)
				(justify left mirror)
			)
		)
		(property "Value" ""
			(at 0 0 90)
			(layer "B.Fab")
			(effects
				(font
					(size 1.27 1.27)
				)
				(justify mirror)
			)
		)
		(duplicate_pad_numbers_are_jumpers no)
		(fp_line
			(start -0.7874 0.4064)
			(end 0.7874 0.4064)
			(stroke
				(width 0.1524)
				(type default)
			)
			(layer "B.SilkS")
		)
		(fp_line
			(start 0.7874 0.4064)
			(end 0.7874 -0.4064)
			(stroke
				(width 0.1524)
				(type default)
			)
			(layer "B.SilkS")
		)
		(fp_line
			(start 0 0.381)
			(end 0 -0.381)
			(stroke
				(width 0.1524)
				(type default)
			)
			(layer "B.SilkS")
		)
		(fp_line
			(start -0.7874 -0.4064)
			(end -0.7874 0.4064)
			(stroke
				(width 0.1524)
				(type default)
			)
			(layer "B.SilkS")
		)
		(fp_line
			(start 0.7874 -0.4064)
			(end -0.7874 -0.4064)
			(stroke
				(width 0.1524)
				(type default)
			)
			(layer "B.SilkS")
		)
		(fp_poly
			(pts
				(xy 0.5334 0.254) (xy 0.635 0.254) (xy 0.635 0.2286) (xy 0.635 -0.254) (xy 0.5334 -0.254) (xy 0.5334 -0.2794)
				(xy -0.5334 -0.2794) (xy -0.5334 -0.254) (xy -0.635 -0.254) (xy -0.635 0.254) (xy -0.5334 0.254)
				(xy -0.5334 0.2794) (xy 0.508 0.2794) (xy 0.5334 0.2794)
			)
			(stroke
				(width 0)
				(type default)
			)
			(fill no)
			(layer "B.CrtYd")
		)
		(pad "1" smd rect
			(at -0.40005 0 90)
			(size 0.4572 0.508)
			(layers "B.Cu" "B.Mask" "B.Paste")
			(net "P1V9_LAN2")
		)
		(pad "2" smd rect
			(at 0.40005 0 90)
			(size 0.4572 0.508)
			(layers "B.Cu" "B.Mask" "B.Paste")
			(net "GND")
		)
	)
	(footprint ""
		(layer "B.Cu")
		(at 62.18301 -132.007356 180)
		(property "Reference" "C273"
			(at 40.635428 -52.99202 0)
			(unlocked yes)
			(layer "B.SilkS")
			(effects
				(font
					(size 0.7874 0.5842)
					(thickness 0.1524)
				)
				(justify left mirror)
			)
		)
		(property "Value" ""
			(at 0 0 0)
			(layer "B.Fab")
			(effects
				(font
					(size 1.27 1.27)
				)
				(justify mirror)
			)
		)
		(duplicate_pad_numbers_are_jumpers no)
		(fp_line
			(start 0.7874 0.4064)
			(end 0.7874 -0.4064)
			(stroke
				(width 0.1524)
				(type default)
			)
			(layer "B.SilkS")
		)
		(fp_line
			(start 0.7874 -0.4064)
			(end -0.7874 -0.4064)
			(stroke
				(width 0.1524)
				(type default)
			)
			(layer "B.SilkS")
		)
		(fp_line
			(start 0 0.381)
			(end 0 -0.381)
			(stroke
				(width 0.1524)
				(type default)
			)
			(layer "B.SilkS")
		)
		(fp_line
			(start -0.7874 0.4064)
			(end 0.7874 0.4064)
			(stroke
				(width 0.1524)
				(type default)
			)
			(layer "B.SilkS")
		)
		(fp_line
			(start -0.7874 -0.4064)
			(end -0.7874 0.4064)
			(stroke
				(width 0.1524)
				(type default)
			)
			(layer "B.SilkS")
		)
		(fp_poly
			(pts
				(xy 0.5334 0.254) (xy 0.635 0.254) (xy 0.635 0.2286) (xy 0.635 -0.254) (xy 0.5334 -0.254) (xy 0.5334 -0.2794)
				(xy -0.5334 -0.2794) (xy -0.5334 -0.254) (xy -0.635 -0.254) (xy -0.635 0.254) (xy -0.5334 0.254)
				(xy -0.5334 0.2794) (xy 0.508 0.2794) (xy 0.5334 0.2794)
			)
			(stroke
				(width 0)
				(type default)
			)
			(fill no)
			(layer "B.CrtYd")
		)
		(pad "1" smd rect
			(at -0.40005 0)
			(size 0.4572 0.508)
			(layers "B.Cu" "B.Mask" "B.Paste")
			(net "GND")
		)
		(pad "2" smd rect
			(at 0.40005 0)
			(size 0.4572 0.508)
			(layers "B.Cu" "B.Mask" "B.Paste")
			(net "P1V538_BMC_NODE1")
		)
	)
	(footprint ""
		(layer "B.Cu")
		(at 128.55575 -51.2572 180)
		(property "Reference" "R1263"
			(at -0.67945 -1.06807 0)
			(unlocked yes)
			(layer "B.SilkS")
			(effects
				(font
					(size 0.7874 0.5842)
					(thickness 0.1524)
				)
				(justify left mirror)
			)
		)
		(property "Value" ""
			(at 0 0 0)
			(layer "B.Fab")
			(effects
				(font
					(size 1.27 1.27)
				)
				(justify mirror)
			)
		)
		(duplicate_pad_numbers_are_jumpers no)
		(fp_line
			(start 0.7874 0.4064)
			(end 0.7874 -0.4064)
			(stroke
				(width 0.1524)
				(type default)
			)
			(layer "B.SilkS")
		)
		(fp_line
			(start 0.7874 -0.4064)
			(end -0.7874 -0.4064)
			(stroke
				(width 0.1524)
				(type default)
			)
			(layer "B.SilkS")
		)
		(fp_line
			(start -0.7874 0.4064)
			(end 0.7874 0.4064)
			(stroke
				(width 0.1524)
				(type default)
			)
			(layer "B.SilkS")
		)
		(fp_line
			(start -0.7874 -0.4064)
			(end -0.7874 0.4064)
			(stroke
				(width 0.1524)
				(type default)
			)
			(layer "B.SilkS")
		)
		(fp_poly
			(pts
				(xy 0.508 0.2794) (xy 0.508 0.2286) (xy 0.635 0.2286) (xy 0.635 -0.254) (xy 0.5334 -0.254) (xy 0.5334 -0.2794)
				(xy -0.5334 -0.2794) (xy -0.5334 -0.254) (xy -0.635 -0.254) (xy -0.635 0.254) (xy -0.5334 0.254)
				(xy -0.5334 0.2794)
			)
			(stroke
				(width 0)
				(type default)
			)
			(fill no)
			(layer "B.CrtYd")
		)
		(pad "1" smd rect
			(at -0.40005 0)
			(size 0.4572 0.508)
			(layers "B.Cu" "B.Mask" "B.Paste")
			(net "P5V_NODE1")
		)
		(pad "2" smd rect
			(at 0.40005 0)
			(size 0.4572 0.508)
			(layers "B.Cu" "B.Mask" "B.Paste")
			(net "UART_RI_P3_N")
		)
	)
	(footprint ""
		(layer "B.Cu")
		(at 165.210998 -155.38323 180)
		(property "Reference" "C472"
			(at 1.075182 -0.629158 0)
			(unlocked yes)
			(layer "B.SilkS")
			(effects
				(font
					(size 0.7874 0.5842)
					(thickness 0.1524)
				)
				(justify left mirror)
			)
		)
		(property "Value" ""
			(at 0 0 0)
			(layer "B.Fab")
			(effects
				(font
					(size 1.27 1.27)
				)
				(justify mirror)
			)
		)
		(duplicate_pad_numbers_are_jumpers no)
		(fp_line
			(start 0.7874 0.4064)
			(end 0.7874 -0.4064)
			(stroke
				(width 0.1524)
				(type default)
			)
			(layer "B.SilkS")
		)
		(fp_line
			(start 0.7874 -0.4064)
			(end -0.7874 -0.4064)
			(stroke
				(width 0.1524)
				(type default)
			)
			(layer "B.SilkS")
		)
		(fp_line
			(start 0 0.381)
			(end 0 -0.381)
			(stroke
				(width 0.1524)
				(type default)
			)
			(layer "B.SilkS")
		)
		(fp_line
			(start -0.7874 0.4064)
			(end 0.7874 0.4064)
			(stroke
				(width 0.1524)
				(type default)
			)
			(layer "B.SilkS")
		)
		(fp_line
			(start -0.7874 -0.4064)
			(end -0.7874 0.4064)
			(stroke
				(width 0.1524)
				(type default)
			)
			(layer "B.SilkS")
		)
		(fp_poly
			(pts
				(xy 0.5334 0.254) (xy 0.635 0.254) (xy 0.635 0.2286) (xy 0.635 -0.254) (xy 0.5334 -0.254) (xy 0.5334 -0.2794)
				(xy -0.5334 -0.2794) (xy -0.5334 -0.254) (xy -0.635 -0.254) (xy -0.635 0.254) (xy -0.5334 0.254)
				(xy -0.5334 0.2794) (xy 0.508 0.2794) (xy 0.5334 0.2794)
			)
			(stroke
				(width 0)
				(type default)
			)
			(fill no)
			(layer "B.CrtYd")
		)
		(pad "1" smd rect
			(at -0.40005 0)
			(size 0.4572 0.508)
			(layers "B.Cu" "B.Mask" "B.Paste")
			(net "P1V9_LAN2")
		)
		(pad "2" smd rect
			(at 0.40005 0)
			(size 0.4572 0.508)
			(layers "B.Cu" "B.Mask" "B.Paste")
			(net "GND")
		)
	)
	(footprint ""
		(layer "B.Cu")
		(at 129.778252 -136.74471 90)
		(property "Reference" "C192"
			(at -5.94741 0.25019 270)
			(unlocked yes)
			(layer "B.SilkS")
			(effects
				(font
					(size 0.7874 0.5842)
					(thickness 0.1524)
				)
				(justify left mirror)
			)
		)
		(property "Value" ""
			(at 0 0 90)
			(layer "B.Fab")
			(effects
				(font
					(size 1.27 1.27)
				)
				(justify mirror)
			)
		)
		(duplicate_pad_numbers_are_jumpers no)
		(fp_line
			(start 0.7874 -0.4064)
			(end -0.7874 -0.4064)
			(stroke
				(width 0.1524)
				(type default)
			)
			(layer "B.SilkS")
		)
		(fp_line
			(start -0.7874 -0.4064)
			(end -0.7874 0.4064)
			(stroke
				(width 0.1524)
				(type default)
			)
			(layer "B.SilkS")
		)
		(fp_line
			(start 0 0.381)
			(end 0 -0.381)
			(stroke
				(width 0.1524)
				(type default)
			)
			(layer "B.SilkS")
		)
		(fp_line
			(start 0.7874 0.4064)
			(end 0.7874 -0.4064)
			(stroke
				(width 0.1524)
				(type default)
			)
			(layer "B.SilkS")
		)
		(fp_line
			(start -0.7874 0.4064)
			(end 0.7874 0.4064)
			(stroke
				(width 0.1524)
				(type default)
			)
			(layer "B.SilkS")
		)
		(fp_poly
			(pts
				(xy 0.5334 0.254) (xy 0.635 0.254) (xy 0.635 0.2286) (xy 0.635 -0.254) (xy 0.5334 -0.254) (xy 0.5334 -0.2794)
				(xy -0.5334 -0.2794) (xy -0.5334 -0.254) (xy -0.635 -0.254) (xy -0.635 0.254) (xy -0.5334 0.254)
				(xy -0.5334 0.2794) (xy 0.508 0.2794) (xy 0.5334 0.2794)
			)
			(stroke
				(width 0)
				(type default)
			)
			(fill no)
			(layer "B.CrtYd")
		)
		(pad "1" smd rect
			(at -0.40005 0 270)
			(size 0.4572 0.508)
			(layers "B.Cu" "B.Mask" "B.Paste")
			(net "CLK_100M_PCIE_SW_NODE1_DP")
		)
		(pad "2" smd rect
			(at 0.40005 0 270)
			(size 0.4572 0.508)
			(layers "B.Cu" "B.Mask" "B.Paste")
			(net "CLK_100M_PCIE_SW_NODE1_C_DP")
		)
	)
	(footprint ""
		(layer "B.Cu")
		(at 62.19317 -135.072374)
		(property "Reference" "C272"
			(at -40.645588 52.933346 0)
			(unlocked yes)
			(layer "B.SilkS")
			(effects
				(font
					(size 0.7874 0.5842)
					(thickness 0.1524)
				)
				(justify left mirror)
			)
		)
		(property "Value" ""
			(at 0 0 0)
			(layer "B.Fab")
			(effects
				(font
					(size 1.27 1.27)
				)
				(justify mirror)
			)
		)
		(duplicate_pad_numbers_are_jumpers no)
		(fp_line
			(start -0.7874 -0.4064)
			(end -0.7874 0.4064)
			(stroke
				(width 0.1524)
				(type default)
			)
			(layer "B.SilkS")
		)
		(fp_line
			(start -0.7874 0.4064)
			(end 0.7874 0.4064)
			(stroke
				(width 0.1524)
				(type default)
			)
			(layer "B.SilkS")
		)
		(fp_line
			(start 0 0.381)
			(end 0 -0.381)
			(stroke
				(width 0.1524)
				(type default)
			)
			(layer "B.SilkS")
		)
		(fp_line
			(start 0.7874 -0.4064)
			(end -0.7874 -0.4064)
			(stroke
				(width 0.1524)
				(type default)
			)
			(layer "B.SilkS")
		)
		(fp_line
			(start 0.7874 0.4064)
			(end 0.7874 -0.4064)
			(stroke
				(width 0.1524)
				(type default)
			)
			(layer "B.SilkS")
		)
		(fp_poly
			(pts
				(xy 0.5334 0.254) (xy 0.635 0.254) (xy 0.635 0.2286) (xy 0.635 -0.254) (xy 0.5334 -0.254) (xy 0.5334 -0.2794)
				(xy -0.5334 -0.2794) (xy -0.5334 -0.254) (xy -0.635 -0.254) (xy -0.635 0.254) (xy -0.5334 0.254)
				(xy -0.5334 0.2794) (xy 0.508 0.2794) (xy 0.5334 0.2794)
			)
			(stroke
				(width 0)
				(type default)
			)
			(fill no)
			(layer "B.CrtYd")
		)
		(pad "1" smd rect
			(at -0.40005 0 180)
			(size 0.4572 0.508)
			(layers "B.Cu" "B.Mask" "B.Paste")
			(net "P1V538_BMC_NODE1")
		)
		(pad "2" smd rect
			(at 0.40005 0 180)
			(size 0.4572 0.508)
			(layers "B.Cu" "B.Mask" "B.Paste")
			(net "GND")
		)
	)
	(footprint ""
		(layer "B.Cu")
		(at 159.02178 -157.744922 -90)
		(property "Reference" "C462"
			(at -0.347218 1.448054 270)
			(unlocked yes)
			(layer "B.SilkS")
			(effects
				(font
					(size 0.7874 0.5842)
					(thickness 0.1524)
				)
				(justify left mirror)
			)
		)
		(property "Value" ""
			(at 0 0 90)
			(layer "B.Fab")
			(effects
				(font
					(size 1.27 1.27)
				)
				(justify mirror)
			)
		)
		(duplicate_pad_numbers_are_jumpers no)
		(fp_line
			(start -0.7874 0.4064)
			(end 0.7874 0.4064)
			(stroke
				(width 0.1524)
				(type default)
			)
			(layer "B.SilkS")
		)
		(fp_line
			(start 0.7874 0.4064)
			(end 0.7874 -0.4064)
			(stroke
				(width 0.1524)
				(type default)
			)
			(layer "B.SilkS")
		)
		(fp_line
			(start 0 0.381)
			(end 0 -0.381)
			(stroke
				(width 0.1524)
				(type default)
			)
			(layer "B.SilkS")
		)
		(fp_line
			(start -0.7874 -0.4064)
			(end -0.7874 0.4064)
			(stroke
				(width 0.1524)
				(type default)
			)
			(layer "B.SilkS")
		)
		(fp_line
			(start 0.7874 -0.4064)
			(end -0.7874 -0.4064)
			(stroke
				(width 0.1524)
				(type default)
			)
			(layer "B.SilkS")
		)
		(fp_poly
			(pts
				(xy 0.5334 0.254) (xy 0.635 0.254) (xy 0.635 0.2286) (xy 0.635 -0.254) (xy 0.5334 -0.254) (xy 0.5334 -0.2794)
				(xy -0.5334 -0.2794) (xy -0.5334 -0.254) (xy -0.635 -0.254) (xy -0.635 0.254) (xy -0.5334 0.254)
				(xy -0.5334 0.2794) (xy 0.508 0.2794) (xy 0.5334 0.2794)
			)
			(stroke
				(width 0)
				(type default)
			)
			(fill no)
			(layer "B.CrtYd")
		)
		(pad "1" smd rect
			(at -0.40005 0 90)
			(size 0.4572 0.508)
			(layers "B.Cu" "B.Mask" "B.Paste")
			(net "P1V05_LAN2")
		)
		(pad "2" smd rect
			(at 0.40005 0 90)
			(size 0.4572 0.508)
			(layers "B.Cu" "B.Mask" "B.Paste")
			(net "GND")
		)
	)
	(footprint ""
		(layer "B.Cu")
		(at 87.90813 -76.678282 180)
		(property "Reference" "R141"
			(at 2.202942 -9.69518 0)
			(unlocked yes)
			(layer "B.SilkS")
			(effects
				(font
					(size 0.7874 0.5842)
					(thickness 0.1524)
				)
				(justify left mirror)
			)
		)
		(property "Value" ""
			(at 0 0 0)
			(layer "B.Fab")
			(effects
				(font
					(size 1.27 1.27)
				)
				(justify mirror)
			)
		)
		(duplicate_pad_numbers_are_jumpers no)
		(fp_line
			(start 0.7874 0.4064)
			(end 0.7874 -0.4064)
			(stroke
				(width 0.1524)
				(type default)
			)
			(layer "B.SilkS")
		)
		(fp_line
			(start 0.7874 -0.4064)
			(end -0.7874 -0.4064)
			(stroke
				(width 0.1524)
				(type default)
			)
			(layer "B.SilkS")
		)
		(fp_line
			(start -0.7874 0.4064)
			(end 0.7874 0.4064)
			(stroke
				(width 0.1524)
				(type default)
			)
			(layer "B.SilkS")
		)
		(fp_line
			(start -0.7874 -0.4064)
			(end -0.7874 0.4064)
			(stroke
				(width 0.1524)
				(type default)
			)
			(layer "B.SilkS")
		)
		(fp_poly
			(pts
				(xy 0.508 0.2794) (xy 0.508 0.2286) (xy 0.635 0.2286) (xy 0.635 -0.254) (xy 0.5334 -0.254) (xy 0.5334 -0.2794)
				(xy -0.5334 -0.2794) (xy -0.5334 -0.254) (xy -0.635 -0.254) (xy -0.635 0.254) (xy -0.5334 0.254)
				(xy -0.5334 0.2794)
			)
			(stroke
				(width 0)
				(type default)
			)
			(fill no)
			(layer "B.CrtYd")
		)
		(pad "1" smd rect
			(at -0.40005 0)
			(size 0.4572 0.508)
			(layers "B.Cu" "B.Mask" "B.Paste")
			(net "GND")
		)
		(pad "2" smd rect
			(at 0.40005 0)
			(size 0.4572 0.508)
			(layers "B.Cu" "B.Mask" "B.Paste")
			(net "PWRGD_CPU_NODE1_EPWRGOOD")
		)
	)
	(footprint ""
		(layer "B.Cu")
		(at 90.81262 -164.878512)
		(property "Reference" "R787"
			(at 24.774144 20.136104 0)
			(unlocked yes)
			(layer "B.SilkS")
			(effects
				(font
					(size 0.7874 0.5842)
					(thickness 0.1524)
				)
				(justify left mirror)
			)
		)
		(property "Value" ""
			(at 0 0 0)
			(layer "B.Fab")
			(effects
				(font
					(size 1.27 1.27)
				)
				(justify mirror)
			)
		)
		(duplicate_pad_numbers_are_jumpers no)
		(fp_line
			(start -0.7874 -0.4064)
			(end -0.7874 0.4064)
			(stroke
				(width 0.1524)
				(type default)
			)
			(layer "B.SilkS")
		)
		(fp_line
			(start -0.7874 0.4064)
			(end 0.7874 0.4064)
			(stroke
				(width 0.1524)
				(type default)
			)
			(layer "B.SilkS")
		)
		(fp_line
			(start 0.7874 -0.4064)
			(end -0.7874 -0.4064)
			(stroke
				(width 0.1524)
				(type default)
			)
			(layer "B.SilkS")
		)
		(fp_line
			(start 0.7874 0.4064)
			(end 0.7874 -0.4064)
			(stroke
				(width 0.1524)
				(type default)
			)
			(layer "B.SilkS")
		)
		(fp_poly
			(pts
				(xy 0.508 0.2794) (xy 0.508 0.2286) (xy 0.635 0.2286) (xy 0.635 -0.254) (xy 0.5334 -0.254) (xy 0.5334 -0.2794)
				(xy -0.5334 -0.2794) (xy -0.5334 -0.254) (xy -0.635 -0.254) (xy -0.635 0.254) (xy -0.5334 0.254)
				(xy -0.5334 0.2794)
			)
			(stroke
				(width 0)
				(type default)
			)
			(fill no)
			(layer "B.CrtYd")
		)
		(pad "1" smd rect
			(at -0.40005 0 180)
			(size 0.4572 0.508)
			(layers "B.Cu" "B.Mask" "B.Paste")
			(net "UART_SW_S3_N")
		)
		(pad "2" smd rect
			(at 0.40005 0 180)
			(size 0.4572 0.508)
			(layers "B.Cu" "B.Mask" "B.Paste")
			(net "P3V3_NODE1")
		)
	)
	(footprint ""
		(layer "B.Cu")
		(at 71.99376 -188.126624 -90)
		(property "Reference" "C680"
			(at -4.318254 0.33401 270)
			(unlocked yes)
			(layer "B.SilkS")
			(effects
				(font
					(size 0.7874 0.5842)
					(thickness 0.1524)
				)
				(justify left mirror)
			)
		)
		(property "Value" ""
			(at 0 0 90)
			(layer "B.Fab")
			(effects
				(font
					(size 1.27 1.27)
				)
				(justify mirror)
			)
		)
		(duplicate_pad_numbers_are_jumpers no)
		(fp_line
			(start -0.7874 0.4064)
			(end 0.7874 0.4064)
			(stroke
				(width 0.1524)
				(type default)
			)
			(layer "B.SilkS")
		)
		(fp_line
			(start 0.7874 0.4064)
			(end 0.7874 -0.4064)
			(stroke
				(width 0.1524)
				(type default)
			)
			(layer "B.SilkS")
		)
		(fp_line
			(start 0 0.381)
			(end 0 -0.381)
			(stroke
				(width 0.1524)
				(type default)
			)
			(layer "B.SilkS")
		)
		(fp_line
			(start -0.7874 -0.4064)
			(end -0.7874 0.4064)
			(stroke
				(width 0.1524)
				(type default)
			)
			(layer "B.SilkS")
		)
		(fp_line
			(start 0.7874 -0.4064)
			(end -0.7874 -0.4064)
			(stroke
				(width 0.1524)
				(type default)
			)
			(layer "B.SilkS")
		)
		(fp_poly
			(pts
				(xy 0.5334 0.254) (xy 0.635 0.254) (xy 0.635 0.2286) (xy 0.635 -0.254) (xy 0.5334 -0.254) (xy 0.5334 -0.2794)
				(xy -0.5334 -0.2794) (xy -0.5334 -0.254) (xy -0.635 -0.254) (xy -0.635 0.254) (xy -0.5334 0.254)
				(xy -0.5334 0.2794) (xy 0.508 0.2794) (xy 0.5334 0.2794)
			)
			(stroke
				(width 0)
				(type default)
			)
			(fill no)
			(layer "B.CrtYd")
		)
		(pad "1" smd rect
			(at -0.40005 0 90)
			(size 0.4572 0.508)
			(layers "B.Cu" "B.Mask" "B.Paste")
			(net "UART_T3_NODE2_TXD_R")
		)
		(pad "2" smd rect
			(at 0.40005 0 90)
			(size 0.4572 0.508)
			(layers "B.Cu" "B.Mask" "B.Paste")
			(net "GND")
		)
	)
	(footprint ""
		(layer "B.Cu")
		(at 118.47576 -185.205624 90)
		(property "Reference" "R875"
			(at 3.957828 0.383794 270)
			(unlocked yes)
			(layer "B.SilkS")
			(effects
				(font
					(size 0.7874 0.5842)
					(thickness 0.1524)
				)
				(justify left mirror)
			)
		)
		(property "Value" ""
			(at 0 0 90)
			(layer "B.Fab")
			(effects
				(font
					(size 1.27 1.27)
				)
				(justify mirror)
			)
		)
		(duplicate_pad_numbers_are_jumpers no)
		(fp_line
			(start 0.7874 -0.4064)
			(end -0.7874 -0.4064)
			(stroke
				(width 0.1524)
				(type default)
			)
			(layer "B.SilkS")
		)
		(fp_line
			(start -0.7874 -0.4064)
			(end -0.7874 0.4064)
			(stroke
				(width 0.1524)
				(type default)
			)
			(layer "B.SilkS")
		)
		(fp_line
			(start 0.7874 0.4064)
			(end 0.7874 -0.4064)
			(stroke
				(width 0.1524)
				(type default)
			)
			(layer "B.SilkS")
		)
		(fp_line
			(start -0.7874 0.4064)
			(end 0.7874 0.4064)
			(stroke
				(width 0.1524)
				(type default)
			)
			(layer "B.SilkS")
		)
		(fp_poly
			(pts
				(xy 0.508 0.2794) (xy 0.508 0.2286) (xy 0.635 0.2286) (xy 0.635 -0.254) (xy 0.5334 -0.254) (xy 0.5334 -0.2794)
				(xy -0.5334 -0.2794) (xy -0.5334 -0.254) (xy -0.635 -0.254) (xy -0.635 0.254) (xy -0.5334 0.254)
				(xy -0.5334 0.2794)
			)
			(stroke
				(width 0)
				(type default)
			)
			(fill no)
			(layer "B.CrtYd")
		)
		(pad "1" smd rect
			(at -0.40005 0 270)
			(size 0.4572 0.508)
			(layers "B.Cu" "B.Mask" "B.Paste")
			(net "T7_NODE2_EN")
		)
		(pad "2" smd rect
			(at 0.40005 0 270)
			(size 0.4572 0.508)
			(layers "B.Cu" "B.Mask" "B.Paste")
			(net "T7_NODE2_EN_R")
		)
	)
	(footprint ""
		(layer "B.Cu")
		(at 142.07236 -171.997624 180)
		(property "Reference" "R729"
			(at 1.275588 0.274828 0)
			(unlocked yes)
			(layer "B.SilkS")
			(effects
				(font
					(size 0.7874 0.5842)
					(thickness 0.1524)
				)
				(justify left mirror)
			)
		)
		(property "Value" ""
			(at 0 0 0)
			(layer "B.Fab")
			(effects
				(font
					(size 1.27 1.27)
				)
				(justify mirror)
			)
		)
		(duplicate_pad_numbers_are_jumpers no)
		(fp_line
			(start 0.7874 0.4064)
			(end 0.7874 -0.4064)
			(stroke
				(width 0.1524)
				(type default)
			)
			(layer "B.SilkS")
		)
		(fp_line
			(start 0.7874 -0.4064)
			(end -0.7874 -0.4064)
			(stroke
				(width 0.1524)
				(type default)
			)
			(layer "B.SilkS")
		)
		(fp_line
			(start -0.7874 0.4064)
			(end 0.7874 0.4064)
			(stroke
				(width 0.1524)
				(type default)
			)
			(layer "B.SilkS")
		)
		(fp_line
			(start -0.7874 -0.4064)
			(end -0.7874 0.4064)
			(stroke
				(width 0.1524)
				(type default)
			)
			(layer "B.SilkS")
		)
		(fp_poly
			(pts
				(xy 0.508 0.2794) (xy 0.508 0.2286) (xy 0.635 0.2286) (xy 0.635 -0.254) (xy 0.5334 -0.254) (xy 0.5334 -0.2794)
				(xy -0.5334 -0.2794) (xy -0.5334 -0.254) (xy -0.635 -0.254) (xy -0.635 0.254) (xy -0.5334 0.254)
				(xy -0.5334 0.2794)
			)
			(stroke
				(width 0)
				(type default)
			)
			(fill no)
			(layer "B.CrtYd")
		)
		(pad "1" smd rect
			(at -0.40005 0)
			(size 0.4572 0.508)
			(layers "B.Cu" "B.Mask" "B.Paste")
			(net "T9_NODE2_EN")
		)
		(pad "2" smd rect
			(at 0.40005 0)
			(size 0.4572 0.508)
			(layers "B.Cu" "B.Mask" "B.Paste")
			(net "P5V_NODE1")
		)
	)
	(footprint ""
		(layer "B.Cu")
		(at 45.669454 -97.078038 -90)
		(property "Reference" "R133"
			(at -1.042162 -1.014476 270)
			(unlocked yes)
			(layer "B.SilkS")
			(effects
				(font
					(size 0.7874 0.5842)
					(thickness 0.1524)
				)
				(justify left mirror)
			)
		)
		(property "Value" ""
			(at 0 0 90)
			(layer "B.Fab")
			(effects
				(font
					(size 1.27 1.27)
				)
				(justify mirror)
			)
		)
		(duplicate_pad_numbers_are_jumpers no)
		(fp_line
			(start -0.7874 0.4064)
			(end 0.7874 0.4064)
			(stroke
				(width 0.1524)
				(type default)
			)
			(layer "B.SilkS")
		)
		(fp_line
			(start 0.7874 0.4064)
			(end 0.7874 -0.4064)
			(stroke
				(width 0.1524)
				(type default)
			)
			(layer "B.SilkS")
		)
		(fp_line
			(start -0.7874 -0.4064)
			(end -0.7874 0.4064)
			(stroke
				(width 0.1524)
				(type default)
			)
			(layer "B.SilkS")
		)
		(fp_line
			(start 0.7874 -0.4064)
			(end -0.7874 -0.4064)
			(stroke
				(width 0.1524)
				(type default)
			)
			(layer "B.SilkS")
		)
		(fp_poly
			(pts
				(xy 0.508 0.2794) (xy 0.508 0.2286) (xy 0.635 0.2286) (xy 0.635 -0.254) (xy 0.5334 -0.254) (xy 0.5334 -0.2794)
				(xy -0.5334 -0.2794) (xy -0.5334 -0.254) (xy -0.635 -0.254) (xy -0.635 0.254) (xy -0.5334 0.254)
				(xy -0.5334 0.2794)
			)
			(stroke
				(width 0)
				(type default)
			)
			(fill no)
			(layer "B.CrtYd")
		)
		(pad "1" smd rect
			(at -0.40005 0 90)
			(size 0.4572 0.508)
			(layers "B.Cu" "B.Mask" "B.Paste")
			(net "P3V3_NODE1")
		)
		(pad "2" smd rect
			(at 0.40005 0 90)
			(size 0.4572 0.508)
			(layers "B.Cu" "B.Mask" "B.Paste")
			(net "SMB_CPU_NODE1_BMC_DAT")
		)
	)
	(footprint ""
		(layer "B.Cu")
		(at 155.644596 -67.23253 -90)
		(property "Reference" "L33"
			(at -0.021082 -5.14731 270)
			(unlocked yes)
			(layer "B.SilkS")
			(effects
				(font
					(size 0.7874 0.5842)
					(thickness 0.1524)
				)
				(justify left mirror)
			)
		)
		(property "Value" ""
			(at 0 0 90)
			(layer "B.Fab")
			(effects
				(font
					(size 1.27 1.27)
				)
				(justify mirror)
			)
		)
		(duplicate_pad_numbers_are_jumpers no)
		(fp_line
			(start -0.7874 0.4064)
			(end 0.7874 0.4064)
			(stroke
				(width 0.1524)
				(type default)
			)
			(layer "B.SilkS")
		)
		(fp_line
			(start -0.0889 0.4064)
			(end -0.0889 -0.4064)
			(stroke
				(width 0.1524)
				(type default)
			)
			(layer "B.SilkS")
		)
		(fp_line
			(start 0.0889 0.4064)
			(end 0.0889 -0.4064)
			(stroke
				(width 0.1524)
				(type default)
			)
			(layer "B.SilkS")
		)
		(fp_line
			(start 0.7874 0.4064)
			(end 0.7874 -0.4064)
			(stroke
				(width 0.1524)
				(type default)
			)
			(layer "B.SilkS")
		)
		(fp_line
			(start -0.7874 -0.4064)
			(end -0.7874 0.4064)
			(stroke
				(width 0.1524)
				(type default)
			)
			(layer "B.SilkS")
		)
		(fp_line
			(start 0.7874 -0.4064)
			(end -0.7874 -0.4064)
			(stroke
				(width 0.1524)
				(type default)
			)
			(layer "B.SilkS")
		)
		(fp_poly
			(pts
				(xy 0.5334 0.254) (xy 0.635 0.254) (xy 0.635 0.2286) (xy 0.635 -0.254) (xy 0.5334 -0.254) (xy 0.5334 -0.2794)
				(xy -0.5334 -0.2794) (xy -0.5334 -0.254) (xy -0.635 -0.254) (xy -0.635 0.254) (xy -0.5334 0.254)
				(xy -0.5334 0.2794) (xy 0.508 0.2794) (xy 0.5334 0.2794)
			)
			(stroke
				(width 0)
				(type default)
			)
			(fill no)
			(layer "B.CrtYd")
		)
		(pad "1" smd rect
			(at -0.40005 0 90)
			(size 0.4572 0.508)
			(layers "B.Cu" "B.Mask" "B.Paste")
			(net "P1V8_NODE1")
		)
		(pad "2" smd rect
			(at 0.40005 0 90)
			(size 0.4572 0.508)
			(layers "B.Cu" "B.Mask" "B.Paste")
			(net "P1V8_SATA_VAA1_NODE1")
		)
	)
	(footprint ""
		(layer "B.Cu")
		(at 23.847298 -110.729522)
		(property "Reference" "C53"
			(at -2.920492 0.178054 0)
			(unlocked yes)
			(layer "B.SilkS")
			(effects
				(font
					(size 0.7874 0.5842)
					(thickness 0.1524)
				)
				(justify left mirror)
			)
		)
		(property "Value" ""
			(at 0 0 0)
			(layer "B.Fab")
			(effects
				(font
					(size 1.27 1.27)
				)
				(justify mirror)
			)
		)
		(duplicate_pad_numbers_are_jumpers no)
		(fp_line
			(start -1.905 -0.8636)
			(end -1.905 0.8636)
			(stroke
				(width 0.1524)
				(type default)
			)
			(layer "B.SilkS")
		)
		(fp_line
			(start -1.905 0.8636)
			(end 1.905 0.8636)
			(stroke
				(width 0.1524)
				(type default)
			)
			(layer "B.SilkS")
		)
		(fp_line
			(start 0 0.8382)
			(end 0 -0.8382)
			(stroke
				(width 0.1524)
				(type default)
			)
			(layer "B.SilkS")
		)
		(fp_line
			(start 1.905 -0.8636)
			(end -1.905 -0.8636)
			(stroke
				(width 0.1524)
				(type default)
			)
			(layer "B.SilkS")
		)
		(fp_line
			(start 1.905 0.8636)
			(end 1.905 -0.8636)
			(stroke
				(width 0.1524)
				(type default)
			)
			(layer "B.SilkS")
		)
		(fp_rect
			(start 1.524 0.7366)
			(end -1.524 -0.7366)
			(stroke
				(width 0)
				(type default)
			)
			(fill no)
			(layer "B.CrtYd")
		)
		(pad "1" smd rect
			(at -0.94996 0 180)
			(size 1.1176 1.3716)
			(layers "B.Cu" "B.Mask" "B.Paste")
			(net "P1V05_NODE1")
		)
		(pad "2" smd rect
			(at 0.94996 0 180)
			(size 1.1176 1.3716)
			(layers "B.Cu" "B.Mask" "B.Paste")
			(net "GND")
		)
	)
	(footprint ""
		(layer "B.Cu")
		(at 67.111372 -80.514698 90)
		(property "Reference" "C65"
			(at -32.09925 -14.534642 270)
			(unlocked yes)
			(layer "B.SilkS")
			(effects
				(font
					(size 0.7874 0.5842)
					(thickness 0.1524)
				)
				(justify left mirror)
			)
		)
		(property "Value" ""
			(at 0 0 90)
			(layer "B.Fab")
			(effects
				(font
					(size 1.27 1.27)
				)
				(justify mirror)
			)
		)
		(duplicate_pad_numbers_are_jumpers no)
		(fp_line
			(start 0.7874 -0.4064)
			(end -0.7874 -0.4064)
			(stroke
				(width 0.1524)
				(type default)
			)
			(layer "B.SilkS")
		)
		(fp_line
			(start -0.7874 -0.4064)
			(end -0.7874 0.4064)
			(stroke
				(width 0.1524)
				(type default)
			)
			(layer "B.SilkS")
		)
		(fp_line
			(start 0 0.381)
			(end 0 -0.381)
			(stroke
				(width 0.1524)
				(type default)
			)
			(layer "B.SilkS")
		)
		(fp_line
			(start 0.7874 0.4064)
			(end 0.7874 -0.4064)
			(stroke
				(width 0.1524)
				(type default)
			)
			(layer "B.SilkS")
		)
		(fp_line
			(start -0.7874 0.4064)
			(end 0.7874 0.4064)
			(stroke
				(width 0.1524)
				(type default)
			)
			(layer "B.SilkS")
		)
		(fp_poly
			(pts
				(xy 0.5334 0.254) (xy 0.635 0.254) (xy 0.635 0.2286) (xy 0.635 -0.254) (xy 0.5334 -0.254) (xy 0.5334 -0.2794)
				(xy -0.5334 -0.2794) (xy -0.5334 -0.254) (xy -0.635 -0.254) (xy -0.635 0.254) (xy -0.5334 0.254)
				(xy -0.5334 0.2794) (xy 0.508 0.2794) (xy 0.5334 0.2794)
			)
			(stroke
				(width 0)
				(type default)
			)
			(fill no)
			(layer "B.CrtYd")
		)
		(pad "1" smd rect
			(at -0.40005 0 270)
			(size 0.4572 0.508)
			(layers "B.Cu" "B.Mask" "B.Paste")
			(net "PV_VCCP_NODE1")
		)
		(pad "2" smd rect
			(at 0.40005 0 270)
			(size 0.4572 0.508)
			(layers "B.Cu" "B.Mask" "B.Paste")
			(net "GND")
		)
	)
	(footprint ""
		(layer "B.Cu")
		(at 163.128452 -99.58959 180)
		(property "Reference" "C376"
			(at -4.541012 0.26543 0)
			(unlocked yes)
			(layer "B.SilkS")
			(effects
				(font
					(size 0.7874 0.5842)
					(thickness 0.1524)
				)
				(justify left mirror)
			)
		)
		(property "Value" ""
			(at 0 0 0)
			(layer "B.Fab")
			(effects
				(font
					(size 1.27 1.27)
				)
				(justify mirror)
			)
		)
		(duplicate_pad_numbers_are_jumpers no)
		(fp_line
			(start 0.7874 0.4064)
			(end 0.7874 -0.4064)
			(stroke
				(width 0.1524)
				(type default)
			)
			(layer "B.SilkS")
		)
		(fp_line
			(start 0.7874 -0.4064)
			(end -0.7874 -0.4064)
			(stroke
				(width 0.1524)
				(type default)
			)
			(layer "B.SilkS")
		)
		(fp_line
			(start 0 0.381)
			(end 0 -0.381)
			(stroke
				(width 0.1524)
				(type default)
			)
			(layer "B.SilkS")
		)
		(fp_line
			(start -0.7874 0.4064)
			(end 0.7874 0.4064)
			(stroke
				(width 0.1524)
				(type default)
			)
			(layer "B.SilkS")
		)
		(fp_line
			(start -0.7874 -0.4064)
			(end -0.7874 0.4064)
			(stroke
				(width 0.1524)
				(type default)
			)
			(layer "B.SilkS")
		)
		(fp_poly
			(pts
				(xy 0.5334 0.254) (xy 0.635 0.254) (xy 0.635 0.2286) (xy 0.635 -0.254) (xy 0.5334 -0.254) (xy 0.5334 -0.2794)
				(xy -0.5334 -0.2794) (xy -0.5334 -0.254) (xy -0.635 -0.254) (xy -0.635 0.254) (xy -0.5334 0.254)
				(xy -0.5334 0.2794) (xy 0.508 0.2794) (xy 0.5334 0.2794)
			)
			(stroke
				(width 0)
				(type default)
			)
			(fill no)
			(layer "B.CrtYd")
		)
		(pad "1" smd rect
			(at -0.40005 0)
			(size 0.4572 0.508)
			(layers "B.Cu" "B.Mask" "B.Paste")
			(net "GND")
		)
		(pad "2" smd rect
			(at 0.40005 0)
			(size 0.4572 0.508)
			(layers "B.Cu" "B.Mask" "B.Paste")
			(net "P1V05_NODE1")
		)
	)
	(footprint ""
		(layer "B.Cu")
		(at 135.747252 -135.87095 90)
		(property "Reference" "C861"
			(at -5.07365 0.34163 270)
			(unlocked yes)
			(layer "B.SilkS")
			(effects
				(font
					(size 0.7874 0.5842)
					(thickness 0.1524)
				)
				(justify left mirror)
			)
		)
		(property "Value" ""
			(at 0 0 90)
			(layer "B.Fab")
			(effects
				(font
					(size 1.27 1.27)
				)
				(justify mirror)
			)
		)
		(duplicate_pad_numbers_are_jumpers no)
		(fp_line
			(start 0.7874 -0.4064)
			(end -0.7874 -0.4064)
			(stroke
				(width 0.1524)
				(type default)
			)
			(layer "B.SilkS")
		)
		(fp_line
			(start -0.7874 -0.4064)
			(end -0.7874 0.4064)
			(stroke
				(width 0.1524)
				(type default)
			)
			(layer "B.SilkS")
		)
		(fp_line
			(start 0 0.381)
			(end 0 -0.381)
			(stroke
				(width 0.1524)
				(type default)
			)
			(layer "B.SilkS")
		)
		(fp_line
			(start 0.7874 0.4064)
			(end 0.7874 -0.4064)
			(stroke
				(width 0.1524)
				(type default)
			)
			(layer "B.SilkS")
		)
		(fp_line
			(start -0.7874 0.4064)
			(end 0.7874 0.4064)
			(stroke
				(width 0.1524)
				(type default)
			)
			(layer "B.SilkS")
		)
		(fp_poly
			(pts
				(xy 0.5334 0.254) (xy 0.635 0.254) (xy 0.635 0.2286) (xy 0.635 -0.254) (xy 0.5334 -0.254) (xy 0.5334 -0.2794)
				(xy -0.5334 -0.2794) (xy -0.5334 -0.254) (xy -0.635 -0.254) (xy -0.635 0.254) (xy -0.5334 0.254)
				(xy -0.5334 0.2794) (xy 0.508 0.2794) (xy 0.5334 0.2794)
			)
			(stroke
				(width 0)
				(type default)
			)
			(fill no)
			(layer "B.CrtYd")
		)
		(pad "1" smd rect
			(at -0.40005 0 270)
			(size 0.4572 0.508)
			(layers "B.Cu" "B.Mask" "B.Paste")
			(net "P1V0_NODE1")
		)
		(pad "2" smd rect
			(at 0.40005 0 270)
			(size 0.4572 0.508)
			(layers "B.Cu" "B.Mask" "B.Paste")
			(net "GND")
		)
	)
	(footprint ""
		(layer "B.Cu")
		(at 77.432154 -81.189322 90)
		(property "Reference" "C63"
			(at -33.359344 -14.106144 270)
			(unlocked yes)
			(layer "B.SilkS")
			(effects
				(font
					(size 0.7874 0.5842)
					(thickness 0.1524)
				)
				(justify left mirror)
			)
		)
		(property "Value" ""
			(at 0 0 90)
			(layer "B.Fab")
			(effects
				(font
					(size 1.27 1.27)
				)
				(justify mirror)
			)
		)
		(duplicate_pad_numbers_are_jumpers no)
		(fp_line
			(start 1.905 -0.8636)
			(end -1.905 -0.8636)
			(stroke
				(width 0.1524)
				(type default)
			)
			(layer "B.SilkS")
		)
		(fp_line
			(start -1.905 -0.8636)
			(end -1.905 0.8636)
			(stroke
				(width 0.1524)
				(type default)
			)
			(layer "B.SilkS")
		)
		(fp_line
			(start 0 0.8382)
			(end 0 -0.8382)
			(stroke
				(width 0.1524)
				(type default)
			)
			(layer "B.SilkS")
		)
		(fp_line
			(start 1.905 0.8636)
			(end 1.905 -0.8636)
			(stroke
				(width 0.1524)
				(type default)
			)
			(layer "B.SilkS")
		)
		(fp_line
			(start -1.905 0.8636)
			(end 1.905 0.8636)
			(stroke
				(width 0.1524)
				(type default)
			)
			(layer "B.SilkS")
		)
		(fp_rect
			(start 1.524 0.7366)
			(end -1.524 -0.7366)
			(stroke
				(width 0)
				(type default)
			)
			(fill no)
			(layer "B.CrtYd")
		)
		(pad "1" smd rect
			(at -0.94996 0 270)
			(size 1.1176 1.3716)
			(layers "B.Cu" "B.Mask" "B.Paste")
			(net "PV_VCCP_NODE1")
		)
		(pad "2" smd rect
			(at 0.94996 0 270)
			(size 1.1176 1.3716)
			(layers "B.Cu" "B.Mask" "B.Paste")
			(net "GND")
		)
	)
	(footprint ""
		(layer "B.Cu")
		(at 68.127372 -80.514698 90)
		(property "Reference" "C84"
			(at -32.158686 -14.55039 270)
			(unlocked yes)
			(layer "B.SilkS")
			(effects
				(font
					(size 0.7874 0.5842)
					(thickness 0.1524)
				)
				(justify left mirror)
			)
		)
		(property "Value" ""
			(at 0 0 90)
			(layer "B.Fab")
			(effects
				(font
					(size 1.27 1.27)
				)
				(justify mirror)
			)
		)
		(duplicate_pad_numbers_are_jumpers no)
		(fp_line
			(start 0.7874 -0.4064)
			(end -0.7874 -0.4064)
			(stroke
				(width 0.1524)
				(type default)
			)
			(layer "B.SilkS")
		)
		(fp_line
			(start -0.7874 -0.4064)
			(end -0.7874 0.4064)
			(stroke
				(width 0.1524)
				(type default)
			)
			(layer "B.SilkS")
		)
		(fp_line
			(start 0 0.381)
			(end 0 -0.381)
			(stroke
				(width 0.1524)
				(type default)
			)
			(layer "B.SilkS")
		)
		(fp_line
			(start 0.7874 0.4064)
			(end 0.7874 -0.4064)
			(stroke
				(width 0.1524)
				(type default)
			)
			(layer "B.SilkS")
		)
		(fp_line
			(start -0.7874 0.4064)
			(end 0.7874 0.4064)
			(stroke
				(width 0.1524)
				(type default)
			)
			(layer "B.SilkS")
		)
		(fp_poly
			(pts
				(xy 0.5334 0.254) (xy 0.635 0.254) (xy 0.635 0.2286) (xy 0.635 -0.254) (xy 0.5334 -0.254) (xy 0.5334 -0.2794)
				(xy -0.5334 -0.2794) (xy -0.5334 -0.254) (xy -0.635 -0.254) (xy -0.635 0.254) (xy -0.5334 0.254)
				(xy -0.5334 0.2794) (xy 0.508 0.2794) (xy 0.5334 0.2794)
			)
			(stroke
				(width 0)
				(type default)
			)
			(fill no)
			(layer "B.CrtYd")
		)
		(pad "1" smd rect
			(at -0.40005 0 270)
			(size 0.4572 0.508)
			(layers "B.Cu" "B.Mask" "B.Paste")
			(net "PV_VCCP_NODE1")
		)
		(pad "2" smd rect
			(at 0.40005 0 270)
			(size 0.4572 0.508)
			(layers "B.Cu" "B.Mask" "B.Paste")
			(net "GND")
		)
	)
	(footprint ""
		(layer "B.Cu")
		(at 168.640252 -97.04959 -90)
		(property "Reference" "C380"
			(at -0.90805 -0.443738 270)
			(unlocked yes)
			(layer "B.SilkS")
			(effects
				(font
					(size 0.7874 0.5842)
					(thickness 0.1524)
				)
				(justify left mirror)
			)
		)
		(property "Value" ""
			(at 0 0 90)
			(layer "B.Fab")
			(effects
				(font
					(size 1.27 1.27)
				)
				(justify mirror)
			)
		)
		(duplicate_pad_numbers_are_jumpers no)
		(fp_line
			(start -0.7874 0.4064)
			(end 0.7874 0.4064)
			(stroke
				(width 0.1524)
				(type default)
			)
			(layer "B.SilkS")
		)
		(fp_line
			(start 0.7874 0.4064)
			(end 0.7874 -0.4064)
			(stroke
				(width 0.1524)
				(type default)
			)
			(layer "B.SilkS")
		)
		(fp_line
			(start 0 0.381)
			(end 0 -0.381)
			(stroke
				(width 0.1524)
				(type default)
			)
			(layer "B.SilkS")
		)
		(fp_line
			(start -0.7874 -0.4064)
			(end -0.7874 0.4064)
			(stroke
				(width 0.1524)
				(type default)
			)
			(layer "B.SilkS")
		)
		(fp_line
			(start 0.7874 -0.4064)
			(end -0.7874 -0.4064)
			(stroke
				(width 0.1524)
				(type default)
			)
			(layer "B.SilkS")
		)
		(fp_poly
			(pts
				(xy 0.5334 0.254) (xy 0.635 0.254) (xy 0.635 0.2286) (xy 0.635 -0.254) (xy 0.5334 -0.254) (xy 0.5334 -0.2794)
				(xy -0.5334 -0.2794) (xy -0.5334 -0.254) (xy -0.635 -0.254) (xy -0.635 0.254) (xy -0.5334 0.254)
				(xy -0.5334 0.2794) (xy 0.508 0.2794) (xy 0.5334 0.2794)
			)
			(stroke
				(width 0)
				(type default)
			)
			(fill no)
			(layer "B.CrtYd")
		)
		(pad "1" smd rect
			(at -0.40005 0 90)
			(size 0.4572 0.508)
			(layers "B.Cu" "B.Mask" "B.Paste")
			(net "GND")
		)
		(pad "2" smd rect
			(at 0.40005 0 90)
			(size 0.4572 0.508)
			(layers "B.Cu" "B.Mask" "B.Paste")
			(net "P3V3_NODE1")
		)
	)
	(footprint ""
		(layer "B.Cu")
		(at 69.818758 -138.847322 180)
		(property "Reference" "C248"
			(at 37.946584 -52.737766 0)
			(unlocked yes)
			(layer "B.SilkS")
			(effects
				(font
					(size 0.7874 0.5842)
					(thickness 0.1524)
				)
				(justify mirror)
			)
		)
		(property "Value" ""
			(at 0 0 0)
			(layer "B.Fab")
			(effects
				(font
					(size 1.27 1.27)
				)
				(justify mirror)
			)
		)
		(duplicate_pad_numbers_are_jumpers no)
		(fp_line
			(start 1.2954 0.5842)
			(end 1.2954 -0.5842)
			(stroke
				(width 0.1524)
				(type default)
			)
			(layer "B.SilkS")
		)
		(fp_line
			(start 1.2954 -0.5842)
			(end -1.2954 -0.5842)
			(stroke
				(width 0.1524)
				(type default)
			)
			(layer "B.SilkS")
		)
		(fp_line
			(start 0 -0.5842)
			(end 0 0.5842)
			(stroke
				(width 0.1524)
				(type default)
			)
			(layer "B.SilkS")
		)
		(fp_line
			(start -1.2954 0.5842)
			(end 1.2954 0.5842)
			(stroke
				(width 0.1524)
				(type default)
			)
			(layer "B.SilkS")
		)
		(fp_line
			(start -1.2954 -0.5842)
			(end -1.2954 0.5842)
			(stroke
				(width 0.1524)
				(type default)
			)
			(layer "B.SilkS")
		)
		(fp_poly
			(pts
				(xy -0.8636 -0.4572) (xy -0.8636 -0.3556) (xy -1.143 -0.3556) (xy -1.143 0.3556) (xy -0.8636 0.3556)
				(xy -0.8636 0.4572) (xy 0.8636 0.4572) (xy 0.8636 0.3556) (xy 1.143 0.3556) (xy 1.143 -0.3556) (xy 0.8636 -0.3556)
				(xy 0.8636 -0.4572)
			)
			(stroke
				(width 0)
				(type default)
			)
			(fill no)
			(layer "B.CrtYd")
		)
		(fp_line
			(start 0.884936 0.504952)
			(end 0.884936 -0.504952)
			(stroke
				(width 0.1)
				(type default)
			)
			(layer "B.Fab")
		)
		(fp_line
			(start 0.884936 -0.504952)
			(end -0.884936 -0.504952)
			(stroke
				(width 0.1)
				(type default)
			)
			(layer "B.Fab")
		)
		(fp_line
			(start -0.884936 0.504952)
			(end 0.884936 0.504952)
			(stroke
				(width 0.1)
				(type default)
			)
			(layer "B.Fab")
		)
		(fp_line
			(start -0.884936 -0.504952)
			(end -0.884936 0.504952)
			(stroke
				(width 0.1)
				(type default)
			)
			(layer "B.Fab")
		)
		(pad "1" smd rect
			(at -0.7366 0 270)
			(size 0.7112 0.8128)
			(layers "B.Cu" "B.Mask" "B.Paste")
			(net "P3V3_NODE1")
		)
		(pad "2" smd rect
			(at 0.7366 0 270)
			(size 0.7112 0.8128)
			(layers "B.Cu" "B.Mask" "B.Paste")
			(net "GND")
		)
	)
	(footprint ""
		(layer "B.Cu")
		(at 48.659542 -28.696158 180)
		(property "Reference" "R211"
			(at 1.514602 0.009144 0)
			(unlocked yes)
			(layer "B.SilkS")
			(effects
				(font
					(size 0.7874 0.5842)
					(thickness 0.1524)
				)
				(justify left mirror)
			)
		)
		(property "Value" ""
			(at 0 0 0)
			(layer "B.Fab")
			(effects
				(font
					(size 1.27 1.27)
				)
				(justify mirror)
			)
		)
		(duplicate_pad_numbers_are_jumpers no)
		(fp_line
			(start 0.7874 0.4064)
			(end 0.7874 -0.4064)
			(stroke
				(width 0.1524)
				(type default)
			)
			(layer "B.SilkS")
		)
		(fp_line
			(start 0.7874 -0.4064)
			(end -0.7874 -0.4064)
			(stroke
				(width 0.1524)
				(type default)
			)
			(layer "B.SilkS")
		)
		(fp_line
			(start -0.7874 0.4064)
			(end 0.7874 0.4064)
			(stroke
				(width 0.1524)
				(type default)
			)
			(layer "B.SilkS")
		)
		(fp_line
			(start -0.7874 -0.4064)
			(end -0.7874 0.4064)
			(stroke
				(width 0.1524)
				(type default)
			)
			(layer "B.SilkS")
		)
		(fp_poly
			(pts
				(xy 0.508 0.2794) (xy 0.508 0.2286) (xy 0.635 0.2286) (xy 0.635 -0.254) (xy 0.5334 -0.254) (xy 0.5334 -0.2794)
				(xy -0.5334 -0.2794) (xy -0.5334 -0.254) (xy -0.635 -0.254) (xy -0.635 0.254) (xy -0.5334 0.254)
				(xy -0.5334 0.2794)
			)
			(stroke
				(width 0)
				(type default)
			)
			(fill no)
			(layer "B.CrtYd")
		)
		(pad "1" smd rect
			(at -0.40005 0)
			(size 0.4572 0.508)
			(layers "B.Cu" "B.Mask" "B.Paste")
			(net "GND")
		)
		(pad "2" smd rect
			(at 0.40005 0)
			(size 0.4572 0.508)
			(layers "B.Cu" "B.Mask" "B.Paste")
			(net "PD_NODE1_DM1")
		)
	)
	(footprint ""
		(layer "B.Cu")
		(at 90.81262 -177.070512)
		(property "Reference" "R698"
			(at 24.902414 20.083272 0)
			(unlocked yes)
			(layer "B.SilkS")
			(effects
				(font
					(size 0.7874 0.5842)
					(thickness 0.1524)
				)
				(justify left mirror)
			)
		)
		(property "Value" ""
			(at 0 0 0)
			(layer "B.Fab")
			(effects
				(font
					(size 1.27 1.27)
				)
				(justify mirror)
			)
		)
		(duplicate_pad_numbers_are_jumpers no)
		(fp_line
			(start -0.7874 -0.4064)
			(end -0.7874 0.4064)
			(stroke
				(width 0.1524)
				(type default)
			)
			(layer "B.SilkS")
		)
		(fp_line
			(start -0.7874 0.4064)
			(end 0.7874 0.4064)
			(stroke
				(width 0.1524)
				(type default)
			)
			(layer "B.SilkS")
		)
		(fp_line
			(start 0.7874 -0.4064)
			(end -0.7874 -0.4064)
			(stroke
				(width 0.1524)
				(type default)
			)
			(layer "B.SilkS")
		)
		(fp_line
			(start 0.7874 0.4064)
			(end 0.7874 -0.4064)
			(stroke
				(width 0.1524)
				(type default)
			)
			(layer "B.SilkS")
		)
		(fp_poly
			(pts
				(xy 0.508 0.2794) (xy 0.508 0.2286) (xy 0.635 0.2286) (xy 0.635 -0.254) (xy 0.5334 -0.254) (xy 0.5334 -0.2794)
				(xy -0.5334 -0.2794) (xy -0.5334 -0.254) (xy -0.635 -0.254) (xy -0.635 0.254) (xy -0.5334 0.254)
				(xy -0.5334 0.2794)
			)
			(stroke
				(width 0)
				(type default)
			)
			(fill no)
			(layer "B.CrtYd")
		)
		(pad "1" smd rect
			(at -0.40005 0 180)
			(size 0.4572 0.508)
			(layers "B.Cu" "B.Mask" "B.Paste")
			(net "T3_NODE2_EN")
		)
		(pad "2" smd rect
			(at 0.40005 0 180)
			(size 0.4572 0.508)
			(layers "B.Cu" "B.Mask" "B.Paste")
			(net "P5V_NODE1")
		)
	)
	(footprint ""
		(layer "B.Cu")
		(at 138.236452 -151.28875 90)
		(property "Reference" "C874"
			(at 1.03378 3.353562 270)
			(unlocked yes)
			(layer "B.SilkS")
			(effects
				(font
					(size 0.7874 0.5842)
					(thickness 0.1524)
				)
				(justify left mirror)
			)
		)
		(property "Value" ""
			(at 0 0 90)
			(layer "B.Fab")
			(effects
				(font
					(size 1.27 1.27)
				)
				(justify mirror)
			)
		)
		(duplicate_pad_numbers_are_jumpers no)
		(fp_line
			(start 0.7874 -0.4064)
			(end -0.7874 -0.4064)
			(stroke
				(width 0.1524)
				(type default)
			)
			(layer "B.SilkS")
		)
		(fp_line
			(start -0.7874 -0.4064)
			(end -0.7874 0.4064)
			(stroke
				(width 0.1524)
				(type default)
			)
			(layer "B.SilkS")
		)
		(fp_line
			(start 0 0.381)
			(end 0 -0.381)
			(stroke
				(width 0.1524)
				(type default)
			)
			(layer "B.SilkS")
		)
		(fp_line
			(start 0.7874 0.4064)
			(end 0.7874 -0.4064)
			(stroke
				(width 0.1524)
				(type default)
			)
			(layer "B.SilkS")
		)
		(fp_line
			(start -0.7874 0.4064)
			(end 0.7874 0.4064)
			(stroke
				(width 0.1524)
				(type default)
			)
			(layer "B.SilkS")
		)
		(fp_poly
			(pts
				(xy 0.5334 0.254) (xy 0.635 0.254) (xy 0.635 0.2286) (xy 0.635 -0.254) (xy 0.5334 -0.254) (xy 0.5334 -0.2794)
				(xy -0.5334 -0.2794) (xy -0.5334 -0.254) (xy -0.635 -0.254) (xy -0.635 0.254) (xy -0.5334 0.254)
				(xy -0.5334 0.2794) (xy 0.508 0.2794) (xy 0.5334 0.2794)
			)
			(stroke
				(width 0)
				(type default)
			)
			(fill no)
			(layer "B.CrtYd")
		)
		(pad "1" smd rect
			(at -0.40005 0 270)
			(size 0.4572 0.508)
			(layers "B.Cu" "B.Mask" "B.Paste")
			(net "P1V0_NODE1")
		)
		(pad "2" smd rect
			(at 0.40005 0 270)
			(size 0.4572 0.508)
			(layers "B.Cu" "B.Mask" "B.Paste")
			(net "GND")
		)
	)
	(footprint ""
		(layer "B.Cu")
		(at 37.591746 -97.067878 -90)
		(property "Reference" "R126"
			(at -0.97155 0.021844 270)
			(unlocked yes)
			(layer "B.SilkS")
			(effects
				(font
					(size 0.7874 0.5842)
					(thickness 0.1524)
				)
				(justify left mirror)
			)
		)
		(property "Value" ""
			(at 0 0 90)
			(layer "B.Fab")
			(effects
				(font
					(size 1.27 1.27)
				)
				(justify mirror)
			)
		)
		(duplicate_pad_numbers_are_jumpers no)
		(fp_line
			(start -0.7874 0.4064)
			(end 0.7874 0.4064)
			(stroke
				(width 0.1524)
				(type default)
			)
			(layer "B.SilkS")
		)
		(fp_line
			(start 0.7874 0.4064)
			(end 0.7874 -0.4064)
			(stroke
				(width 0.1524)
				(type default)
			)
			(layer "B.SilkS")
		)
		(fp_line
			(start -0.7874 -0.4064)
			(end -0.7874 0.4064)
			(stroke
				(width 0.1524)
				(type default)
			)
			(layer "B.SilkS")
		)
		(fp_line
			(start 0.7874 -0.4064)
			(end -0.7874 -0.4064)
			(stroke
				(width 0.1524)
				(type default)
			)
			(layer "B.SilkS")
		)
		(fp_poly
			(pts
				(xy 0.508 0.2794) (xy 0.508 0.2286) (xy 0.635 0.2286) (xy 0.635 -0.254) (xy 0.5334 -0.254) (xy 0.5334 -0.2794)
				(xy -0.5334 -0.2794) (xy -0.5334 -0.254) (xy -0.635 -0.254) (xy -0.635 0.254) (xy -0.5334 0.254)
				(xy -0.5334 0.2794)
			)
			(stroke
				(width 0)
				(type default)
			)
			(fill no)
			(layer "B.CrtYd")
		)
		(pad "1" smd rect
			(at -0.40005 0 90)
			(size 0.4572 0.508)
			(layers "B.Cu" "B.Mask" "B.Paste")
			(net "P3V3_NODE1")
		)
		(pad "2" smd rect
			(at 0.40005 0 90)
			(size 0.4572 0.508)
			(layers "B.Cu" "B.Mask" "B.Paste")
			(net "SMB_MUX_CPU_ICS_NODE1_CLK")
		)
	)
	(footprint ""
		(layer "B.Cu")
		(at 119.49176 -185.205624 90)
		(property "Reference" "R872"
			(at 3.957828 0.26797 270)
			(unlocked yes)
			(layer "B.SilkS")
			(effects
				(font
					(size 0.7874 0.5842)
					(thickness 0.1524)
				)
				(justify left mirror)
			)
		)
		(property "Value" ""
			(at 0 0 90)
			(layer "B.Fab")
			(effects
				(font
					(size 1.27 1.27)
				)
				(justify mirror)
			)
		)
		(duplicate_pad_numbers_are_jumpers no)
		(fp_line
			(start 0.7874 -0.4064)
			(end -0.7874 -0.4064)
			(stroke
				(width 0.1524)
				(type default)
			)
			(layer "B.SilkS")
		)
		(fp_line
			(start -0.7874 -0.4064)
			(end -0.7874 0.4064)
			(stroke
				(width 0.1524)
				(type default)
			)
			(layer "B.SilkS")
		)
		(fp_line
			(start 0.7874 0.4064)
			(end 0.7874 -0.4064)
			(stroke
				(width 0.1524)
				(type default)
			)
			(layer "B.SilkS")
		)
		(fp_line
			(start -0.7874 0.4064)
			(end 0.7874 0.4064)
			(stroke
				(width 0.1524)
				(type default)
			)
			(layer "B.SilkS")
		)
		(fp_poly
			(pts
				(xy 0.508 0.2794) (xy 0.508 0.2286) (xy 0.635 0.2286) (xy 0.635 -0.254) (xy 0.5334 -0.254) (xy 0.5334 -0.2794)
				(xy -0.5334 -0.2794) (xy -0.5334 -0.254) (xy -0.635 -0.254) (xy -0.635 0.254) (xy -0.5334 0.254)
				(xy -0.5334 0.2794)
			)
			(stroke
				(width 0)
				(type default)
			)
			(fill no)
			(layer "B.CrtYd")
		)
		(pad "1" smd rect
			(at -0.40005 0 270)
			(size 0.4572 0.508)
			(layers "B.Cu" "B.Mask" "B.Paste")
			(net "T7_NODE1_EN")
		)
		(pad "2" smd rect
			(at 0.40005 0 270)
			(size 0.4572 0.508)
			(layers "B.Cu" "B.Mask" "B.Paste")
			(net "T7_NODE1_EN_R")
		)
	)
	(footprint ""
		(layer "B.Cu")
		(at 47.766732 -94.40037 90)
		(property "Reference" "R123"
			(at -4.703318 -4.33197 270)
			(unlocked yes)
			(layer "B.SilkS")
			(effects
				(font
					(size 0.7874 0.5842)
					(thickness 0.1524)
				)
				(justify left mirror)
			)
		)
		(property "Value" ""
			(at 0 0 90)
			(layer "B.Fab")
			(effects
				(font
					(size 1.27 1.27)
				)
				(justify mirror)
			)
		)
		(duplicate_pad_numbers_are_jumpers no)
		(fp_line
			(start 0.7874 -0.4064)
			(end -0.7874 -0.4064)
			(stroke
				(width 0.1524)
				(type default)
			)
			(layer "B.SilkS")
		)
		(fp_line
			(start -0.7874 -0.4064)
			(end -0.7874 0.4064)
			(stroke
				(width 0.1524)
				(type default)
			)
			(layer "B.SilkS")
		)
		(fp_line
			(start 0.7874 0.4064)
			(end 0.7874 -0.4064)
			(stroke
				(width 0.1524)
				(type default)
			)
			(layer "B.SilkS")
		)
		(fp_line
			(start -0.7874 0.4064)
			(end 0.7874 0.4064)
			(stroke
				(width 0.1524)
				(type default)
			)
			(layer "B.SilkS")
		)
		(fp_poly
			(pts
				(xy 0.508 0.2794) (xy 0.508 0.2286) (xy 0.635 0.2286) (xy 0.635 -0.254) (xy 0.5334 -0.254) (xy 0.5334 -0.2794)
				(xy -0.5334 -0.2794) (xy -0.5334 -0.254) (xy -0.635 -0.254) (xy -0.635 0.254) (xy -0.5334 0.254)
				(xy -0.5334 0.2794)
			)
			(stroke
				(width 0)
				(type default)
			)
			(fill no)
			(layer "B.CrtYd")
		)
		(pad "1" smd rect
			(at -0.40005 0 270)
			(size 0.4572 0.508)
			(layers "B.Cu" "B.Mask" "B.Paste")
			(net "SMB_CPU_NODE1_XDP_DAT_R")
		)
		(pad "2" smd rect
			(at 0.40005 0 270)
			(size 0.4572 0.508)
			(layers "B.Cu" "B.Mask" "B.Paste")
			(net "SMB_CPU_NODE1_XDP_DAT")
		)
	)
	(footprint ""
		(layer "B.Cu")
		(at 90.81262 -170.974512)
		(property "Reference" "R709"
			(at 24.902414 20.163028 0)
			(unlocked yes)
			(layer "B.SilkS")
			(effects
				(font
					(size 0.7874 0.5842)
					(thickness 0.1524)
				)
				(justify left mirror)
			)
		)
		(property "Value" ""
			(at 0 0 0)
			(layer "B.Fab")
			(effects
				(font
					(size 1.27 1.27)
				)
				(justify mirror)
			)
		)
		(duplicate_pad_numbers_are_jumpers no)
		(fp_line
			(start -0.7874 -0.4064)
			(end -0.7874 0.4064)
			(stroke
				(width 0.1524)
				(type default)
			)
			(layer "B.SilkS")
		)
		(fp_line
			(start -0.7874 0.4064)
			(end 0.7874 0.4064)
			(stroke
				(width 0.1524)
				(type default)
			)
			(layer "B.SilkS")
		)
		(fp_line
			(start 0.7874 -0.4064)
			(end -0.7874 -0.4064)
			(stroke
				(width 0.1524)
				(type default)
			)
			(layer "B.SilkS")
		)
		(fp_line
			(start 0.7874 0.4064)
			(end 0.7874 -0.4064)
			(stroke
				(width 0.1524)
				(type default)
			)
			(layer "B.SilkS")
		)
		(fp_poly
			(pts
				(xy 0.508 0.2794) (xy 0.508 0.2286) (xy 0.635 0.2286) (xy 0.635 -0.254) (xy 0.5334 -0.254) (xy 0.5334 -0.2794)
				(xy -0.5334 -0.2794) (xy -0.5334 -0.254) (xy -0.635 -0.254) (xy -0.635 0.254) (xy -0.5334 0.254)
				(xy -0.5334 0.2794)
			)
			(stroke
				(width 0)
				(type default)
			)
			(fill no)
			(layer "B.CrtYd")
		)
		(pad "1" smd rect
			(at -0.40005 0 180)
			(size 0.4572 0.508)
			(layers "B.Cu" "B.Mask" "B.Paste")
			(net "T4_NODE4_EN")
		)
		(pad "2" smd rect
			(at 0.40005 0 180)
			(size 0.4572 0.508)
			(layers "B.Cu" "B.Mask" "B.Paste")
			(net "P5V_NODE1")
		)
	)
	(footprint ""
		(layer "B.Cu")
		(at 147.305014 -72.667622 180)
		(property "Reference" "C348"
			(at -4.93522 0.651764 0)
			(unlocked yes)
			(layer "B.SilkS")
			(effects
				(font
					(size 0.7874 0.5842)
					(thickness 0.1524)
				)
				(justify left mirror)
			)
		)
		(property "Value" ""
			(at 0 0 0)
			(layer "B.Fab")
			(effects
				(font
					(size 1.27 1.27)
				)
				(justify mirror)
			)
		)
		(duplicate_pad_numbers_are_jumpers no)
		(fp_line
			(start 0.7874 0.4064)
			(end 0.7874 -0.4064)
			(stroke
				(width 0.1524)
				(type default)
			)
			(layer "B.SilkS")
		)
		(fp_line
			(start 0.7874 -0.4064)
			(end -0.7874 -0.4064)
			(stroke
				(width 0.1524)
				(type default)
			)
			(layer "B.SilkS")
		)
		(fp_line
			(start 0 0.381)
			(end 0 -0.381)
			(stroke
				(width 0.1524)
				(type default)
			)
			(layer "B.SilkS")
		)
		(fp_line
			(start -0.7874 0.4064)
			(end 0.7874 0.4064)
			(stroke
				(width 0.1524)
				(type default)
			)
			(layer "B.SilkS")
		)
		(fp_line
			(start -0.7874 -0.4064)
			(end -0.7874 0.4064)
			(stroke
				(width 0.1524)
				(type default)
			)
			(layer "B.SilkS")
		)
		(fp_poly
			(pts
				(xy 0.5334 0.254) (xy 0.635 0.254) (xy 0.635 0.2286) (xy 0.635 -0.254) (xy 0.5334 -0.254) (xy 0.5334 -0.2794)
				(xy -0.5334 -0.2794) (xy -0.5334 -0.254) (xy -0.635 -0.254) (xy -0.635 0.254) (xy -0.5334 0.254)
				(xy -0.5334 0.2794) (xy 0.508 0.2794) (xy 0.5334 0.2794)
			)
			(stroke
				(width 0)
				(type default)
			)
			(fill no)
			(layer "B.CrtYd")
		)
		(pad "1" smd rect
			(at -0.40005 0)
			(size 0.4572 0.508)
			(layers "B.Cu" "B.Mask" "B.Paste")
			(net "P1V8_SATA_AVDD_NODE1")
		)
		(pad "2" smd rect
			(at 0.40005 0)
			(size 0.4572 0.508)
			(layers "B.Cu" "B.Mask" "B.Paste")
			(net "GND")
		)
	)
	(footprint ""
		(layer "B.Cu")
		(at 159.62376 -187.872624 90)
		(property "Reference" "R830"
			(at 4.565396 -4.067556 270)
			(unlocked yes)
			(layer "B.SilkS")
			(effects
				(font
					(size 0.7874 0.5842)
					(thickness 0.1524)
				)
				(justify left mirror)
			)
		)
		(property "Value" ""
			(at 0 0 90)
			(layer "B.Fab")
			(effects
				(font
					(size 1.27 1.27)
				)
				(justify mirror)
			)
		)
		(duplicate_pad_numbers_are_jumpers no)
		(fp_line
			(start 0.7874 -0.4064)
			(end -0.7874 -0.4064)
			(stroke
				(width 0.1524)
				(type default)
			)
			(layer "B.SilkS")
		)
		(fp_line
			(start -0.7874 -0.4064)
			(end -0.7874 0.4064)
			(stroke
				(width 0.1524)
				(type default)
			)
			(layer "B.SilkS")
		)
		(fp_line
			(start 0.7874 0.4064)
			(end 0.7874 -0.4064)
			(stroke
				(width 0.1524)
				(type default)
			)
			(layer "B.SilkS")
		)
		(fp_line
			(start -0.7874 0.4064)
			(end 0.7874 0.4064)
			(stroke
				(width 0.1524)
				(type default)
			)
			(layer "B.SilkS")
		)
		(fp_poly
			(pts
				(xy 0.508 0.2794) (xy 0.508 0.2286) (xy 0.635 0.2286) (xy 0.635 -0.254) (xy 0.5334 -0.254) (xy 0.5334 -0.2794)
				(xy -0.5334 -0.2794) (xy -0.5334 -0.254) (xy -0.635 -0.254) (xy -0.635 0.254) (xy -0.5334 0.254)
				(xy -0.5334 0.2794)
			)
			(stroke
				(width 0)
				(type default)
			)
			(fill no)
			(layer "B.CrtYd")
		)
		(pad "1" smd rect
			(at -0.40005 0 270)
			(size 0.4572 0.508)
			(layers "B.Cu" "B.Mask" "B.Paste")
			(net "FAN6_TACH")
		)
		(pad "2" smd rect
			(at 0.40005 0 270)
			(size 0.4572 0.508)
			(layers "B.Cu" "B.Mask" "B.Paste")
			(net "FAN6_TACH_R")
		)
	)
	(footprint ""
		(layer "B.Cu")
		(at 102.557072 -171.750482)
		(property "Reference" "R799"
			(at 8.71601 1.026668 0)
			(unlocked yes)
			(layer "B.SilkS")
			(effects
				(font
					(size 0.7874 0.5842)
					(thickness 0.1524)
				)
				(justify left mirror)
			)
		)
		(property "Value" ""
			(at 0 0 0)
			(layer "B.Fab")
			(effects
				(font
					(size 1.27 1.27)
				)
				(justify mirror)
			)
		)
		(duplicate_pad_numbers_are_jumpers no)
		(fp_line
			(start -0.7874 -0.4064)
			(end -0.7874 0.4064)
			(stroke
				(width 0.1524)
				(type default)
			)
			(layer "B.SilkS")
		)
		(fp_line
			(start -0.7874 0.4064)
			(end 0.7874 0.4064)
			(stroke
				(width 0.1524)
				(type default)
			)
			(layer "B.SilkS")
		)
		(fp_line
			(start 0.7874 -0.4064)
			(end -0.7874 -0.4064)
			(stroke
				(width 0.1524)
				(type default)
			)
			(layer "B.SilkS")
		)
		(fp_line
			(start 0.7874 0.4064)
			(end 0.7874 -0.4064)
			(stroke
				(width 0.1524)
				(type default)
			)
			(layer "B.SilkS")
		)
		(fp_poly
			(pts
				(xy 0.508 0.2794) (xy 0.508 0.2286) (xy 0.635 0.2286) (xy 0.635 -0.254) (xy 0.5334 -0.254) (xy 0.5334 -0.2794)
				(xy -0.5334 -0.2794) (xy -0.5334 -0.254) (xy -0.635 -0.254) (xy -0.635 0.254) (xy -0.5334 0.254)
				(xy -0.5334 0.2794)
			)
			(stroke
				(width 0)
				(type default)
			)
			(fill no)
			(layer "B.CrtYd")
		)
		(pad "1" smd rect
			(at -0.40005 0 180)
			(size 0.4572 0.508)
			(layers "B.Cu" "B.Mask" "B.Paste")
			(net "P3V3_NODE1")
		)
		(pad "2" smd rect
			(at 0.40005 0 180)
			(size 0.4572 0.508)
			(layers "B.Cu" "B.Mask" "B.Paste")
			(net "FAN_PWM_BUF")
		)
	)
	(footprint ""
		(layer "B.Cu")
		(at 94.451932 -172.124624)
		(property "Reference" "R701"
			(at 1.83642 14.389608 0)
			(unlocked yes)
			(layer "B.SilkS")
			(effects
				(font
					(size 0.7874 0.5842)
					(thickness 0.1524)
				)
				(justify left mirror)
			)
		)
		(property "Value" ""
			(at 0 0 0)
			(layer "B.Fab")
			(effects
				(font
					(size 1.27 1.27)
				)
				(justify mirror)
			)
		)
		(duplicate_pad_numbers_are_jumpers no)
		(fp_line
			(start -0.7874 -0.4064)
			(end -0.7874 0.4064)
			(stroke
				(width 0.1524)
				(type default)
			)
			(layer "B.SilkS")
		)
		(fp_line
			(start -0.7874 0.4064)
			(end 0.7874 0.4064)
			(stroke
				(width 0.1524)
				(type default)
			)
			(layer "B.SilkS")
		)
		(fp_line
			(start 0.7874 -0.4064)
			(end -0.7874 -0.4064)
			(stroke
				(width 0.1524)
				(type default)
			)
			(layer "B.SilkS")
		)
		(fp_line
			(start 0.7874 0.4064)
			(end 0.7874 -0.4064)
			(stroke
				(width 0.1524)
				(type default)
			)
			(layer "B.SilkS")
		)
		(fp_poly
			(pts
				(xy 0.508 0.2794) (xy 0.508 0.2286) (xy 0.635 0.2286) (xy 0.635 -0.254) (xy 0.5334 -0.254) (xy 0.5334 -0.2794)
				(xy -0.5334 -0.2794) (xy -0.5334 -0.254) (xy -0.635 -0.254) (xy -0.635 0.254) (xy -0.5334 0.254)
				(xy -0.5334 0.2794)
			)
			(stroke
				(width 0)
				(type default)
			)
			(fill no)
			(layer "B.CrtYd")
		)
		(pad "1" smd rect
			(at -0.40005 0 180)
			(size 0.4572 0.508)
			(layers "B.Cu" "B.Mask" "B.Paste")
			(net "P3V3_NODE1")
		)
		(pad "2" smd rect
			(at 0.40005 0 180)
			(size 0.4572 0.508)
			(layers "B.Cu" "B.Mask" "B.Paste")
			(net "N21701263")
		)
	)
	(footprint ""
		(layer "B.Cu")
		(at 137.972038 -163.812474)
		(property "Reference" "C905"
			(at 0.758952 1.266444 0)
			(unlocked yes)
			(layer "B.SilkS")
			(effects
				(font
					(size 0.7874 0.5842)
					(thickness 0.1524)
				)
				(justify left mirror)
			)
		)
		(property "Value" ""
			(at 0 0 0)
			(layer "B.Fab")
			(effects
				(font
					(size 1.27 1.27)
				)
				(justify mirror)
			)
		)
		(duplicate_pad_numbers_are_jumpers no)
		(fp_line
			(start -0.7874 -0.4064)
			(end -0.7874 0.4064)
			(stroke
				(width 0.1524)
				(type default)
			)
			(layer "B.SilkS")
		)
		(fp_line
			(start -0.7874 0.4064)
			(end 0.7874 0.4064)
			(stroke
				(width 0.1524)
				(type default)
			)
			(layer "B.SilkS")
		)
		(fp_line
			(start 0 0.381)
			(end 0 -0.381)
			(stroke
				(width 0.1524)
				(type default)
			)
			(layer "B.SilkS")
		)
		(fp_line
			(start 0.7874 -0.4064)
			(end -0.7874 -0.4064)
			(stroke
				(width 0.1524)
				(type default)
			)
			(layer "B.SilkS")
		)
		(fp_line
			(start 0.7874 0.4064)
			(end 0.7874 -0.4064)
			(stroke
				(width 0.1524)
				(type default)
			)
			(layer "B.SilkS")
		)
		(fp_poly
			(pts
				(xy 0.5334 0.254) (xy 0.635 0.254) (xy 0.635 0.2286) (xy 0.635 -0.254) (xy 0.5334 -0.254) (xy 0.5334 -0.2794)
				(xy -0.5334 -0.2794) (xy -0.5334 -0.254) (xy -0.635 -0.254) (xy -0.635 0.254) (xy -0.5334 0.254)
				(xy -0.5334 0.2794) (xy 0.508 0.2794) (xy 0.5334 0.2794)
			)
			(stroke
				(width 0)
				(type default)
			)
			(fill no)
			(layer "B.CrtYd")
		)
		(pad "1" smd rect
			(at -0.40005 0 180)
			(size 0.4572 0.508)
			(layers "B.Cu" "B.Mask" "B.Paste")
			(net "P3V3_NODE1")
		)
		(pad "2" smd rect
			(at 0.40005 0 180)
			(size 0.4572 0.508)
			(layers "B.Cu" "B.Mask" "B.Paste")
			(net "GND")
		)
	)
	(footprint ""
		(layer "B.Cu")
		(at 173.600872 -159.346138 -90)
		(property "Reference" "C521"
			(at -2.549398 0.127254 270)
			(unlocked yes)
			(layer "B.SilkS")
			(effects
				(font
					(size 0.7874 0.5842)
					(thickness 0.1524)
				)
				(justify left mirror)
			)
		)
		(property "Value" ""
			(at 0 0 90)
			(layer "B.Fab")
			(effects
				(font
					(size 1.27 1.27)
				)
				(justify mirror)
			)
		)
		(duplicate_pad_numbers_are_jumpers no)
		(fp_line
			(start -0.7874 0.4064)
			(end 0.7874 0.4064)
			(stroke
				(width 0.1524)
				(type default)
			)
			(layer "B.SilkS")
		)
		(fp_line
			(start 0.7874 0.4064)
			(end 0.7874 -0.4064)
			(stroke
				(width 0.1524)
				(type default)
			)
			(layer "B.SilkS")
		)
		(fp_line
			(start 0 0.381)
			(end 0 -0.381)
			(stroke
				(width 0.1524)
				(type default)
			)
			(layer "B.SilkS")
		)
		(fp_line
			(start -0.7874 -0.4064)
			(end -0.7874 0.4064)
			(stroke
				(width 0.1524)
				(type default)
			)
			(layer "B.SilkS")
		)
		(fp_line
			(start 0.7874 -0.4064)
			(end -0.7874 -0.4064)
			(stroke
				(width 0.1524)
				(type default)
			)
			(layer "B.SilkS")
		)
		(fp_poly
			(pts
				(xy 0.5334 0.254) (xy 0.635 0.254) (xy 0.635 0.2286) (xy 0.635 -0.254) (xy 0.5334 -0.254) (xy 0.5334 -0.2794)
				(xy -0.5334 -0.2794) (xy -0.5334 -0.254) (xy -0.635 -0.254) (xy -0.635 0.254) (xy -0.5334 0.254)
				(xy -0.5334 0.2794) (xy 0.508 0.2794) (xy 0.5334 0.2794)
			)
			(stroke
				(width 0)
				(type default)
			)
			(fill no)
			(layer "B.CrtYd")
		)
		(pad "1" smd rect
			(at -0.40005 0 90)
			(size 0.4572 0.508)
			(layers "B.Cu" "B.Mask" "B.Paste")
			(net "P1V9_LAN2")
		)
		(pad "2" smd rect
			(at 0.40005 0 90)
			(size 0.4572 0.508)
			(layers "B.Cu" "B.Mask" "B.Paste")
			(net "GND")
		)
	)
	(footprint ""
		(layer "B.Cu")
		(at 50.278538 -79.658718 180)
		(property "Reference" "C99"
			(at 14.413738 -31.336234 0)
			(unlocked yes)
			(layer "B.SilkS")
			(effects
				(font
					(size 0.7874 0.5842)
					(thickness 0.1524)
				)
				(justify left mirror)
			)
		)
		(property "Value" ""
			(at 0 0 0)
			(layer "B.Fab")
			(effects
				(font
					(size 1.27 1.27)
				)
				(justify mirror)
			)
		)
		(duplicate_pad_numbers_are_jumpers no)
		(fp_line
			(start 0.7874 0.4064)
			(end 0.7874 -0.4064)
			(stroke
				(width 0.1524)
				(type default)
			)
			(layer "B.SilkS")
		)
		(fp_line
			(start 0.7874 -0.4064)
			(end -0.7874 -0.4064)
			(stroke
				(width 0.1524)
				(type default)
			)
			(layer "B.SilkS")
		)
		(fp_line
			(start 0 0.381)
			(end 0 -0.381)
			(stroke
				(width 0.1524)
				(type default)
			)
			(layer "B.SilkS")
		)
		(fp_line
			(start -0.7874 0.4064)
			(end 0.7874 0.4064)
			(stroke
				(width 0.1524)
				(type default)
			)
			(layer "B.SilkS")
		)
		(fp_line
			(start -0.7874 -0.4064)
			(end -0.7874 0.4064)
			(stroke
				(width 0.1524)
				(type default)
			)
			(layer "B.SilkS")
		)
		(fp_poly
			(pts
				(xy 0.5334 0.254) (xy 0.635 0.254) (xy 0.635 0.2286) (xy 0.635 -0.254) (xy 0.5334 -0.254) (xy 0.5334 -0.2794)
				(xy -0.5334 -0.2794) (xy -0.5334 -0.254) (xy -0.635 -0.254) (xy -0.635 0.254) (xy -0.5334 0.254)
				(xy -0.5334 0.2794) (xy 0.508 0.2794) (xy 0.5334 0.2794)
			)
			(stroke
				(width 0)
				(type default)
			)
			(fill no)
			(layer "B.CrtYd")
		)
		(pad "1" smd rect
			(at -0.40005 0)
			(size 0.4572 0.508)
			(layers "B.Cu" "B.Mask" "B.Paste")
			(net "P1V05_NODE1")
		)
		(pad "2" smd rect
			(at 0.40005 0)
			(size 0.4572 0.508)
			(layers "B.Cu" "B.Mask" "B.Paste")
			(net "GND")
		)
	)
	(footprint ""
		(layer "B.Cu")
		(at 55.592218 -132.756402 -90)
		(property "Reference" "C205"
			(at -1.982978 0.008128 270)
			(unlocked yes)
			(layer "B.SilkS")
			(effects
				(font
					(size 0.7874 0.5842)
					(thickness 0.1524)
				)
				(justify left mirror)
			)
		)
		(property "Value" ""
			(at 0 0 90)
			(layer "B.Fab")
			(effects
				(font
					(size 1.27 1.27)
				)
				(justify mirror)
			)
		)
		(duplicate_pad_numbers_are_jumpers no)
		(fp_line
			(start -0.7874 0.4064)
			(end 0.7874 0.4064)
			(stroke
				(width 0.1524)
				(type default)
			)
			(layer "B.SilkS")
		)
		(fp_line
			(start 0.7874 0.4064)
			(end 0.7874 -0.4064)
			(stroke
				(width 0.1524)
				(type default)
			)
			(layer "B.SilkS")
		)
		(fp_line
			(start 0 0.381)
			(end 0 -0.381)
			(stroke
				(width 0.1524)
				(type default)
			)
			(layer "B.SilkS")
		)
		(fp_line
			(start -0.7874 -0.4064)
			(end -0.7874 0.4064)
			(stroke
				(width 0.1524)
				(type default)
			)
			(layer "B.SilkS")
		)
		(fp_line
			(start 0.7874 -0.4064)
			(end -0.7874 -0.4064)
			(stroke
				(width 0.1524)
				(type default)
			)
			(layer "B.SilkS")
		)
		(fp_poly
			(pts
				(xy 0.5334 0.254) (xy 0.635 0.254) (xy 0.635 0.2286) (xy 0.635 -0.254) (xy 0.5334 -0.254) (xy 0.5334 -0.2794)
				(xy -0.5334 -0.2794) (xy -0.5334 -0.254) (xy -0.635 -0.254) (xy -0.635 0.254) (xy -0.5334 0.254)
				(xy -0.5334 0.2794) (xy 0.508 0.2794) (xy 0.5334 0.2794)
			)
			(stroke
				(width 0)
				(type default)
			)
			(fill no)
			(layer "B.CrtYd")
		)
		(pad "1" smd rect
			(at -0.40005 0 90)
			(size 0.4572 0.508)
			(layers "B.Cu" "B.Mask" "B.Paste")
			(net "GND")
		)
		(pad "2" smd rect
			(at 0.40005 0 90)
			(size 0.4572 0.508)
			(layers "B.Cu" "B.Mask" "B.Paste")
			(net "P0V75_BMC_VTTREF_NODE1")
		)
	)
	(footprint ""
		(layer "B.Cu")
		(at 82.04327 -21.09724 90)
		(property "Reference" "C163"
			(at -5.835904 -0.68834 270)
			(unlocked yes)
			(layer "B.SilkS")
			(effects
				(font
					(size 0.7874 0.5842)
					(thickness 0.1524)
				)
				(justify left mirror)
			)
		)
		(property "Value" ""
			(at 0 0 90)
			(layer "B.Fab")
			(effects
				(font
					(size 1.27 1.27)
				)
				(justify mirror)
			)
		)
		(duplicate_pad_numbers_are_jumpers no)
		(fp_line
			(start 0.7874 -0.4064)
			(end -0.7874 -0.4064)
			(stroke
				(width 0.1524)
				(type default)
			)
			(layer "B.SilkS")
		)
		(fp_line
			(start -0.7874 -0.4064)
			(end -0.7874 0.4064)
			(stroke
				(width 0.1524)
				(type default)
			)
			(layer "B.SilkS")
		)
		(fp_line
			(start 0 0.381)
			(end 0 -0.381)
			(stroke
				(width 0.1524)
				(type default)
			)
			(layer "B.SilkS")
		)
		(fp_line
			(start 0.7874 0.4064)
			(end 0.7874 -0.4064)
			(stroke
				(width 0.1524)
				(type default)
			)
			(layer "B.SilkS")
		)
		(fp_line
			(start -0.7874 0.4064)
			(end 0.7874 0.4064)
			(stroke
				(width 0.1524)
				(type default)
			)
			(layer "B.SilkS")
		)
		(fp_poly
			(pts
				(xy 0.5334 0.254) (xy 0.635 0.254) (xy 0.635 0.2286) (xy 0.635 -0.254) (xy 0.5334 -0.254) (xy 0.5334 -0.2794)
				(xy -0.5334 -0.2794) (xy -0.5334 -0.254) (xy -0.635 -0.254) (xy -0.635 0.254) (xy -0.5334 0.254)
				(xy -0.5334 0.2794) (xy 0.508 0.2794) (xy 0.5334 0.2794)
			)
			(stroke
				(width 0)
				(type default)
			)
			(fill no)
			(layer "B.CrtYd")
		)
		(pad "1" smd rect
			(at -0.40005 0 270)
			(size 0.4572 0.508)
			(layers "B.Cu" "B.Mask" "B.Paste")
			(net "PV_VDDR_NODE1")
		)
		(pad "2" smd rect
			(at 0.40005 0 270)
			(size 0.4572 0.508)
			(layers "B.Cu" "B.Mask" "B.Paste")
			(net "GND")
		)
	)
	(footprint ""
		(layer "B.Cu")
		(at 132.775452 -135.87095 -90)
		(property "Reference" "C873"
			(at 5.07365 -0.26797 270)
			(unlocked yes)
			(layer "B.SilkS")
			(effects
				(font
					(size 0.7874 0.5842)
					(thickness 0.1524)
				)
				(justify left mirror)
			)
		)
		(property "Value" ""
			(at 0 0 90)
			(layer "B.Fab")
			(effects
				(font
					(size 1.27 1.27)
				)
				(justify mirror)
			)
		)
		(duplicate_pad_numbers_are_jumpers no)
		(fp_line
			(start -0.7874 0.4064)
			(end 0.7874 0.4064)
			(stroke
				(width 0.1524)
				(type default)
			)
			(layer "B.SilkS")
		)
		(fp_line
			(start 0.7874 0.4064)
			(end 0.7874 -0.4064)
			(stroke
				(width 0.1524)
				(type default)
			)
			(layer "B.SilkS")
		)
		(fp_line
			(start 0 0.381)
			(end 0 -0.381)
			(stroke
				(width 0.1524)
				(type default)
			)
			(layer "B.SilkS")
		)
		(fp_line
			(start -0.7874 -0.4064)
			(end -0.7874 0.4064)
			(stroke
				(width 0.1524)
				(type default)
			)
			(layer "B.SilkS")
		)
		(fp_line
			(start 0.7874 -0.4064)
			(end -0.7874 -0.4064)
			(stroke
				(width 0.1524)
				(type default)
			)
			(layer "B.SilkS")
		)
		(fp_poly
			(pts
				(xy 0.5334 0.254) (xy 0.635 0.254) (xy 0.635 0.2286) (xy 0.635 -0.254) (xy 0.5334 -0.254) (xy 0.5334 -0.2794)
				(xy -0.5334 -0.2794) (xy -0.5334 -0.254) (xy -0.635 -0.254) (xy -0.635 0.254) (xy -0.5334 0.254)
				(xy -0.5334 0.2794) (xy 0.508 0.2794) (xy 0.5334 0.2794)
			)
			(stroke
				(width 0)
				(type default)
			)
			(fill no)
			(layer "B.CrtYd")
		)
		(pad "1" smd rect
			(at -0.40005 0 90)
			(size 0.4572 0.508)
			(layers "B.Cu" "B.Mask" "B.Paste")
			(net "P1V0_NODE1")
		)
		(pad "2" smd rect
			(at 0.40005 0 90)
			(size 0.4572 0.508)
			(layers "B.Cu" "B.Mask" "B.Paste")
			(net "GND")
		)
	)
	(footprint ""
		(layer "B.Cu")
		(at 145.65376 -187.999624 -90)
		(property "Reference" "C729"
			(at -4.438396 1.850644 270)
			(unlocked yes)
			(layer "B.SilkS")
			(effects
				(font
					(size 0.7874 0.5842)
					(thickness 0.1524)
				)
				(justify left mirror)
			)
		)
		(property "Value" ""
			(at 0 0 90)
			(layer "B.Fab")
			(effects
				(font
					(size 1.27 1.27)
				)
				(justify mirror)
			)
		)
		(duplicate_pad_numbers_are_jumpers no)
		(fp_line
			(start -0.7874 0.4064)
			(end 0.7874 0.4064)
			(stroke
				(width 0.1524)
				(type default)
			)
			(layer "B.SilkS")
		)
		(fp_line
			(start 0.7874 0.4064)
			(end 0.7874 -0.4064)
			(stroke
				(width 0.1524)
				(type default)
			)
			(layer "B.SilkS")
		)
		(fp_line
			(start 0 0.381)
			(end 0 -0.381)
			(stroke
				(width 0.1524)
				(type default)
			)
			(layer "B.SilkS")
		)
		(fp_line
			(start -0.7874 -0.4064)
			(end -0.7874 0.4064)
			(stroke
				(width 0.1524)
				(type default)
			)
			(layer "B.SilkS")
		)
		(fp_line
			(start 0.7874 -0.4064)
			(end -0.7874 -0.4064)
			(stroke
				(width 0.1524)
				(type default)
			)
			(layer "B.SilkS")
		)
		(fp_poly
			(pts
				(xy 0.5334 0.254) (xy 0.635 0.254) (xy 0.635 0.2286) (xy 0.635 -0.254) (xy 0.5334 -0.254) (xy 0.5334 -0.2794)
				(xy -0.5334 -0.2794) (xy -0.5334 -0.254) (xy -0.635 -0.254) (xy -0.635 0.254) (xy -0.5334 0.254)
				(xy -0.5334 0.2794) (xy 0.508 0.2794) (xy 0.5334 0.2794)
			)
			(stroke
				(width 0)
				(type default)
			)
			(fill no)
			(layer "B.CrtYd")
		)
		(pad "1" smd rect
			(at -0.40005 0 90)
			(size 0.4572 0.508)
			(layers "B.Cu" "B.Mask" "B.Paste")
			(net "UART_T11_NODE2_TXD_R")
		)
		(pad "2" smd rect
			(at 0.40005 0 90)
			(size 0.4572 0.508)
			(layers "B.Cu" "B.Mask" "B.Paste")
			(net "GND")
		)
	)
	(footprint ""
		(layer "B.Cu")
		(at 41.58869 -96.994726 -90)
		(property "Reference" "R122"
			(at -1.09347 0.02032 270)
			(unlocked yes)
			(layer "B.SilkS")
			(effects
				(font
					(size 0.7874 0.5842)
					(thickness 0.1524)
				)
				(justify left mirror)
			)
		)
		(property "Value" ""
			(at 0 0 90)
			(layer "B.Fab")
			(effects
				(font
					(size 1.27 1.27)
				)
				(justify mirror)
			)
		)
		(duplicate_pad_numbers_are_jumpers no)
		(fp_line
			(start -0.7874 0.4064)
			(end 0.7874 0.4064)
			(stroke
				(width 0.1524)
				(type default)
			)
			(layer "B.SilkS")
		)
		(fp_line
			(start 0.7874 0.4064)
			(end 0.7874 -0.4064)
			(stroke
				(width 0.1524)
				(type default)
			)
			(layer "B.SilkS")
		)
		(fp_line
			(start -0.7874 -0.4064)
			(end -0.7874 0.4064)
			(stroke
				(width 0.1524)
				(type default)
			)
			(layer "B.SilkS")
		)
		(fp_line
			(start 0.7874 -0.4064)
			(end -0.7874 -0.4064)
			(stroke
				(width 0.1524)
				(type default)
			)
			(layer "B.SilkS")
		)
		(fp_poly
			(pts
				(xy 0.508 0.2794) (xy 0.508 0.2286) (xy 0.635 0.2286) (xy 0.635 -0.254) (xy 0.5334 -0.254) (xy 0.5334 -0.2794)
				(xy -0.5334 -0.2794) (xy -0.5334 -0.254) (xy -0.635 -0.254) (xy -0.635 0.254) (xy -0.5334 0.254)
				(xy -0.5334 0.2794)
			)
			(stroke
				(width 0)
				(type default)
			)
			(fill no)
			(layer "B.CrtYd")
		)
		(pad "1" smd rect
			(at -0.40005 0 90)
			(size 0.4572 0.508)
			(layers "B.Cu" "B.Mask" "B.Paste")
			(net "P3V3_NODE1")
		)
		(pad "2" smd rect
			(at 0.40005 0 90)
			(size 0.4572 0.508)
			(layers "B.Cu" "B.Mask" "B.Paste")
			(net "SMB_CPU_NODE1_XDP_CLK")
		)
	)
	(footprint ""
		(layer "B.Cu")
		(at 173.54042 -116.280946 -90)
		(property "Reference" "C793"
			(at 3.061208 -0.771906 270)
			(unlocked yes)
			(layer "B.SilkS")
			(effects
				(font
					(size 0.7874 0.5842)
					(thickness 0.1524)
				)
				(justify mirror)
			)
		)
		(property "Value" ""
			(at 0 0 90)
			(layer "B.Fab")
			(effects
				(font
					(size 1.27 1.27)
				)
				(justify mirror)
			)
		)
		(duplicate_pad_numbers_are_jumpers no)
		(fp_line
			(start -1.2954 0.5842)
			(end 1.2954 0.5842)
			(stroke
				(width 0.1524)
				(type default)
			)
			(layer "B.SilkS")
		)
		(fp_line
			(start 1.2954 0.5842)
			(end 1.2954 -0.5842)
			(stroke
				(width 0.1524)
				(type default)
			)
			(layer "B.SilkS")
		)
		(fp_line
			(start -1.2954 -0.5842)
			(end -1.2954 0.5842)
			(stroke
				(width 0.1524)
				(type default)
			)
			(layer "B.SilkS")
		)
		(fp_line
			(start 0 -0.5842)
			(end 0 0.5842)
			(stroke
				(width 0.1524)
				(type default)
			)
			(layer "B.SilkS")
		)
		(fp_line
			(start 1.2954 -0.5842)
			(end -1.2954 -0.5842)
			(stroke
				(width 0.1524)
				(type default)
			)
			(layer "B.SilkS")
		)
		(fp_poly
			(pts
				(xy -0.8636 -0.4572) (xy -0.8636 -0.3556) (xy -1.143 -0.3556) (xy -1.143 0.3556) (xy -0.8636 0.3556)
				(xy -0.8636 0.4572) (xy 0.8636 0.4572) (xy 0.8636 0.3556) (xy 1.143 0.3556) (xy 1.143 -0.3556) (xy 0.8636 -0.3556)
				(xy 0.8636 -0.4572)
			)
			(stroke
				(width 0)
				(type default)
			)
			(fill no)
			(layer "B.CrtYd")
		)
		(fp_line
			(start -0.884936 0.504952)
			(end 0.884936 0.504952)
			(stroke
				(width 0.1)
				(type default)
			)
			(layer "B.Fab")
		)
		(fp_line
			(start 0.884936 0.504952)
			(end 0.884936 -0.504952)
			(stroke
				(width 0.1)
				(type default)
			)
			(layer "B.Fab")
		)
		(fp_line
			(start -0.884936 -0.504952)
			(end -0.884936 0.504952)
			(stroke
				(width 0.1)
				(type default)
			)
			(layer "B.Fab")
		)
		(fp_line
			(start 0.884936 -0.504952)
			(end -0.884936 -0.504952)
			(stroke
				(width 0.1)
				(type default)
			)
			(layer "B.Fab")
		)
		(pad "1" smd rect
			(at -0.7366 0)
			(size 0.7112 0.8128)
			(layers "B.Cu" "B.Mask" "B.Paste")
			(net "P3V3_STB_NODE1")
		)
		(pad "2" smd rect
			(at 0.7366 0)
			(size 0.7112 0.8128)
			(layers "B.Cu" "B.Mask" "B.Paste")
			(net "GND")
		)
	)
	(footprint ""
		(layer "B.Cu")
		(at 137.970006 -38.45941 180)
		(property "Reference" "R1179"
			(at 4.172458 -18.307812 0)
			(unlocked yes)
			(layer "B.SilkS")
			(effects
				(font
					(size 0.7874 0.5842)
					(thickness 0.1524)
				)
				(justify left mirror)
			)
		)
		(property "Value" ""
			(at 0 0 0)
			(layer "B.Fab")
			(effects
				(font
					(size 1.27 1.27)
				)
				(justify mirror)
			)
		)
		(duplicate_pad_numbers_are_jumpers no)
		(fp_line
			(start 0.7874 0.4064)
			(end 0.7874 -0.4064)
			(stroke
				(width 0.1524)
				(type default)
			)
			(layer "B.SilkS")
		)
		(fp_line
			(start 0.7874 -0.4064)
			(end -0.7874 -0.4064)
			(stroke
				(width 0.1524)
				(type default)
			)
			(layer "B.SilkS")
		)
		(fp_line
			(start -0.7874 0.4064)
			(end 0.7874 0.4064)
			(stroke
				(width 0.1524)
				(type default)
			)
			(layer "B.SilkS")
		)
		(fp_line
			(start -0.7874 -0.4064)
			(end -0.7874 0.4064)
			(stroke
				(width 0.1524)
				(type default)
			)
			(layer "B.SilkS")
		)
		(fp_poly
			(pts
				(xy 0.508 0.2794) (xy 0.508 0.2286) (xy 0.635 0.2286) (xy 0.635 -0.254) (xy 0.5334 -0.254) (xy 0.5334 -0.2794)
				(xy -0.5334 -0.2794) (xy -0.5334 -0.254) (xy -0.635 -0.254) (xy -0.635 0.254) (xy -0.5334 0.254)
				(xy -0.5334 0.2794)
			)
			(stroke
				(width 0)
				(type default)
			)
			(fill no)
			(layer "B.CrtYd")
		)
		(pad "1" smd rect
			(at -0.40005 0)
			(size 0.4572 0.508)
			(layers "B.Cu" "B.Mask" "B.Paste")
			(net "CPLD_WDT3_R")
		)
		(pad "2" smd rect
			(at 0.40005 0)
			(size 0.4572 0.508)
			(layers "B.Cu" "B.Mask" "B.Paste")
			(net "CPLD_WDT3")
		)
	)
	(footprint ""
		(layer "B.Cu")
		(at 76.05776 -188.126624 -90)
		(property "Reference" "C655"
			(at -4.318254 0.3683 270)
			(unlocked yes)
			(layer "B.SilkS")
			(effects
				(font
					(size 0.7874 0.5842)
					(thickness 0.1524)
				)
				(justify left mirror)
			)
		)
		(property "Value" ""
			(at 0 0 90)
			(layer "B.Fab")
			(effects
				(font
					(size 1.27 1.27)
				)
				(justify mirror)
			)
		)
		(duplicate_pad_numbers_are_jumpers no)
		(fp_line
			(start -0.7874 0.4064)
			(end 0.7874 0.4064)
			(stroke
				(width 0.1524)
				(type default)
			)
			(layer "B.SilkS")
		)
		(fp_line
			(start 0.7874 0.4064)
			(end 0.7874 -0.4064)
			(stroke
				(width 0.1524)
				(type default)
			)
			(layer "B.SilkS")
		)
		(fp_line
			(start 0 0.381)
			(end 0 -0.381)
			(stroke
				(width 0.1524)
				(type default)
			)
			(layer "B.SilkS")
		)
		(fp_line
			(start -0.7874 -0.4064)
			(end -0.7874 0.4064)
			(stroke
				(width 0.1524)
				(type default)
			)
			(layer "B.SilkS")
		)
		(fp_line
			(start 0.7874 -0.4064)
			(end -0.7874 -0.4064)
			(stroke
				(width 0.1524)
				(type default)
			)
			(layer "B.SilkS")
		)
		(fp_poly
			(pts
				(xy 0.5334 0.254) (xy 0.635 0.254) (xy 0.635 0.2286) (xy 0.635 -0.254) (xy 0.5334 -0.254) (xy 0.5334 -0.2794)
				(xy -0.5334 -0.2794) (xy -0.5334 -0.254) (xy -0.635 -0.254) (xy -0.635 0.254) (xy -0.5334 0.254)
				(xy -0.5334 0.2794) (xy 0.508 0.2794) (xy 0.5334 0.2794)
			)
			(stroke
				(width 0)
				(type default)
			)
			(fill no)
			(layer "B.CrtYd")
		)
		(pad "1" smd rect
			(at -0.40005 0 90)
			(size 0.4572 0.508)
			(layers "B.Cu" "B.Mask" "B.Paste")
			(net "T3_NODE4_EN_R")
		)
		(pad "2" smd rect
			(at 0.40005 0 90)
			(size 0.4572 0.508)
			(layers "B.Cu" "B.Mask" "B.Paste")
			(net "GND")
		)
	)
	(footprint ""
		(layer "B.Cu")
		(at 181.803294 -159.333692 -90)
		(property "Reference" "C524"
			(at -2.625598 0.04445 270)
			(unlocked yes)
			(layer "B.SilkS")
			(effects
				(font
					(size 0.7874 0.5842)
					(thickness 0.1524)
				)
				(justify left mirror)
			)
		)
		(property "Value" ""
			(at 0 0 90)
			(layer "B.Fab")
			(effects
				(font
					(size 1.27 1.27)
				)
				(justify mirror)
			)
		)
		(duplicate_pad_numbers_are_jumpers no)
		(fp_line
			(start -0.7874 0.406146)
			(end 0.7874 0.406146)
			(stroke
				(width 0.1524)
				(type default)
			)
			(layer "B.SilkS")
		)
		(fp_line
			(start 0.7874 0.406146)
			(end 0.7874 -0.406146)
			(stroke
				(width 0.1524)
				(type default)
			)
			(layer "B.SilkS")
		)
		(fp_line
			(start 0 0.381)
			(end 0 -0.381)
			(stroke
				(width 0.1524)
				(type default)
			)
			(layer "B.SilkS")
		)
		(fp_line
			(start -0.7874 -0.406146)
			(end -0.7874 0.406146)
			(stroke
				(width 0.1524)
				(type default)
			)
			(layer "B.SilkS")
		)
		(fp_line
			(start 0.7874 -0.406146)
			(end -0.7874 -0.406146)
			(stroke
				(width 0.1524)
				(type default)
			)
			(layer "B.SilkS")
		)
		(fp_poly
			(pts
				(xy 0.5334 0.254) (xy 0.635 0.254) (xy 0.635 0.2286) (xy 0.635 -0.254) (xy 0.5334 -0.254) (xy 0.5334 -0.2794)
				(xy -0.5334 -0.2794) (xy -0.5334 -0.254) (xy -0.635 -0.254) (xy -0.635 0.254) (xy -0.5334 0.254)
				(xy -0.5334 0.2794) (xy 0.508 0.2794) (xy 0.5334 0.2794)
			)
			(stroke
				(width 0)
				(type default)
			)
			(fill no)
			(layer "B.CrtYd")
		)
		(pad "1" smd rect
			(at -0.40005 0 90)
			(size 0.4572 0.508)
			(layers "B.Cu" "B.Mask" "B.Paste")
			(net "P1V9_LAN2")
		)
		(pad "2" smd rect
			(at 0.40005 0 90)
			(size 0.4572 0.508)
			(layers "B.Cu" "B.Mask" "B.Paste")
			(net "GND")
		)
	)
	(footprint ""
		(layer "B.Cu")
		(at 135.196834 -38.391084 180)
		(property "Reference" "R1180"
			(at 5.415788 -18.226532 0)
			(unlocked yes)
			(layer "B.SilkS")
			(effects
				(font
					(size 0.7874 0.5842)
					(thickness 0.1524)
				)
				(justify left mirror)
			)
		)
		(property "Value" ""
			(at 0 0 0)
			(layer "B.Fab")
			(effects
				(font
					(size 1.27 1.27)
				)
				(justify mirror)
			)
		)
		(duplicate_pad_numbers_are_jumpers no)
		(fp_line
			(start 0.7874 0.4064)
			(end 0.7874 -0.4064)
			(stroke
				(width 0.1524)
				(type default)
			)
			(layer "B.SilkS")
		)
		(fp_line
			(start 0.7874 -0.4064)
			(end -0.7874 -0.4064)
			(stroke
				(width 0.1524)
				(type default)
			)
			(layer "B.SilkS")
		)
		(fp_line
			(start -0.7874 0.4064)
			(end 0.7874 0.4064)
			(stroke
				(width 0.1524)
				(type default)
			)
			(layer "B.SilkS")
		)
		(fp_line
			(start -0.7874 -0.4064)
			(end -0.7874 0.4064)
			(stroke
				(width 0.1524)
				(type default)
			)
			(layer "B.SilkS")
		)
		(fp_poly
			(pts
				(xy 0.508 0.2794) (xy 0.508 0.2286) (xy 0.635 0.2286) (xy 0.635 -0.254) (xy 0.5334 -0.254) (xy 0.5334 -0.2794)
				(xy -0.5334 -0.2794) (xy -0.5334 -0.254) (xy -0.635 -0.254) (xy -0.635 0.254) (xy -0.5334 0.254)
				(xy -0.5334 0.2794)
			)
			(stroke
				(width 0)
				(type default)
			)
			(fill no)
			(layer "B.CrtYd")
		)
		(pad "1" smd rect
			(at -0.40005 0)
			(size 0.4572 0.508)
			(layers "B.Cu" "B.Mask" "B.Paste")
			(net "CPLD_WDT3")
		)
		(pad "2" smd rect
			(at 0.40005 0)
			(size 0.4572 0.508)
			(layers "B.Cu" "B.Mask" "B.Paste")
			(net "GND")
		)
	)
	(footprint ""
		(layer "B.Cu")
		(at 61.877448 -85.05444 90)
		(property "Reference" "C76"
			(at 1.0287 0.424942 270)
			(unlocked yes)
			(layer "B.SilkS")
			(effects
				(font
					(size 0.7874 0.5842)
					(thickness 0.1524)
				)
				(justify left mirror)
			)
		)
		(property "Value" ""
			(at 0 0 90)
			(layer "B.Fab")
			(effects
				(font
					(size 1.27 1.27)
				)
				(justify mirror)
			)
		)
		(duplicate_pad_numbers_are_jumpers no)
		(fp_line
			(start 0.7874 -0.4064)
			(end -0.7874 -0.4064)
			(stroke
				(width 0.1524)
				(type default)
			)
			(layer "B.SilkS")
		)
		(fp_line
			(start -0.7874 -0.4064)
			(end -0.7874 0.4064)
			(stroke
				(width 0.1524)
				(type default)
			)
			(layer "B.SilkS")
		)
		(fp_line
			(start 0 0.381)
			(end 0 -0.381)
			(stroke
				(width 0.1524)
				(type default)
			)
			(layer "B.SilkS")
		)
		(fp_line
			(start 0.7874 0.4064)
			(end 0.7874 -0.4064)
			(stroke
				(width 0.1524)
				(type default)
			)
			(layer "B.SilkS")
		)
		(fp_line
			(start -0.7874 0.4064)
			(end 0.7874 0.4064)
			(stroke
				(width 0.1524)
				(type default)
			)
			(layer "B.SilkS")
		)
		(fp_poly
			(pts
				(xy 0.5334 0.254) (xy 0.635 0.254) (xy 0.635 0.2286) (xy 0.635 -0.254) (xy 0.5334 -0.254) (xy 0.5334 -0.2794)
				(xy -0.5334 -0.2794) (xy -0.5334 -0.254) (xy -0.635 -0.254) (xy -0.635 0.254) (xy -0.5334 0.254)
				(xy -0.5334 0.2794) (xy 0.508 0.2794) (xy 0.5334 0.2794)
			)
			(stroke
				(width 0)
				(type default)
			)
			(fill no)
			(layer "B.CrtYd")
		)
		(pad "1" smd rect
			(at -0.40005 0 270)
			(size 0.4572 0.508)
			(layers "B.Cu" "B.Mask" "B.Paste")
			(net "P1V8_SUS_NODE1")
		)
		(pad "2" smd rect
			(at 0.40005 0 270)
			(size 0.4572 0.508)
			(layers "B.Cu" "B.Mask" "B.Paste")
			(net "GND")
		)
	)
	(footprint ""
		(layer "B.Cu")
		(at 126.039626 -40.071294 180)
		(property "Reference" "R620"
			(at -1.493774 -1.235964 0)
			(unlocked yes)
			(layer "B.SilkS")
			(effects
				(font
					(size 0.7874 0.5842)
					(thickness 0.1524)
				)
				(justify left mirror)
			)
		)
		(property "Value" ""
			(at 0 0 0)
			(layer "B.Fab")
			(effects
				(font
					(size 1.27 1.27)
				)
				(justify mirror)
			)
		)
		(duplicate_pad_numbers_are_jumpers no)
		(fp_line
			(start 0.7874 0.4064)
			(end 0.7874 -0.4064)
			(stroke
				(width 0.1524)
				(type default)
			)
			(layer "B.SilkS")
		)
		(fp_line
			(start 0.7874 -0.4064)
			(end -0.7874 -0.4064)
			(stroke
				(width 0.1524)
				(type default)
			)
			(layer "B.SilkS")
		)
		(fp_line
			(start -0.7874 0.4064)
			(end 0.7874 0.4064)
			(stroke
				(width 0.1524)
				(type default)
			)
			(layer "B.SilkS")
		)
		(fp_line
			(start -0.7874 -0.4064)
			(end -0.7874 0.4064)
			(stroke
				(width 0.1524)
				(type default)
			)
			(layer "B.SilkS")
		)
		(fp_poly
			(pts
				(xy 0.508 0.2794) (xy 0.508 0.2286) (xy 0.635 0.2286) (xy 0.635 -0.254) (xy 0.5334 -0.254) (xy 0.5334 -0.2794)
				(xy -0.5334 -0.2794) (xy -0.5334 -0.254) (xy -0.635 -0.254) (xy -0.635 0.254) (xy -0.5334 0.254)
				(xy -0.5334 0.2794)
			)
			(stroke
				(width 0)
				(type default)
			)
			(fill no)
			(layer "B.CrtYd")
		)
		(pad "1" smd rect
			(at -0.40005 0)
			(size 0.4572 0.508)
			(layers "B.Cu" "B.Mask" "B.Paste")
			(net "P3V3_NODE1")
		)
		(pad "2" smd rect
			(at 0.40005 0)
			(size 0.4572 0.508)
			(layers "B.Cu" "B.Mask" "B.Paste")
			(net "SIO_PWROK2")
		)
	)
	(footprint ""
		(layer "B.Cu")
		(at 130.79476 -184.951624 -90)
		(property "Reference" "C731"
			(at -4.354576 2.44983 270)
			(unlocked yes)
			(layer "B.SilkS")
			(effects
				(font
					(size 0.7874 0.5842)
					(thickness 0.1524)
				)
				(justify left mirror)
			)
		)
		(property "Value" ""
			(at 0 0 90)
			(layer "B.Fab")
			(effects
				(font
					(size 1.27 1.27)
				)
				(justify mirror)
			)
		)
		(duplicate_pad_numbers_are_jumpers no)
		(fp_line
			(start -0.7874 0.4064)
			(end 0.7874 0.4064)
			(stroke
				(width 0.1524)
				(type default)
			)
			(layer "B.SilkS")
		)
		(fp_line
			(start 0.7874 0.4064)
			(end 0.7874 -0.4064)
			(stroke
				(width 0.1524)
				(type default)
			)
			(layer "B.SilkS")
		)
		(fp_line
			(start 0 0.381)
			(end 0 -0.381)
			(stroke
				(width 0.1524)
				(type default)
			)
			(layer "B.SilkS")
		)
		(fp_line
			(start -0.7874 -0.4064)
			(end -0.7874 0.4064)
			(stroke
				(width 0.1524)
				(type default)
			)
			(layer "B.SilkS")
		)
		(fp_line
			(start 0.7874 -0.4064)
			(end -0.7874 -0.4064)
			(stroke
				(width 0.1524)
				(type default)
			)
			(layer "B.SilkS")
		)
		(fp_poly
			(pts
				(xy 0.5334 0.254) (xy 0.635 0.254) (xy 0.635 0.2286) (xy 0.635 -0.254) (xy 0.5334 -0.254) (xy 0.5334 -0.2794)
				(xy -0.5334 -0.2794) (xy -0.5334 -0.254) (xy -0.635 -0.254) (xy -0.635 0.254) (xy -0.5334 0.254)
				(xy -0.5334 0.2794) (xy 0.508 0.2794) (xy 0.5334 0.2794)
			)
			(stroke
				(width 0)
				(type default)
			)
			(fill no)
			(layer "B.CrtYd")
		)
		(pad "1" smd rect
			(at -0.40005 0 90)
			(size 0.4572 0.508)
			(layers "B.Cu" "B.Mask" "B.Paste")
			(net "UART_T9_NODE3_RXD")
		)
		(pad "2" smd rect
			(at 0.40005 0 90)
			(size 0.4572 0.508)
			(layers "B.Cu" "B.Mask" "B.Paste")
			(net "GND")
		)
	)
	(footprint ""
		(layer "B.Cu")
		(at 116.44376 -185.205624 90)
		(property "Reference" "R881"
			(at 3.957828 0.575056 270)
			(unlocked yes)
			(layer "B.SilkS")
			(effects
				(font
					(size 0.7874 0.5842)
					(thickness 0.1524)
				)
				(justify left mirror)
			)
		)
		(property "Value" ""
			(at 0 0 90)
			(layer "B.Fab")
			(effects
				(font
					(size 1.27 1.27)
				)
				(justify mirror)
			)
		)
		(duplicate_pad_numbers_are_jumpers no)
		(fp_line
			(start 0.7874 -0.4064)
			(end -0.7874 -0.4064)
			(stroke
				(width 0.1524)
				(type default)
			)
			(layer "B.SilkS")
		)
		(fp_line
			(start -0.7874 -0.4064)
			(end -0.7874 0.4064)
			(stroke
				(width 0.1524)
				(type default)
			)
			(layer "B.SilkS")
		)
		(fp_line
			(start 0.7874 0.4064)
			(end 0.7874 -0.4064)
			(stroke
				(width 0.1524)
				(type default)
			)
			(layer "B.SilkS")
		)
		(fp_line
			(start -0.7874 0.4064)
			(end 0.7874 0.4064)
			(stroke
				(width 0.1524)
				(type default)
			)
			(layer "B.SilkS")
		)
		(fp_poly
			(pts
				(xy 0.508 0.2794) (xy 0.508 0.2286) (xy 0.635 0.2286) (xy 0.635 -0.254) (xy 0.5334 -0.254) (xy 0.5334 -0.2794)
				(xy -0.5334 -0.2794) (xy -0.5334 -0.254) (xy -0.635 -0.254) (xy -0.635 0.254) (xy -0.5334 0.254)
				(xy -0.5334 0.2794)
			)
			(stroke
				(width 0)
				(type default)
			)
			(fill no)
			(layer "B.CrtYd")
		)
		(pad "1" smd rect
			(at -0.40005 0 270)
			(size 0.4572 0.508)
			(layers "B.Cu" "B.Mask" "B.Paste")
			(net "T7_NODE4_EN")
		)
		(pad "2" smd rect
			(at 0.40005 0 270)
			(size 0.4572 0.508)
			(layers "B.Cu" "B.Mask" "B.Paste")
			(net "T7_NODE4_EN_R")
		)
	)
	(footprint ""
		(layer "B.Cu")
		(at 16.250666 -134.106158)
		(property "Reference" "PR25"
			(at 3.271012 -1.273556 0)
			(unlocked yes)
			(layer "B.SilkS")
			(effects
				(font
					(size 0.7874 0.5842)
					(thickness 0.1524)
				)
				(justify left mirror)
			)
		)
		(property "Value" ""
			(at 0 0 0)
			(layer "B.Fab")
			(effects
				(font
					(size 1.27 1.27)
				)
				(justify mirror)
			)
		)
		(duplicate_pad_numbers_are_jumpers no)
		(fp_line
			(start -0.7874 -0.4064)
			(end -0.7874 0.4064)
			(stroke
				(width 0.1524)
				(type default)
			)
			(layer "B.SilkS")
		)
		(fp_line
			(start -0.7874 0.4064)
			(end 0.7874 0.4064)
			(stroke
				(width 0.1524)
				(type default)
			)
			(layer "B.SilkS")
		)
		(fp_line
			(start 0.7874 -0.4064)
			(end -0.7874 -0.4064)
			(stroke
				(width 0.1524)
				(type default)
			)
			(layer "B.SilkS")
		)
		(fp_line
			(start 0.7874 0.4064)
			(end 0.7874 -0.4064)
			(stroke
				(width 0.1524)
				(type default)
			)
			(layer "B.SilkS")
		)
		(fp_poly
			(pts
				(xy 0.508 0.2794) (xy 0.508 0.2286) (xy 0.635 0.2286) (xy 0.635 -0.254) (xy 0.5334 -0.254) (xy 0.5334 -0.2794)
				(xy -0.5334 -0.2794) (xy -0.5334 -0.254) (xy -0.635 -0.254) (xy -0.635 0.254) (xy -0.5334 0.254)
				(xy -0.5334 0.2794)
			)
			(stroke
				(width 0)
				(type default)
			)
			(fill no)
			(layer "B.CrtYd")
		)
		(pad "1" smd rect
			(at -0.40005 0 180)
			(size 0.4572 0.508)
			(layers "B.Cu" "B.Mask" "B.Paste")
			(net "P3V3_NODE1")
		)
		(pad "2" smd rect
			(at 0.40005 0 180)
			(size 0.4572 0.508)
			(layers "B.Cu" "B.Mask" "B.Paste")
			(net "P1V05_NODE1_VREFIN")
		)
	)
	(footprint ""
		(layer "B.Cu")
		(at 63.832486 -118.783862 -90)
		(property "Reference" "R320"
			(at 5.06603 0.06731 270)
			(unlocked yes)
			(layer "B.SilkS")
			(effects
				(font
					(size 0.7874 0.5842)
					(thickness 0.1524)
				)
				(justify left mirror)
			)
		)
		(property "Value" ""
			(at 0 0 90)
			(layer "B.Fab")
			(effects
				(font
					(size 1.27 1.27)
				)
				(justify mirror)
			)
		)
		(duplicate_pad_numbers_are_jumpers no)
		(fp_line
			(start -0.7874 0.4064)
			(end 0.7874 0.4064)
			(stroke
				(width 0.1524)
				(type default)
			)
			(layer "B.SilkS")
		)
		(fp_line
			(start 0.7874 0.4064)
			(end 0.7874 -0.4064)
			(stroke
				(width 0.1524)
				(type default)
			)
			(layer "B.SilkS")
		)
		(fp_line
			(start -0.7874 -0.4064)
			(end -0.7874 0.4064)
			(stroke
				(width 0.1524)
				(type default)
			)
			(layer "B.SilkS")
		)
		(fp_line
			(start 0.7874 -0.4064)
			(end -0.7874 -0.4064)
			(stroke
				(width 0.1524)
				(type default)
			)
			(layer "B.SilkS")
		)
		(fp_poly
			(pts
				(xy 0.508 0.2794) (xy 0.508 0.2286) (xy 0.635 0.2286) (xy 0.635 -0.254) (xy 0.5334 -0.254) (xy 0.5334 -0.2794)
				(xy -0.5334 -0.2794) (xy -0.5334 -0.254) (xy -0.635 -0.254) (xy -0.635 0.254) (xy -0.5334 0.254)
				(xy -0.5334 0.2794)
			)
			(stroke
				(width 0)
				(type default)
			)
			(fill no)
			(layer "B.CrtYd")
		)
		(pad "1" smd rect
			(at -0.40005 0 90)
			(size 0.4572 0.508)
			(layers "B.Cu" "B.Mask" "B.Paste")
			(net "P3V3_NODE1")
		)
		(pad "2" smd rect
			(at 0.40005 0 90)
			(size 0.4572 0.508)
			(layers "B.Cu" "B.Mask" "B.Paste")
			(net "BMC_ROMA4")
		)
	)
	(footprint ""
		(layer "B.Cu")
		(at 50.659538 -77.804518 -90)
		(property "Reference" "C51"
			(at 32.2707 15.438628 270)
			(unlocked yes)
			(layer "B.SilkS")
			(effects
				(font
					(size 0.7874 0.5842)
					(thickness 0.1524)
				)
				(justify left mirror)
			)
		)
		(property "Value" ""
			(at 0 0 90)
			(layer "B.Fab")
			(effects
				(font
					(size 1.27 1.27)
				)
				(justify mirror)
			)
		)
		(duplicate_pad_numbers_are_jumpers no)
		(fp_line
			(start -0.7874 0.4064)
			(end 0.7874 0.4064)
			(stroke
				(width 0.1524)
				(type default)
			)
			(layer "B.SilkS")
		)
		(fp_line
			(start 0.7874 0.4064)
			(end 0.7874 -0.4064)
			(stroke
				(width 0.1524)
				(type default)
			)
			(layer "B.SilkS")
		)
		(fp_line
			(start 0 0.381)
			(end 0 -0.381)
			(stroke
				(width 0.1524)
				(type default)
			)
			(layer "B.SilkS")
		)
		(fp_line
			(start -0.7874 -0.4064)
			(end -0.7874 0.4064)
			(stroke
				(width 0.1524)
				(type default)
			)
			(layer "B.SilkS")
		)
		(fp_line
			(start 0.7874 -0.4064)
			(end -0.7874 -0.4064)
			(stroke
				(width 0.1524)
				(type default)
			)
			(layer "B.SilkS")
		)
		(fp_poly
			(pts
				(xy 0.5334 0.254) (xy 0.635 0.254) (xy 0.635 0.2286) (xy 0.635 -0.254) (xy 0.5334 -0.254) (xy 0.5334 -0.2794)
				(xy -0.5334 -0.2794) (xy -0.5334 -0.254) (xy -0.635 -0.254) (xy -0.635 0.254) (xy -0.5334 0.254)
				(xy -0.5334 0.2794) (xy 0.508 0.2794) (xy 0.5334 0.2794)
			)
			(stroke
				(width 0)
				(type default)
			)
			(fill no)
			(layer "B.CrtYd")
		)
		(pad "1" smd rect
			(at -0.40005 0 90)
			(size 0.4572 0.508)
			(layers "B.Cu" "B.Mask" "B.Paste")
			(net "P1V05_NODE1")
		)
		(pad "2" smd rect
			(at 0.40005 0 90)
			(size 0.4572 0.508)
			(layers "B.Cu" "B.Mask" "B.Paste")
			(net "GND")
		)
	)
	(footprint ""
		(layer "B.Cu")
		(at 165.998652 -104.87279 -90)
		(property "Reference" "C369"
			(at -1.398016 -6.444742 270)
			(unlocked yes)
			(layer "B.SilkS")
			(effects
				(font
					(size 0.7874 0.5842)
					(thickness 0.1524)
				)
				(justify left mirror)
			)
		)
		(property "Value" ""
			(at 0 0 90)
			(layer "B.Fab")
			(effects
				(font
					(size 1.27 1.27)
				)
				(justify mirror)
			)
		)
		(duplicate_pad_numbers_are_jumpers no)
		(fp_line
			(start -0.7874 0.4064)
			(end 0.7874 0.4064)
			(stroke
				(width 0.1524)
				(type default)
			)
			(layer "B.SilkS")
		)
		(fp_line
			(start 0.7874 0.4064)
			(end 0.7874 -0.4064)
			(stroke
				(width 0.1524)
				(type default)
			)
			(layer "B.SilkS")
		)
		(fp_line
			(start 0 0.381)
			(end 0 -0.381)
			(stroke
				(width 0.1524)
				(type default)
			)
			(layer "B.SilkS")
		)
		(fp_line
			(start -0.7874 -0.4064)
			(end -0.7874 0.4064)
			(stroke
				(width 0.1524)
				(type default)
			)
			(layer "B.SilkS")
		)
		(fp_line
			(start 0.7874 -0.4064)
			(end -0.7874 -0.4064)
			(stroke
				(width 0.1524)
				(type default)
			)
			(layer "B.SilkS")
		)
		(fp_poly
			(pts
				(xy 0.5334 0.254) (xy 0.635 0.254) (xy 0.635 0.2286) (xy 0.635 -0.254) (xy 0.5334 -0.254) (xy 0.5334 -0.2794)
				(xy -0.5334 -0.2794) (xy -0.5334 -0.254) (xy -0.635 -0.254) (xy -0.635 0.254) (xy -0.5334 0.254)
				(xy -0.5334 0.2794) (xy 0.508 0.2794) (xy 0.5334 0.2794)
			)
			(stroke
				(width 0)
				(type default)
			)
			(fill no)
			(layer "B.CrtYd")
		)
		(pad "1" smd rect
			(at -0.40005 0 90)
			(size 0.4572 0.508)
			(layers "B.Cu" "B.Mask" "B.Paste")
			(net "P1V05_NODE1")
		)
		(pad "2" smd rect
			(at 0.40005 0 90)
			(size 0.4572 0.508)
			(layers "B.Cu" "B.Mask" "B.Paste")
			(net "GND")
		)
	)
	(footprint ""
		(layer "B.Cu")
		(at 120.634252 -168.560242 180)
		(property "Reference" "R1244"
			(at -0.6858 2.08153 0)
			(unlocked yes)
			(layer "B.SilkS")
			(effects
				(font
					(size 0.7874 0.5842)
					(thickness 0.1524)
				)
				(justify left mirror)
			)
		)
		(property "Value" ""
			(at 0 0 0)
			(layer "B.Fab")
			(effects
				(font
					(size 1.27 1.27)
				)
				(justify mirror)
			)
		)
		(duplicate_pad_numbers_are_jumpers no)
		(fp_line
			(start 0.7874 0.4064)
			(end 0.7874 -0.4064)
			(stroke
				(width 0.1524)
				(type default)
			)
			(layer "B.SilkS")
		)
		(fp_line
			(start 0.7874 -0.4064)
			(end -0.7874 -0.4064)
			(stroke
				(width 0.1524)
				(type default)
			)
			(layer "B.SilkS")
		)
		(fp_line
			(start -0.7874 0.4064)
			(end 0.7874 0.4064)
			(stroke
				(width 0.1524)
				(type default)
			)
			(layer "B.SilkS")
		)
		(fp_line
			(start -0.7874 -0.4064)
			(end -0.7874 0.4064)
			(stroke
				(width 0.1524)
				(type default)
			)
			(layer "B.SilkS")
		)
		(fp_poly
			(pts
				(xy 0.508 0.2794) (xy 0.508 0.2286) (xy 0.635 0.2286) (xy 0.635 -0.254) (xy 0.5334 -0.254) (xy 0.5334 -0.2794)
				(xy -0.5334 -0.2794) (xy -0.5334 -0.254) (xy -0.635 -0.254) (xy -0.635 0.254) (xy -0.5334 0.254)
				(xy -0.5334 0.2794)
			)
			(stroke
				(width 0)
				(type default)
			)
			(fill no)
			(layer "B.CrtYd")
		)
		(pad "1" smd rect
			(at -0.40005 0)
			(size 0.4572 0.508)
			(layers "B.Cu" "B.Mask" "B.Paste")
			(net "GND")
		)
		(pad "2" smd rect
			(at 0.40005 0)
			(size 0.4572 0.508)
			(layers "B.Cu" "B.Mask" "B.Paste")
			(net "PSU2_HUB_EN")
		)
	)
	(footprint ""
		(layer "B.Cu")
		(at 33.72104 -104.873806 90)
		(property "Reference" "C820"
			(at 0.041402 -5.707888 270)
			(unlocked yes)
			(layer "B.SilkS")
			(effects
				(font
					(size 0.7874 0.5842)
					(thickness 0.1524)
				)
				(justify left mirror)
			)
		)
		(property "Value" ""
			(at 0 0 90)
			(layer "B.Fab")
			(effects
				(font
					(size 1.27 1.27)
				)
				(justify mirror)
			)
		)
		(duplicate_pad_numbers_are_jumpers no)
		(fp_line
			(start 1.905 -0.8636)
			(end -1.905 -0.8636)
			(stroke
				(width 0.1524)
				(type default)
			)
			(layer "B.SilkS")
		)
		(fp_line
			(start -1.905 -0.8636)
			(end -1.905 0.8636)
			(stroke
				(width 0.1524)
				(type default)
			)
			(layer "B.SilkS")
		)
		(fp_line
			(start 0 0.8382)
			(end 0 -0.8382)
			(stroke
				(width 0.1524)
				(type default)
			)
			(layer "B.SilkS")
		)
		(fp_line
			(start 1.905 0.8636)
			(end 1.905 -0.8636)
			(stroke
				(width 0.1524)
				(type default)
			)
			(layer "B.SilkS")
		)
		(fp_line
			(start -1.905 0.8636)
			(end 1.905 0.8636)
			(stroke
				(width 0.1524)
				(type default)
			)
			(layer "B.SilkS")
		)
		(fp_rect
			(start 1.524 0.7366)
			(end -1.524 -0.7366)
			(stroke
				(width 0)
				(type default)
			)
			(fill no)
			(layer "B.CrtYd")
		)
		(pad "1" smd rect
			(at -0.94996 0 270)
			(size 1.1176 1.3716)
			(layers "B.Cu" "B.Mask" "B.Paste")
			(net "P1V5_SUS_NODE1")
		)
		(pad "2" smd rect
			(at 0.94996 0 270)
			(size 1.1176 1.3716)
			(layers "B.Cu" "B.Mask" "B.Paste")
			(net "GND")
		)
	)
	(footprint ""
		(layer "B.Cu")
		(at 146.78152 -100.391468 -90)
		(property "Reference" ""
			(at 0 0 90)
			(layer "B.SilkS")
			(hide yes)
			(effects
				(font
					(size 1.27 1.27)
				)
				(justify mirror)
			)
		)
		(property "Value" ""
			(at 0 0 90)
			(layer "B.Fab")
			(effects
				(font
					(size 1.27 1.27)
				)
				(justify mirror)
			)
		)
		(duplicate_pad_numbers_are_jumpers no)
		(fp_poly
			(pts
				(arc
					(start 0 -1.4986)
					(mid 0 1.4986)
					(end 0 -1.4986)
				)
			)
			(stroke
				(width 0)
				(type default)
			)
			(fill no)
			(layer "B.CrtYd")
		)
		(pad "1" smd circle
			(at 0 0 90)
			(size 0.9906 0.9906)
			(layers "B.Cu" "B.Mask" "B.Paste")
			(net "Net_32")
		)
		(zone
			(layer "B.Cu")
			(hatch none 0.5)
			(connect_pads
				(clearance 0)
			)
			(min_thickness 0.25)
			(keepout
				(tracks not_allowed)
				(vias allowed)
				(pads allowed)
				(copperpour not_allowed)
				(footprints allowed)
			)
			(placement
				(enabled no)
				(sheetname "")
			)
			(fill
				(thermal_gap 0.5)
				(thermal_bridge_width 0.5)
				(island_removal_mode 0)
			)
			(polygon
				(pts
					(arc
						(start 148.40712 -100.391468)
						(mid 145.15592 -100.391468)
						(end 148.40712 -100.391468)
					)
				)
			)
		)
	)
	(footprint ""
		(layer "B.Cu")
		(at 171.846494 -123.401836 180)
		(property "Reference" "C784"
			(at 1.3335 3.452876 0)
			(unlocked yes)
			(layer "B.SilkS")
			(effects
				(font
					(size 0.7874 0.5842)
					(thickness 0.1524)
				)
				(justify mirror)
			)
		)
		(property "Value" ""
			(at 0 0 0)
			(layer "B.Fab")
			(effects
				(font
					(size 1.27 1.27)
				)
				(justify mirror)
			)
		)
		(duplicate_pad_numbers_are_jumpers no)
		(fp_line
			(start 1.2954 0.5842)
			(end 1.2954 -0.5842)
			(stroke
				(width 0.1524)
				(type default)
			)
			(layer "B.SilkS")
		)
		(fp_line
			(start 1.2954 -0.5842)
			(end -1.2954 -0.5842)
			(stroke
				(width 0.1524)
				(type default)
			)
			(layer "B.SilkS")
		)
		(fp_line
			(start 0 -0.5842)
			(end 0 0.5842)
			(stroke
				(width 0.1524)
				(type default)
			)
			(layer "B.SilkS")
		)
		(fp_line
			(start -1.2954 0.5842)
			(end 1.2954 0.5842)
			(stroke
				(width 0.1524)
				(type default)
			)
			(layer "B.SilkS")
		)
		(fp_line
			(start -1.2954 -0.5842)
			(end -1.2954 0.5842)
			(stroke
				(width 0.1524)
				(type default)
			)
			(layer "B.SilkS")
		)
		(fp_poly
			(pts
				(xy -0.8636 -0.4572) (xy -0.8636 -0.3556) (xy -1.143 -0.3556) (xy -1.143 0.3556) (xy -0.8636 0.3556)
				(xy -0.8636 0.4572) (xy 0.8636 0.4572) (xy 0.8636 0.3556) (xy 1.143 0.3556) (xy 1.143 -0.3556) (xy 0.8636 -0.3556)
				(xy 0.8636 -0.4572)
			)
			(stroke
				(width 0)
				(type default)
			)
			(fill no)
			(layer "B.CrtYd")
		)
		(fp_line
			(start 0.884936 0.504952)
			(end 0.884936 -0.504952)
			(stroke
				(width 0.1)
				(type default)
			)
			(layer "B.Fab")
		)
		(fp_line
			(start 0.884936 -0.504952)
			(end -0.884936 -0.504952)
			(stroke
				(width 0.1)
				(type default)
			)
			(layer "B.Fab")
		)
		(fp_line
			(start -0.884936 0.504952)
			(end 0.884936 0.504952)
			(stroke
				(width 0.1)
				(type default)
			)
			(layer "B.Fab")
		)
		(fp_line
			(start -0.884936 -0.504952)
			(end -0.884936 0.504952)
			(stroke
				(width 0.1)
				(type default)
			)
			(layer "B.Fab")
		)
		(pad "1" smd rect
			(at -0.7366 0 270)
			(size 0.7112 0.8128)
			(layers "B.Cu" "B.Mask" "B.Paste")
			(net "P3V3_STB_NODE1")
		)
		(pad "2" smd rect
			(at 0.7366 0 270)
			(size 0.7112 0.8128)
			(layers "B.Cu" "B.Mask" "B.Paste")
			(net "GND")
		)
	)
	(footprint ""
		(layer "B.Cu")
		(at 104.408224 -68.244466 180)
		(property "Reference" "R227"
			(at 4.704842 -0.713232 0)
			(unlocked yes)
			(layer "B.SilkS")
			(effects
				(font
					(size 0.7874 0.5842)
					(thickness 0.1524)
				)
				(justify left mirror)
			)
		)
		(property "Value" ""
			(at 0 0 0)
			(layer "B.Fab")
			(effects
				(font
					(size 1.27 1.27)
				)
				(justify mirror)
			)
		)
		(duplicate_pad_numbers_are_jumpers no)
		(fp_line
			(start 0.7874 0.4064)
			(end 0.7874 -0.4064)
			(stroke
				(width 0.1524)
				(type default)
			)
			(layer "B.SilkS")
		)
		(fp_line
			(start 0.7874 -0.4064)
			(end -0.7874 -0.4064)
			(stroke
				(width 0.1524)
				(type default)
			)
			(layer "B.SilkS")
		)
		(fp_line
			(start -0.7874 0.4064)
			(end 0.7874 0.4064)
			(stroke
				(width 0.1524)
				(type default)
			)
			(layer "B.SilkS")
		)
		(fp_line
			(start -0.7874 -0.4064)
			(end -0.7874 0.4064)
			(stroke
				(width 0.1524)
				(type default)
			)
			(layer "B.SilkS")
		)
		(fp_poly
			(pts
				(xy 0.508 0.2794) (xy 0.508 0.2286) (xy 0.635 0.2286) (xy 0.635 -0.254) (xy 0.5334 -0.254) (xy 0.5334 -0.2794)
				(xy -0.5334 -0.2794) (xy -0.5334 -0.254) (xy -0.635 -0.254) (xy -0.635 0.254) (xy -0.5334 0.254)
				(xy -0.5334 0.2794)
			)
			(stroke
				(width 0)
				(type default)
			)
			(fill no)
			(layer "B.CrtYd")
		)
		(pad "1" smd rect
			(at -0.40005 0)
			(size 0.4572 0.508)
			(layers "B.Cu" "B.Mask" "B.Paste")
			(net "XDP_CPU_NODE1_PWROK_STALL_L")
		)
		(pad "2" smd rect
			(at 0.40005 0)
			(size 0.4572 0.508)
			(layers "B.Cu" "B.Mask" "B.Paste")
			(net "GND")
		)
	)
	(footprint ""
		(layer "B.Cu")
		(at 68.81876 -188.126624 90)
		(property "Reference" "R926"
			(at 4.318254 -0.325882 270)
			(unlocked yes)
			(layer "B.SilkS")
			(effects
				(font
					(size 0.7874 0.5842)
					(thickness 0.1524)
				)
				(justify left mirror)
			)
		)
		(property "Value" ""
			(at 0 0 90)
			(layer "B.Fab")
			(effects
				(font
					(size 1.27 1.27)
				)
				(justify mirror)
			)
		)
		(duplicate_pad_numbers_are_jumpers no)
		(fp_line
			(start 0.7874 -0.4064)
			(end -0.7874 -0.4064)
			(stroke
				(width 0.1524)
				(type default)
			)
			(layer "B.SilkS")
		)
		(fp_line
			(start -0.7874 -0.4064)
			(end -0.7874 0.4064)
			(stroke
				(width 0.1524)
				(type default)
			)
			(layer "B.SilkS")
		)
		(fp_line
			(start 0.7874 0.4064)
			(end 0.7874 -0.4064)
			(stroke
				(width 0.1524)
				(type default)
			)
			(layer "B.SilkS")
		)
		(fp_line
			(start -0.7874 0.4064)
			(end 0.7874 0.4064)
			(stroke
				(width 0.1524)
				(type default)
			)
			(layer "B.SilkS")
		)
		(fp_poly
			(pts
				(xy 0.508 0.2794) (xy 0.508 0.2286) (xy 0.635 0.2286) (xy 0.635 -0.254) (xy 0.5334 -0.254) (xy 0.5334 -0.2794)
				(xy -0.5334 -0.2794) (xy -0.5334 -0.254) (xy -0.635 -0.254) (xy -0.635 0.254) (xy -0.5334 0.254)
				(xy -0.5334 0.2794)
			)
			(stroke
				(width 0)
				(type default)
			)
			(fill no)
			(layer "B.CrtYd")
		)
		(pad "1" smd rect
			(at -0.40005 0 270)
			(size 0.4572 0.508)
			(layers "B.Cu" "B.Mask" "B.Paste")
			(net "UART_T3_NODE4_RXD")
		)
		(pad "2" smd rect
			(at 0.40005 0 270)
			(size 0.4572 0.508)
			(layers "B.Cu" "B.Mask" "B.Paste")
			(net "UART_T3_NODE4_RXD_R")
		)
	)
	(footprint ""
		(layer "B.Cu")
		(at 165.87978 -158.608522)
		(property "Reference" "C443"
			(at 3.599942 -1.091946 0)
			(unlocked yes)
			(layer "B.SilkS")
			(effects
				(font
					(size 0.7874 0.5842)
					(thickness 0.1524)
				)
				(justify left mirror)
			)
		)
		(property "Value" ""
			(at 0 0 0)
			(layer "B.Fab")
			(effects
				(font
					(size 1.27 1.27)
				)
				(justify mirror)
			)
		)
		(duplicate_pad_numbers_are_jumpers no)
		(fp_line
			(start -0.7874 -0.4064)
			(end -0.7874 0.4064)
			(stroke
				(width 0.1524)
				(type default)
			)
			(layer "B.SilkS")
		)
		(fp_line
			(start -0.7874 0.4064)
			(end 0.7874 0.4064)
			(stroke
				(width 0.1524)
				(type default)
			)
			(layer "B.SilkS")
		)
		(fp_line
			(start 0 0.381)
			(end 0 -0.381)
			(stroke
				(width 0.1524)
				(type default)
			)
			(layer "B.SilkS")
		)
		(fp_line
			(start 0.7874 -0.4064)
			(end -0.7874 -0.4064)
			(stroke
				(width 0.1524)
				(type default)
			)
			(layer "B.SilkS")
		)
		(fp_line
			(start 0.7874 0.4064)
			(end 0.7874 -0.4064)
			(stroke
				(width 0.1524)
				(type default)
			)
			(layer "B.SilkS")
		)
		(fp_poly
			(pts
				(xy 0.5334 0.254) (xy 0.635 0.254) (xy 0.635 0.2286) (xy 0.635 -0.254) (xy 0.5334 -0.254) (xy 0.5334 -0.2794)
				(xy -0.5334 -0.2794) (xy -0.5334 -0.254) (xy -0.635 -0.254) (xy -0.635 0.254) (xy -0.5334 0.254)
				(xy -0.5334 0.2794) (xy 0.508 0.2794) (xy 0.5334 0.2794)
			)
			(stroke
				(width 0)
				(type default)
			)
			(fill no)
			(layer "B.CrtYd")
		)
		(pad "1" smd rect
			(at -0.40005 0 180)
			(size 0.4572 0.508)
			(layers "B.Cu" "B.Mask" "B.Paste")
			(net "P3V3_NODE1")
		)
		(pad "2" smd rect
			(at 0.40005 0 180)
			(size 0.4572 0.508)
			(layers "B.Cu" "B.Mask" "B.Paste")
			(net "GND")
		)
	)
	(footprint ""
		(layer "B.Cu")
		(at 151.572214 -62.075822 -90)
		(property "Reference" "C358"
			(at 2.829814 -6.163564 270)
			(unlocked yes)
			(layer "B.SilkS")
			(effects
				(font
					(size 0.7874 0.5842)
					(thickness 0.1524)
				)
				(justify left mirror)
			)
		)
		(property "Value" ""
			(at 0 0 90)
			(layer "B.Fab")
			(effects
				(font
					(size 1.27 1.27)
				)
				(justify mirror)
			)
		)
		(duplicate_pad_numbers_are_jumpers no)
		(fp_line
			(start -0.7874 0.4064)
			(end 0.7874 0.4064)
			(stroke
				(width 0.1524)
				(type default)
			)
			(layer "B.SilkS")
		)
		(fp_line
			(start 0.7874 0.4064)
			(end 0.7874 -0.4064)
			(stroke
				(width 0.1524)
				(type default)
			)
			(layer "B.SilkS")
		)
		(fp_line
			(start 0 0.381)
			(end 0 -0.381)
			(stroke
				(width 0.1524)
				(type default)
			)
			(layer "B.SilkS")
		)
		(fp_line
			(start -0.7874 -0.4064)
			(end -0.7874 0.4064)
			(stroke
				(width 0.1524)
				(type default)
			)
			(layer "B.SilkS")
		)
		(fp_line
			(start 0.7874 -0.4064)
			(end -0.7874 -0.4064)
			(stroke
				(width 0.1524)
				(type default)
			)
			(layer "B.SilkS")
		)
		(fp_poly
			(pts
				(xy 0.5334 0.254) (xy 0.635 0.254) (xy 0.635 0.2286) (xy 0.635 -0.254) (xy 0.5334 -0.254) (xy 0.5334 -0.2794)
				(xy -0.5334 -0.2794) (xy -0.5334 -0.254) (xy -0.635 -0.254) (xy -0.635 0.254) (xy -0.5334 0.254)
				(xy -0.5334 0.2794) (xy 0.508 0.2794) (xy 0.5334 0.2794)
			)
			(stroke
				(width 0)
				(type default)
			)
			(fill no)
			(layer "B.CrtYd")
		)
		(pad "1" smd rect
			(at -0.40005 0 90)
			(size 0.4572 0.508)
			(layers "B.Cu" "B.Mask" "B.Paste")
			(net "P1V8_SATA_VAA2_1_NODE1")
		)
		(pad "2" smd rect
			(at 0.40005 0 90)
			(size 0.4572 0.508)
			(layers "B.Cu" "B.Mask" "B.Paste")
			(net "GND")
		)
	)
	(footprint ""
		(layer "B.Cu")
		(at 65.38976 -188.126624 -90)
		(property "Reference" "C625"
			(at -4.318254 0.435864 270)
			(unlocked yes)
			(layer "B.SilkS")
			(effects
				(font
					(size 0.7874 0.5842)
					(thickness 0.1524)
				)
				(justify left mirror)
			)
		)
		(property "Value" ""
			(at 0 0 90)
			(layer "B.Fab")
			(effects
				(font
					(size 1.27 1.27)
				)
				(justify mirror)
			)
		)
		(duplicate_pad_numbers_are_jumpers no)
		(fp_line
			(start -0.7874 0.4064)
			(end 0.7874 0.4064)
			(stroke
				(width 0.1524)
				(type default)
			)
			(layer "B.SilkS")
		)
		(fp_line
			(start 0.7874 0.4064)
			(end 0.7874 -0.4064)
			(stroke
				(width 0.1524)
				(type default)
			)
			(layer "B.SilkS")
		)
		(fp_line
			(start 0 0.381)
			(end 0 -0.381)
			(stroke
				(width 0.1524)
				(type default)
			)
			(layer "B.SilkS")
		)
		(fp_line
			(start -0.7874 -0.4064)
			(end -0.7874 0.4064)
			(stroke
				(width 0.1524)
				(type default)
			)
			(layer "B.SilkS")
		)
		(fp_line
			(start 0.7874 -0.4064)
			(end -0.7874 -0.4064)
			(stroke
				(width 0.1524)
				(type default)
			)
			(layer "B.SilkS")
		)
		(fp_poly
			(pts
				(xy 0.5334 0.254) (xy 0.635 0.254) (xy 0.635 0.2286) (xy 0.635 -0.254) (xy 0.5334 -0.254) (xy 0.5334 -0.2794)
				(xy -0.5334 -0.2794) (xy -0.5334 -0.254) (xy -0.635 -0.254) (xy -0.635 0.254) (xy -0.5334 0.254)
				(xy -0.5334 0.2794) (xy 0.508 0.2794) (xy 0.5334 0.2794)
			)
			(stroke
				(width 0)
				(type default)
			)
			(fill no)
			(layer "B.CrtYd")
		)
		(pad "1" smd rect
			(at -0.40005 0 90)
			(size 0.4572 0.508)
			(layers "B.Cu" "B.Mask" "B.Paste")
			(net "T1_NODE2_EN_R")
		)
		(pad "2" smd rect
			(at 0.40005 0 90)
			(size 0.4572 0.508)
			(layers "B.Cu" "B.Mask" "B.Paste")
			(net "GND")
		)
	)
	(footprint ""
		(layer "B.Cu")
		(at 114.092482 -164.891466 -90)
		(property "Reference" "R774"
			(at 3.178048 2.394458 270)
			(unlocked yes)
			(layer "B.SilkS")
			(effects
				(font
					(size 0.7874 0.5842)
					(thickness 0.1524)
				)
				(justify left mirror)
			)
		)
		(property "Value" ""
			(at 0 0 90)
			(layer "B.Fab")
			(effects
				(font
					(size 1.27 1.27)
				)
				(justify mirror)
			)
		)
		(duplicate_pad_numbers_are_jumpers no)
		(fp_line
			(start -0.7874 0.4064)
			(end 0.7874 0.4064)
			(stroke
				(width 0.1524)
				(type default)
			)
			(layer "B.SilkS")
		)
		(fp_line
			(start 0.7874 0.4064)
			(end 0.7874 -0.4064)
			(stroke
				(width 0.1524)
				(type default)
			)
			(layer "B.SilkS")
		)
		(fp_line
			(start -0.7874 -0.4064)
			(end -0.7874 0.4064)
			(stroke
				(width 0.1524)
				(type default)
			)
			(layer "B.SilkS")
		)
		(fp_line
			(start 0.7874 -0.4064)
			(end -0.7874 -0.4064)
			(stroke
				(width 0.1524)
				(type default)
			)
			(layer "B.SilkS")
		)
		(fp_poly
			(pts
				(xy 0.508 0.2794) (xy 0.508 0.2286) (xy 0.635 0.2286) (xy 0.635 -0.254) (xy 0.5334 -0.254) (xy 0.5334 -0.2794)
				(xy -0.5334 -0.2794) (xy -0.5334 -0.254) (xy -0.635 -0.254) (xy -0.635 0.254) (xy -0.5334 0.254)
				(xy -0.5334 0.2794)
			)
			(stroke
				(width 0)
				(type default)
			)
			(fill no)
			(layer "B.CrtYd")
		)
		(pad "1" smd rect
			(at -0.40005 0 90)
			(size 0.4572 0.508)
			(layers "B.Cu" "B.Mask" "B.Paste")
			(net "I2C_SDA_FANCTRL2_R")
		)
		(pad "2" smd rect
			(at 0.40005 0 90)
			(size 0.4572 0.508)
			(layers "B.Cu" "B.Mask" "B.Paste")
			(net "I2C_COM3_SDA")
		)
	)
	(footprint ""
		(layer "B.Cu")
		(at 45.712634 -133.130798)
		(property "Reference" "R260"
			(at 4.766818 0.385826 0)
			(unlocked yes)
			(layer "B.SilkS")
			(effects
				(font
					(size 0.7874 0.5842)
					(thickness 0.1524)
				)
				(justify left mirror)
			)
		)
		(property "Value" ""
			(at 0 0 0)
			(layer "B.Fab")
			(effects
				(font
					(size 1.27 1.27)
				)
				(justify mirror)
			)
		)
		(duplicate_pad_numbers_are_jumpers no)
		(fp_line
			(start -0.7874 -0.4064)
			(end -0.7874 0.4064)
			(stroke
				(width 0.1524)
				(type default)
			)
			(layer "B.SilkS")
		)
		(fp_line
			(start -0.7874 0.4064)
			(end 0.7874 0.4064)
			(stroke
				(width 0.1524)
				(type default)
			)
			(layer "B.SilkS")
		)
		(fp_line
			(start 0.7874 -0.4064)
			(end -0.7874 -0.4064)
			(stroke
				(width 0.1524)
				(type default)
			)
			(layer "B.SilkS")
		)
		(fp_line
			(start 0.7874 0.4064)
			(end 0.7874 -0.4064)
			(stroke
				(width 0.1524)
				(type default)
			)
			(layer "B.SilkS")
		)
		(fp_poly
			(pts
				(xy 0.508 0.2794) (xy 0.508 0.2286) (xy 0.635 0.2286) (xy 0.635 -0.254) (xy 0.5334 -0.254) (xy 0.5334 -0.2794)
				(xy -0.5334 -0.2794) (xy -0.5334 -0.254) (xy -0.635 -0.254) (xy -0.635 0.254) (xy -0.5334 0.254)
				(xy -0.5334 0.2794)
			)
			(stroke
				(width 0)
				(type default)
			)
			(fill no)
			(layer "B.CrtYd")
		)
		(pad "1" smd rect
			(at -0.40005 0 180)
			(size 0.4572 0.508)
			(layers "B.Cu" "B.Mask" "B.Paste")
			(net "BMC_NODE1_DDR3_ZQ")
		)
		(pad "2" smd rect
			(at 0.40005 0 180)
			(size 0.4572 0.508)
			(layers "B.Cu" "B.Mask" "B.Paste")
			(net "GND")
		)
	)
	(footprint ""
		(layer "B.Cu")
		(at 154.594814 -67.232022 90)
		(property "Reference" "C359"
			(at 0.02159 5.137912 270)
			(unlocked yes)
			(layer "B.SilkS")
			(effects
				(font
					(size 0.7874 0.5842)
					(thickness 0.1524)
				)
				(justify left mirror)
			)
		)
		(property "Value" ""
			(at 0 0 90)
			(layer "B.Fab")
			(effects
				(font
					(size 1.27 1.27)
				)
				(justify mirror)
			)
		)
		(duplicate_pad_numbers_are_jumpers no)
		(fp_line
			(start 0.7874 -0.4064)
			(end -0.7874 -0.4064)
			(stroke
				(width 0.1524)
				(type default)
			)
			(layer "B.SilkS")
		)
		(fp_line
			(start -0.7874 -0.4064)
			(end -0.7874 0.4064)
			(stroke
				(width 0.1524)
				(type default)
			)
			(layer "B.SilkS")
		)
		(fp_line
			(start 0 0.381)
			(end 0 -0.381)
			(stroke
				(width 0.1524)
				(type default)
			)
			(layer "B.SilkS")
		)
		(fp_line
			(start 0.7874 0.4064)
			(end 0.7874 -0.4064)
			(stroke
				(width 0.1524)
				(type default)
			)
			(layer "B.SilkS")
		)
		(fp_line
			(start -0.7874 0.4064)
			(end 0.7874 0.4064)
			(stroke
				(width 0.1524)
				(type default)
			)
			(layer "B.SilkS")
		)
		(fp_poly
			(pts
				(xy 0.5334 0.254) (xy 0.635 0.254) (xy 0.635 0.2286) (xy 0.635 -0.254) (xy 0.5334 -0.254) (xy 0.5334 -0.2794)
				(xy -0.5334 -0.2794) (xy -0.5334 -0.254) (xy -0.635 -0.254) (xy -0.635 0.254) (xy -0.5334 0.254)
				(xy -0.5334 0.2794) (xy 0.508 0.2794) (xy 0.5334 0.2794)
			)
			(stroke
				(width 0)
				(type default)
			)
			(fill no)
			(layer "B.CrtYd")
		)
		(pad "1" smd rect
			(at -0.40005 0 270)
			(size 0.4572 0.508)
			(layers "B.Cu" "B.Mask" "B.Paste")
			(net "P1V8_SATA_VAA1_NODE1")
		)
		(pad "2" smd rect
			(at 0.40005 0 270)
			(size 0.4572 0.508)
			(layers "B.Cu" "B.Mask" "B.Paste")
			(net "GND")
		)
	)
	(footprint ""
		(layer "B.Cu")
		(at 106.588052 -173.118526 180)
		(property "Reference" "C571"
			(at -1.49987 -1.106424 0)
			(unlocked yes)
			(layer "B.SilkS")
			(effects
				(font
					(size 0.7874 0.5842)
					(thickness 0.1524)
				)
				(justify left mirror)
			)
		)
		(property "Value" ""
			(at 0 0 0)
			(layer "B.Fab")
			(effects
				(font
					(size 1.27 1.27)
				)
				(justify mirror)
			)
		)
		(duplicate_pad_numbers_are_jumpers no)
		(fp_line
			(start 0.7874 0.4064)
			(end 0.7874 -0.4064)
			(stroke
				(width 0.1524)
				(type default)
			)
			(layer "B.SilkS")
		)
		(fp_line
			(start 0.7874 -0.4064)
			(end -0.7874 -0.4064)
			(stroke
				(width 0.1524)
				(type default)
			)
			(layer "B.SilkS")
		)
		(fp_line
			(start 0 0.381)
			(end 0 -0.381)
			(stroke
				(width 0.1524)
				(type default)
			)
			(layer "B.SilkS")
		)
		(fp_line
			(start -0.7874 0.4064)
			(end 0.7874 0.4064)
			(stroke
				(width 0.1524)
				(type default)
			)
			(layer "B.SilkS")
		)
		(fp_line
			(start -0.7874 -0.4064)
			(end -0.7874 0.4064)
			(stroke
				(width 0.1524)
				(type default)
			)
			(layer "B.SilkS")
		)
		(fp_poly
			(pts
				(xy 0.5334 0.254) (xy 0.635 0.254) (xy 0.635 0.2286) (xy 0.635 -0.254) (xy 0.5334 -0.254) (xy 0.5334 -0.2794)
				(xy -0.5334 -0.2794) (xy -0.5334 -0.254) (xy -0.635 -0.254) (xy -0.635 0.254) (xy -0.5334 0.254)
				(xy -0.5334 0.2794) (xy 0.508 0.2794) (xy 0.5334 0.2794)
			)
			(stroke
				(width 0)
				(type default)
			)
			(fill no)
			(layer "B.CrtYd")
		)
		(pad "1" smd rect
			(at -0.40005 0)
			(size 0.4572 0.508)
			(layers "B.Cu" "B.Mask" "B.Paste")
			(net "GND")
		)
		(pad "2" smd rect
			(at 0.40005 0)
			(size 0.4572 0.508)
			(layers "B.Cu" "B.Mask" "B.Paste")
			(net "P3V3_NODE1")
		)
	)
	(footprint ""
		(layer "B.Cu")
		(at 140.760196 -61.82233)
		(property "Reference" "C353"
			(at -4.939792 0.007874 0)
			(unlocked yes)
			(layer "B.SilkS")
			(effects
				(font
					(size 0.7874 0.5842)
					(thickness 0.1524)
				)
				(justify left mirror)
			)
		)
		(property "Value" ""
			(at 0 0 0)
			(layer "B.Fab")
			(effects
				(font
					(size 1.27 1.27)
				)
				(justify mirror)
			)
		)
		(duplicate_pad_numbers_are_jumpers no)
		(fp_line
			(start -0.7874 -0.4064)
			(end -0.7874 0.4064)
			(stroke
				(width 0.1524)
				(type default)
			)
			(layer "B.SilkS")
		)
		(fp_line
			(start -0.7874 0.4064)
			(end 0.7874 0.4064)
			(stroke
				(width 0.1524)
				(type default)
			)
			(layer "B.SilkS")
		)
		(fp_line
			(start 0 0.381)
			(end 0 -0.381)
			(stroke
				(width 0.1524)
				(type default)
			)
			(layer "B.SilkS")
		)
		(fp_line
			(start 0.7874 -0.4064)
			(end -0.7874 -0.4064)
			(stroke
				(width 0.1524)
				(type default)
			)
			(layer "B.SilkS")
		)
		(fp_line
			(start 0.7874 0.4064)
			(end 0.7874 -0.4064)
			(stroke
				(width 0.1524)
				(type default)
			)
			(layer "B.SilkS")
		)
		(fp_poly
			(pts
				(xy 0.5334 0.254) (xy 0.635 0.254) (xy 0.635 0.2286) (xy 0.635 -0.254) (xy 0.5334 -0.254) (xy 0.5334 -0.2794)
				(xy -0.5334 -0.2794) (xy -0.5334 -0.254) (xy -0.635 -0.254) (xy -0.635 0.254) (xy -0.5334 0.254)
				(xy -0.5334 0.2794) (xy 0.508 0.2794) (xy 0.5334 0.2794)
			)
			(stroke
				(width 0)
				(type default)
			)
			(fill no)
			(layer "B.CrtYd")
		)
		(pad "1" smd rect
			(at -0.40005 0 180)
			(size 0.4572 0.508)
			(layers "B.Cu" "B.Mask" "B.Paste")
			(net "P3V3_NODE1")
		)
		(pad "2" smd rect
			(at 0.40005 0 180)
			(size 0.4572 0.508)
			(layers "B.Cu" "B.Mask" "B.Paste")
			(net "GND")
		)
	)
	(footprint ""
		(layer "B.Cu")
		(at 57.158636 -138.163046 90)
		(property "Reference" "C271"
			(at 1.7653 -1.199134 270)
			(unlocked yes)
			(layer "B.SilkS")
			(effects
				(font
					(size 0.7874 0.5842)
					(thickness 0.1524)
				)
				(justify mirror)
			)
		)
		(property "Value" ""
			(at 0 0 90)
			(layer "B.Fab")
			(effects
				(font
					(size 1.27 1.27)
				)
				(justify mirror)
			)
		)
		(duplicate_pad_numbers_are_jumpers no)
		(fp_line
			(start 1.2954 -0.5842)
			(end -1.2954 -0.5842)
			(stroke
				(width 0.1524)
				(type default)
			)
			(layer "B.SilkS")
		)
		(fp_line
			(start 0 -0.5842)
			(end 0 0.5842)
			(stroke
				(width 0.1524)
				(type default)
			)
			(layer "B.SilkS")
		)
		(fp_line
			(start -1.2954 -0.5842)
			(end -1.2954 0.5842)
			(stroke
				(width 0.1524)
				(type default)
			)
			(layer "B.SilkS")
		)
		(fp_line
			(start 1.2954 0.5842)
			(end 1.2954 -0.5842)
			(stroke
				(width 0.1524)
				(type default)
			)
			(layer "B.SilkS")
		)
		(fp_line
			(start -1.2954 0.5842)
			(end 1.2954 0.5842)
			(stroke
				(width 0.1524)
				(type default)
			)
			(layer "B.SilkS")
		)
		(fp_poly
			(pts
				(xy -0.8636 -0.4572) (xy -0.8636 -0.3556) (xy -1.143 -0.3556) (xy -1.143 0.3556) (xy -0.8636 0.3556)
				(xy -0.8636 0.4572) (xy 0.8636 0.4572) (xy 0.8636 0.3556) (xy 1.143 0.3556) (xy 1.143 -0.3556) (xy 0.8636 -0.3556)
				(xy 0.8636 -0.4572)
			)
			(stroke
				(width 0)
				(type default)
			)
			(fill no)
			(layer "B.CrtYd")
		)
		(fp_line
			(start 0.884936 -0.504952)
			(end -0.884936 -0.504952)
			(stroke
				(width 0.1)
				(type default)
			)
			(layer "B.Fab")
		)
		(fp_line
			(start -0.884936 -0.504952)
			(end -0.884936 0.504952)
			(stroke
				(width 0.1)
				(type default)
			)
			(layer "B.Fab")
		)
		(fp_line
			(start 0.884936 0.504952)
			(end 0.884936 -0.504952)
			(stroke
				(width 0.1)
				(type default)
			)
			(layer "B.Fab")
		)
		(fp_line
			(start -0.884936 0.504952)
			(end 0.884936 0.504952)
			(stroke
				(width 0.1)
				(type default)
			)
			(layer "B.Fab")
		)
		(pad "1" smd rect
			(at -0.7366 0 180)
			(size 0.7112 0.8128)
			(layers "B.Cu" "B.Mask" "B.Paste")
			(net "P1V538_BMC_NODE1")
		)
		(pad "2" smd rect
			(at 0.7366 0 180)
			(size 0.7112 0.8128)
			(layers "B.Cu" "B.Mask" "B.Paste")
			(net "GND")
		)
	)
	(footprint ""
		(layer "B.Cu")
		(at 66.076322 -69.607684 90)
		(property "Reference" "C115"
			(at -34.680398 -13.222732 270)
			(unlocked yes)
			(layer "B.SilkS")
			(effects
				(font
					(size 0.7874 0.5842)
					(thickness 0.1524)
				)
				(justify left mirror)
			)
		)
		(property "Value" ""
			(at 0 0 90)
			(layer "B.Fab")
			(effects
				(font
					(size 1.27 1.27)
				)
				(justify mirror)
			)
		)
		(duplicate_pad_numbers_are_jumpers no)
		(fp_line
			(start 0.7874 -0.4064)
			(end -0.7874 -0.4064)
			(stroke
				(width 0.1524)
				(type default)
			)
			(layer "B.SilkS")
		)
		(fp_line
			(start -0.7874 -0.4064)
			(end -0.7874 0.4064)
			(stroke
				(width 0.1524)
				(type default)
			)
			(layer "B.SilkS")
		)
		(fp_line
			(start 0 0.381)
			(end 0 -0.381)
			(stroke
				(width 0.1524)
				(type default)
			)
			(layer "B.SilkS")
		)
		(fp_line
			(start 0.7874 0.4064)
			(end 0.7874 -0.4064)
			(stroke
				(width 0.1524)
				(type default)
			)
			(layer "B.SilkS")
		)
		(fp_line
			(start -0.7874 0.4064)
			(end 0.7874 0.4064)
			(stroke
				(width 0.1524)
				(type default)
			)
			(layer "B.SilkS")
		)
		(fp_poly
			(pts
				(xy 0.5334 0.254) (xy 0.635 0.254) (xy 0.635 0.2286) (xy 0.635 -0.254) (xy 0.5334 -0.254) (xy 0.5334 -0.2794)
				(xy -0.5334 -0.2794) (xy -0.5334 -0.254) (xy -0.635 -0.254) (xy -0.635 0.254) (xy -0.5334 0.254)
				(xy -0.5334 0.2794) (xy 0.508 0.2794) (xy 0.5334 0.2794)
			)
			(stroke
				(width 0)
				(type default)
			)
			(fill no)
			(layer "B.CrtYd")
		)
		(pad "1" smd rect
			(at -0.40005 0 270)
			(size 0.4572 0.508)
			(layers "B.Cu" "B.Mask" "B.Paste")
			(net "PV_VDDR_NODE1")
		)
		(pad "2" smd rect
			(at 0.40005 0 270)
			(size 0.4572 0.508)
			(layers "B.Cu" "B.Mask" "B.Paste")
			(net "GND")
		)
	)
	(footprint ""
		(layer "B.Cu")
		(at 134.22376 -184.951624 90)
		(property "Reference" "R959"
			(at 4.357624 -1.658874 270)
			(unlocked yes)
			(layer "B.SilkS")
			(effects
				(font
					(size 0.7874 0.5842)
					(thickness 0.1524)
				)
				(justify left mirror)
			)
		)
		(property "Value" ""
			(at 0 0 90)
			(layer "B.Fab")
			(effects
				(font
					(size 1.27 1.27)
				)
				(justify mirror)
			)
		)
		(duplicate_pad_numbers_are_jumpers no)
		(fp_line
			(start 0.7874 -0.4064)
			(end -0.7874 -0.4064)
			(stroke
				(width 0.1524)
				(type default)
			)
			(layer "B.SilkS")
		)
		(fp_line
			(start -0.7874 -0.4064)
			(end -0.7874 0.4064)
			(stroke
				(width 0.1524)
				(type default)
			)
			(layer "B.SilkS")
		)
		(fp_line
			(start 0.7874 0.4064)
			(end 0.7874 -0.4064)
			(stroke
				(width 0.1524)
				(type default)
			)
			(layer "B.SilkS")
		)
		(fp_line
			(start -0.7874 0.4064)
			(end 0.7874 0.4064)
			(stroke
				(width 0.1524)
				(type default)
			)
			(layer "B.SilkS")
		)
		(fp_poly
			(pts
				(xy 0.508 0.2794) (xy 0.508 0.2286) (xy 0.635 0.2286) (xy 0.635 -0.254) (xy 0.5334 -0.254) (xy 0.5334 -0.2794)
				(xy -0.5334 -0.2794) (xy -0.5334 -0.254) (xy -0.635 -0.254) (xy -0.635 0.254) (xy -0.5334 0.254)
				(xy -0.5334 0.2794)
			)
			(stroke
				(width 0)
				(type default)
			)
			(fill no)
			(layer "B.CrtYd")
		)
		(pad "1" smd rect
			(at -0.40005 0 270)
			(size 0.4572 0.508)
			(layers "B.Cu" "B.Mask" "B.Paste")
			(net "UART_T9_NODE1_TXD")
		)
		(pad "2" smd rect
			(at 0.40005 0 270)
			(size 0.4572 0.508)
			(layers "B.Cu" "B.Mask" "B.Paste")
			(net "UART_T9_NODE1_TXD_R")
		)
	)
	(footprint ""
		(layer "B.Cu")
		(at 23.847298 -113.015522)
		(property "Reference" "C54"
			(at -2.11963 -0.579374 0)
			(unlocked yes)
			(layer "B.SilkS")
			(effects
				(font
					(size 0.7874 0.5842)
					(thickness 0.1524)
				)
				(justify left mirror)
			)
		)
		(property "Value" ""
			(at 0 0 0)
			(layer "B.Fab")
			(effects
				(font
					(size 1.27 1.27)
				)
				(justify mirror)
			)
		)
		(duplicate_pad_numbers_are_jumpers no)
		(fp_line
			(start -1.905 -0.8636)
			(end -1.905 0.8636)
			(stroke
				(width 0.1524)
				(type default)
			)
			(layer "B.SilkS")
		)
		(fp_line
			(start -1.905 0.8636)
			(end 1.905 0.8636)
			(stroke
				(width 0.1524)
				(type default)
			)
			(layer "B.SilkS")
		)
		(fp_line
			(start 0 0.8382)
			(end 0 -0.8382)
			(stroke
				(width 0.1524)
				(type default)
			)
			(layer "B.SilkS")
		)
		(fp_line
			(start 1.905 -0.8636)
			(end -1.905 -0.8636)
			(stroke
				(width 0.1524)
				(type default)
			)
			(layer "B.SilkS")
		)
		(fp_line
			(start 1.905 0.8636)
			(end 1.905 -0.8636)
			(stroke
				(width 0.1524)
				(type default)
			)
			(layer "B.SilkS")
		)
		(fp_rect
			(start 1.524 0.7366)
			(end -1.524 -0.7366)
			(stroke
				(width 0)
				(type default)
			)
			(fill no)
			(layer "B.CrtYd")
		)
		(pad "1" smd rect
			(at -0.94996 0 180)
			(size 1.1176 1.3716)
			(layers "B.Cu" "B.Mask" "B.Paste")
			(net "P1V05_NODE1")
		)
		(pad "2" smd rect
			(at 0.94996 0 180)
			(size 1.1176 1.3716)
			(layers "B.Cu" "B.Mask" "B.Paste")
			(net "GND")
		)
	)
	(footprint ""
		(layer "B.Cu")
		(at 18.28038 -90.893392 -90)
		(property "Reference" ""
			(at 0 0 90)
			(layer "B.SilkS")
			(hide yes)
			(effects
				(font
					(size 1.27 1.27)
				)
				(justify mirror)
			)
		)
		(property "Value" ""
			(at 0 0 90)
			(layer "B.Fab")
			(effects
				(font
					(size 1.27 1.27)
				)
				(justify mirror)
			)
		)
		(duplicate_pad_numbers_are_jumpers no)
		(fp_poly
			(pts
				(arc
					(start 0 -1.4986)
					(mid 0 1.4986)
					(end 0 -1.4986)
				)
			)
			(stroke
				(width 0)
				(type default)
			)
			(fill no)
			(layer "B.CrtYd")
		)
		(pad "1" smd circle
			(at 0 0 90)
			(size 0.9906 0.9906)
			(layers "B.Cu" "B.Mask" "B.Paste")
			(net "Net_29")
		)
		(zone
			(layer "B.Cu")
			(hatch none 0.5)
			(connect_pads
				(clearance 0)
			)
			(min_thickness 0.25)
			(keepout
				(tracks not_allowed)
				(vias allowed)
				(pads allowed)
				(copperpour not_allowed)
				(footprints allowed)
			)
			(placement
				(enabled no)
				(sheetname "")
			)
			(fill
				(thermal_gap 0.5)
				(thermal_bridge_width 0.5)
				(island_removal_mode 0)
			)
			(polygon
				(pts
					(arc
						(start 19.90598 -90.893392)
						(mid 16.65478 -90.893392)
						(end 19.90598 -90.893392)
					)
				)
			)
		)
	)
	(footprint ""
		(layer "B.Cu")
		(at 69.335142 -137.52322 180)
		(property "Reference" "C252"
			(at 36.007802 -52.728622 0)
			(unlocked yes)
			(layer "B.SilkS")
			(effects
				(font
					(size 0.7874 0.5842)
					(thickness 0.1524)
				)
				(justify left mirror)
			)
		)
		(property "Value" ""
			(at 0 0 0)
			(layer "B.Fab")
			(effects
				(font
					(size 1.27 1.27)
				)
				(justify mirror)
			)
		)
		(duplicate_pad_numbers_are_jumpers no)
		(fp_line
			(start 0.7874 0.4064)
			(end 0.7874 -0.4064)
			(stroke
				(width 0.1524)
				(type default)
			)
			(layer "B.SilkS")
		)
		(fp_line
			(start 0.7874 -0.4064)
			(end -0.7874 -0.4064)
			(stroke
				(width 0.1524)
				(type default)
			)
			(layer "B.SilkS")
		)
		(fp_line
			(start 0 0.381)
			(end 0 -0.381)
			(stroke
				(width 0.1524)
				(type default)
			)
			(layer "B.SilkS")
		)
		(fp_line
			(start -0.7874 0.4064)
			(end 0.7874 0.4064)
			(stroke
				(width 0.1524)
				(type default)
			)
			(layer "B.SilkS")
		)
		(fp_line
			(start -0.7874 -0.4064)
			(end -0.7874 0.4064)
			(stroke
				(width 0.1524)
				(type default)
			)
			(layer "B.SilkS")
		)
		(fp_poly
			(pts
				(xy 0.5334 0.254) (xy 0.635 0.254) (xy 0.635 0.2286) (xy 0.635 -0.254) (xy 0.5334 -0.254) (xy 0.5334 -0.2794)
				(xy -0.5334 -0.2794) (xy -0.5334 -0.254) (xy -0.635 -0.254) (xy -0.635 0.254) (xy -0.5334 0.254)
				(xy -0.5334 0.2794) (xy 0.508 0.2794) (xy 0.5334 0.2794)
			)
			(stroke
				(width 0)
				(type default)
			)
			(fill no)
			(layer "B.CrtYd")
		)
		(pad "1" smd rect
			(at -0.40005 0)
			(size 0.4572 0.508)
			(layers "B.Cu" "B.Mask" "B.Paste")
			(net "P3V3_NODE1")
		)
		(pad "2" smd rect
			(at 0.40005 0)
			(size 0.4572 0.508)
			(layers "B.Cu" "B.Mask" "B.Paste")
			(net "GND")
		)
	)
	(footprint ""
		(layer "B.Cu")
		(at 130.8862 -46.3804)
		(property "Reference" "R1325"
			(at -1.3716 -0.40513 0)
			(unlocked yes)
			(layer "B.SilkS")
			(effects
				(font
					(size 0.7874 0.5842)
					(thickness 0.1524)
				)
				(justify left mirror)
			)
		)
		(property "Value" ""
			(at 0 0 0)
			(layer "B.Fab")
			(effects
				(font
					(size 1.27 1.27)
				)
				(justify mirror)
			)
		)
		(duplicate_pad_numbers_are_jumpers no)
		(fp_line
			(start -0.7874 -0.4064)
			(end -0.7874 0.4064)
			(stroke
				(width 0.1524)
				(type default)
			)
			(layer "B.SilkS")
		)
		(fp_line
			(start -0.7874 0.4064)
			(end 0.7874 0.4064)
			(stroke
				(width 0.1524)
				(type default)
			)
			(layer "B.SilkS")
		)
		(fp_line
			(start 0.7874 -0.4064)
			(end -0.7874 -0.4064)
			(stroke
				(width 0.1524)
				(type default)
			)
			(layer "B.SilkS")
		)
		(fp_line
			(start 0.7874 0.4064)
			(end 0.7874 -0.4064)
			(stroke
				(width 0.1524)
				(type default)
			)
			(layer "B.SilkS")
		)
		(fp_poly
			(pts
				(xy 0.508 0.2794) (xy 0.508 0.2286) (xy 0.635 0.2286) (xy 0.635 -0.254) (xy 0.5334 -0.254) (xy 0.5334 -0.2794)
				(xy -0.5334 -0.2794) (xy -0.5334 -0.254) (xy -0.635 -0.254) (xy -0.635 0.254) (xy -0.5334 0.254)
				(xy -0.5334 0.2794)
			)
			(stroke
				(width 0)
				(type default)
			)
			(fill no)
			(layer "B.CrtYd")
		)
		(pad "1" smd rect
			(at -0.40005 0 180)
			(size 0.4572 0.508)
			(layers "B.Cu" "B.Mask" "B.Paste")
			(net "P5V_NODE1")
		)
		(pad "2" smd rect
			(at 0.40005 0 180)
			(size 0.4572 0.508)
			(layers "B.Cu" "B.Mask" "B.Paste")
			(net "UART_CTS_P4_N")
		)
	)
	(footprint ""
		(layer "B.Cu")
		(at 144.909032 -38.710616)
		(property "Reference" "R1195"
			(at 1.24714 17.425924 0)
			(unlocked yes)
			(layer "B.SilkS")
			(effects
				(font
					(size 0.7874 0.5842)
					(thickness 0.1524)
				)
				(justify left mirror)
			)
		)
		(property "Value" ""
			(at 0 0 0)
			(layer "B.Fab")
			(effects
				(font
					(size 1.27 1.27)
				)
				(justify mirror)
			)
		)
		(duplicate_pad_numbers_are_jumpers no)
		(fp_line
			(start -0.7874 -0.4064)
			(end -0.7874 0.4064)
			(stroke
				(width 0.1524)
				(type default)
			)
			(layer "B.SilkS")
		)
		(fp_line
			(start -0.7874 0.4064)
			(end 0.7874 0.4064)
			(stroke
				(width 0.1524)
				(type default)
			)
			(layer "B.SilkS")
		)
		(fp_line
			(start 0.7874 -0.4064)
			(end -0.7874 -0.4064)
			(stroke
				(width 0.1524)
				(type default)
			)
			(layer "B.SilkS")
		)
		(fp_line
			(start 0.7874 0.4064)
			(end 0.7874 -0.4064)
			(stroke
				(width 0.1524)
				(type default)
			)
			(layer "B.SilkS")
		)
		(fp_poly
			(pts
				(xy 0.508 0.2794) (xy 0.508 0.2286) (xy 0.635 0.2286) (xy 0.635 -0.254) (xy 0.5334 -0.254) (xy 0.5334 -0.2794)
				(xy -0.5334 -0.2794) (xy -0.5334 -0.254) (xy -0.635 -0.254) (xy -0.635 0.254) (xy -0.5334 0.254)
				(xy -0.5334 0.2794)
			)
			(stroke
				(width 0)
				(type default)
			)
			(fill no)
			(layer "B.CrtYd")
		)
		(pad "1" smd rect
			(at -0.40005 0 180)
			(size 0.4572 0.508)
			(layers "B.Cu" "B.Mask" "B.Paste")
			(net "CPLD_WDT3_R")
		)
		(pad "2" smd rect
			(at 0.40005 0 180)
			(size 0.4572 0.508)
			(layers "B.Cu" "B.Mask" "B.Paste")
			(net "P3V3_NODE1")
		)
	)
	(footprint ""
		(layer "B.Cu")
		(at 88.840818 -80.83042)
		(property "Reference" "R119"
			(at -2.168398 9.526524 0)
			(unlocked yes)
			(layer "B.SilkS")
			(effects
				(font
					(size 0.7874 0.5842)
					(thickness 0.1524)
				)
				(justify left mirror)
			)
		)
		(property "Value" ""
			(at 0 0 0)
			(layer "B.Fab")
			(effects
				(font
					(size 1.27 1.27)
				)
				(justify mirror)
			)
		)
		(duplicate_pad_numbers_are_jumpers no)
		(fp_line
			(start -0.7874 -0.4064)
			(end -0.7874 0.4064)
			(stroke
				(width 0.1524)
				(type default)
			)
			(layer "B.SilkS")
		)
		(fp_line
			(start -0.7874 0.4064)
			(end 0.7874 0.4064)
			(stroke
				(width 0.1524)
				(type default)
			)
			(layer "B.SilkS")
		)
		(fp_line
			(start 0.7874 -0.4064)
			(end -0.7874 -0.4064)
			(stroke
				(width 0.1524)
				(type default)
			)
			(layer "B.SilkS")
		)
		(fp_line
			(start 0.7874 0.4064)
			(end 0.7874 -0.4064)
			(stroke
				(width 0.1524)
				(type default)
			)
			(layer "B.SilkS")
		)
		(fp_poly
			(pts
				(xy 0.508 0.2794) (xy 0.508 0.2286) (xy 0.635 0.2286) (xy 0.635 -0.254) (xy 0.5334 -0.254) (xy 0.5334 -0.2794)
				(xy -0.5334 -0.2794) (xy -0.5334 -0.254) (xy -0.635 -0.254) (xy -0.635 0.254) (xy -0.5334 0.254)
				(xy -0.5334 0.2794)
			)
			(stroke
				(width 0)
				(type default)
			)
			(fill no)
			(layer "B.CrtYd")
		)
		(pad "1" smd rect
			(at -0.40005 0 180)
			(size 0.4572 0.508)
			(layers "B.Cu" "B.Mask" "B.Paste")
			(net "SVID_CPU_NODE1_PVCCP_ALERT_L")
		)
		(pad "2" smd rect
			(at 0.40005 0 180)
			(size 0.4572 0.508)
			(layers "B.Cu" "B.Mask" "B.Paste")
			(net "P1V05_NODE1")
		)
	)
	(footprint ""
		(layer "B.Cu")
		(at 13.043916 -124.093478 180)
		(property "Reference" "PC57"
			(at 2.429764 0.090424 0)
			(unlocked yes)
			(layer "B.SilkS")
			(effects
				(font
					(size 0.7874 0.5842)
					(thickness 0.1524)
				)
				(justify left mirror)
			)
		)
		(property "Value" ""
			(at 0 0 0)
			(layer "B.Fab")
			(effects
				(font
					(size 1.27 1.27)
				)
				(justify mirror)
			)
		)
		(duplicate_pad_numbers_are_jumpers no)
		(fp_line
			(start 2.2098 0.9398)
			(end 2.2098 -0.9398)
			(stroke
				(width 0.1524)
				(type default)
			)
			(layer "B.SilkS")
		)
		(fp_line
			(start 2.2098 -0.9398)
			(end -2.2098 -0.9398)
			(stroke
				(width 0.1524)
				(type default)
			)
			(layer "B.SilkS")
		)
		(fp_line
			(start 0 -0.9398)
			(end 0 0.9398)
			(stroke
				(width 0.1524)
				(type default)
			)
			(layer "B.SilkS")
		)
		(fp_line
			(start -2.2098 0.9398)
			(end 2.2098 0.9398)
			(stroke
				(width 0.1524)
				(type default)
			)
			(layer "B.SilkS")
		)
		(fp_line
			(start -2.2098 -0.9398)
			(end -2.2098 0.9398)
			(stroke
				(width 0.1524)
				(type default)
			)
			(layer "B.SilkS")
		)
		(fp_poly
			(pts
				(xy 1.6764 0.889) (xy 1.6764 0.7874) (xy 2.0574 0.7874) (xy 2.0574 -0.7874) (xy 1.6764 -0.7874)
				(xy 1.6764 -0.9398) (xy -1.6764 -0.9398) (xy -1.6764 -0.7874) (xy -2.0574 -0.7874) (xy -2.0574 0.7874)
				(xy -1.6764 0.7874) (xy -1.6764 0.9398) (xy 1.6764 0.9398)
			)
			(stroke
				(width 0)
				(type default)
			)
			(fill no)
			(layer "B.CrtYd")
		)
		(fp_line
			(start 1.700022 0.899922)
			(end 1.700022 -0.899922)
			(stroke
				(width 0.1)
				(type default)
			)
			(layer "B.Fab")
		)
		(fp_line
			(start 1.700022 -0.899922)
			(end -1.700022 -0.899922)
			(stroke
				(width 0.1)
				(type default)
			)
			(layer "B.Fab")
		)
		(fp_line
			(start -1.700022 0.899922)
			(end 1.700022 0.899922)
			(stroke
				(width 0.1)
				(type default)
			)
			(layer "B.Fab")
		)
		(fp_line
			(start -1.700022 -0.899922)
			(end -1.700022 0.899922)
			(stroke
				(width 0.1)
				(type default)
			)
			(layer "B.Fab")
		)
		(pad "1" smd rect
			(at -1.4732 0)
			(size 1.1684 1.5748)
			(layers "B.Cu" "B.Mask" "B.Paste")
			(net "SW_P1V05_NODE1_VIN_FLT")
		)
		(pad "2" smd rect
			(at 1.4732 0)
			(size 1.1684 1.5748)
			(layers "B.Cu" "B.Mask" "B.Paste")
			(net "GND")
		)
	)
	(footprint ""
		(layer "B.Cu")
		(at 180.16093 -117.48262)
		(property "Reference" "C783"
			(at 2.884678 -0.19685 0)
			(unlocked yes)
			(layer "B.SilkS")
			(effects
				(font
					(size 0.7874 0.5842)
					(thickness 0.1524)
				)
				(justify mirror)
			)
		)
		(property "Value" ""
			(at 0 0 0)
			(layer "B.Fab")
			(effects
				(font
					(size 1.27 1.27)
				)
				(justify mirror)
			)
		)
		(duplicate_pad_numbers_are_jumpers no)
		(fp_line
			(start -1.2954 -0.5842)
			(end -1.2954 0.5842)
			(stroke
				(width 0.1524)
				(type default)
			)
			(layer "B.SilkS")
		)
		(fp_line
			(start -1.2954 0.5842)
			(end 1.2954 0.5842)
			(stroke
				(width 0.1524)
				(type default)
			)
			(layer "B.SilkS")
		)
		(fp_line
			(start 0 -0.5842)
			(end 0 0.5842)
			(stroke
				(width 0.1524)
				(type default)
			)
			(layer "B.SilkS")
		)
		(fp_line
			(start 1.2954 -0.5842)
			(end -1.2954 -0.5842)
			(stroke
				(width 0.1524)
				(type default)
			)
			(layer "B.SilkS")
		)
		(fp_line
			(start 1.2954 0.5842)
			(end 1.2954 -0.5842)
			(stroke
				(width 0.1524)
				(type default)
			)
			(layer "B.SilkS")
		)
		(fp_poly
			(pts
				(xy -0.8636 -0.4572) (xy -0.8636 -0.3556) (xy -1.143 -0.3556) (xy -1.143 0.3556) (xy -0.8636 0.3556)
				(xy -0.8636 0.4572) (xy 0.8636 0.4572) (xy 0.8636 0.3556) (xy 1.143 0.3556) (xy 1.143 -0.3556) (xy 0.8636 -0.3556)
				(xy 0.8636 -0.4572)
			)
			(stroke
				(width 0)
				(type default)
			)
			(fill no)
			(layer "B.CrtYd")
		)
		(fp_line
			(start -0.884936 -0.504952)
			(end -0.884936 0.504952)
			(stroke
				(width 0.1)
				(type default)
			)
			(layer "B.Fab")
		)
		(fp_line
			(start -0.884936 0.504952)
			(end 0.884936 0.504952)
			(stroke
				(width 0.1)
				(type default)
			)
			(layer "B.Fab")
		)
		(fp_line
			(start 0.884936 -0.504952)
			(end -0.884936 -0.504952)
			(stroke
				(width 0.1)
				(type default)
			)
			(layer "B.Fab")
		)
		(fp_line
			(start 0.884936 0.504952)
			(end 0.884936 -0.504952)
			(stroke
				(width 0.1)
				(type default)
			)
			(layer "B.Fab")
		)
		(pad "1" smd rect
			(at -0.7366 0 90)
			(size 0.7112 0.8128)
			(layers "B.Cu" "B.Mask" "B.Paste")
			(net "P3V3_STB_NODE1")
		)
		(pad "2" smd rect
			(at 0.7366 0 90)
			(size 0.7112 0.8128)
			(layers "B.Cu" "B.Mask" "B.Paste")
			(net "GND")
		)
	)
	(footprint ""
		(layer "B.Cu")
		(at 152.588214 -64.971422 90)
		(property "Reference" "C345"
			(at -2.01422 5.912866 270)
			(unlocked yes)
			(layer "B.SilkS")
			(effects
				(font
					(size 0.7874 0.5842)
					(thickness 0.1524)
				)
				(justify left mirror)
			)
		)
		(property "Value" ""
			(at 0 0 90)
			(layer "B.Fab")
			(effects
				(font
					(size 1.27 1.27)
				)
				(justify mirror)
			)
		)
		(duplicate_pad_numbers_are_jumpers no)
		(fp_line
			(start 0.7874 -0.4064)
			(end -0.7874 -0.4064)
			(stroke
				(width 0.1524)
				(type default)
			)
			(layer "B.SilkS")
		)
		(fp_line
			(start -0.7874 -0.4064)
			(end -0.7874 0.4064)
			(stroke
				(width 0.1524)
				(type default)
			)
			(layer "B.SilkS")
		)
		(fp_line
			(start 0 0.381)
			(end 0 -0.381)
			(stroke
				(width 0.1524)
				(type default)
			)
			(layer "B.SilkS")
		)
		(fp_line
			(start 0.7874 0.4064)
			(end 0.7874 -0.4064)
			(stroke
				(width 0.1524)
				(type default)
			)
			(layer "B.SilkS")
		)
		(fp_line
			(start -0.7874 0.4064)
			(end 0.7874 0.4064)
			(stroke
				(width 0.1524)
				(type default)
			)
			(layer "B.SilkS")
		)
		(fp_poly
			(pts
				(xy 0.5334 0.254) (xy 0.635 0.254) (xy 0.635 0.2286) (xy 0.635 -0.254) (xy 0.5334 -0.254) (xy 0.5334 -0.2794)
				(xy -0.5334 -0.2794) (xy -0.5334 -0.254) (xy -0.635 -0.254) (xy -0.635 0.254) (xy -0.5334 0.254)
				(xy -0.5334 0.2794) (xy 0.508 0.2794) (xy 0.5334 0.2794)
			)
			(stroke
				(width 0)
				(type default)
			)
			(fill no)
			(layer "B.CrtYd")
		)
		(pad "1" smd rect
			(at -0.40005 0 270)
			(size 0.4572 0.508)
			(layers "B.Cu" "B.Mask" "B.Paste")
			(net "GND")
		)
		(pad "2" smd rect
			(at 0.40005 0 270)
			(size 0.4572 0.508)
			(layers "B.Cu" "B.Mask" "B.Paste")
			(net "P1V8_SATA_VAA2_0_NODE1")
		)
	)
	(footprint ""
		(layer "B.Cu")
		(at 123.70816 -174.410624)
		(property "Reference" "R727"
			(at -28.598876 31.521146 0)
			(unlocked yes)
			(layer "B.SilkS")
			(effects
				(font
					(size 0.7874 0.5842)
					(thickness 0.1524)
				)
				(justify left mirror)
			)
		)
		(property "Value" ""
			(at 0 0 0)
			(layer "B.Fab")
			(effects
				(font
					(size 1.27 1.27)
				)
				(justify mirror)
			)
		)
		(duplicate_pad_numbers_are_jumpers no)
		(fp_line
			(start -0.7874 -0.4064)
			(end -0.7874 0.4064)
			(stroke
				(width 0.1524)
				(type default)
			)
			(layer "B.SilkS")
		)
		(fp_line
			(start -0.7874 0.4064)
			(end 0.7874 0.4064)
			(stroke
				(width 0.1524)
				(type default)
			)
			(layer "B.SilkS")
		)
		(fp_line
			(start 0.7874 -0.4064)
			(end -0.7874 -0.4064)
			(stroke
				(width 0.1524)
				(type default)
			)
			(layer "B.SilkS")
		)
		(fp_line
			(start 0.7874 0.4064)
			(end 0.7874 -0.4064)
			(stroke
				(width 0.1524)
				(type default)
			)
			(layer "B.SilkS")
		)
		(fp_poly
			(pts
				(xy 0.508 0.2794) (xy 0.508 0.2286) (xy 0.635 0.2286) (xy 0.635 -0.254) (xy 0.5334 -0.254) (xy 0.5334 -0.2794)
				(xy -0.5334 -0.2794) (xy -0.5334 -0.254) (xy -0.635 -0.254) (xy -0.635 0.254) (xy -0.5334 0.254)
				(xy -0.5334 0.2794)
			)
			(stroke
				(width 0)
				(type default)
			)
			(fill no)
			(layer "B.CrtYd")
		)
		(pad "1" smd rect
			(at -0.40005 0 180)
			(size 0.4572 0.508)
			(layers "B.Cu" "B.Mask" "B.Paste")
			(net "T8_NODE4_EN")
		)
		(pad "2" smd rect
			(at 0.40005 0 180)
			(size 0.4572 0.508)
			(layers "B.Cu" "B.Mask" "B.Paste")
			(net "P5V_NODE1")
		)
	)
	(footprint ""
		(layer "B.Cu")
		(at 53.193442 -29.199078)
		(property "Reference" "R210"
			(at 4.075938 -0.073152 0)
			(unlocked yes)
			(layer "B.SilkS")
			(effects
				(font
					(size 0.7874 0.5842)
					(thickness 0.1524)
				)
				(justify left mirror)
			)
		)
		(property "Value" ""
			(at 0 0 0)
			(layer "B.Fab")
			(effects
				(font
					(size 1.27 1.27)
				)
				(justify mirror)
			)
		)
		(duplicate_pad_numbers_are_jumpers no)
		(fp_line
			(start -0.7874 -0.4064)
			(end -0.7874 0.4064)
			(stroke
				(width 0.1524)
				(type default)
			)
			(layer "B.SilkS")
		)
		(fp_line
			(start -0.7874 0.4064)
			(end 0.7874 0.4064)
			(stroke
				(width 0.1524)
				(type default)
			)
			(layer "B.SilkS")
		)
		(fp_line
			(start 0.7874 -0.4064)
			(end -0.7874 -0.4064)
			(stroke
				(width 0.1524)
				(type default)
			)
			(layer "B.SilkS")
		)
		(fp_line
			(start 0.7874 0.4064)
			(end 0.7874 -0.4064)
			(stroke
				(width 0.1524)
				(type default)
			)
			(layer "B.SilkS")
		)
		(fp_poly
			(pts
				(xy 0.508 0.2794) (xy 0.508 0.2286) (xy 0.635 0.2286) (xy 0.635 -0.254) (xy 0.5334 -0.254) (xy 0.5334 -0.2794)
				(xy -0.5334 -0.2794) (xy -0.5334 -0.254) (xy -0.635 -0.254) (xy -0.635 0.254) (xy -0.5334 0.254)
				(xy -0.5334 0.2794)
			)
			(stroke
				(width 0)
				(type default)
			)
			(fill no)
			(layer "B.CrtYd")
		)
		(pad "1" smd rect
			(at -0.40005 0 180)
			(size 0.4572 0.508)
			(layers "B.Cu" "B.Mask" "B.Paste")
			(net "GND")
		)
		(pad "2" smd rect
			(at 0.40005 0 180)
			(size 0.4572 0.508)
			(layers "B.Cu" "B.Mask" "B.Paste")
			(net "PD_NODE1_DM2")
		)
	)
	(footprint ""
		(layer "B.Cu")
		(at 138.038078 -165.170358 180)
		(property "Reference" "R977"
			(at -3.46329 1.252982 0)
			(unlocked yes)
			(layer "B.SilkS")
			(effects
				(font
					(size 0.7874 0.5842)
					(thickness 0.1524)
				)
				(justify left mirror)
			)
		)
		(property "Value" ""
			(at 0 0 0)
			(layer "B.Fab")
			(effects
				(font
					(size 1.27 1.27)
				)
				(justify mirror)
			)
		)
		(duplicate_pad_numbers_are_jumpers no)
		(fp_line
			(start 0.7874 0.4064)
			(end 0.7874 -0.4064)
			(stroke
				(width 0.1524)
				(type default)
			)
			(layer "B.SilkS")
		)
		(fp_line
			(start 0.7874 -0.4064)
			(end -0.7874 -0.4064)
			(stroke
				(width 0.1524)
				(type default)
			)
			(layer "B.SilkS")
		)
		(fp_line
			(start -0.7874 0.4064)
			(end 0.7874 0.4064)
			(stroke
				(width 0.1524)
				(type default)
			)
			(layer "B.SilkS")
		)
		(fp_line
			(start -0.7874 -0.4064)
			(end -0.7874 0.4064)
			(stroke
				(width 0.1524)
				(type default)
			)
			(layer "B.SilkS")
		)
		(fp_poly
			(pts
				(xy 0.508 0.2794) (xy 0.508 0.2286) (xy 0.635 0.2286) (xy 0.635 -0.254) (xy 0.5334 -0.254) (xy 0.5334 -0.2794)
				(xy -0.5334 -0.2794) (xy -0.5334 -0.254) (xy -0.635 -0.254) (xy -0.635 0.254) (xy -0.5334 0.254)
				(xy -0.5334 0.2794)
			)
			(stroke
				(width 0)
				(type default)
			)
			(fill no)
			(layer "B.CrtYd")
		)
		(pad "1" smd rect
			(at -0.40005 0)
			(size 0.4572 0.508)
			(layers "B.Cu" "B.Mask" "B.Paste")
			(net "UART_T9_NODE4_TXD")
		)
		(pad "2" smd rect
			(at 0.40005 0)
			(size 0.4572 0.508)
			(layers "B.Cu" "B.Mask" "B.Paste")
			(net "UART_T9_NODE4_TXD_R")
		)
	)
	(footprint ""
		(layer "B.Cu")
		(at 153.578814 -67.232022 90)
		(property "Reference" "C360"
			(at 0.02159 5.137912 270)
			(unlocked yes)
			(layer "B.SilkS")
			(effects
				(font
					(size 0.7874 0.5842)
					(thickness 0.1524)
				)
				(justify left mirror)
			)
		)
		(property "Value" ""
			(at 0 0 90)
			(layer "B.Fab")
			(effects
				(font
					(size 1.27 1.27)
				)
				(justify mirror)
			)
		)
		(duplicate_pad_numbers_are_jumpers no)
		(fp_line
			(start 0.7874 -0.4064)
			(end -0.7874 -0.4064)
			(stroke
				(width 0.1524)
				(type default)
			)
			(layer "B.SilkS")
		)
		(fp_line
			(start -0.7874 -0.4064)
			(end -0.7874 0.4064)
			(stroke
				(width 0.1524)
				(type default)
			)
			(layer "B.SilkS")
		)
		(fp_line
			(start 0 0.381)
			(end 0 -0.381)
			(stroke
				(width 0.1524)
				(type default)
			)
			(layer "B.SilkS")
		)
		(fp_line
			(start 0.7874 0.4064)
			(end 0.7874 -0.4064)
			(stroke
				(width 0.1524)
				(type default)
			)
			(layer "B.SilkS")
		)
		(fp_line
			(start -0.7874 0.4064)
			(end 0.7874 0.4064)
			(stroke
				(width 0.1524)
				(type default)
			)
			(layer "B.SilkS")
		)
		(fp_poly
			(pts
				(xy 0.5334 0.254) (xy 0.635 0.254) (xy 0.635 0.2286) (xy 0.635 -0.254) (xy 0.5334 -0.254) (xy 0.5334 -0.2794)
				(xy -0.5334 -0.2794) (xy -0.5334 -0.254) (xy -0.635 -0.254) (xy -0.635 0.254) (xy -0.5334 0.254)
				(xy -0.5334 0.2794) (xy 0.508 0.2794) (xy 0.5334 0.2794)
			)
			(stroke
				(width 0)
				(type default)
			)
			(fill no)
			(layer "B.CrtYd")
		)
		(pad "1" smd rect
			(at -0.40005 0 270)
			(size 0.4572 0.508)
			(layers "B.Cu" "B.Mask" "B.Paste")
			(net "P1V8_SATA_VAA1_NODE1")
		)
		(pad "2" smd rect
			(at 0.40005 0 270)
			(size 0.4572 0.508)
			(layers "B.Cu" "B.Mask" "B.Paste")
			(net "GND")
		)
	)
	(footprint ""
		(layer "B.Cu")
		(at 151.62276 -184.951624 90)
		(property "Reference" "R894"
			(at 4.357624 -3.26517 270)
			(unlocked yes)
			(layer "B.SilkS")
			(effects
				(font
					(size 0.7874 0.5842)
					(thickness 0.1524)
				)
				(justify left mirror)
			)
		)
		(property "Value" ""
			(at 0 0 90)
			(layer "B.Fab")
			(effects
				(font
					(size 1.27 1.27)
				)
				(justify mirror)
			)
		)
		(duplicate_pad_numbers_are_jumpers no)
		(fp_line
			(start 0.7874 -0.4064)
			(end -0.7874 -0.4064)
			(stroke
				(width 0.1524)
				(type default)
			)
			(layer "B.SilkS")
		)
		(fp_line
			(start -0.7874 -0.4064)
			(end -0.7874 0.4064)
			(stroke
				(width 0.1524)
				(type default)
			)
			(layer "B.SilkS")
		)
		(fp_line
			(start 0.7874 0.4064)
			(end 0.7874 -0.4064)
			(stroke
				(width 0.1524)
				(type default)
			)
			(layer "B.SilkS")
		)
		(fp_line
			(start -0.7874 0.4064)
			(end 0.7874 0.4064)
			(stroke
				(width 0.1524)
				(type default)
			)
			(layer "B.SilkS")
		)
		(fp_poly
			(pts
				(xy 0.508 0.2794) (xy 0.508 0.2286) (xy 0.635 0.2286) (xy 0.635 -0.254) (xy 0.5334 -0.254) (xy 0.5334 -0.2794)
				(xy -0.5334 -0.2794) (xy -0.5334 -0.254) (xy -0.635 -0.254) (xy -0.635 0.254) (xy -0.5334 0.254)
				(xy -0.5334 0.2794)
			)
			(stroke
				(width 0)
				(type default)
			)
			(fill no)
			(layer "B.CrtYd")
		)
		(pad "1" smd rect
			(at -0.40005 0 270)
			(size 0.4572 0.508)
			(layers "B.Cu" "B.Mask" "B.Paste")
			(net "T11_NODE4_EN")
		)
		(pad "2" smd rect
			(at 0.40005 0 270)
			(size 0.4572 0.508)
			(layers "B.Cu" "B.Mask" "B.Paste")
			(net "T11_NODE4_EN_R")
		)
	)
	(footprint ""
		(layer "B.Cu")
		(at 64.121538 -64.799718)
		(property "Reference" "C14"
			(at 0.00889 5.282946 0)
			(unlocked yes)
			(layer "B.SilkS")
			(effects
				(font
					(size 0.7874 0.5842)
					(thickness 0.1524)
				)
				(justify left mirror)
			)
		)
		(property "Value" ""
			(at 0 0 0)
			(layer "B.Fab")
			(effects
				(font
					(size 1.27 1.27)
				)
				(justify mirror)
			)
		)
		(duplicate_pad_numbers_are_jumpers no)
		(fp_line
			(start -0.7874 -0.4064)
			(end -0.7874 0.4064)
			(stroke
				(width 0.1524)
				(type default)
			)
			(layer "B.SilkS")
		)
		(fp_line
			(start -0.7874 0.4064)
			(end 0.7874 0.4064)
			(stroke
				(width 0.1524)
				(type default)
			)
			(layer "B.SilkS")
		)
		(fp_line
			(start 0 0.381)
			(end 0 -0.381)
			(stroke
				(width 0.1524)
				(type default)
			)
			(layer "B.SilkS")
		)
		(fp_line
			(start 0.7874 -0.4064)
			(end -0.7874 -0.4064)
			(stroke
				(width 0.1524)
				(type default)
			)
			(layer "B.SilkS")
		)
		(fp_line
			(start 0.7874 0.4064)
			(end 0.7874 -0.4064)
			(stroke
				(width 0.1524)
				(type default)
			)
			(layer "B.SilkS")
		)
		(fp_poly
			(pts
				(xy 0.5334 0.254) (xy 0.635 0.254) (xy 0.635 0.2286) (xy 0.635 -0.254) (xy 0.5334 -0.254) (xy 0.5334 -0.2794)
				(xy -0.5334 -0.2794) (xy -0.5334 -0.254) (xy -0.635 -0.254) (xy -0.635 0.254) (xy -0.5334 0.254)
				(xy -0.5334 0.2794) (xy 0.508 0.2794) (xy 0.5334 0.2794)
			)
			(stroke
				(width 0)
				(type default)
			)
			(fill no)
			(layer "B.CrtYd")
		)
		(pad "1" smd rect
			(at -0.40005 0 180)
			(size 0.4572 0.508)
			(layers "B.Cu" "B.Mask" "B.Paste")
			(net "N29180194")
		)
		(pad "2" smd rect
			(at 0.40005 0 180)
			(size 0.4572 0.508)
			(layers "B.Cu" "B.Mask" "B.Paste")
			(net "GND")
		)
	)
	(footprint ""
		(layer "B.Cu")
		(at 78.83144 -165.393624 180)
		(property "Reference" "R782"
			(at -30.555946 -20.931886 0)
			(unlocked yes)
			(layer "B.SilkS")
			(effects
				(font
					(size 0.7874 0.5842)
					(thickness 0.1524)
				)
				(justify left mirror)
			)
		)
		(property "Value" ""
			(at 0 0 0)
			(layer "B.Fab")
			(effects
				(font
					(size 1.27 1.27)
				)
				(justify mirror)
			)
		)
		(duplicate_pad_numbers_are_jumpers no)
		(fp_line
			(start 0.7874 0.4064)
			(end 0.7874 -0.4064)
			(stroke
				(width 0.1524)
				(type default)
			)
			(layer "B.SilkS")
		)
		(fp_line
			(start 0.7874 -0.4064)
			(end -0.7874 -0.4064)
			(stroke
				(width 0.1524)
				(type default)
			)
			(layer "B.SilkS")
		)
		(fp_line
			(start -0.7874 0.4064)
			(end 0.7874 0.4064)
			(stroke
				(width 0.1524)
				(type default)
			)
			(layer "B.SilkS")
		)
		(fp_line
			(start -0.7874 -0.4064)
			(end -0.7874 0.4064)
			(stroke
				(width 0.1524)
				(type default)
			)
			(layer "B.SilkS")
		)
		(fp_poly
			(pts
				(xy 0.508 0.2794) (xy 0.508 0.2286) (xy 0.635 0.2286) (xy 0.635 -0.254) (xy 0.5334 -0.254) (xy 0.5334 -0.2794)
				(xy -0.5334 -0.2794) (xy -0.5334 -0.254) (xy -0.635 -0.254) (xy -0.635 0.254) (xy -0.5334 0.254)
				(xy -0.5334 0.2794)
			)
			(stroke
				(width 0)
				(type default)
			)
			(fill no)
			(layer "B.CrtYd")
		)
		(pad "1" smd rect
			(at -0.40005 0)
			(size 0.4572 0.508)
			(layers "B.Cu" "B.Mask" "B.Paste")
			(net "SDC_WAKEUP")
		)
		(pad "2" smd rect
			(at 0.40005 0)
			(size 0.4572 0.508)
			(layers "B.Cu" "B.Mask" "B.Paste")
			(net "P3V3_NODE1")
		)
	)
	(footprint ""
		(layer "B.Cu")
		(at 69.649086 -131.280662 90)
		(property "Reference" "C255"
			(at -55.866538 -38.53434 270)
			(unlocked yes)
			(layer "B.SilkS")
			(effects
				(font
					(size 0.7874 0.5842)
					(thickness 0.1524)
				)
				(justify left mirror)
			)
		)
		(property "Value" ""
			(at 0 0 90)
			(layer "B.Fab")
			(effects
				(font
					(size 1.27 1.27)
				)
				(justify mirror)
			)
		)
		(duplicate_pad_numbers_are_jumpers no)
		(fp_line
			(start 0.7874 -0.4064)
			(end -0.7874 -0.4064)
			(stroke
				(width 0.1524)
				(type default)
			)
			(layer "B.SilkS")
		)
		(fp_line
			(start -0.7874 -0.4064)
			(end -0.7874 0.4064)
			(stroke
				(width 0.1524)
				(type default)
			)
			(layer "B.SilkS")
		)
		(fp_line
			(start 0 0.381)
			(end 0 -0.381)
			(stroke
				(width 0.1524)
				(type default)
			)
			(layer "B.SilkS")
		)
		(fp_line
			(start 0.7874 0.4064)
			(end 0.7874 -0.4064)
			(stroke
				(width 0.1524)
				(type default)
			)
			(layer "B.SilkS")
		)
		(fp_line
			(start -0.7874 0.4064)
			(end 0.7874 0.4064)
			(stroke
				(width 0.1524)
				(type default)
			)
			(layer "B.SilkS")
		)
		(fp_poly
			(pts
				(xy 0.5334 0.254) (xy 0.635 0.254) (xy 0.635 0.2286) (xy 0.635 -0.254) (xy 0.5334 -0.254) (xy 0.5334 -0.2794)
				(xy -0.5334 -0.2794) (xy -0.5334 -0.254) (xy -0.635 -0.254) (xy -0.635 0.254) (xy -0.5334 0.254)
				(xy -0.5334 0.2794) (xy 0.508 0.2794) (xy 0.5334 0.2794)
			)
			(stroke
				(width 0)
				(type default)
			)
			(fill no)
			(layer "B.CrtYd")
		)
		(pad "1" smd rect
			(at -0.40005 0 270)
			(size 0.4572 0.508)
			(layers "B.Cu" "B.Mask" "B.Paste")
			(net "P3V3_NODE1")
		)
		(pad "2" smd rect
			(at 0.40005 0 270)
			(size 0.4572 0.508)
			(layers "B.Cu" "B.Mask" "B.Paste")
			(net "GND")
		)
	)
	(footprint ""
		(layer "B.Cu")
		(at 171.846494 -120.607836 180)
		(property "Reference" "C790"
			(at 1.413002 4.142994 0)
			(unlocked yes)
			(layer "B.SilkS")
			(effects
				(font
					(size 0.7874 0.5842)
					(thickness 0.1524)
				)
				(justify mirror)
			)
		)
		(property "Value" ""
			(at 0 0 0)
			(layer "B.Fab")
			(effects
				(font
					(size 1.27 1.27)
				)
				(justify mirror)
			)
		)
		(duplicate_pad_numbers_are_jumpers no)
		(fp_line
			(start 1.2954 0.5842)
			(end 1.2954 -0.5842)
			(stroke
				(width 0.1524)
				(type default)
			)
			(layer "B.SilkS")
		)
		(fp_line
			(start 1.2954 -0.5842)
			(end -1.2954 -0.5842)
			(stroke
				(width 0.1524)
				(type default)
			)
			(layer "B.SilkS")
		)
		(fp_line
			(start 0 -0.5842)
			(end 0 0.5842)
			(stroke
				(width 0.1524)
				(type default)
			)
			(layer "B.SilkS")
		)
		(fp_line
			(start -1.2954 0.5842)
			(end 1.2954 0.5842)
			(stroke
				(width 0.1524)
				(type default)
			)
			(layer "B.SilkS")
		)
		(fp_line
			(start -1.2954 -0.5842)
			(end -1.2954 0.5842)
			(stroke
				(width 0.1524)
				(type default)
			)
			(layer "B.SilkS")
		)
		(fp_poly
			(pts
				(xy -0.8636 -0.4572) (xy -0.8636 -0.3556) (xy -1.143 -0.3556) (xy -1.143 0.3556) (xy -0.8636 0.3556)
				(xy -0.8636 0.4572) (xy 0.8636 0.4572) (xy 0.8636 0.3556) (xy 1.143 0.3556) (xy 1.143 -0.3556) (xy 0.8636 -0.3556)
				(xy 0.8636 -0.4572)
			)
			(stroke
				(width 0)
				(type default)
			)
			(fill no)
			(layer "B.CrtYd")
		)
		(fp_line
			(start 0.884936 0.504952)
			(end 0.884936 -0.504952)
			(stroke
				(width 0.1)
				(type default)
			)
			(layer "B.Fab")
		)
		(fp_line
			(start 0.884936 -0.504952)
			(end -0.884936 -0.504952)
			(stroke
				(width 0.1)
				(type default)
			)
			(layer "B.Fab")
		)
		(fp_line
			(start -0.884936 0.504952)
			(end 0.884936 0.504952)
			(stroke
				(width 0.1)
				(type default)
			)
			(layer "B.Fab")
		)
		(fp_line
			(start -0.884936 -0.504952)
			(end -0.884936 0.504952)
			(stroke
				(width 0.1)
				(type default)
			)
			(layer "B.Fab")
		)
		(pad "1" smd rect
			(at -0.7366 0 270)
			(size 0.7112 0.8128)
			(layers "B.Cu" "B.Mask" "B.Paste")
			(net "P3V3_STB_NODE1")
		)
		(pad "2" smd rect
			(at 0.7366 0 270)
			(size 0.7112 0.8128)
			(layers "B.Cu" "B.Mask" "B.Paste")
			(net "GND")
		)
	)
	(footprint ""
		(layer "B.Cu")
		(at 64.112648 -62.719966 180)
		(property "Reference" "R27"
			(at -0.01778 -5.286502 0)
			(unlocked yes)
			(layer "B.SilkS")
			(effects
				(font
					(size 0.7874 0.5842)
					(thickness 0.1524)
				)
				(justify left mirror)
			)
		)
		(property "Value" ""
			(at 0 0 0)
			(layer "B.Fab")
			(effects
				(font
					(size 1.27 1.27)
				)
				(justify mirror)
			)
		)
		(duplicate_pad_numbers_are_jumpers no)
		(fp_line
			(start 0.7874 0.4064)
			(end 0.7874 -0.4064)
			(stroke
				(width 0.1524)
				(type default)
			)
			(layer "B.SilkS")
		)
		(fp_line
			(start 0.7874 -0.4064)
			(end -0.7874 -0.4064)
			(stroke
				(width 0.1524)
				(type default)
			)
			(layer "B.SilkS")
		)
		(fp_line
			(start -0.7874 0.4064)
			(end 0.7874 0.4064)
			(stroke
				(width 0.1524)
				(type default)
			)
			(layer "B.SilkS")
		)
		(fp_line
			(start -0.7874 -0.4064)
			(end -0.7874 0.4064)
			(stroke
				(width 0.1524)
				(type default)
			)
			(layer "B.SilkS")
		)
		(fp_poly
			(pts
				(xy 0.508 0.2794) (xy 0.508 0.2286) (xy 0.635 0.2286) (xy 0.635 -0.254) (xy 0.5334 -0.254) (xy 0.5334 -0.2794)
				(xy -0.5334 -0.2794) (xy -0.5334 -0.254) (xy -0.635 -0.254) (xy -0.635 0.254) (xy -0.5334 0.254)
				(xy -0.5334 0.2794)
			)
			(stroke
				(width 0)
				(type default)
			)
			(fill no)
			(layer "B.CrtYd")
		)
		(pad "1" smd rect
			(at -0.40005 0)
			(size 0.4572 0.508)
			(layers "B.Cu" "B.Mask" "B.Paste")
			(net "PV_VDDR_NODE1")
		)
		(pad "2" smd rect
			(at 0.40005 0)
			(size 0.4572 0.508)
			(layers "B.Cu" "B.Mask" "B.Paste")
			(net "N29180194")
		)
	)
	(footprint ""
		(layer "B.Cu")
		(at 48.257206 -114.430302)
		(property "Reference" "PC13"
			(at 1.684782 -1.669288 0)
			(unlocked yes)
			(layer "B.SilkS")
			(effects
				(font
					(size 0.7874 0.5842)
					(thickness 0.1524)
				)
				(justify left mirror)
			)
		)
		(property "Value" ""
			(at 0 0 0)
			(layer "B.Fab")
			(effects
				(font
					(size 1.27 1.27)
				)
				(justify mirror)
			)
		)
		(duplicate_pad_numbers_are_jumpers no)
		(fp_line
			(start -2.2098 -0.9398)
			(end -2.2098 0.9398)
			(stroke
				(width 0.1524)
				(type default)
			)
			(layer "B.SilkS")
		)
		(fp_line
			(start -2.2098 0.9398)
			(end 2.2098 0.9398)
			(stroke
				(width 0.1524)
				(type default)
			)
			(layer "B.SilkS")
		)
		(fp_line
			(start 0 -0.9398)
			(end 0 0.9398)
			(stroke
				(width 0.1524)
				(type default)
			)
			(layer "B.SilkS")
		)
		(fp_line
			(start 2.2098 -0.9398)
			(end -2.2098 -0.9398)
			(stroke
				(width 0.1524)
				(type default)
			)
			(layer "B.SilkS")
		)
		(fp_line
			(start 2.2098 0.9398)
			(end 2.2098 -0.9398)
			(stroke
				(width 0.1524)
				(type default)
			)
			(layer "B.SilkS")
		)
		(fp_poly
			(pts
				(xy 1.6764 0.889) (xy 1.6764 0.7874) (xy 2.0574 0.7874) (xy 2.0574 -0.7874) (xy 1.6764 -0.7874)
				(xy 1.6764 -0.9398) (xy -1.6764 -0.9398) (xy -1.6764 -0.7874) (xy -2.0574 -0.7874) (xy -2.0574 0.7874)
				(xy -1.6764 0.7874) (xy -1.6764 0.9398) (xy 1.6764 0.9398)
			)
			(stroke
				(width 0)
				(type default)
			)
			(fill no)
			(layer "B.CrtYd")
		)
		(fp_line
			(start -1.700022 -0.899922)
			(end -1.700022 0.899922)
			(stroke
				(width 0.1)
				(type default)
			)
			(layer "B.Fab")
		)
		(fp_line
			(start -1.700022 0.899922)
			(end 1.700022 0.899922)
			(stroke
				(width 0.1)
				(type default)
			)
			(layer "B.Fab")
		)
		(fp_line
			(start 1.700022 -0.899922)
			(end -1.700022 -0.899922)
			(stroke
				(width 0.1)
				(type default)
			)
			(layer "B.Fab")
		)
		(fp_line
			(start 1.700022 0.899922)
			(end 1.700022 -0.899922)
			(stroke
				(width 0.1)
				(type default)
			)
			(layer "B.Fab")
		)
		(pad "1" smd rect
			(at -1.4732 0 180)
			(size 1.1684 1.5748)
			(layers "B.Cu" "B.Mask" "B.Paste")
			(net "P12V_AUX")
		)
		(pad "2" smd rect
			(at 1.4732 0 180)
			(size 1.1684 1.5748)
			(layers "B.Cu" "B.Mask" "B.Paste")
			(net "GND")
		)
	)
	(footprint ""
		(layer "B.Cu")
		(at 79.991204 -21.117306 90)
		(property "Reference" "C167"
			(at -5.827014 -0.770128 270)
			(unlocked yes)
			(layer "B.SilkS")
			(effects
				(font
					(size 0.7874 0.5842)
					(thickness 0.1524)
				)
				(justify left mirror)
			)
		)
		(property "Value" ""
			(at 0 0 90)
			(layer "B.Fab")
			(effects
				(font
					(size 1.27 1.27)
				)
				(justify mirror)
			)
		)
		(duplicate_pad_numbers_are_jumpers no)
		(fp_line
			(start 0.7874 -0.4064)
			(end -0.7874 -0.4064)
			(stroke
				(width 0.1524)
				(type default)
			)
			(layer "B.SilkS")
		)
		(fp_line
			(start -0.7874 -0.4064)
			(end -0.7874 0.4064)
			(stroke
				(width 0.1524)
				(type default)
			)
			(layer "B.SilkS")
		)
		(fp_line
			(start 0 0.381)
			(end 0 -0.381)
			(stroke
				(width 0.1524)
				(type default)
			)
			(layer "B.SilkS")
		)
		(fp_line
			(start 0.7874 0.4064)
			(end 0.7874 -0.4064)
			(stroke
				(width 0.1524)
				(type default)
			)
			(layer "B.SilkS")
		)
		(fp_line
			(start -0.7874 0.4064)
			(end 0.7874 0.4064)
			(stroke
				(width 0.1524)
				(type default)
			)
			(layer "B.SilkS")
		)
		(fp_poly
			(pts
				(xy 0.5334 0.254) (xy 0.635 0.254) (xy 0.635 0.2286) (xy 0.635 -0.254) (xy 0.5334 -0.254) (xy 0.5334 -0.2794)
				(xy -0.5334 -0.2794) (xy -0.5334 -0.254) (xy -0.635 -0.254) (xy -0.635 0.254) (xy -0.5334 0.254)
				(xy -0.5334 0.2794) (xy 0.508 0.2794) (xy 0.5334 0.2794)
			)
			(stroke
				(width 0)
				(type default)
			)
			(fill no)
			(layer "B.CrtYd")
		)
		(pad "1" smd rect
			(at -0.40005 0 270)
			(size 0.4572 0.508)
			(layers "B.Cu" "B.Mask" "B.Paste")
			(net "PV_VDDR_NODE1")
		)
		(pad "2" smd rect
			(at 0.40005 0 270)
			(size 0.4572 0.508)
			(layers "B.Cu" "B.Mask" "B.Paste")
			(net "GND")
		)
	)
	(footprint ""
		(layer "B.Cu")
		(at 44.770802 -150.249382 90)
		(property "Reference" "C396"
			(at 7.961122 -12.448286 270)
			(unlocked yes)
			(layer "B.SilkS")
			(effects
				(font
					(size 0.7874 0.5842)
					(thickness 0.1524)
				)
				(justify left mirror)
			)
		)
		(property "Value" ""
			(at 0 0 90)
			(layer "B.Fab")
			(effects
				(font
					(size 1.27 1.27)
				)
				(justify mirror)
			)
		)
		(duplicate_pad_numbers_are_jumpers no)
		(fp_line
			(start 0.7874 -0.4064)
			(end -0.7874 -0.4064)
			(stroke
				(width 0.1524)
				(type default)
			)
			(layer "B.SilkS")
		)
		(fp_line
			(start -0.7874 -0.4064)
			(end -0.7874 0.4064)
			(stroke
				(width 0.1524)
				(type default)
			)
			(layer "B.SilkS")
		)
		(fp_line
			(start 0 0.381)
			(end 0 -0.381)
			(stroke
				(width 0.1524)
				(type default)
			)
			(layer "B.SilkS")
		)
		(fp_line
			(start 0.7874 0.4064)
			(end 0.7874 -0.4064)
			(stroke
				(width 0.1524)
				(type default)
			)
			(layer "B.SilkS")
		)
		(fp_line
			(start -0.7874 0.4064)
			(end 0.7874 0.4064)
			(stroke
				(width 0.1524)
				(type default)
			)
			(layer "B.SilkS")
		)
		(fp_poly
			(pts
				(xy 0.5334 0.254) (xy 0.635 0.254) (xy 0.635 0.2286) (xy 0.635 -0.254) (xy 0.5334 -0.254) (xy 0.5334 -0.2794)
				(xy -0.5334 -0.2794) (xy -0.5334 -0.254) (xy -0.635 -0.254) (xy -0.635 0.254) (xy -0.5334 0.254)
				(xy -0.5334 0.2794) (xy 0.508 0.2794) (xy 0.5334 0.2794)
			)
			(stroke
				(width 0)
				(type default)
			)
			(fill no)
			(layer "B.CrtYd")
		)
		(pad "1" smd rect
			(at -0.40005 0 270)
			(size 0.4572 0.508)
			(layers "B.Cu" "B.Mask" "B.Paste")
			(net "P3V3_NODE1")
		)
		(pad "2" smd rect
			(at 0.40005 0 270)
			(size 0.4572 0.508)
			(layers "B.Cu" "B.Mask" "B.Paste")
			(net "GND")
		)
	)
	(footprint ""
		(layer "B.Cu")
		(at 71.721472 -121.059702 90)
		(property "Reference" "R272"
			(at -7.400798 9.931908 270)
			(unlocked yes)
			(layer "B.SilkS")
			(effects
				(font
					(size 0.7874 0.5842)
					(thickness 0.1524)
				)
				(justify left mirror)
			)
		)
		(property "Value" ""
			(at 0 0 90)
			(layer "B.Fab")
			(effects
				(font
					(size 1.27 1.27)
				)
				(justify mirror)
			)
		)
		(duplicate_pad_numbers_are_jumpers no)
		(fp_line
			(start 0.7874 -0.4064)
			(end -0.7874 -0.4064)
			(stroke
				(width 0.1524)
				(type default)
			)
			(layer "B.SilkS")
		)
		(fp_line
			(start -0.7874 -0.4064)
			(end -0.7874 0.4064)
			(stroke
				(width 0.1524)
				(type default)
			)
			(layer "B.SilkS")
		)
		(fp_line
			(start 0.7874 0.4064)
			(end 0.7874 -0.4064)
			(stroke
				(width 0.1524)
				(type default)
			)
			(layer "B.SilkS")
		)
		(fp_line
			(start -0.7874 0.4064)
			(end 0.7874 0.4064)
			(stroke
				(width 0.1524)
				(type default)
			)
			(layer "B.SilkS")
		)
		(fp_poly
			(pts
				(xy 0.508 0.2794) (xy 0.508 0.2286) (xy 0.635 0.2286) (xy 0.635 -0.254) (xy 0.5334 -0.254) (xy 0.5334 -0.2794)
				(xy -0.5334 -0.2794) (xy -0.5334 -0.254) (xy -0.635 -0.254) (xy -0.635 0.254) (xy -0.5334 0.254)
				(xy -0.5334 0.2794)
			)
			(stroke
				(width 0)
				(type default)
			)
			(fill no)
			(layer "B.CrtYd")
		)
		(pad "1" smd rect
			(at -0.40005 0 270)
			(size 0.4572 0.508)
			(layers "B.Cu" "B.Mask" "B.Paste")
			(net "PE_SW_BMC_PERST_L")
		)
		(pad "2" smd rect
			(at 0.40005 0 270)
			(size 0.4572 0.508)
			(layers "B.Cu" "B.Mask" "B.Paste")
			(net "RST_BMC_NODE1_PERST_L")
		)
	)
	(footprint ""
		(layer "B.Cu")
		(at 137.970006 -41.50741 180)
		(property "Reference" "R1080"
			(at 4.172458 -18.349722 0)
			(unlocked yes)
			(layer "B.SilkS")
			(effects
				(font
					(size 0.7874 0.5842)
					(thickness 0.1524)
				)
				(justify left mirror)
			)
		)
		(property "Value" ""
			(at 0 0 0)
			(layer "B.Fab")
			(effects
				(font
					(size 1.27 1.27)
				)
				(justify mirror)
			)
		)
		(duplicate_pad_numbers_are_jumpers no)
		(fp_line
			(start 0.7874 0.4064)
			(end 0.7874 -0.4064)
			(stroke
				(width 0.1524)
				(type default)
			)
			(layer "B.SilkS")
		)
		(fp_line
			(start 0.7874 -0.4064)
			(end -0.7874 -0.4064)
			(stroke
				(width 0.1524)
				(type default)
			)
			(layer "B.SilkS")
		)
		(fp_line
			(start -0.7874 0.4064)
			(end 0.7874 0.4064)
			(stroke
				(width 0.1524)
				(type default)
			)
			(layer "B.SilkS")
		)
		(fp_line
			(start -0.7874 -0.4064)
			(end -0.7874 0.4064)
			(stroke
				(width 0.1524)
				(type default)
			)
			(layer "B.SilkS")
		)
		(fp_poly
			(pts
				(xy 0.508 0.2794) (xy 0.508 0.2286) (xy 0.635 0.2286) (xy 0.635 -0.254) (xy 0.5334 -0.254) (xy 0.5334 -0.2794)
				(xy -0.5334 -0.2794) (xy -0.5334 -0.254) (xy -0.635 -0.254) (xy -0.635 0.254) (xy -0.5334 0.254)
				(xy -0.5334 0.2794)
			)
			(stroke
				(width 0)
				(type default)
			)
			(fill no)
			(layer "B.CrtYd")
		)
		(pad "1" smd rect
			(at -0.40005 0)
			(size 0.4572 0.508)
			(layers "B.Cu" "B.Mask" "B.Paste")
			(net "SIO_JTAG_CPLD2_TDO")
		)
		(pad "2" smd rect
			(at 0.40005 0)
			(size 0.4572 0.508)
			(layers "B.Cu" "B.Mask" "B.Paste")
			(net "JTAG_CPLD2_TDO")
		)
	)
	(footprint ""
		(layer "B.Cu")
		(at 71.006208 -21.166582 90)
		(property "Reference" "C156"
			(at -5.87629 -0.810006 270)
			(unlocked yes)
			(layer "B.SilkS")
			(effects
				(font
					(size 0.7874 0.5842)
					(thickness 0.1524)
				)
				(justify left mirror)
			)
		)
		(property "Value" ""
			(at 0 0 90)
			(layer "B.Fab")
			(effects
				(font
					(size 1.27 1.27)
				)
				(justify mirror)
			)
		)
		(duplicate_pad_numbers_are_jumpers no)
		(fp_line
			(start 0.7874 -0.4064)
			(end -0.7874 -0.4064)
			(stroke
				(width 0.1524)
				(type default)
			)
			(layer "B.SilkS")
		)
		(fp_line
			(start -0.7874 -0.4064)
			(end -0.7874 0.4064)
			(stroke
				(width 0.1524)
				(type default)
			)
			(layer "B.SilkS")
		)
		(fp_line
			(start 0 0.381)
			(end 0 -0.381)
			(stroke
				(width 0.1524)
				(type default)
			)
			(layer "B.SilkS")
		)
		(fp_line
			(start 0.7874 0.4064)
			(end 0.7874 -0.4064)
			(stroke
				(width 0.1524)
				(type default)
			)
			(layer "B.SilkS")
		)
		(fp_line
			(start -0.7874 0.4064)
			(end 0.7874 0.4064)
			(stroke
				(width 0.1524)
				(type default)
			)
			(layer "B.SilkS")
		)
		(fp_poly
			(pts
				(xy 0.5334 0.254) (xy 0.635 0.254) (xy 0.635 0.2286) (xy 0.635 -0.254) (xy 0.5334 -0.254) (xy 0.5334 -0.2794)
				(xy -0.5334 -0.2794) (xy -0.5334 -0.254) (xy -0.635 -0.254) (xy -0.635 0.254) (xy -0.5334 0.254)
				(xy -0.5334 0.2794) (xy 0.508 0.2794) (xy 0.5334 0.2794)
			)
			(stroke
				(width 0)
				(type default)
			)
			(fill no)
			(layer "B.CrtYd")
		)
		(pad "1" smd rect
			(at -0.40005 0 270)
			(size 0.4572 0.508)
			(layers "B.Cu" "B.Mask" "B.Paste")
			(net "PV_VDDR_NODE1")
		)
		(pad "2" smd rect
			(at 0.40005 0 270)
			(size 0.4572 0.508)
			(layers "B.Cu" "B.Mask" "B.Paste")
			(net "GND")
		)
	)
	(footprint ""
		(layer "B.Cu")
		(at 152.562814 -67.232022 -90)
		(property "Reference" "C361"
			(at -0.02159 -5.145786 270)
			(unlocked yes)
			(layer "B.SilkS")
			(effects
				(font
					(size 0.7874 0.5842)
					(thickness 0.1524)
				)
				(justify left mirror)
			)
		)
		(property "Value" ""
			(at 0 0 90)
			(layer "B.Fab")
			(effects
				(font
					(size 1.27 1.27)
				)
				(justify mirror)
			)
		)
		(duplicate_pad_numbers_are_jumpers no)
		(fp_line
			(start -0.7874 0.4064)
			(end 0.7874 0.4064)
			(stroke
				(width 0.1524)
				(type default)
			)
			(layer "B.SilkS")
		)
		(fp_line
			(start 0.7874 0.4064)
			(end 0.7874 -0.4064)
			(stroke
				(width 0.1524)
				(type default)
			)
			(layer "B.SilkS")
		)
		(fp_line
			(start 0 0.381)
			(end 0 -0.381)
			(stroke
				(width 0.1524)
				(type default)
			)
			(layer "B.SilkS")
		)
		(fp_line
			(start -0.7874 -0.4064)
			(end -0.7874 0.4064)
			(stroke
				(width 0.1524)
				(type default)
			)
			(layer "B.SilkS")
		)
		(fp_line
			(start 0.7874 -0.4064)
			(end -0.7874 -0.4064)
			(stroke
				(width 0.1524)
				(type default)
			)
			(layer "B.SilkS")
		)
		(fp_poly
			(pts
				(xy 0.5334 0.254) (xy 0.635 0.254) (xy 0.635 0.2286) (xy 0.635 -0.254) (xy 0.5334 -0.254) (xy 0.5334 -0.2794)
				(xy -0.5334 -0.2794) (xy -0.5334 -0.254) (xy -0.635 -0.254) (xy -0.635 0.254) (xy -0.5334 0.254)
				(xy -0.5334 0.2794) (xy 0.508 0.2794) (xy 0.5334 0.2794)
			)
			(stroke
				(width 0)
				(type default)
			)
			(fill no)
			(layer "B.CrtYd")
		)
		(pad "1" smd rect
			(at -0.40005 0 90)
			(size 0.4572 0.508)
			(layers "B.Cu" "B.Mask" "B.Paste")
			(net "GND")
		)
		(pad "2" smd rect
			(at 0.40005 0 90)
			(size 0.4572 0.508)
			(layers "B.Cu" "B.Mask" "B.Paste")
			(net "P1V8_SATA_VAA1_NODE1")
		)
	)
	(footprint ""
		(layer "B.Cu")
		(at 56.86298 -62.869826)
		(property "Reference" "R28"
			(at -14.72438 29.520896 0)
			(unlocked yes)
			(layer "B.SilkS")
			(effects
				(font
					(size 0.7874 0.5842)
					(thickness 0.1524)
				)
				(justify left mirror)
			)
		)
		(property "Value" ""
			(at 0 0 0)
			(layer "B.Fab")
			(effects
				(font
					(size 1.27 1.27)
				)
				(justify mirror)
			)
		)
		(duplicate_pad_numbers_are_jumpers no)
		(fp_line
			(start -0.7874 -0.4064)
			(end -0.7874 0.4064)
			(stroke
				(width 0.1524)
				(type default)
			)
			(layer "B.SilkS")
		)
		(fp_line
			(start -0.7874 0.4064)
			(end 0.7874 0.4064)
			(stroke
				(width 0.1524)
				(type default)
			)
			(layer "B.SilkS")
		)
		(fp_line
			(start 0.7874 -0.4064)
			(end -0.7874 -0.4064)
			(stroke
				(width 0.1524)
				(type default)
			)
			(layer "B.SilkS")
		)
		(fp_line
			(start 0.7874 0.4064)
			(end 0.7874 -0.4064)
			(stroke
				(width 0.1524)
				(type default)
			)
			(layer "B.SilkS")
		)
		(fp_poly
			(pts
				(xy 0.508 0.2794) (xy 0.508 0.2286) (xy 0.635 0.2286) (xy 0.635 -0.254) (xy 0.5334 -0.254) (xy 0.5334 -0.2794)
				(xy -0.5334 -0.2794) (xy -0.5334 -0.254) (xy -0.635 -0.254) (xy -0.635 0.254) (xy -0.5334 0.254)
				(xy -0.5334 0.2794)
			)
			(stroke
				(width 0)
				(type default)
			)
			(fill no)
			(layer "B.CrtYd")
		)
		(pad "1" smd rect
			(at -0.40005 0 180)
			(size 0.4572 0.508)
			(layers "B.Cu" "B.Mask" "B.Paste")
			(net "GND")
		)
		(pad "2" smd rect
			(at 0.40005 0 180)
			(size 0.4572 0.508)
			(layers "B.Cu" "B.Mask" "B.Paste")
			(net "M_DDR3_NODE1_CMDPU")
		)
	)
	(footprint ""
		(layer "B.Cu")
		(at 115.010184 -162.251644)
		(property "Reference" "C590"
			(at 1.710436 2.15265 0)
			(unlocked yes)
			(layer "B.SilkS")
			(effects
				(font
					(size 0.7874 0.5842)
					(thickness 0.1524)
				)
				(justify left mirror)
			)
		)
		(property "Value" ""
			(at 0 0 0)
			(layer "B.Fab")
			(effects
				(font
					(size 1.27 1.27)
				)
				(justify mirror)
			)
		)
		(duplicate_pad_numbers_are_jumpers no)
		(fp_line
			(start -0.7874 -0.4064)
			(end -0.7874 0.4064)
			(stroke
				(width 0.1524)
				(type default)
			)
			(layer "B.SilkS")
		)
		(fp_line
			(start -0.7874 0.4064)
			(end 0.7874 0.4064)
			(stroke
				(width 0.1524)
				(type default)
			)
			(layer "B.SilkS")
		)
		(fp_line
			(start 0 0.381)
			(end 0 -0.381)
			(stroke
				(width 0.1524)
				(type default)
			)
			(layer "B.SilkS")
		)
		(fp_line
			(start 0.7874 -0.4064)
			(end -0.7874 -0.4064)
			(stroke
				(width 0.1524)
				(type default)
			)
			(layer "B.SilkS")
		)
		(fp_line
			(start 0.7874 0.4064)
			(end 0.7874 -0.4064)
			(stroke
				(width 0.1524)
				(type default)
			)
			(layer "B.SilkS")
		)
		(fp_poly
			(pts
				(xy 0.5334 0.254) (xy 0.635 0.254) (xy 0.635 0.2286) (xy 0.635 -0.254) (xy 0.5334 -0.254) (xy 0.5334 -0.2794)
				(xy -0.5334 -0.2794) (xy -0.5334 -0.254) (xy -0.635 -0.254) (xy -0.635 0.254) (xy -0.5334 0.254)
				(xy -0.5334 0.2794) (xy 0.508 0.2794) (xy 0.5334 0.2794)
			)
			(stroke
				(width 0)
				(type default)
			)
			(fill no)
			(layer "B.CrtYd")
		)
		(pad "1" smd rect
			(at -0.40005 0 180)
			(size 0.4572 0.508)
			(layers "B.Cu" "B.Mask" "B.Paste")
			(net "GND")
		)
		(pad "2" smd rect
			(at 0.40005 0 180)
			(size 0.4572 0.508)
			(layers "B.Cu" "B.Mask" "B.Paste")
			(net "I2C_COM3_SDA_RC")
		)
	)
	(footprint ""
		(layer "B.Cu")
		(at 128.701546 -37.258244 180)
		(property "Reference" "R1210"
			(at -0.438658 -7.56793 0)
			(unlocked yes)
			(layer "B.SilkS")
			(effects
				(font
					(size 0.7874 0.5842)
					(thickness 0.1524)
				)
				(justify left mirror)
			)
		)
		(property "Value" ""
			(at 0 0 0)
			(layer "B.Fab")
			(effects
				(font
					(size 1.27 1.27)
				)
				(justify mirror)
			)
		)
		(duplicate_pad_numbers_are_jumpers no)
		(fp_line
			(start 0.7874 0.4064)
			(end 0.7874 -0.4064)
			(stroke
				(width 0.1524)
				(type default)
			)
			(layer "B.SilkS")
		)
		(fp_line
			(start 0.7874 -0.4064)
			(end -0.7874 -0.4064)
			(stroke
				(width 0.1524)
				(type default)
			)
			(layer "B.SilkS")
		)
		(fp_line
			(start -0.7874 0.4064)
			(end 0.7874 0.4064)
			(stroke
				(width 0.1524)
				(type default)
			)
			(layer "B.SilkS")
		)
		(fp_line
			(start -0.7874 -0.4064)
			(end -0.7874 0.4064)
			(stroke
				(width 0.1524)
				(type default)
			)
			(layer "B.SilkS")
		)
		(fp_poly
			(pts
				(xy 0.508 0.2794) (xy 0.508 0.2286) (xy 0.635 0.2286) (xy 0.635 -0.254) (xy 0.5334 -0.254) (xy 0.5334 -0.2794)
				(xy -0.5334 -0.2794) (xy -0.5334 -0.254) (xy -0.635 -0.254) (xy -0.635 0.254) (xy -0.5334 0.254)
				(xy -0.5334 0.2794)
			)
			(stroke
				(width 0)
				(type default)
			)
			(fill no)
			(layer "B.CrtYd")
		)
		(pad "1" smd rect
			(at -0.40005 0)
			(size 0.4572 0.508)
			(layers "B.Cu" "B.Mask" "B.Paste")
			(net "SIO_JTAG_CPLD3_TCK")
		)
		(pad "2" smd rect
			(at 0.40005 0)
			(size 0.4572 0.508)
			(layers "B.Cu" "B.Mask" "B.Paste")
			(net "GND")
		)
	)
	(footprint ""
		(layer "B.Cu")
		(at 78.83144 -166.409624 180)
		(property "Reference" "R791"
			(at -30.555946 -20.918678 0)
			(unlocked yes)
			(layer "B.SilkS")
			(effects
				(font
					(size 0.7874 0.5842)
					(thickness 0.1524)
				)
				(justify left mirror)
			)
		)
		(property "Value" ""
			(at 0 0 0)
			(layer "B.Fab")
			(effects
				(font
					(size 1.27 1.27)
				)
				(justify mirror)
			)
		)
		(duplicate_pad_numbers_are_jumpers no)
		(fp_line
			(start 0.7874 0.4064)
			(end 0.7874 -0.4064)
			(stroke
				(width 0.1524)
				(type default)
			)
			(layer "B.SilkS")
		)
		(fp_line
			(start 0.7874 -0.4064)
			(end -0.7874 -0.4064)
			(stroke
				(width 0.1524)
				(type default)
			)
			(layer "B.SilkS")
		)
		(fp_line
			(start -0.7874 0.4064)
			(end 0.7874 0.4064)
			(stroke
				(width 0.1524)
				(type default)
			)
			(layer "B.SilkS")
		)
		(fp_line
			(start -0.7874 -0.4064)
			(end -0.7874 0.4064)
			(stroke
				(width 0.1524)
				(type default)
			)
			(layer "B.SilkS")
		)
		(fp_poly
			(pts
				(xy 0.508 0.2794) (xy 0.508 0.2286) (xy 0.635 0.2286) (xy 0.635 -0.254) (xy 0.5334 -0.254) (xy 0.5334 -0.2794)
				(xy -0.5334 -0.2794) (xy -0.5334 -0.254) (xy -0.635 -0.254) (xy -0.635 0.254) (xy -0.5334 0.254)
				(xy -0.5334 0.2794)
			)
			(stroke
				(width 0)
				(type default)
			)
			(fill no)
			(layer "B.CrtYd")
		)
		(pad "1" smd rect
			(at -0.40005 0)
			(size 0.4572 0.508)
			(layers "B.Cu" "B.Mask" "B.Paste")
			(net "UART_SW_S5_N")
		)
		(pad "2" smd rect
			(at 0.40005 0)
			(size 0.4572 0.508)
			(layers "B.Cu" "B.Mask" "B.Paste")
			(net "P3V3_NODE1")
		)
	)
	(footprint ""
		(layer "B.Cu")
		(at 42.78122 -159.13989 -90)
		(property "Reference" "C409"
			(at -7.11327 6.84276 270)
			(unlocked yes)
			(layer "B.SilkS")
			(effects
				(font
					(size 0.7874 0.5842)
					(thickness 0.1524)
				)
				(justify left mirror)
			)
		)
		(property "Value" ""
			(at 0 0 90)
			(layer "B.Fab")
			(effects
				(font
					(size 1.27 1.27)
				)
				(justify mirror)
			)
		)
		(duplicate_pad_numbers_are_jumpers no)
		(fp_line
			(start -0.7874 0.4064)
			(end 0.7874 0.4064)
			(stroke
				(width 0.1524)
				(type default)
			)
			(layer "B.SilkS")
		)
		(fp_line
			(start 0.7874 0.4064)
			(end 0.7874 -0.4064)
			(stroke
				(width 0.1524)
				(type default)
			)
			(layer "B.SilkS")
		)
		(fp_line
			(start 0 0.381)
			(end 0 -0.381)
			(stroke
				(width 0.1524)
				(type default)
			)
			(layer "B.SilkS")
		)
		(fp_line
			(start -0.7874 -0.4064)
			(end -0.7874 0.4064)
			(stroke
				(width 0.1524)
				(type default)
			)
			(layer "B.SilkS")
		)
		(fp_line
			(start 0.7874 -0.4064)
			(end -0.7874 -0.4064)
			(stroke
				(width 0.1524)
				(type default)
			)
			(layer "B.SilkS")
		)
		(fp_poly
			(pts
				(xy 0.5334 0.254) (xy 0.635 0.254) (xy 0.635 0.2286) (xy 0.635 -0.254) (xy 0.5334 -0.254) (xy 0.5334 -0.2794)
				(xy -0.5334 -0.2794) (xy -0.5334 -0.254) (xy -0.635 -0.254) (xy -0.635 0.254) (xy -0.5334 0.254)
				(xy -0.5334 0.2794) (xy 0.508 0.2794) (xy 0.5334 0.2794)
			)
			(stroke
				(width 0)
				(type default)
			)
			(fill no)
			(layer "B.CrtYd")
		)
		(pad "1" smd rect
			(at -0.40005 0 90)
			(size 0.4572 0.508)
			(layers "B.Cu" "B.Mask" "B.Paste")
			(net "P1V9_LAN1")
		)
		(pad "2" smd rect
			(at 0.40005 0 90)
			(size 0.4572 0.508)
			(layers "B.Cu" "B.Mask" "B.Paste")
			(net "GND")
		)
	)
	(footprint ""
		(layer "B.Cu")
		(at 116.586 -51.943 -90)
		(property "Reference" "R1289"
			(at -1.27 0.02667 270)
			(unlocked yes)
			(layer "B.SilkS")
			(effects
				(font
					(size 0.7874 0.5842)
					(thickness 0.1524)
				)
				(justify left mirror)
			)
		)
		(property "Value" ""
			(at 0 0 90)
			(layer "B.Fab")
			(effects
				(font
					(size 1.27 1.27)
				)
				(justify mirror)
			)
		)
		(duplicate_pad_numbers_are_jumpers no)
		(fp_line
			(start -0.7874 0.4064)
			(end 0.7874 0.4064)
			(stroke
				(width 0.1524)
				(type default)
			)
			(layer "B.SilkS")
		)
		(fp_line
			(start 0.7874 0.4064)
			(end 0.7874 -0.4064)
			(stroke
				(width 0.1524)
				(type default)
			)
			(layer "B.SilkS")
		)
		(fp_line
			(start -0.7874 -0.4064)
			(end -0.7874 0.4064)
			(stroke
				(width 0.1524)
				(type default)
			)
			(layer "B.SilkS")
		)
		(fp_line
			(start 0.7874 -0.4064)
			(end -0.7874 -0.4064)
			(stroke
				(width 0.1524)
				(type default)
			)
			(layer "B.SilkS")
		)
		(fp_poly
			(pts
				(xy 0.508 0.2794) (xy 0.508 0.2286) (xy 0.635 0.2286) (xy 0.635 -0.254) (xy 0.5334 -0.254) (xy 0.5334 -0.2794)
				(xy -0.5334 -0.2794) (xy -0.5334 -0.254) (xy -0.635 -0.254) (xy -0.635 0.254) (xy -0.5334 0.254)
				(xy -0.5334 0.2794)
			)
			(stroke
				(width 0)
				(type default)
			)
			(fill no)
			(layer "B.CrtYd")
		)
		(pad "1" smd rect
			(at -0.40005 0 90)
			(size 0.4572 0.508)
			(layers "B.Cu" "B.Mask" "B.Paste")
			(net "SIO_JTAG_CPLD1_TDI_R")
		)
		(pad "2" smd rect
			(at 0.40005 0 90)
			(size 0.4572 0.508)
			(layers "B.Cu" "B.Mask" "B.Paste")
			(net "P3V3_NODE1")
		)
	)
	(footprint ""
		(layer "B.Cu")
		(at 64.899286 -118.758462 -90)
		(property "Reference" "R334"
			(at 5.056632 0.107188 270)
			(unlocked yes)
			(layer "B.SilkS")
			(effects
				(font
					(size 0.7874 0.5842)
					(thickness 0.1524)
				)
				(justify left mirror)
			)
		)
		(property "Value" ""
			(at 0 0 90)
			(layer "B.Fab")
			(effects
				(font
					(size 1.27 1.27)
				)
				(justify mirror)
			)
		)
		(duplicate_pad_numbers_are_jumpers no)
		(fp_line
			(start -0.7874 0.4064)
			(end 0.7874 0.4064)
			(stroke
				(width 0.1524)
				(type default)
			)
			(layer "B.SilkS")
		)
		(fp_line
			(start 0.7874 0.4064)
			(end 0.7874 -0.4064)
			(stroke
				(width 0.1524)
				(type default)
			)
			(layer "B.SilkS")
		)
		(fp_line
			(start -0.7874 -0.4064)
			(end -0.7874 0.4064)
			(stroke
				(width 0.1524)
				(type default)
			)
			(layer "B.SilkS")
		)
		(fp_line
			(start 0.7874 -0.4064)
			(end -0.7874 -0.4064)
			(stroke
				(width 0.1524)
				(type default)
			)
			(layer "B.SilkS")
		)
		(fp_poly
			(pts
				(xy 0.508 0.2794) (xy 0.508 0.2286) (xy 0.635 0.2286) (xy 0.635 -0.254) (xy 0.5334 -0.254) (xy 0.5334 -0.2794)
				(xy -0.5334 -0.2794) (xy -0.5334 -0.254) (xy -0.635 -0.254) (xy -0.635 0.254) (xy -0.5334 0.254)
				(xy -0.5334 0.2794)
			)
			(stroke
				(width 0)
				(type default)
			)
			(fill no)
			(layer "B.CrtYd")
		)
		(pad "1" smd rect
			(at -0.40005 0 90)
			(size 0.4572 0.508)
			(layers "B.Cu" "B.Mask" "B.Paste")
			(net "P3V3_NODE1")
		)
		(pad "2" smd rect
			(at 0.40005 0 90)
			(size 0.4572 0.508)
			(layers "B.Cu" "B.Mask" "B.Paste")
			(net "BMC_ROMA18")
		)
	)
	(footprint ""
		(layer "B.Cu")
		(at 60.81776 -188.126624 -90)
		(property "Reference" "C679"
			(at -4.276598 0.006096 270)
			(unlocked yes)
			(layer "B.SilkS")
			(effects
				(font
					(size 0.7874 0.5842)
					(thickness 0.1524)
				)
				(justify left mirror)
			)
		)
		(property "Value" ""
			(at 0 0 90)
			(layer "B.Fab")
			(effects
				(font
					(size 1.27 1.27)
				)
				(justify mirror)
			)
		)
		(duplicate_pad_numbers_are_jumpers no)
		(fp_line
			(start -0.7874 0.4064)
			(end 0.7874 0.4064)
			(stroke
				(width 0.1524)
				(type default)
			)
			(layer "B.SilkS")
		)
		(fp_line
			(start 0.7874 0.4064)
			(end 0.7874 -0.4064)
			(stroke
				(width 0.1524)
				(type default)
			)
			(layer "B.SilkS")
		)
		(fp_line
			(start 0 0.381)
			(end 0 -0.381)
			(stroke
				(width 0.1524)
				(type default)
			)
			(layer "B.SilkS")
		)
		(fp_line
			(start -0.7874 -0.4064)
			(end -0.7874 0.4064)
			(stroke
				(width 0.1524)
				(type default)
			)
			(layer "B.SilkS")
		)
		(fp_line
			(start 0.7874 -0.4064)
			(end -0.7874 -0.4064)
			(stroke
				(width 0.1524)
				(type default)
			)
			(layer "B.SilkS")
		)
		(fp_poly
			(pts
				(xy 0.5334 0.254) (xy 0.635 0.254) (xy 0.635 0.2286) (xy 0.635 -0.254) (xy 0.5334 -0.254) (xy 0.5334 -0.2794)
				(xy -0.5334 -0.2794) (xy -0.5334 -0.254) (xy -0.635 -0.254) (xy -0.635 0.254) (xy -0.5334 0.254)
				(xy -0.5334 0.2794) (xy 0.508 0.2794) (xy 0.5334 0.2794)
			)
			(stroke
				(width 0)
				(type default)
			)
			(fill no)
			(layer "B.CrtYd")
		)
		(pad "1" smd rect
			(at -0.40005 0 90)
			(size 0.4572 0.508)
			(layers "B.Cu" "B.Mask" "B.Paste")
			(net "UART_T1_NODE2_TXD_R")
		)
		(pad "2" smd rect
			(at 0.40005 0 90)
			(size 0.4572 0.508)
			(layers "B.Cu" "B.Mask" "B.Paste")
			(net "GND")
		)
	)
	(footprint ""
		(layer "B.Cu")
		(at 147.305014 -74.699622)
		(property "Reference" "L31"
			(at 4.93522 -0.838962 0)
			(unlocked yes)
			(layer "B.SilkS")
			(effects
				(font
					(size 0.7874 0.5842)
					(thickness 0.1524)
				)
				(justify left mirror)
			)
		)
		(property "Value" ""
			(at 0 0 0)
			(layer "B.Fab")
			(effects
				(font
					(size 1.27 1.27)
				)
				(justify mirror)
			)
		)
		(duplicate_pad_numbers_are_jumpers no)
		(fp_line
			(start -0.7874 -0.4064)
			(end -0.7874 0.4064)
			(stroke
				(width 0.1524)
				(type default)
			)
			(layer "B.SilkS")
		)
		(fp_line
			(start -0.7874 0.4064)
			(end 0.7874 0.4064)
			(stroke
				(width 0.1524)
				(type default)
			)
			(layer "B.SilkS")
		)
		(fp_line
			(start -0.0889 0.4064)
			(end -0.0889 -0.4064)
			(stroke
				(width 0.1524)
				(type default)
			)
			(layer "B.SilkS")
		)
		(fp_line
			(start 0.0889 0.4064)
			(end 0.0889 -0.4064)
			(stroke
				(width 0.1524)
				(type default)
			)
			(layer "B.SilkS")
		)
		(fp_line
			(start 0.7874 -0.4064)
			(end -0.7874 -0.4064)
			(stroke
				(width 0.1524)
				(type default)
			)
			(layer "B.SilkS")
		)
		(fp_line
			(start 0.7874 0.4064)
			(end 0.7874 -0.4064)
			(stroke
				(width 0.1524)
				(type default)
			)
			(layer "B.SilkS")
		)
		(fp_poly
			(pts
				(xy 0.5334 0.254) (xy 0.635 0.254) (xy 0.635 0.2286) (xy 0.635 -0.254) (xy 0.5334 -0.254) (xy 0.5334 -0.2794)
				(xy -0.5334 -0.2794) (xy -0.5334 -0.254) (xy -0.635 -0.254) (xy -0.635 0.254) (xy -0.5334 0.254)
				(xy -0.5334 0.2794) (xy 0.508 0.2794) (xy 0.5334 0.2794)
			)
			(stroke
				(width 0)
				(type default)
			)
			(fill no)
			(layer "B.CrtYd")
		)
		(pad "1" smd rect
			(at -0.40005 0 180)
			(size 0.4572 0.508)
			(layers "B.Cu" "B.Mask" "B.Paste")
			(net "P1V8_NODE1")
		)
		(pad "2" smd rect
			(at 0.40005 0 180)
			(size 0.4572 0.508)
			(layers "B.Cu" "B.Mask" "B.Paste")
			(net "P1V8_SATA_AVDD_NODE1")
		)
	)
	(footprint ""
		(layer "B.Cu")
		(at 59.67476 -188.126624 90)
		(property "Reference" "R919"
			(at 4.276598 0.050546 270)
			(unlocked yes)
			(layer "B.SilkS")
			(effects
				(font
					(size 0.7874 0.5842)
					(thickness 0.1524)
				)
				(justify left mirror)
			)
		)
		(property "Value" ""
			(at 0 0 90)
			(layer "B.Fab")
			(effects
				(font
					(size 1.27 1.27)
				)
				(justify mirror)
			)
		)
		(duplicate_pad_numbers_are_jumpers no)
		(fp_line
			(start 0.7874 -0.4064)
			(end -0.7874 -0.4064)
			(stroke
				(width 0.1524)
				(type default)
			)
			(layer "B.SilkS")
		)
		(fp_line
			(start -0.7874 -0.4064)
			(end -0.7874 0.4064)
			(stroke
				(width 0.1524)
				(type default)
			)
			(layer "B.SilkS")
		)
		(fp_line
			(start 0.7874 0.4064)
			(end 0.7874 -0.4064)
			(stroke
				(width 0.1524)
				(type default)
			)
			(layer "B.SilkS")
		)
		(fp_line
			(start -0.7874 0.4064)
			(end 0.7874 0.4064)
			(stroke
				(width 0.1524)
				(type default)
			)
			(layer "B.SilkS")
		)
		(fp_poly
			(pts
				(xy 0.508 0.2794) (xy 0.508 0.2286) (xy 0.635 0.2286) (xy 0.635 -0.254) (xy 0.5334 -0.254) (xy 0.5334 -0.2794)
				(xy -0.5334 -0.2794) (xy -0.5334 -0.254) (xy -0.635 -0.254) (xy -0.635 0.254) (xy -0.5334 0.254)
				(xy -0.5334 0.2794)
			)
			(stroke
				(width 0)
				(type default)
			)
			(fill no)
			(layer "B.CrtYd")
		)
		(pad "1" smd rect
			(at -0.40005 0 270)
			(size 0.4572 0.508)
			(layers "B.Cu" "B.Mask" "B.Paste")
			(net "UART_T1_NODE3_RXD")
		)
		(pad "2" smd rect
			(at 0.40005 0 270)
			(size 0.4572 0.508)
			(layers "B.Cu" "B.Mask" "B.Paste")
			(net "UART_T1_NODE3_RXD_R")
		)
	)
	(footprint ""
		(layer "B.Cu")
		(at 137.970006 -37.44341 180)
		(property "Reference" "R1187"
			(at 3.629406 -18.52168 0)
			(unlocked yes)
			(layer "B.SilkS")
			(effects
				(font
					(size 0.7874 0.5842)
					(thickness 0.1524)
				)
				(justify left mirror)
			)
		)
		(property "Value" ""
			(at 0 0 0)
			(layer "B.Fab")
			(effects
				(font
					(size 1.27 1.27)
				)
				(justify mirror)
			)
		)
		(duplicate_pad_numbers_are_jumpers no)
		(fp_line
			(start 0.7874 0.4064)
			(end 0.7874 -0.4064)
			(stroke
				(width 0.1524)
				(type default)
			)
			(layer "B.SilkS")
		)
		(fp_line
			(start 0.7874 -0.4064)
			(end -0.7874 -0.4064)
			(stroke
				(width 0.1524)
				(type default)
			)
			(layer "B.SilkS")
		)
		(fp_line
			(start -0.7874 0.4064)
			(end 0.7874 0.4064)
			(stroke
				(width 0.1524)
				(type default)
			)
			(layer "B.SilkS")
		)
		(fp_line
			(start -0.7874 -0.4064)
			(end -0.7874 0.4064)
			(stroke
				(width 0.1524)
				(type default)
			)
			(layer "B.SilkS")
		)
		(fp_poly
			(pts
				(xy 0.508 0.2794) (xy 0.508 0.2286) (xy 0.635 0.2286) (xy 0.635 -0.254) (xy 0.5334 -0.254) (xy 0.5334 -0.2794)
				(xy -0.5334 -0.2794) (xy -0.5334 -0.254) (xy -0.635 -0.254) (xy -0.635 0.254) (xy -0.5334 0.254)
				(xy -0.5334 0.2794)
			)
			(stroke
				(width 0)
				(type default)
			)
			(fill no)
			(layer "B.CrtYd")
		)
		(pad "1" smd rect
			(at -0.40005 0)
			(size 0.4572 0.508)
			(layers "B.Cu" "B.Mask" "B.Paste")
			(net "SIO_JTAG_CPLD2_TDI_R")
		)
		(pad "2" smd rect
			(at 0.40005 0)
			(size 0.4572 0.508)
			(layers "B.Cu" "B.Mask" "B.Paste")
			(net "SIO_JTAG_CPLD2_TDI")
		)
	)
	(footprint ""
		(layer "B.Cu")
		(at 64.109346 -66.988182 -90)
		(property "Reference" "C119"
			(at 35.382454 14.578076 270)
			(unlocked yes)
			(layer "B.SilkS")
			(effects
				(font
					(size 0.7874 0.5842)
					(thickness 0.1524)
				)
				(justify left mirror)
			)
		)
		(property "Value" ""
			(at 0 0 90)
			(layer "B.Fab")
			(effects
				(font
					(size 1.27 1.27)
				)
				(justify mirror)
			)
		)
		(duplicate_pad_numbers_are_jumpers no)
		(fp_line
			(start -0.7874 0.4064)
			(end 0.7874 0.4064)
			(stroke
				(width 0.1524)
				(type default)
			)
			(layer "B.SilkS")
		)
		(fp_line
			(start 0.7874 0.4064)
			(end 0.7874 -0.4064)
			(stroke
				(width 0.1524)
				(type default)
			)
			(layer "B.SilkS")
		)
		(fp_line
			(start 0 0.381)
			(end 0 -0.381)
			(stroke
				(width 0.1524)
				(type default)
			)
			(layer "B.SilkS")
		)
		(fp_line
			(start -0.7874 -0.4064)
			(end -0.7874 0.4064)
			(stroke
				(width 0.1524)
				(type default)
			)
			(layer "B.SilkS")
		)
		(fp_line
			(start 0.7874 -0.4064)
			(end -0.7874 -0.4064)
			(stroke
				(width 0.1524)
				(type default)
			)
			(layer "B.SilkS")
		)
		(fp_poly
			(pts
				(xy 0.5334 0.254) (xy 0.635 0.254) (xy 0.635 0.2286) (xy 0.635 -0.254) (xy 0.5334 -0.254) (xy 0.5334 -0.2794)
				(xy -0.5334 -0.2794) (xy -0.5334 -0.254) (xy -0.635 -0.254) (xy -0.635 0.254) (xy -0.5334 0.254)
				(xy -0.5334 0.2794) (xy 0.508 0.2794) (xy 0.5334 0.2794)
			)
			(stroke
				(width 0)
				(type default)
			)
			(fill no)
			(layer "B.CrtYd")
		)
		(pad "1" smd rect
			(at -0.40005 0 90)
			(size 0.4572 0.508)
			(layers "B.Cu" "B.Mask" "B.Paste")
			(net "PV_VDDR_NODE1")
		)
		(pad "2" smd rect
			(at 0.40005 0 90)
			(size 0.4572 0.508)
			(layers "B.Cu" "B.Mask" "B.Paste")
			(net "GND")
		)
	)
	(footprint ""
		(layer "B.Cu")
		(at 26.37282 -164.748718)
		(property "Reference" "C511"
			(at 0.4826 2.188972 0)
			(unlocked yes)
			(layer "B.SilkS")
			(effects
				(font
					(size 0.7874 0.5842)
					(thickness 0.1524)
				)
				(justify left mirror)
			)
		)
		(property "Value" ""
			(at 0 0 0)
			(layer "B.Fab")
			(effects
				(font
					(size 1.27 1.27)
				)
				(justify mirror)
			)
		)
		(duplicate_pad_numbers_are_jumpers no)
		(fp_line
			(start -0.7874 -0.4064)
			(end -0.7874 0.4064)
			(stroke
				(width 0.1524)
				(type default)
			)
			(layer "B.SilkS")
		)
		(fp_line
			(start -0.7874 0.4064)
			(end 0.7874 0.4064)
			(stroke
				(width 0.1524)
				(type default)
			)
			(layer "B.SilkS")
		)
		(fp_line
			(start 0 0.381)
			(end 0 -0.381)
			(stroke
				(width 0.1524)
				(type default)
			)
			(layer "B.SilkS")
		)
		(fp_line
			(start 0.7874 -0.4064)
			(end -0.7874 -0.4064)
			(stroke
				(width 0.1524)
				(type default)
			)
			(layer "B.SilkS")
		)
		(fp_line
			(start 0.7874 0.4064)
			(end 0.7874 -0.4064)
			(stroke
				(width 0.1524)
				(type default)
			)
			(layer "B.SilkS")
		)
		(fp_poly
			(pts
				(xy 0.5334 0.254) (xy 0.635 0.254) (xy 0.635 0.2286) (xy 0.635 -0.254) (xy 0.5334 -0.254) (xy 0.5334 -0.2794)
				(xy -0.5334 -0.2794) (xy -0.5334 -0.254) (xy -0.635 -0.254) (xy -0.635 0.254) (xy -0.5334 0.254)
				(xy -0.5334 0.2794) (xy 0.508 0.2794) (xy 0.5334 0.2794)
			)
			(stroke
				(width 0)
				(type default)
			)
			(fill no)
			(layer "B.CrtYd")
		)
		(pad "1" smd rect
			(at -0.40005 0 180)
			(size 0.4572 0.508)
			(layers "B.Cu" "B.Mask" "B.Paste")
			(net "P1V9_LAN1")
		)
		(pad "2" smd rect
			(at 0.40005 0 180)
			(size 0.4572 0.508)
			(layers "B.Cu" "B.Mask" "B.Paste")
			(net "GND")
		)
	)
	(footprint ""
		(layer "B.Cu")
		(at 55.8165 -75.445874 180)
		(property "Reference" "C129"
			(at 13.379196 -31.487364 0)
			(unlocked yes)
			(layer "B.SilkS")
			(effects
				(font
					(size 0.7874 0.5842)
					(thickness 0.1524)
				)
				(justify left mirror)
			)
		)
		(property "Value" ""
			(at 0 0 0)
			(layer "B.Fab")
			(effects
				(font
					(size 1.27 1.27)
				)
				(justify mirror)
			)
		)
		(duplicate_pad_numbers_are_jumpers no)
		(fp_line
			(start 0.7874 0.4064)
			(end 0.7874 -0.4064)
			(stroke
				(width 0.1524)
				(type default)
			)
			(layer "B.SilkS")
		)
		(fp_line
			(start 0.7874 -0.4064)
			(end -0.7874 -0.4064)
			(stroke
				(width 0.1524)
				(type default)
			)
			(layer "B.SilkS")
		)
		(fp_line
			(start 0 0.381)
			(end 0 -0.381)
			(stroke
				(width 0.1524)
				(type default)
			)
			(layer "B.SilkS")
		)
		(fp_line
			(start -0.7874 0.4064)
			(end 0.7874 0.4064)
			(stroke
				(width 0.1524)
				(type default)
			)
			(layer "B.SilkS")
		)
		(fp_line
			(start -0.7874 -0.4064)
			(end -0.7874 0.4064)
			(stroke
				(width 0.1524)
				(type default)
			)
			(layer "B.SilkS")
		)
		(fp_poly
			(pts
				(xy 0.5334 0.254) (xy 0.635 0.254) (xy 0.635 0.2286) (xy 0.635 -0.254) (xy 0.5334 -0.254) (xy 0.5334 -0.2794)
				(xy -0.5334 -0.2794) (xy -0.5334 -0.254) (xy -0.635 -0.254) (xy -0.635 0.254) (xy -0.5334 0.254)
				(xy -0.5334 0.2794) (xy 0.508 0.2794) (xy 0.5334 0.2794)
			)
			(stroke
				(width 0)
				(type default)
			)
			(fill no)
			(layer "B.CrtYd")
		)
		(pad "1" smd rect
			(at -0.40005 0)
			(size 0.4572 0.508)
			(layers "B.Cu" "B.Mask" "B.Paste")
			(net "P1V05_NODE1")
		)
		(pad "2" smd rect
			(at 0.40005 0)
			(size 0.4572 0.508)
			(layers "B.Cu" "B.Mask" "B.Paste")
			(net "GND")
		)
	)
	(footprint ""
		(layer "B.Cu")
		(at 58.015632 -74.371962 -90)
		(property "Reference" "C123"
			(at 32.731964 14.633702 270)
			(unlocked yes)
			(layer "B.SilkS")
			(effects
				(font
					(size 0.7874 0.5842)
					(thickness 0.1524)
				)
				(justify left mirror)
			)
		)
		(property "Value" ""
			(at 0 0 90)
			(layer "B.Fab")
			(effects
				(font
					(size 1.27 1.27)
				)
				(justify mirror)
			)
		)
		(duplicate_pad_numbers_are_jumpers no)
		(fp_line
			(start -0.7874 0.4064)
			(end 0.7874 0.4064)
			(stroke
				(width 0.1524)
				(type default)
			)
			(layer "B.SilkS")
		)
		(fp_line
			(start 0.7874 0.4064)
			(end 0.7874 -0.4064)
			(stroke
				(width 0.1524)
				(type default)
			)
			(layer "B.SilkS")
		)
		(fp_line
			(start 0 0.381)
			(end 0 -0.381)
			(stroke
				(width 0.1524)
				(type default)
			)
			(layer "B.SilkS")
		)
		(fp_line
			(start -0.7874 -0.4064)
			(end -0.7874 0.4064)
			(stroke
				(width 0.1524)
				(type default)
			)
			(layer "B.SilkS")
		)
		(fp_line
			(start 0.7874 -0.4064)
			(end -0.7874 -0.4064)
			(stroke
				(width 0.1524)
				(type default)
			)
			(layer "B.SilkS")
		)
		(fp_poly
			(pts
				(xy 0.5334 0.254) (xy 0.635 0.254) (xy 0.635 0.2286) (xy 0.635 -0.254) (xy 0.5334 -0.254) (xy 0.5334 -0.2794)
				(xy -0.5334 -0.2794) (xy -0.5334 -0.254) (xy -0.635 -0.254) (xy -0.635 0.254) (xy -0.5334 0.254)
				(xy -0.5334 0.2794) (xy 0.508 0.2794) (xy 0.5334 0.2794)
			)
			(stroke
				(width 0)
				(type default)
			)
			(fill no)
			(layer "B.CrtYd")
		)
		(pad "1" smd rect
			(at -0.40005 0 90)
			(size 0.4572 0.508)
			(layers "B.Cu" "B.Mask" "B.Paste")
			(net "P1V05_NODE1")
		)
		(pad "2" smd rect
			(at 0.40005 0 90)
			(size 0.4572 0.508)
			(layers "B.Cu" "B.Mask" "B.Paste")
			(net "GND")
		)
	)
	(footprint ""
		(layer "B.Cu")
		(at 37.48786 -164.561012 -90)
		(property "Reference" ""
			(at 0 0 90)
			(layer "B.SilkS")
			(hide yes)
			(effects
				(font
					(size 1.27 1.27)
				)
				(justify mirror)
			)
		)
		(property "Value" ""
			(at 0 0 90)
			(layer "B.Fab")
			(effects
				(font
					(size 1.27 1.27)
				)
				(justify mirror)
			)
		)
		(duplicate_pad_numbers_are_jumpers no)
		(fp_poly
			(pts
				(arc
					(start 0 -1.4986)
					(mid 0 1.4986)
					(end 0 -1.4986)
				)
			)
			(stroke
				(width 0)
				(type default)
			)
			(fill no)
			(layer "B.CrtYd")
		)
		(pad "1" smd circle
			(at 0 0 90)
			(size 0.9906 0.9906)
			(layers "B.Cu" "B.Mask" "B.Paste")
			(net "Net_36")
		)
		(zone
			(layer "B.Cu")
			(hatch none 0.5)
			(connect_pads
				(clearance 0)
			)
			(min_thickness 0.25)
			(keepout
				(tracks not_allowed)
				(vias allowed)
				(pads allowed)
				(copperpour not_allowed)
				(footprints allowed)
			)
			(placement
				(enabled no)
				(sheetname "")
			)
			(fill
				(thermal_gap 0.5)
				(thermal_bridge_width 0.5)
				(island_removal_mode 0)
			)
			(polygon
				(pts
					(arc
						(start 39.11346 -164.561012)
						(mid 35.86226 -164.561012)
						(end 39.11346 -164.561012)
					)
				)
			)
		)
	)
	(footprint ""
		(layer "B.Cu")
		(at 115.30076 -188.126624 -90)
		(property "Reference" "C721"
			(at -4.080256 -0.700786 270)
			(unlocked yes)
			(layer "B.SilkS")
			(effects
				(font
					(size 0.7874 0.5842)
					(thickness 0.1524)
				)
				(justify left mirror)
			)
		)
		(property "Value" ""
			(at 0 0 90)
			(layer "B.Fab")
			(effects
				(font
					(size 1.27 1.27)
				)
				(justify mirror)
			)
		)
		(duplicate_pad_numbers_are_jumpers no)
		(fp_line
			(start -0.7874 0.4064)
			(end 0.7874 0.4064)
			(stroke
				(width 0.1524)
				(type default)
			)
			(layer "B.SilkS")
		)
		(fp_line
			(start 0.7874 0.4064)
			(end 0.7874 -0.4064)
			(stroke
				(width 0.1524)
				(type default)
			)
			(layer "B.SilkS")
		)
		(fp_line
			(start 0 0.381)
			(end 0 -0.381)
			(stroke
				(width 0.1524)
				(type default)
			)
			(layer "B.SilkS")
		)
		(fp_line
			(start -0.7874 -0.4064)
			(end -0.7874 0.4064)
			(stroke
				(width 0.1524)
				(type default)
			)
			(layer "B.SilkS")
		)
		(fp_line
			(start 0.7874 -0.4064)
			(end -0.7874 -0.4064)
			(stroke
				(width 0.1524)
				(type default)
			)
			(layer "B.SilkS")
		)
		(fp_poly
			(pts
				(xy 0.5334 0.254) (xy 0.635 0.254) (xy 0.635 0.2286) (xy 0.635 -0.254) (xy 0.5334 -0.254) (xy 0.5334 -0.2794)
				(xy -0.5334 -0.2794) (xy -0.5334 -0.254) (xy -0.635 -0.254) (xy -0.635 0.254) (xy -0.5334 0.254)
				(xy -0.5334 0.2794) (xy 0.508 0.2794) (xy 0.5334 0.2794)
			)
			(stroke
				(width 0)
				(type default)
			)
			(fill no)
			(layer "B.CrtYd")
		)
		(pad "1" smd rect
			(at -0.40005 0 90)
			(size 0.4572 0.508)
			(layers "B.Cu" "B.Mask" "B.Paste")
			(net "UART_T7_NODE1_TXD_R")
		)
		(pad "2" smd rect
			(at 0.40005 0 90)
			(size 0.4572 0.508)
			(layers "B.Cu" "B.Mask" "B.Paste")
			(net "GND")
		)
	)
	(footprint ""
		(layer "B.Cu")
		(at 88.77935 -73.685654)
		(property "Reference" "R161"
			(at -1.91516 9.834118 0)
			(unlocked yes)
			(layer "B.SilkS")
			(effects
				(font
					(size 0.7874 0.5842)
					(thickness 0.1524)
				)
				(justify left mirror)
			)
		)
		(property "Value" ""
			(at 0 0 0)
			(layer "B.Fab")
			(effects
				(font
					(size 1.27 1.27)
				)
				(justify mirror)
			)
		)
		(duplicate_pad_numbers_are_jumpers no)
		(fp_line
			(start -0.7874 -0.4064)
			(end -0.7874 0.4064)
			(stroke
				(width 0.1524)
				(type default)
			)
			(layer "B.SilkS")
		)
		(fp_line
			(start -0.7874 0.4064)
			(end 0.7874 0.4064)
			(stroke
				(width 0.1524)
				(type default)
			)
			(layer "B.SilkS")
		)
		(fp_line
			(start 0.7874 -0.4064)
			(end -0.7874 -0.4064)
			(stroke
				(width 0.1524)
				(type default)
			)
			(layer "B.SilkS")
		)
		(fp_line
			(start 0.7874 0.4064)
			(end 0.7874 -0.4064)
			(stroke
				(width 0.1524)
				(type default)
			)
			(layer "B.SilkS")
		)
		(fp_poly
			(pts
				(xy 0.508 0.2794) (xy 0.508 0.2286) (xy 0.635 0.2286) (xy 0.635 -0.254) (xy 0.5334 -0.254) (xy 0.5334 -0.2794)
				(xy -0.5334 -0.2794) (xy -0.5334 -0.254) (xy -0.635 -0.254) (xy -0.635 0.254) (xy -0.5334 0.254)
				(xy -0.5334 0.2794)
			)
			(stroke
				(width 0)
				(type default)
			)
			(fill no)
			(layer "B.CrtYd")
		)
		(pad "1" smd rect
			(at -0.40005 0 180)
			(size 0.4572 0.508)
			(layers "B.Cu" "B.Mask" "B.Paste")
			(net "GND")
		)
		(pad "2" smd rect
			(at 0.40005 0 180)
			(size 0.4572 0.508)
			(layers "B.Cu" "B.Mask" "B.Paste")
			(net "PD_CPU_NODE1_SPD_EN_L")
		)
	)
	(footprint ""
		(layer "B.Cu")
		(at 26.364184 -163.66363)
		(property "Reference" "C510"
			(at 0.4826 2.188972 0)
			(unlocked yes)
			(layer "B.SilkS")
			(effects
				(font
					(size 0.7874 0.5842)
					(thickness 0.1524)
				)
				(justify left mirror)
			)
		)
		(property "Value" ""
			(at 0 0 0)
			(layer "B.Fab")
			(effects
				(font
					(size 1.27 1.27)
				)
				(justify mirror)
			)
		)
		(duplicate_pad_numbers_are_jumpers no)
		(fp_line
			(start -0.7874 -0.4064)
			(end -0.7874 0.4064)
			(stroke
				(width 0.1524)
				(type default)
			)
			(layer "B.SilkS")
		)
		(fp_line
			(start -0.7874 0.4064)
			(end 0.7874 0.4064)
			(stroke
				(width 0.1524)
				(type default)
			)
			(layer "B.SilkS")
		)
		(fp_line
			(start 0 0.381)
			(end 0 -0.381)
			(stroke
				(width 0.1524)
				(type default)
			)
			(layer "B.SilkS")
		)
		(fp_line
			(start 0.7874 -0.4064)
			(end -0.7874 -0.4064)
			(stroke
				(width 0.1524)
				(type default)
			)
			(layer "B.SilkS")
		)
		(fp_line
			(start 0.7874 0.4064)
			(end 0.7874 -0.4064)
			(stroke
				(width 0.1524)
				(type default)
			)
			(layer "B.SilkS")
		)
		(fp_poly
			(pts
				(xy 0.5334 0.254) (xy 0.635 0.254) (xy 0.635 0.2286) (xy 0.635 -0.254) (xy 0.5334 -0.254) (xy 0.5334 -0.2794)
				(xy -0.5334 -0.2794) (xy -0.5334 -0.254) (xy -0.635 -0.254) (xy -0.635 0.254) (xy -0.5334 0.254)
				(xy -0.5334 0.2794) (xy 0.508 0.2794) (xy 0.5334 0.2794)
			)
			(stroke
				(width 0)
				(type default)
			)
			(fill no)
			(layer "B.CrtYd")
		)
		(pad "1" smd rect
			(at -0.40005 0 180)
			(size 0.4572 0.508)
			(layers "B.Cu" "B.Mask" "B.Paste")
			(net "P1V9_LAN1")
		)
		(pad "2" smd rect
			(at 0.40005 0 180)
			(size 0.4572 0.508)
			(layers "B.Cu" "B.Mask" "B.Paste")
			(net "GND")
		)
	)
	(footprint ""
		(layer "B.Cu")
		(at 153.90876 -184.951624 90)
		(property "Reference" "R888"
			(at 4.281424 -2.403602 270)
			(unlocked yes)
			(layer "B.SilkS")
			(effects
				(font
					(size 0.7874 0.5842)
					(thickness 0.1524)
				)
				(justify left mirror)
			)
		)
		(property "Value" ""
			(at 0 0 90)
			(layer "B.Fab")
			(effects
				(font
					(size 1.27 1.27)
				)
				(justify mirror)
			)
		)
		(duplicate_pad_numbers_are_jumpers no)
		(fp_line
			(start 0.7874 -0.4064)
			(end -0.7874 -0.4064)
			(stroke
				(width 0.1524)
				(type default)
			)
			(layer "B.SilkS")
		)
		(fp_line
			(start -0.7874 -0.4064)
			(end -0.7874 0.4064)
			(stroke
				(width 0.1524)
				(type default)
			)
			(layer "B.SilkS")
		)
		(fp_line
			(start 0.7874 0.4064)
			(end 0.7874 -0.4064)
			(stroke
				(width 0.1524)
				(type default)
			)
			(layer "B.SilkS")
		)
		(fp_line
			(start -0.7874 0.4064)
			(end 0.7874 0.4064)
			(stroke
				(width 0.1524)
				(type default)
			)
			(layer "B.SilkS")
		)
		(fp_poly
			(pts
				(xy 0.508 0.2794) (xy 0.508 0.2286) (xy 0.635 0.2286) (xy 0.635 -0.254) (xy 0.5334 -0.254) (xy 0.5334 -0.2794)
				(xy -0.5334 -0.2794) (xy -0.5334 -0.254) (xy -0.635 -0.254) (xy -0.635 0.254) (xy -0.5334 0.254)
				(xy -0.5334 0.2794)
			)
			(stroke
				(width 0)
				(type default)
			)
			(fill no)
			(layer "B.CrtYd")
		)
		(pad "1" smd rect
			(at -0.40005 0 270)
			(size 0.4572 0.508)
			(layers "B.Cu" "B.Mask" "B.Paste")
			(net "T11_NODE2_EN")
		)
		(pad "2" smd rect
			(at 0.40005 0 270)
			(size 0.4572 0.508)
			(layers "B.Cu" "B.Mask" "B.Paste")
			(net "T11_NODE2_EN_R")
		)
	)
	(footprint ""
		(layer "B.Cu")
		(at 53.072538 -88.040718 90)
		(property "Reference" "C92"
			(at 2.385822 -1.412748 270)
			(unlocked yes)
			(layer "B.SilkS")
			(effects
				(font
					(size 0.7874 0.5842)
					(thickness 0.1524)
				)
				(justify mirror)
			)
		)
		(property "Value" ""
			(at 0 0 90)
			(layer "B.Fab")
			(effects
				(font
					(size 1.27 1.27)
				)
				(justify mirror)
			)
		)
		(duplicate_pad_numbers_are_jumpers no)
		(fp_line
			(start 1.2954 -0.5842)
			(end -1.2954 -0.5842)
			(stroke
				(width 0.1524)
				(type default)
			)
			(layer "B.SilkS")
		)
		(fp_line
			(start 0 -0.5842)
			(end 0 0.5842)
			(stroke
				(width 0.1524)
				(type default)
			)
			(layer "B.SilkS")
		)
		(fp_line
			(start -1.2954 -0.5842)
			(end -1.2954 0.5842)
			(stroke
				(width 0.1524)
				(type default)
			)
			(layer "B.SilkS")
		)
		(fp_line
			(start 1.2954 0.5842)
			(end 1.2954 -0.5842)
			(stroke
				(width 0.1524)
				(type default)
			)
			(layer "B.SilkS")
		)
		(fp_line
			(start -1.2954 0.5842)
			(end 1.2954 0.5842)
			(stroke
				(width 0.1524)
				(type default)
			)
			(layer "B.SilkS")
		)
		(fp_poly
			(pts
				(xy -0.8636 -0.4572) (xy -0.8636 -0.3556) (xy -1.143 -0.3556) (xy -1.143 0.3556) (xy -0.8636 0.3556)
				(xy -0.8636 0.4572) (xy 0.8636 0.4572) (xy 0.8636 0.3556) (xy 1.143 0.3556) (xy 1.143 -0.3556) (xy 0.8636 -0.3556)
				(xy 0.8636 -0.4572)
			)
			(stroke
				(width 0)
				(type default)
			)
			(fill no)
			(layer "B.CrtYd")
		)
		(fp_line
			(start 0.884936 -0.504952)
			(end -0.884936 -0.504952)
			(stroke
				(width 0.1)
				(type default)
			)
			(layer "B.Fab")
		)
		(fp_line
			(start -0.884936 -0.504952)
			(end -0.884936 0.504952)
			(stroke
				(width 0.1)
				(type default)
			)
			(layer "B.Fab")
		)
		(fp_line
			(start 0.884936 0.504952)
			(end 0.884936 -0.504952)
			(stroke
				(width 0.1)
				(type default)
			)
			(layer "B.Fab")
		)
		(fp_line
			(start -0.884936 0.504952)
			(end 0.884936 0.504952)
			(stroke
				(width 0.1)
				(type default)
			)
			(layer "B.Fab")
		)
		(pad "1" smd rect
			(at -0.7366 0 180)
			(size 0.7112 0.8128)
			(layers "B.Cu" "B.Mask" "B.Paste")
			(net "P1V8_NODE1")
		)
		(pad "2" smd rect
			(at 0.7366 0 180)
			(size 0.7112 0.8128)
			(layers "B.Cu" "B.Mask" "B.Paste")
			(net "GND")
		)
	)
	(footprint ""
		(layer "B.Cu")
		(at 129.600452 -119.055642)
		(property "Reference" "C7"
			(at 2.577338 0.113284 0)
			(unlocked yes)
			(layer "B.SilkS")
			(effects
				(font
					(size 0.7874 0.5842)
					(thickness 0.1524)
				)
				(justify left mirror)
			)
		)
		(property "Value" ""
			(at 0 0 0)
			(layer "B.Fab")
			(effects
				(font
					(size 1.27 1.27)
				)
				(justify mirror)
			)
		)
		(duplicate_pad_numbers_are_jumpers no)
		(fp_line
			(start -0.7874 -0.4064)
			(end -0.7874 0.4064)
			(stroke
				(width 0.1524)
				(type default)
			)
			(layer "B.SilkS")
		)
		(fp_line
			(start -0.7874 0.4064)
			(end 0.7874 0.4064)
			(stroke
				(width 0.1524)
				(type default)
			)
			(layer "B.SilkS")
		)
		(fp_line
			(start 0 0.381)
			(end 0 -0.381)
			(stroke
				(width 0.1524)
				(type default)
			)
			(layer "B.SilkS")
		)
		(fp_line
			(start 0.7874 -0.4064)
			(end -0.7874 -0.4064)
			(stroke
				(width 0.1524)
				(type default)
			)
			(layer "B.SilkS")
		)
		(fp_line
			(start 0.7874 0.4064)
			(end 0.7874 -0.4064)
			(stroke
				(width 0.1524)
				(type default)
			)
			(layer "B.SilkS")
		)
		(fp_poly
			(pts
				(xy 0.5334 0.254) (xy 0.635 0.254) (xy 0.635 0.2286) (xy 0.635 -0.254) (xy 0.5334 -0.254) (xy 0.5334 -0.2794)
				(xy -0.5334 -0.2794) (xy -0.5334 -0.254) (xy -0.635 -0.254) (xy -0.635 0.254) (xy -0.5334 0.254)
				(xy -0.5334 0.2794) (xy 0.508 0.2794) (xy 0.5334 0.2794)
			)
			(stroke
				(width 0)
				(type default)
			)
			(fill no)
			(layer "B.CrtYd")
		)
		(pad "1" smd rect
			(at -0.40005 0 180)
			(size 0.4572 0.508)
			(layers "B.Cu" "B.Mask" "B.Paste")
			(net "P1V5_CLK_NODE1")
		)
		(pad "2" smd rect
			(at 0.40005 0 180)
			(size 0.4572 0.508)
			(layers "B.Cu" "B.Mask" "B.Paste")
			(net "GND")
		)
	)
	(footprint ""
		(layer "B.Cu")
		(at 58.53176 -188.126624 -90)
		(property "Reference" "C685"
			(at -4.276598 -0.118364 270)
			(unlocked yes)
			(layer "B.SilkS")
			(effects
				(font
					(size 0.7874 0.5842)
					(thickness 0.1524)
				)
				(justify left mirror)
			)
		)
		(property "Value" ""
			(at 0 0 90)
			(layer "B.Fab")
			(effects
				(font
					(size 1.27 1.27)
				)
				(justify mirror)
			)
		)
		(duplicate_pad_numbers_are_jumpers no)
		(fp_line
			(start -0.7874 0.4064)
			(end 0.7874 0.4064)
			(stroke
				(width 0.1524)
				(type default)
			)
			(layer "B.SilkS")
		)
		(fp_line
			(start 0.7874 0.4064)
			(end 0.7874 -0.4064)
			(stroke
				(width 0.1524)
				(type default)
			)
			(layer "B.SilkS")
		)
		(fp_line
			(start 0 0.381)
			(end 0 -0.381)
			(stroke
				(width 0.1524)
				(type default)
			)
			(layer "B.SilkS")
		)
		(fp_line
			(start -0.7874 -0.4064)
			(end -0.7874 0.4064)
			(stroke
				(width 0.1524)
				(type default)
			)
			(layer "B.SilkS")
		)
		(fp_line
			(start 0.7874 -0.4064)
			(end -0.7874 -0.4064)
			(stroke
				(width 0.1524)
				(type default)
			)
			(layer "B.SilkS")
		)
		(fp_poly
			(pts
				(xy 0.5334 0.254) (xy 0.635 0.254) (xy 0.635 0.2286) (xy 0.635 -0.254) (xy 0.5334 -0.254) (xy 0.5334 -0.2794)
				(xy -0.5334 -0.2794) (xy -0.5334 -0.254) (xy -0.635 -0.254) (xy -0.635 0.254) (xy -0.5334 0.254)
				(xy -0.5334 0.2794) (xy 0.508 0.2794) (xy 0.5334 0.2794)
			)
			(stroke
				(width 0)
				(type default)
			)
			(fill no)
			(layer "B.CrtYd")
		)
		(pad "1" smd rect
			(at -0.40005 0 90)
			(size 0.4572 0.508)
			(layers "B.Cu" "B.Mask" "B.Paste")
			(net "UART_T1_NODE3_TXD_R")
		)
		(pad "2" smd rect
			(at 0.40005 0 90)
			(size 0.4572 0.508)
			(layers "B.Cu" "B.Mask" "B.Paste")
			(net "GND")
		)
	)
	(footprint ""
		(layer "B.Cu")
		(at 147.305014 -73.683622 180)
		(property "Reference" "C347"
			(at -4.93522 0.710184 0)
			(unlocked yes)
			(layer "B.SilkS")
			(effects
				(font
					(size 0.7874 0.5842)
					(thickness 0.1524)
				)
				(justify left mirror)
			)
		)
		(property "Value" ""
			(at 0 0 0)
			(layer "B.Fab")
			(effects
				(font
					(size 1.27 1.27)
				)
				(justify mirror)
			)
		)
		(duplicate_pad_numbers_are_jumpers no)
		(fp_line
			(start 0.7874 0.4064)
			(end 0.7874 -0.4064)
			(stroke
				(width 0.1524)
				(type default)
			)
			(layer "B.SilkS")
		)
		(fp_line
			(start 0.7874 -0.4064)
			(end -0.7874 -0.4064)
			(stroke
				(width 0.1524)
				(type default)
			)
			(layer "B.SilkS")
		)
		(fp_line
			(start 0 0.381)
			(end 0 -0.381)
			(stroke
				(width 0.1524)
				(type default)
			)
			(layer "B.SilkS")
		)
		(fp_line
			(start -0.7874 0.4064)
			(end 0.7874 0.4064)
			(stroke
				(width 0.1524)
				(type default)
			)
			(layer "B.SilkS")
		)
		(fp_line
			(start -0.7874 -0.4064)
			(end -0.7874 0.4064)
			(stroke
				(width 0.1524)
				(type default)
			)
			(layer "B.SilkS")
		)
		(fp_poly
			(pts
				(xy 0.5334 0.254) (xy 0.635 0.254) (xy 0.635 0.2286) (xy 0.635 -0.254) (xy 0.5334 -0.254) (xy 0.5334 -0.2794)
				(xy -0.5334 -0.2794) (xy -0.5334 -0.254) (xy -0.635 -0.254) (xy -0.635 0.254) (xy -0.5334 0.254)
				(xy -0.5334 0.2794) (xy 0.508 0.2794) (xy 0.5334 0.2794)
			)
			(stroke
				(width 0)
				(type default)
			)
			(fill no)
			(layer "B.CrtYd")
		)
		(pad "1" smd rect
			(at -0.40005 0)
			(size 0.4572 0.508)
			(layers "B.Cu" "B.Mask" "B.Paste")
			(net "P1V8_SATA_AVDD_NODE1")
		)
		(pad "2" smd rect
			(at 0.40005 0)
			(size 0.4572 0.508)
			(layers "B.Cu" "B.Mask" "B.Paste")
			(net "GND")
		)
	)
	(footprint ""
		(layer "B.Cu")
		(at 79.55026 -86.557612 90)
		(property "Reference" "C33"
			(at 1.103884 -0.01397 270)
			(unlocked yes)
			(layer "B.SilkS")
			(effects
				(font
					(size 0.7874 0.5842)
					(thickness 0.1524)
				)
				(justify left mirror)
			)
		)
		(property "Value" ""
			(at 0 0 90)
			(layer "B.Fab")
			(effects
				(font
					(size 1.27 1.27)
				)
				(justify mirror)
			)
		)
		(duplicate_pad_numbers_are_jumpers no)
		(fp_line
			(start 0.7874 -0.4064)
			(end -0.7874 -0.4064)
			(stroke
				(width 0.1524)
				(type default)
			)
			(layer "B.SilkS")
		)
		(fp_line
			(start -0.7874 -0.4064)
			(end -0.7874 0.4064)
			(stroke
				(width 0.1524)
				(type default)
			)
			(layer "B.SilkS")
		)
		(fp_line
			(start 0 0.381)
			(end 0 -0.381)
			(stroke
				(width 0.1524)
				(type default)
			)
			(layer "B.SilkS")
		)
		(fp_line
			(start 0.7874 0.4064)
			(end 0.7874 -0.4064)
			(stroke
				(width 0.1524)
				(type default)
			)
			(layer "B.SilkS")
		)
		(fp_line
			(start -0.7874 0.4064)
			(end 0.7874 0.4064)
			(stroke
				(width 0.1524)
				(type default)
			)
			(layer "B.SilkS")
		)
		(fp_poly
			(pts
				(xy 0.5334 0.254) (xy 0.635 0.254) (xy 0.635 0.2286) (xy 0.635 -0.254) (xy 0.5334 -0.254) (xy 0.5334 -0.2794)
				(xy -0.5334 -0.2794) (xy -0.5334 -0.254) (xy -0.635 -0.254) (xy -0.635 0.254) (xy -0.5334 0.254)
				(xy -0.5334 0.2794) (xy 0.508 0.2794) (xy 0.5334 0.2794)
			)
			(stroke
				(width 0)
				(type default)
			)
			(fill no)
			(layer "B.CrtYd")
		)
		(pad "1" smd rect
			(at -0.40005 0 270)
			(size 0.4572 0.508)
			(layers "B.Cu" "B.Mask" "B.Paste")
			(net "P3V3_RTC_NODE1")
		)
		(pad "2" smd rect
			(at 0.40005 0 270)
			(size 0.4572 0.508)
			(layers "B.Cu" "B.Mask" "B.Paste")
			(net "GND")
		)
	)
	(footprint ""
		(layer "B.Cu")
		(at 106.788458 -174.156116 180)
		(property "Reference" "R704"
			(at -1.765046 -0.685292 270)
			(unlocked yes)
			(layer "B.SilkS")
			(effects
				(font
					(size 0.7874 0.5842)
					(thickness 0.1524)
				)
				(justify left mirror)
			)
		)
		(property "Value" ""
			(at 0 0 0)
			(layer "B.Fab")
			(effects
				(font
					(size 1.27 1.27)
				)
				(justify mirror)
			)
		)
		(duplicate_pad_numbers_are_jumpers no)
		(fp_line
			(start 0.7874 0.4064)
			(end 0.7874 -0.4064)
			(stroke
				(width 0.1524)
				(type default)
			)
			(layer "B.SilkS")
		)
		(fp_line
			(start 0.7874 -0.4064)
			(end -0.7874 -0.4064)
			(stroke
				(width 0.1524)
				(type default)
			)
			(layer "B.SilkS")
		)
		(fp_line
			(start -0.7874 0.4064)
			(end 0.7874 0.4064)
			(stroke
				(width 0.1524)
				(type default)
			)
			(layer "B.SilkS")
		)
		(fp_line
			(start -0.7874 -0.4064)
			(end -0.7874 0.4064)
			(stroke
				(width 0.1524)
				(type default)
			)
			(layer "B.SilkS")
		)
		(fp_poly
			(pts
				(xy 0.508 0.2794) (xy 0.508 0.2286) (xy 0.635 0.2286) (xy 0.635 -0.254) (xy 0.5334 -0.254) (xy 0.5334 -0.2794)
				(xy -0.5334 -0.2794) (xy -0.5334 -0.254) (xy -0.635 -0.254) (xy -0.635 0.254) (xy -0.5334 0.254)
				(xy -0.5334 0.2794)
			)
			(stroke
				(width 0)
				(type default)
			)
			(fill no)
			(layer "B.CrtYd")
		)
		(pad "1" smd rect
			(at -0.40005 0)
			(size 0.4572 0.508)
			(layers "B.Cu" "B.Mask" "B.Paste")
			(net "P3V3_NODE1")
		)
		(pad "2" smd rect
			(at 0.40005 0)
			(size 0.4572 0.508)
			(layers "B.Cu" "B.Mask" "B.Paste")
			(net "N21698979")
		)
	)
	(footprint ""
		(layer "B.Cu")
		(at 37.929312 -157.23489 180)
		(property "Reference" "C407"
			(at 6.960616 9.003792 0)
			(unlocked yes)
			(layer "B.SilkS")
			(effects
				(font
					(size 0.7874 0.5842)
					(thickness 0.1524)
				)
				(justify left mirror)
			)
		)
		(property "Value" ""
			(at 0 0 0)
			(layer "B.Fab")
			(effects
				(font
					(size 1.27 1.27)
				)
				(justify mirror)
			)
		)
		(duplicate_pad_numbers_are_jumpers no)
		(fp_line
			(start 0.7874 0.4064)
			(end 0.7874 -0.4064)
			(stroke
				(width 0.1524)
				(type default)
			)
			(layer "B.SilkS")
		)
		(fp_line
			(start 0.7874 -0.4064)
			(end -0.7874 -0.4064)
			(stroke
				(width 0.1524)
				(type default)
			)
			(layer "B.SilkS")
		)
		(fp_line
			(start 0 0.381)
			(end 0 -0.381)
			(stroke
				(width 0.1524)
				(type default)
			)
			(layer "B.SilkS")
		)
		(fp_line
			(start -0.7874 0.4064)
			(end 0.7874 0.4064)
			(stroke
				(width 0.1524)
				(type default)
			)
			(layer "B.SilkS")
		)
		(fp_line
			(start -0.7874 -0.4064)
			(end -0.7874 0.4064)
			(stroke
				(width 0.1524)
				(type default)
			)
			(layer "B.SilkS")
		)
		(fp_poly
			(pts
				(xy 0.5334 0.254) (xy 0.635 0.254) (xy 0.635 0.2286) (xy 0.635 -0.254) (xy 0.5334 -0.254) (xy 0.5334 -0.2794)
				(xy -0.5334 -0.2794) (xy -0.5334 -0.254) (xy -0.635 -0.254) (xy -0.635 0.254) (xy -0.5334 0.254)
				(xy -0.5334 0.2794) (xy 0.508 0.2794) (xy 0.5334 0.2794)
			)
			(stroke
				(width 0)
				(type default)
			)
			(fill no)
			(layer "B.CrtYd")
		)
		(pad "1" smd rect
			(at -0.40005 0)
			(size 0.4572 0.508)
			(layers "B.Cu" "B.Mask" "B.Paste")
			(net "P1V9_LAN1")
		)
		(pad "2" smd rect
			(at 0.40005 0)
			(size 0.4572 0.508)
			(layers "B.Cu" "B.Mask" "B.Paste")
			(net "GND")
		)
	)
	(footprint ""
		(layer "B.Cu")
		(at 60.42914 -70.133718 90)
		(property "Reference" "C62"
			(at -32.210248 -10.29589 270)
			(unlocked yes)
			(layer "B.SilkS")
			(effects
				(font
					(size 0.7874 0.5842)
					(thickness 0.1524)
				)
				(justify left mirror)
			)
		)
		(property "Value" ""
			(at 0 0 90)
			(layer "B.Fab")
			(effects
				(font
					(size 1.27 1.27)
				)
				(justify mirror)
			)
		)
		(duplicate_pad_numbers_are_jumpers no)
		(fp_line
			(start 0.7874 -0.4064)
			(end -0.7874 -0.4064)
			(stroke
				(width 0.1524)
				(type default)
			)
			(layer "B.SilkS")
		)
		(fp_line
			(start -0.7874 -0.4064)
			(end -0.7874 0.4064)
			(stroke
				(width 0.1524)
				(type default)
			)
			(layer "B.SilkS")
		)
		(fp_line
			(start 0 0.381)
			(end 0 -0.381)
			(stroke
				(width 0.1524)
				(type default)
			)
			(layer "B.SilkS")
		)
		(fp_line
			(start 0.7874 0.4064)
			(end 0.7874 -0.4064)
			(stroke
				(width 0.1524)
				(type default)
			)
			(layer "B.SilkS")
		)
		(fp_line
			(start -0.7874 0.4064)
			(end 0.7874 0.4064)
			(stroke
				(width 0.1524)
				(type default)
			)
			(layer "B.SilkS")
		)
		(fp_poly
			(pts
				(xy 0.5334 0.254) (xy 0.635 0.254) (xy 0.635 0.2286) (xy 0.635 -0.254) (xy 0.5334 -0.254) (xy 0.5334 -0.2794)
				(xy -0.5334 -0.2794) (xy -0.5334 -0.254) (xy -0.635 -0.254) (xy -0.635 0.254) (xy -0.5334 0.254)
				(xy -0.5334 0.2794) (xy 0.508 0.2794) (xy 0.5334 0.2794)
			)
			(stroke
				(width 0)
				(type default)
			)
			(fill no)
			(layer "B.CrtYd")
		)
		(pad "1" smd rect
			(at -0.40005 0 270)
			(size 0.4572 0.508)
			(layers "B.Cu" "B.Mask" "B.Paste")
			(net "P1V05_VCCPLL_DDR3_NODE1")
		)
		(pad "2" smd rect
			(at 0.40005 0 270)
			(size 0.4572 0.508)
			(layers "B.Cu" "B.Mask" "B.Paste")
			(net "GND")
		)
	)
	(footprint ""
		(layer "B.Cu")
		(at 71.175372 -80.514698 90)
		(property "Reference" "C72"
			(at -32.158686 -14.55039 270)
			(unlocked yes)
			(layer "B.SilkS")
			(effects
				(font
					(size 0.7874 0.5842)
					(thickness 0.1524)
				)
				(justify left mirror)
			)
		)
		(property "Value" ""
			(at 0 0 90)
			(layer "B.Fab")
			(effects
				(font
					(size 1.27 1.27)
				)
				(justify mirror)
			)
		)
		(duplicate_pad_numbers_are_jumpers no)
		(fp_line
			(start 0.7874 -0.4064)
			(end -0.7874 -0.4064)
			(stroke
				(width 0.1524)
				(type default)
			)
			(layer "B.SilkS")
		)
		(fp_line
			(start -0.7874 -0.4064)
			(end -0.7874 0.4064)
			(stroke
				(width 0.1524)
				(type default)
			)
			(layer "B.SilkS")
		)
		(fp_line
			(start 0 0.381)
			(end 0 -0.381)
			(stroke
				(width 0.1524)
				(type default)
			)
			(layer "B.SilkS")
		)
		(fp_line
			(start 0.7874 0.4064)
			(end 0.7874 -0.4064)
			(stroke
				(width 0.1524)
				(type default)
			)
			(layer "B.SilkS")
		)
		(fp_line
			(start -0.7874 0.4064)
			(end 0.7874 0.4064)
			(stroke
				(width 0.1524)
				(type default)
			)
			(layer "B.SilkS")
		)
		(fp_poly
			(pts
				(xy 0.5334 0.254) (xy 0.635 0.254) (xy 0.635 0.2286) (xy 0.635 -0.254) (xy 0.5334 -0.254) (xy 0.5334 -0.2794)
				(xy -0.5334 -0.2794) (xy -0.5334 -0.254) (xy -0.635 -0.254) (xy -0.635 0.254) (xy -0.5334 0.254)
				(xy -0.5334 0.2794) (xy 0.508 0.2794) (xy 0.5334 0.2794)
			)
			(stroke
				(width 0)
				(type default)
			)
			(fill no)
			(layer "B.CrtYd")
		)
		(pad "1" smd rect
			(at -0.40005 0 270)
			(size 0.4572 0.508)
			(layers "B.Cu" "B.Mask" "B.Paste")
			(net "PV_VCCP_NODE1")
		)
		(pad "2" smd rect
			(at 0.40005 0 270)
			(size 0.4572 0.508)
			(layers "B.Cu" "B.Mask" "B.Paste")
			(net "GND")
		)
	)
	(footprint ""
		(layer "B.Cu")
		(at 103.329994 -115.01882)
		(property "Reference" "PC113"
			(at -2.577846 0.01651 0)
			(unlocked yes)
			(layer "B.SilkS")
			(effects
				(font
					(size 0.7874 0.5842)
					(thickness 0.1524)
				)
				(justify left mirror)
			)
		)
		(property "Value" ""
			(at 0 0 0)
			(layer "B.Fab")
			(effects
				(font
					(size 1.27 1.27)
				)
				(justify mirror)
			)
		)
		(duplicate_pad_numbers_are_jumpers no)
		(fp_line
			(start -1.905 -0.8636)
			(end -1.905 0.8636)
			(stroke
				(width 0.1524)
				(type default)
			)
			(layer "B.SilkS")
		)
		(fp_line
			(start -1.905 0.8636)
			(end 1.905 0.8636)
			(stroke
				(width 0.1524)
				(type default)
			)
			(layer "B.SilkS")
		)
		(fp_line
			(start 0 0.8382)
			(end 0 -0.8382)
			(stroke
				(width 0.1524)
				(type default)
			)
			(layer "B.SilkS")
		)
		(fp_line
			(start 1.905 -0.8636)
			(end -1.905 -0.8636)
			(stroke
				(width 0.1524)
				(type default)
			)
			(layer "B.SilkS")
		)
		(fp_line
			(start 1.905 0.8636)
			(end 1.905 -0.8636)
			(stroke
				(width 0.1524)
				(type default)
			)
			(layer "B.SilkS")
		)
		(fp_rect
			(start 1.524 0.7366)
			(end -1.524 -0.7366)
			(stroke
				(width 0)
				(type default)
			)
			(fill no)
			(layer "B.CrtYd")
		)
		(pad "1" smd rect
			(at -0.94996 0 180)
			(size 1.1176 1.3716)
			(layers "B.Cu" "B.Mask" "B.Paste")
			(net "GND")
		)
		(pad "2" smd rect
			(at 0.94996 0 180)
			(size 1.1176 1.3716)
			(layers "B.Cu" "B.Mask" "B.Paste")
			(net "PV_VCCP_NODE1")
		)
	)
	(footprint ""
		(layer "B.Cu")
		(at 63.231014 -74.678286)
		(property "Reference" "C130"
			(at -13.807694 30.18409 0)
			(unlocked yes)
			(layer "B.SilkS")
			(effects
				(font
					(size 0.7874 0.5842)
					(thickness 0.1524)
				)
				(justify left mirror)
			)
		)
		(property "Value" ""
			(at 0 0 0)
			(layer "B.Fab")
			(effects
				(font
					(size 1.27 1.27)
				)
				(justify mirror)
			)
		)
		(duplicate_pad_numbers_are_jumpers no)
		(fp_line
			(start -0.7874 -0.4064)
			(end -0.7874 0.4064)
			(stroke
				(width 0.1524)
				(type default)
			)
			(layer "B.SilkS")
		)
		(fp_line
			(start -0.7874 0.4064)
			(end 0.7874 0.4064)
			(stroke
				(width 0.1524)
				(type default)
			)
			(layer "B.SilkS")
		)
		(fp_line
			(start 0 0.381)
			(end 0 -0.381)
			(stroke
				(width 0.1524)
				(type default)
			)
			(layer "B.SilkS")
		)
		(fp_line
			(start 0.7874 -0.4064)
			(end -0.7874 -0.4064)
			(stroke
				(width 0.1524)
				(type default)
			)
			(layer "B.SilkS")
		)
		(fp_line
			(start 0.7874 0.4064)
			(end 0.7874 -0.4064)
			(stroke
				(width 0.1524)
				(type default)
			)
			(layer "B.SilkS")
		)
		(fp_poly
			(pts
				(xy 0.5334 0.254) (xy 0.635 0.254) (xy 0.635 0.2286) (xy 0.635 -0.254) (xy 0.5334 -0.254) (xy 0.5334 -0.2794)
				(xy -0.5334 -0.2794) (xy -0.5334 -0.254) (xy -0.635 -0.254) (xy -0.635 0.254) (xy -0.5334 0.254)
				(xy -0.5334 0.2794) (xy 0.508 0.2794) (xy 0.5334 0.2794)
			)
			(stroke
				(width 0)
				(type default)
			)
			(fill no)
			(layer "B.CrtYd")
		)
		(pad "1" smd rect
			(at -0.40005 0 180)
			(size 0.4572 0.508)
			(layers "B.Cu" "B.Mask" "B.Paste")
			(net "P1V05_NODE1")
		)
		(pad "2" smd rect
			(at 0.40005 0 180)
			(size 0.4572 0.508)
			(layers "B.Cu" "B.Mask" "B.Paste")
			(net "GND")
		)
	)
	(footprint ""
		(layer "B.Cu")
		(at 171.180252 -99.66579)
		(property "Reference" "C379"
			(at 7.70509 -0.00381 0)
			(unlocked yes)
			(layer "B.SilkS")
			(effects
				(font
					(size 0.7874 0.5842)
					(thickness 0.1524)
				)
				(justify left mirror)
			)
		)
		(property "Value" ""
			(at 0 0 0)
			(layer "B.Fab")
			(effects
				(font
					(size 1.27 1.27)
				)
				(justify mirror)
			)
		)
		(duplicate_pad_numbers_are_jumpers no)
		(fp_line
			(start -0.7874 -0.4064)
			(end -0.7874 0.4064)
			(stroke
				(width 0.1524)
				(type default)
			)
			(layer "B.SilkS")
		)
		(fp_line
			(start -0.7874 0.4064)
			(end 0.7874 0.4064)
			(stroke
				(width 0.1524)
				(type default)
			)
			(layer "B.SilkS")
		)
		(fp_line
			(start 0 0.381)
			(end 0 -0.381)
			(stroke
				(width 0.1524)
				(type default)
			)
			(layer "B.SilkS")
		)
		(fp_line
			(start 0.7874 -0.4064)
			(end -0.7874 -0.4064)
			(stroke
				(width 0.1524)
				(type default)
			)
			(layer "B.SilkS")
		)
		(fp_line
			(start 0.7874 0.4064)
			(end 0.7874 -0.4064)
			(stroke
				(width 0.1524)
				(type default)
			)
			(layer "B.SilkS")
		)
		(fp_poly
			(pts
				(xy 0.5334 0.254) (xy 0.635 0.254) (xy 0.635 0.2286) (xy 0.635 -0.254) (xy 0.5334 -0.254) (xy 0.5334 -0.2794)
				(xy -0.5334 -0.2794) (xy -0.5334 -0.254) (xy -0.635 -0.254) (xy -0.635 0.254) (xy -0.5334 0.254)
				(xy -0.5334 0.2794) (xy 0.508 0.2794) (xy 0.5334 0.2794)
			)
			(stroke
				(width 0)
				(type default)
			)
			(fill no)
			(layer "B.CrtYd")
		)
		(pad "1" smd rect
			(at -0.40005 0 180)
			(size 0.4572 0.508)
			(layers "B.Cu" "B.Mask" "B.Paste")
			(net "GND")
		)
		(pad "2" smd rect
			(at 0.40005 0 180)
			(size 0.4572 0.508)
			(layers "B.Cu" "B.Mask" "B.Paste")
			(net "P3V3_NODE1")
		)
	)
	(footprint ""
		(layer "B.Cu")
		(at 48.35398 -178.291744 180)
		(property "Reference" "R688"
			(at -1.274064 -0.998982 0)
			(unlocked yes)
			(layer "B.SilkS")
			(effects
				(font
					(size 0.7874 0.5842)
					(thickness 0.1524)
				)
				(justify left mirror)
			)
		)
		(property "Value" ""
			(at 0 0 0)
			(layer "B.Fab")
			(effects
				(font
					(size 1.27 1.27)
				)
				(justify mirror)
			)
		)
		(duplicate_pad_numbers_are_jumpers no)
		(fp_line
			(start 0.7874 0.4064)
			(end 0.7874 -0.4064)
			(stroke
				(width 0.1524)
				(type default)
			)
			(layer "B.SilkS")
		)
		(fp_line
			(start 0.7874 -0.4064)
			(end -0.7874 -0.4064)
			(stroke
				(width 0.1524)
				(type default)
			)
			(layer "B.SilkS")
		)
		(fp_line
			(start -0.7874 0.4064)
			(end 0.7874 0.4064)
			(stroke
				(width 0.1524)
				(type default)
			)
			(layer "B.SilkS")
		)
		(fp_line
			(start -0.7874 -0.4064)
			(end -0.7874 0.4064)
			(stroke
				(width 0.1524)
				(type default)
			)
			(layer "B.SilkS")
		)
		(fp_poly
			(pts
				(xy 0.508 0.2794) (xy 0.508 0.2286) (xy 0.635 0.2286) (xy 0.635 -0.254) (xy 0.5334 -0.254) (xy 0.5334 -0.2794)
				(xy -0.5334 -0.2794) (xy -0.5334 -0.254) (xy -0.635 -0.254) (xy -0.635 0.254) (xy -0.5334 0.254)
				(xy -0.5334 0.2794)
			)
			(stroke
				(width 0)
				(type default)
			)
			(fill no)
			(layer "B.CrtYd")
		)
		(pad "1" smd rect
			(at -0.40005 0)
			(size 0.4572 0.508)
			(layers "B.Cu" "B.Mask" "B.Paste")
			(net "N21699710")
		)
		(pad "2" smd rect
			(at 0.40005 0)
			(size 0.4572 0.508)
			(layers "B.Cu" "B.Mask" "B.Paste")
			(net "GND")
		)
	)
	(footprint ""
		(layer "B.Cu")
		(at 78.83144 -172.505624 180)
		(property "Reference" "R691"
			(at -30.562296 -20.108164 0)
			(unlocked yes)
			(layer "B.SilkS")
			(effects
				(font
					(size 0.7874 0.5842)
					(thickness 0.1524)
				)
				(justify left mirror)
			)
		)
		(property "Value" ""
			(at 0 0 0)
			(layer "B.Fab")
			(effects
				(font
					(size 1.27 1.27)
				)
				(justify mirror)
			)
		)
		(duplicate_pad_numbers_are_jumpers no)
		(fp_line
			(start 0.7874 0.4064)
			(end 0.7874 -0.4064)
			(stroke
				(width 0.1524)
				(type default)
			)
			(layer "B.SilkS")
		)
		(fp_line
			(start 0.7874 -0.4064)
			(end -0.7874 -0.4064)
			(stroke
				(width 0.1524)
				(type default)
			)
			(layer "B.SilkS")
		)
		(fp_line
			(start -0.7874 0.4064)
			(end 0.7874 0.4064)
			(stroke
				(width 0.1524)
				(type default)
			)
			(layer "B.SilkS")
		)
		(fp_line
			(start -0.7874 -0.4064)
			(end -0.7874 0.4064)
			(stroke
				(width 0.1524)
				(type default)
			)
			(layer "B.SilkS")
		)
		(fp_poly
			(pts
				(xy 0.508 0.2794) (xy 0.508 0.2286) (xy 0.635 0.2286) (xy 0.635 -0.254) (xy 0.5334 -0.254) (xy 0.5334 -0.2794)
				(xy -0.5334 -0.2794) (xy -0.5334 -0.254) (xy -0.635 -0.254) (xy -0.635 0.254) (xy -0.5334 0.254)
				(xy -0.5334 0.2794)
			)
			(stroke
				(width 0)
				(type default)
			)
			(fill no)
			(layer "B.CrtYd")
		)
		(pad "1" smd rect
			(at -0.40005 0)
			(size 0.4572 0.508)
			(layers "B.Cu" "B.Mask" "B.Paste")
			(net "T1_NODE3_EN")
		)
		(pad "2" smd rect
			(at 0.40005 0)
			(size 0.4572 0.508)
			(layers "B.Cu" "B.Mask" "B.Paste")
			(net "P5V_NODE1")
		)
	)
	(footprint ""
		(layer "B.Cu")
		(at 99.943158 -150.322534 180)
		(property "Reference" "PC34"
			(at -1.211326 -1.882394 0)
			(unlocked yes)
			(layer "B.SilkS")
			(effects
				(font
					(size 0.7874 0.5842)
					(thickness 0.1524)
				)
				(justify left mirror)
			)
		)
		(property "Value" ""
			(at 0 0 0)
			(layer "B.Fab")
			(effects
				(font
					(size 1.27 1.27)
				)
				(justify mirror)
			)
		)
		(duplicate_pad_numbers_are_jumpers no)
		(fp_line
			(start 2.2098 0.9398)
			(end 2.2098 -0.9398)
			(stroke
				(width 0.1524)
				(type default)
			)
			(layer "B.SilkS")
		)
		(fp_line
			(start 2.2098 -0.9398)
			(end -2.2098 -0.9398)
			(stroke
				(width 0.1524)
				(type default)
			)
			(layer "B.SilkS")
		)
		(fp_line
			(start 0 -0.9398)
			(end 0 0.9398)
			(stroke
				(width 0.1524)
				(type default)
			)
			(layer "B.SilkS")
		)
		(fp_line
			(start -2.2098 0.9398)
			(end 2.2098 0.9398)
			(stroke
				(width 0.1524)
				(type default)
			)
			(layer "B.SilkS")
		)
		(fp_line
			(start -2.2098 -0.9398)
			(end -2.2098 0.9398)
			(stroke
				(width 0.1524)
				(type default)
			)
			(layer "B.SilkS")
		)
		(fp_poly
			(pts
				(xy 1.6764 0.889) (xy 1.6764 0.7874) (xy 2.0574 0.7874) (xy 2.0574 -0.7874) (xy 1.6764 -0.7874)
				(xy 1.6764 -0.9398) (xy -1.6764 -0.9398) (xy -1.6764 -0.7874) (xy -2.0574 -0.7874) (xy -2.0574 0.7874)
				(xy -1.6764 0.7874) (xy -1.6764 0.9398) (xy 1.6764 0.9398)
			)
			(stroke
				(width 0)
				(type default)
			)
			(fill no)
			(layer "B.CrtYd")
		)
		(fp_line
			(start 1.700022 0.899922)
			(end 1.700022 -0.899922)
			(stroke
				(width 0.1)
				(type default)
			)
			(layer "B.Fab")
		)
		(fp_line
			(start 1.700022 -0.899922)
			(end -1.700022 -0.899922)
			(stroke
				(width 0.1)
				(type default)
			)
			(layer "B.Fab")
		)
		(fp_line
			(start -1.700022 0.899922)
			(end 1.700022 0.899922)
			(stroke
				(width 0.1)
				(type default)
			)
			(layer "B.Fab")
		)
		(fp_line
			(start -1.700022 -0.899922)
			(end -1.700022 0.899922)
			(stroke
				(width 0.1)
				(type default)
			)
			(layer "B.Fab")
		)
		(pad "1" smd rect
			(at -1.4732 0)
			(size 1.1684 1.5748)
			(layers "B.Cu" "B.Mask" "B.Paste")
			(net "P12V_AUX")
		)
		(pad "2" smd rect
			(at 1.4732 0)
			(size 1.1684 1.5748)
			(layers "B.Cu" "B.Mask" "B.Paste")
			(net "GND")
		)
	)
	(footprint ""
		(layer "B.Cu")
		(at 47.10176 -188.126624 -90)
		(property "Reference" "R858"
			(at -4.318254 0.408432 270)
			(unlocked yes)
			(layer "B.SilkS")
			(effects
				(font
					(size 0.7874 0.5842)
					(thickness 0.1524)
				)
				(justify left mirror)
			)
		)
		(property "Value" ""
			(at 0 0 90)
			(layer "B.Fab")
			(effects
				(font
					(size 1.27 1.27)
				)
				(justify mirror)
			)
		)
		(duplicate_pad_numbers_are_jumpers no)
		(fp_line
			(start -0.7874 0.4064)
			(end 0.7874 0.4064)
			(stroke
				(width 0.1524)
				(type default)
			)
			(layer "B.SilkS")
		)
		(fp_line
			(start 0.7874 0.4064)
			(end 0.7874 -0.4064)
			(stroke
				(width 0.1524)
				(type default)
			)
			(layer "B.SilkS")
		)
		(fp_line
			(start -0.7874 -0.4064)
			(end -0.7874 0.4064)
			(stroke
				(width 0.1524)
				(type default)
			)
			(layer "B.SilkS")
		)
		(fp_line
			(start 0.7874 -0.4064)
			(end -0.7874 -0.4064)
			(stroke
				(width 0.1524)
				(type default)
			)
			(layer "B.SilkS")
		)
		(fp_poly
			(pts
				(xy 0.508 0.2794) (xy 0.508 0.2286) (xy 0.635 0.2286) (xy 0.635 -0.254) (xy 0.5334 -0.254) (xy 0.5334 -0.2794)
				(xy -0.5334 -0.2794) (xy -0.5334 -0.254) (xy -0.635 -0.254) (xy -0.635 0.254) (xy -0.5334 0.254)
				(xy -0.5334 0.2794)
			)
			(stroke
				(width 0)
				(type default)
			)
			(fill no)
			(layer "B.CrtYd")
		)
		(pad "1" smd rect
			(at -0.40005 0 90)
			(size 0.4572 0.508)
			(layers "B.Cu" "B.Mask" "B.Paste")
			(net "PSU6_DC_OK_R")
		)
		(pad "2" smd rect
			(at 0.40005 0 90)
			(size 0.4572 0.508)
			(layers "B.Cu" "B.Mask" "B.Paste")
			(net "GND")
		)
	)
	(footprint ""
		(layer "B.Cu")
		(at 165.77564 -188.19749 -90)
		(property "Reference" "C613"
			(at -2.15011 0.16891 270)
			(unlocked yes)
			(layer "B.SilkS")
			(effects
				(font
					(size 0.7874 0.5842)
					(thickness 0.1524)
				)
				(justify left mirror)
			)
		)
		(property "Value" ""
			(at 0 0 90)
			(layer "B.Fab")
			(effects
				(font
					(size 1.27 1.27)
				)
				(justify mirror)
			)
		)
		(duplicate_pad_numbers_are_jumpers no)
		(fp_line
			(start -0.7874 0.4064)
			(end 0.7874 0.4064)
			(stroke
				(width 0.1524)
				(type default)
			)
			(layer "B.SilkS")
		)
		(fp_line
			(start 0.7874 0.4064)
			(end 0.7874 -0.4064)
			(stroke
				(width 0.1524)
				(type default)
			)
			(layer "B.SilkS")
		)
		(fp_line
			(start 0 0.381)
			(end 0 -0.381)
			(stroke
				(width 0.1524)
				(type default)
			)
			(layer "B.SilkS")
		)
		(fp_line
			(start -0.7874 -0.4064)
			(end -0.7874 0.4064)
			(stroke
				(width 0.1524)
				(type default)
			)
			(layer "B.SilkS")
		)
		(fp_line
			(start 0.7874 -0.4064)
			(end -0.7874 -0.4064)
			(stroke
				(width 0.1524)
				(type default)
			)
			(layer "B.SilkS")
		)
		(fp_poly
			(pts
				(xy 0.5334 0.254) (xy 0.635 0.254) (xy 0.635 0.2286) (xy 0.635 -0.254) (xy 0.5334 -0.254) (xy 0.5334 -0.2794)
				(xy -0.5334 -0.2794) (xy -0.5334 -0.254) (xy -0.635 -0.254) (xy -0.635 0.254) (xy -0.5334 0.254)
				(xy -0.5334 0.2794) (xy 0.508 0.2794) (xy 0.5334 0.2794)
			)
			(stroke
				(width 0)
				(type default)
			)
			(fill no)
			(layer "B.CrtYd")
		)
		(pad "1" smd rect
			(at -0.40005 0 90)
			(size 0.4572 0.508)
			(layers "B.Cu" "B.Mask" "B.Paste")
			(net "I2C_PDB_R_SDA")
		)
		(pad "2" smd rect
			(at 0.40005 0 90)
			(size 0.4572 0.508)
			(layers "B.Cu" "B.Mask" "B.Paste")
			(net "GND")
		)
	)
	(footprint ""
		(layer "B.Cu")
		(at 139.717272 -163.363402 180)
		(property "Reference" "R989"
			(at 0.583946 -4.085844 270)
			(unlocked yes)
			(layer "B.SilkS")
			(effects
				(font
					(size 0.7874 0.5842)
					(thickness 0.1524)
				)
				(justify left mirror)
			)
		)
		(property "Value" ""
			(at 0 0 0)
			(layer "B.Fab")
			(effects
				(font
					(size 1.27 1.27)
				)
				(justify mirror)
			)
		)
		(duplicate_pad_numbers_are_jumpers no)
		(fp_line
			(start 0.7874 0.4064)
			(end 0.7874 -0.4064)
			(stroke
				(width 0.1524)
				(type default)
			)
			(layer "B.SilkS")
		)
		(fp_line
			(start 0.7874 -0.4064)
			(end -0.7874 -0.4064)
			(stroke
				(width 0.1524)
				(type default)
			)
			(layer "B.SilkS")
		)
		(fp_line
			(start -0.7874 0.4064)
			(end 0.7874 0.4064)
			(stroke
				(width 0.1524)
				(type default)
			)
			(layer "B.SilkS")
		)
		(fp_line
			(start -0.7874 -0.4064)
			(end -0.7874 0.4064)
			(stroke
				(width 0.1524)
				(type default)
			)
			(layer "B.SilkS")
		)
		(fp_poly
			(pts
				(xy 0.508 0.2794) (xy 0.508 0.2286) (xy 0.635 0.2286) (xy 0.635 -0.254) (xy 0.5334 -0.254) (xy 0.5334 -0.2794)
				(xy -0.5334 -0.2794) (xy -0.5334 -0.254) (xy -0.635 -0.254) (xy -0.635 0.254) (xy -0.5334 0.254)
				(xy -0.5334 0.2794)
			)
			(stroke
				(width 0)
				(type default)
			)
			(fill no)
			(layer "B.CrtYd")
		)
		(pad "1" smd rect
			(at -0.40005 0)
			(size 0.4572 0.508)
			(layers "B.Cu" "B.Mask" "B.Paste")
			(net "UART_T10_NODE2_TXD")
		)
		(pad "2" smd rect
			(at 0.40005 0)
			(size 0.4572 0.508)
			(layers "B.Cu" "B.Mask" "B.Paste")
			(net "UART_T10_NODE2_TXD_R")
		)
	)
	(footprint ""
		(layer "B.Cu")
		(at 79.0194 -162.340544)
		(property "Reference" "C579"
			(at 2.930144 1.514602 0)
			(unlocked yes)
			(layer "B.SilkS")
			(effects
				(font
					(size 0.7874 0.5842)
					(thickness 0.1524)
				)
				(justify left mirror)
			)
		)
		(property "Value" ""
			(at 0 0 0)
			(layer "B.Fab")
			(effects
				(font
					(size 1.27 1.27)
				)
				(justify mirror)
			)
		)
		(duplicate_pad_numbers_are_jumpers no)
		(fp_line
			(start -0.7874 -0.4064)
			(end -0.7874 0.4064)
			(stroke
				(width 0.1524)
				(type default)
			)
			(layer "B.SilkS")
		)
		(fp_line
			(start -0.7874 0.4064)
			(end 0.7874 0.4064)
			(stroke
				(width 0.1524)
				(type default)
			)
			(layer "B.SilkS")
		)
		(fp_line
			(start 0 0.381)
			(end 0 -0.381)
			(stroke
				(width 0.1524)
				(type default)
			)
			(layer "B.SilkS")
		)
		(fp_line
			(start 0.7874 -0.4064)
			(end -0.7874 -0.4064)
			(stroke
				(width 0.1524)
				(type default)
			)
			(layer "B.SilkS")
		)
		(fp_line
			(start 0.7874 0.4064)
			(end 0.7874 -0.4064)
			(stroke
				(width 0.1524)
				(type default)
			)
			(layer "B.SilkS")
		)
		(fp_poly
			(pts
				(xy 0.5334 0.254) (xy 0.635 0.254) (xy 0.635 0.2286) (xy 0.635 -0.254) (xy 0.5334 -0.254) (xy 0.5334 -0.2794)
				(xy -0.5334 -0.2794) (xy -0.5334 -0.254) (xy -0.635 -0.254) (xy -0.635 0.254) (xy -0.5334 0.254)
				(xy -0.5334 0.2794) (xy 0.508 0.2794) (xy 0.5334 0.2794)
			)
			(stroke
				(width 0)
				(type default)
			)
			(fill no)
			(layer "B.CrtYd")
		)
		(pad "1" smd rect
			(at -0.40005 0 180)
			(size 0.4572 0.508)
			(layers "B.Cu" "B.Mask" "B.Paste")
			(net "GND")
		)
		(pad "2" smd rect
			(at 0.40005 0 180)
			(size 0.4572 0.508)
			(layers "B.Cu" "B.Mask" "B.Paste")
			(net "P3V3_NODE1")
		)
	)
	(footprint ""
		(layer "B.Cu")
		(at 141.08176 -184.951624 90)
		(property "Reference" "R978"
			(at 4.357624 -2.102612 270)
			(unlocked yes)
			(layer "B.SilkS")
			(effects
				(font
					(size 0.7874 0.5842)
					(thickness 0.1524)
				)
				(justify left mirror)
			)
		)
		(property "Value" ""
			(at 0 0 90)
			(layer "B.Fab")
			(effects
				(font
					(size 1.27 1.27)
				)
				(justify mirror)
			)
		)
		(duplicate_pad_numbers_are_jumpers no)
		(fp_line
			(start 0.7874 -0.4064)
			(end -0.7874 -0.4064)
			(stroke
				(width 0.1524)
				(type default)
			)
			(layer "B.SilkS")
		)
		(fp_line
			(start -0.7874 -0.4064)
			(end -0.7874 0.4064)
			(stroke
				(width 0.1524)
				(type default)
			)
			(layer "B.SilkS")
		)
		(fp_line
			(start 0.7874 0.4064)
			(end 0.7874 -0.4064)
			(stroke
				(width 0.1524)
				(type default)
			)
			(layer "B.SilkS")
		)
		(fp_line
			(start -0.7874 0.4064)
			(end 0.7874 0.4064)
			(stroke
				(width 0.1524)
				(type default)
			)
			(layer "B.SilkS")
		)
		(fp_poly
			(pts
				(xy 0.508 0.2794) (xy 0.508 0.2286) (xy 0.635 0.2286) (xy 0.635 -0.254) (xy 0.5334 -0.254) (xy 0.5334 -0.2794)
				(xy -0.5334 -0.2794) (xy -0.5334 -0.254) (xy -0.635 -0.254) (xy -0.635 0.254) (xy -0.5334 0.254)
				(xy -0.5334 0.2794)
			)
			(stroke
				(width 0)
				(type default)
			)
			(fill no)
			(layer "B.CrtYd")
		)
		(pad "1" smd rect
			(at -0.40005 0 270)
			(size 0.4572 0.508)
			(layers "B.Cu" "B.Mask" "B.Paste")
			(net "UART_T11_NODE4_TXD")
		)
		(pad "2" smd rect
			(at 0.40005 0 270)
			(size 0.4572 0.508)
			(layers "B.Cu" "B.Mask" "B.Paste")
			(net "UART_T11_NODE4_TXD_R")
		)
	)
	(footprint ""
		(layer "B.Cu")
		(at 137.245852 -151.28875 90)
		(property "Reference" "C881"
			(at 1.03124 3.336798 270)
			(unlocked yes)
			(layer "B.SilkS")
			(effects
				(font
					(size 0.7874 0.5842)
					(thickness 0.1524)
				)
				(justify left mirror)
			)
		)
		(property "Value" ""
			(at 0 0 90)
			(layer "B.Fab")
			(effects
				(font
					(size 1.27 1.27)
				)
				(justify mirror)
			)
		)
		(duplicate_pad_numbers_are_jumpers no)
		(fp_line
			(start 0.7874 -0.4064)
			(end -0.7874 -0.4064)
			(stroke
				(width 0.1524)
				(type default)
			)
			(layer "B.SilkS")
		)
		(fp_line
			(start -0.7874 -0.4064)
			(end -0.7874 0.4064)
			(stroke
				(width 0.1524)
				(type default)
			)
			(layer "B.SilkS")
		)
		(fp_line
			(start 0 0.381)
			(end 0 -0.381)
			(stroke
				(width 0.1524)
				(type default)
			)
			(layer "B.SilkS")
		)
		(fp_line
			(start 0.7874 0.4064)
			(end 0.7874 -0.4064)
			(stroke
				(width 0.1524)
				(type default)
			)
			(layer "B.SilkS")
		)
		(fp_line
			(start -0.7874 0.4064)
			(end 0.7874 0.4064)
			(stroke
				(width 0.1524)
				(type default)
			)
			(layer "B.SilkS")
		)
		(fp_poly
			(pts
				(xy 0.5334 0.254) (xy 0.635 0.254) (xy 0.635 0.2286) (xy 0.635 -0.254) (xy 0.5334 -0.254) (xy 0.5334 -0.2794)
				(xy -0.5334 -0.2794) (xy -0.5334 -0.254) (xy -0.635 -0.254) (xy -0.635 0.254) (xy -0.5334 0.254)
				(xy -0.5334 0.2794) (xy 0.508 0.2794) (xy 0.5334 0.2794)
			)
			(stroke
				(width 0)
				(type default)
			)
			(fill no)
			(layer "B.CrtYd")
		)
		(pad "1" smd rect
			(at -0.40005 0 270)
			(size 0.4572 0.508)
			(layers "B.Cu" "B.Mask" "B.Paste")
			(net "P3V3_NODE1")
		)
		(pad "2" smd rect
			(at 0.40005 0 270)
			(size 0.4572 0.508)
			(layers "B.Cu" "B.Mask" "B.Paste")
			(net "GND")
		)
	)
	(footprint ""
		(layer "B.Cu")
		(at 79.948024 -96.258634)
		(property "Reference" "R139"
			(at 3.854196 0.039624 0)
			(unlocked yes)
			(layer "B.SilkS")
			(effects
				(font
					(size 0.7874 0.5842)
					(thickness 0.1524)
				)
				(justify left mirror)
			)
		)
		(property "Value" ""
			(at 0 0 0)
			(layer "B.Fab")
			(effects
				(font
					(size 1.27 1.27)
				)
				(justify mirror)
			)
		)
		(duplicate_pad_numbers_are_jumpers no)
		(fp_line
			(start -0.7874 -0.4064)
			(end -0.7874 0.4064)
			(stroke
				(width 0.1524)
				(type default)
			)
			(layer "B.SilkS")
		)
		(fp_line
			(start -0.7874 0.4064)
			(end 0.7874 0.4064)
			(stroke
				(width 0.1524)
				(type default)
			)
			(layer "B.SilkS")
		)
		(fp_line
			(start 0.7874 -0.4064)
			(end -0.7874 -0.4064)
			(stroke
				(width 0.1524)
				(type default)
			)
			(layer "B.SilkS")
		)
		(fp_line
			(start 0.7874 0.4064)
			(end 0.7874 -0.4064)
			(stroke
				(width 0.1524)
				(type default)
			)
			(layer "B.SilkS")
		)
		(fp_poly
			(pts
				(xy 0.508 0.2794) (xy 0.508 0.2286) (xy 0.635 0.2286) (xy 0.635 -0.254) (xy 0.5334 -0.254) (xy 0.5334 -0.2794)
				(xy -0.5334 -0.2794) (xy -0.5334 -0.254) (xy -0.635 -0.254) (xy -0.635 0.254) (xy -0.5334 0.254)
				(xy -0.5334 0.2794)
			)
			(stroke
				(width 0)
				(type default)
			)
			(fill no)
			(layer "B.CrtYd")
		)
		(pad "1" smd rect
			(at -0.40005 0 180)
			(size 0.4572 0.508)
			(layers "B.Cu" "B.Mask" "B.Paste")
			(net "CLK_33K_CPU_NODE1_SUSCLK")
		)
		(pad "2" smd rect
			(at 0.40005 0 180)
			(size 0.4572 0.508)
			(layers "B.Cu" "B.Mask" "B.Paste")
			(net "CLK_33K_CPU_NODE1_SUSCLK_RR")
		)
	)
	(footprint ""
		(layer "B.Cu")
		(at 88.77935 -78.765654 180)
		(property "Reference" "R173"
			(at 1.91516 -9.611614 0)
			(unlocked yes)
			(layer "B.SilkS")
			(effects
				(font
					(size 0.7874 0.5842)
					(thickness 0.1524)
				)
				(justify left mirror)
			)
		)
		(property "Value" ""
			(at 0 0 0)
			(layer "B.Fab")
			(effects
				(font
					(size 1.27 1.27)
				)
				(justify mirror)
			)
		)
		(duplicate_pad_numbers_are_jumpers no)
		(fp_line
			(start 0.7874 0.4064)
			(end 0.7874 -0.4064)
			(stroke
				(width 0.1524)
				(type default)
			)
			(layer "B.SilkS")
		)
		(fp_line
			(start 0.7874 -0.4064)
			(end -0.7874 -0.4064)
			(stroke
				(width 0.1524)
				(type default)
			)
			(layer "B.SilkS")
		)
		(fp_line
			(start -0.7874 0.4064)
			(end 0.7874 0.4064)
			(stroke
				(width 0.1524)
				(type default)
			)
			(layer "B.SilkS")
		)
		(fp_line
			(start -0.7874 -0.4064)
			(end -0.7874 0.4064)
			(stroke
				(width 0.1524)
				(type default)
			)
			(layer "B.SilkS")
		)
		(fp_poly
			(pts
				(xy 0.508 0.2794) (xy 0.508 0.2286) (xy 0.635 0.2286) (xy 0.635 -0.254) (xy 0.5334 -0.254) (xy 0.5334 -0.2794)
				(xy -0.5334 -0.2794) (xy -0.5334 -0.254) (xy -0.635 -0.254) (xy -0.635 0.254) (xy -0.5334 0.254)
				(xy -0.5334 0.2794)
			)
			(stroke
				(width 0)
				(type default)
			)
			(fill no)
			(layer "B.CrtYd")
		)
		(pad "1" smd rect
			(at -0.40005 0)
			(size 0.4572 0.508)
			(layers "B.Cu" "B.Mask" "B.Paste")
			(net "GND")
		)
		(pad "2" smd rect
			(at 0.40005 0)
			(size 0.4572 0.508)
			(layers "B.Cu" "B.Mask" "B.Paste")
			(net "PU_CPU_NODE1_MEM_SPEED0")
		)
	)
	(footprint ""
		(layer "B.Cu")
		(at 165.420548 -199.03567)
		(property "Reference" "TP9"
			(at 0 0 0)
			(layer "B.SilkS")
			(hide yes)
			(effects
				(font
					(size 1.27 1.27)
				)
				(justify mirror)
			)
		)
		(property "Value" ""
			(at 0 0 0)
			(layer "B.Fab")
			(effects
				(font
					(size 1.27 1.27)
				)
				(justify mirror)
			)
		)
		(duplicate_pad_numbers_are_jumpers no)
		(fp_poly
			(pts
				(arc
					(start 0.381 0)
					(mid -0.381 0)
					(end 0.381 0)
				)
			)
			(stroke
				(width 0)
				(type default)
			)
			(fill no)
			(layer "B.CrtYd")
		)
		(pad "1" smd circle
			(at 0 0 180)
			(size 0.762 0.762)
			(layers "B.Cu" "B.Mask" "B.Paste")
			(net "UART_DSR_RP5_L")
		)
	)
	(footprint ""
		(layer "B.Cu")
		(at 32.639 -188.7728)
		(property "Reference" "R1332"
			(at 1.7018 -0.98933 0)
			(unlocked yes)
			(layer "B.SilkS")
			(effects
				(font
					(size 0.7874 0.5842)
					(thickness 0.1524)
				)
				(justify left mirror)
			)
		)
		(property "Value" ""
			(at 0 0 0)
			(layer "B.Fab")
			(effects
				(font
					(size 1.27 1.27)
				)
				(justify mirror)
			)
		)
		(duplicate_pad_numbers_are_jumpers no)
		(fp_line
			(start -0.7874 -0.4064)
			(end -0.7874 0.4064)
			(stroke
				(width 0.1524)
				(type default)
			)
			(layer "B.SilkS")
		)
		(fp_line
			(start -0.7874 0.4064)
			(end 0.7874 0.4064)
			(stroke
				(width 0.1524)
				(type default)
			)
			(layer "B.SilkS")
		)
		(fp_line
			(start 0.7874 -0.4064)
			(end -0.7874 -0.4064)
			(stroke
				(width 0.1524)
				(type default)
			)
			(layer "B.SilkS")
		)
		(fp_line
			(start 0.7874 0.4064)
			(end 0.7874 -0.4064)
			(stroke
				(width 0.1524)
				(type default)
			)
			(layer "B.SilkS")
		)
		(fp_poly
			(pts
				(xy 0.508 0.2794) (xy 0.508 0.2286) (xy 0.635 0.2286) (xy 0.635 -0.254) (xy 0.5334 -0.254) (xy 0.5334 -0.2794)
				(xy -0.5334 -0.2794) (xy -0.5334 -0.254) (xy -0.635 -0.254) (xy -0.635 0.254) (xy -0.5334 0.254)
				(xy -0.5334 0.2794)
			)
			(stroke
				(width 0)
				(type default)
			)
			(fill no)
			(layer "B.CrtYd")
		)
		(pad "1" smd rect
			(at -0.40005 0 180)
			(size 0.4572 0.508)
			(layers "B.Cu" "B.Mask" "B.Paste")
			(net "UART_RI_P5_L_N")
		)
		(pad "2" smd rect
			(at 0.40005 0 180)
			(size 0.4572 0.508)
			(layers "B.Cu" "B.Mask" "B.Paste")
			(net "UART_RI_P5_L_N_R")
		)
	)
	(footprint ""
		(layer "B.Cu")
		(at 141.801596 -37.915596)
		(property "Reference" "R1056"
			(at -3.549396 19.425666 0)
			(unlocked yes)
			(layer "B.SilkS")
			(effects
				(font
					(size 0.7874 0.5842)
					(thickness 0.1524)
				)
				(justify left mirror)
			)
		)
		(property "Value" ""
			(at 0 0 0)
			(layer "B.Fab")
			(effects
				(font
					(size 1.27 1.27)
				)
				(justify mirror)
			)
		)
		(duplicate_pad_numbers_are_jumpers no)
		(fp_line
			(start -0.7874 -0.4064)
			(end -0.7874 0.4064)
			(stroke
				(width 0.1524)
				(type default)
			)
			(layer "B.SilkS")
		)
		(fp_line
			(start -0.7874 0.4064)
			(end 0.7874 0.4064)
			(stroke
				(width 0.1524)
				(type default)
			)
			(layer "B.SilkS")
		)
		(fp_line
			(start 0.7874 -0.4064)
			(end -0.7874 -0.4064)
			(stroke
				(width 0.1524)
				(type default)
			)
			(layer "B.SilkS")
		)
		(fp_line
			(start 0.7874 0.4064)
			(end 0.7874 -0.4064)
			(stroke
				(width 0.1524)
				(type default)
			)
			(layer "B.SilkS")
		)
		(fp_poly
			(pts
				(xy 0.508 0.2794) (xy 0.508 0.2286) (xy 0.635 0.2286) (xy 0.635 -0.254) (xy 0.5334 -0.254) (xy 0.5334 -0.2794)
				(xy -0.5334 -0.2794) (xy -0.5334 -0.254) (xy -0.635 -0.254) (xy -0.635 0.254) (xy -0.5334 0.254)
				(xy -0.5334 0.2794)
			)
			(stroke
				(width 0)
				(type default)
			)
			(fill no)
			(layer "B.CrtYd")
		)
		(pad "1" smd rect
			(at -0.40005 0 180)
			(size 0.4572 0.508)
			(layers "B.Cu" "B.Mask" "B.Paste")
			(net "SIO_JTAG_CPLD2_TDO")
		)
		(pad "2" smd rect
			(at 0.40005 0 180)
			(size 0.4572 0.508)
			(layers "B.Cu" "B.Mask" "B.Paste")
			(net "P3V3_NODE1")
		)
	)
	(footprint ""
		(layer "B.Cu")
		(at 78.83144 -174.537624 180)
		(property "Reference" "R693"
			(at -30.562296 -20.108164 0)
			(unlocked yes)
			(layer "B.SilkS")
			(effects
				(font
					(size 0.7874 0.5842)
					(thickness 0.1524)
				)
				(justify left mirror)
			)
		)
		(property "Value" ""
			(at 0 0 0)
			(layer "B.Fab")
			(effects
				(font
					(size 1.27 1.27)
				)
				(justify mirror)
			)
		)
		(duplicate_pad_numbers_are_jumpers no)
		(fp_line
			(start 0.7874 0.4064)
			(end 0.7874 -0.4064)
			(stroke
				(width 0.1524)
				(type default)
			)
			(layer "B.SilkS")
		)
		(fp_line
			(start 0.7874 -0.4064)
			(end -0.7874 -0.4064)
			(stroke
				(width 0.1524)
				(type default)
			)
			(layer "B.SilkS")
		)
		(fp_line
			(start -0.7874 0.4064)
			(end 0.7874 0.4064)
			(stroke
				(width 0.1524)
				(type default)
			)
			(layer "B.SilkS")
		)
		(fp_line
			(start -0.7874 -0.4064)
			(end -0.7874 0.4064)
			(stroke
				(width 0.1524)
				(type default)
			)
			(layer "B.SilkS")
		)
		(fp_poly
			(pts
				(xy 0.508 0.2794) (xy 0.508 0.2286) (xy 0.635 0.2286) (xy 0.635 -0.254) (xy 0.5334 -0.254) (xy 0.5334 -0.2794)
				(xy -0.5334 -0.2794) (xy -0.5334 -0.254) (xy -0.635 -0.254) (xy -0.635 0.254) (xy -0.5334 0.254)
				(xy -0.5334 0.2794)
			)
			(stroke
				(width 0)
				(type default)
			)
			(fill no)
			(layer "B.CrtYd")
		)
		(pad "1" smd rect
			(at -0.40005 0)
			(size 0.4572 0.508)
			(layers "B.Cu" "B.Mask" "B.Paste")
			(net "T2_NODE1_EN")
		)
		(pad "2" smd rect
			(at 0.40005 0)
			(size 0.4572 0.508)
			(layers "B.Cu" "B.Mask" "B.Paste")
			(net "P5V_NODE1")
		)
	)
	(footprint ""
		(layer "B.Cu")
		(at 103.506524 -165.566852 90)
		(property "Reference" "C576"
			(at -2.20091 2.379726 270)
			(unlocked yes)
			(layer "B.SilkS")
			(effects
				(font
					(size 0.7874 0.5842)
					(thickness 0.1524)
				)
				(justify left mirror)
			)
		)
		(property "Value" ""
			(at 0 0 90)
			(layer "B.Fab")
			(effects
				(font
					(size 1.27 1.27)
				)
				(justify mirror)
			)
		)
		(duplicate_pad_numbers_are_jumpers no)
		(fp_line
			(start 0.7874 -0.4064)
			(end -0.7874 -0.4064)
			(stroke
				(width 0.1524)
				(type default)
			)
			(layer "B.SilkS")
		)
		(fp_line
			(start -0.7874 -0.4064)
			(end -0.7874 0.4064)
			(stroke
				(width 0.1524)
				(type default)
			)
			(layer "B.SilkS")
		)
		(fp_line
			(start 0 0.381)
			(end 0 -0.381)
			(stroke
				(width 0.1524)
				(type default)
			)
			(layer "B.SilkS")
		)
		(fp_line
			(start 0.7874 0.4064)
			(end 0.7874 -0.4064)
			(stroke
				(width 0.1524)
				(type default)
			)
			(layer "B.SilkS")
		)
		(fp_line
			(start -0.7874 0.4064)
			(end 0.7874 0.4064)
			(stroke
				(width 0.1524)
				(type default)
			)
			(layer "B.SilkS")
		)
		(fp_poly
			(pts
				(xy 0.5334 0.254) (xy 0.635 0.254) (xy 0.635 0.2286) (xy 0.635 -0.254) (xy 0.5334 -0.254) (xy 0.5334 -0.2794)
				(xy -0.5334 -0.2794) (xy -0.5334 -0.254) (xy -0.635 -0.254) (xy -0.635 0.254) (xy -0.5334 0.254)
				(xy -0.5334 0.2794) (xy 0.508 0.2794) (xy 0.5334 0.2794)
			)
			(stroke
				(width 0)
				(type default)
			)
			(fill no)
			(layer "B.CrtYd")
		)
		(pad "1" smd rect
			(at -0.40005 0 270)
			(size 0.4572 0.508)
			(layers "B.Cu" "B.Mask" "B.Paste")
			(net "P3V3_NODE1")
		)
		(pad "2" smd rect
			(at 0.40005 0 270)
			(size 0.4572 0.508)
			(layers "B.Cu" "B.Mask" "B.Paste")
			(net "GND")
		)
	)
	(footprint ""
		(layer "B.Cu")
		(at 61.884306 -62.541912)
		(property "Reference" "R34"
			(at -0.385064 2.108962 0)
			(unlocked yes)
			(layer "B.SilkS")
			(effects
				(font
					(size 0.7874 0.5842)
					(thickness 0.1524)
				)
				(justify left mirror)
			)
		)
		(property "Value" ""
			(at 0 0 0)
			(layer "B.Fab")
			(effects
				(font
					(size 1.27 1.27)
				)
				(justify mirror)
			)
		)
		(duplicate_pad_numbers_are_jumpers no)
		(fp_line
			(start -0.7874 -0.4064)
			(end -0.7874 0.4064)
			(stroke
				(width 0.1524)
				(type default)
			)
			(layer "B.SilkS")
		)
		(fp_line
			(start -0.7874 0.4064)
			(end 0.7874 0.4064)
			(stroke
				(width 0.1524)
				(type default)
			)
			(layer "B.SilkS")
		)
		(fp_line
			(start 0.7874 -0.4064)
			(end -0.7874 -0.4064)
			(stroke
				(width 0.1524)
				(type default)
			)
			(layer "B.SilkS")
		)
		(fp_line
			(start 0.7874 0.4064)
			(end 0.7874 -0.4064)
			(stroke
				(width 0.1524)
				(type default)
			)
			(layer "B.SilkS")
		)
		(fp_poly
			(pts
				(xy 0.508 0.2794) (xy 0.508 0.2286) (xy 0.635 0.2286) (xy 0.635 -0.254) (xy 0.5334 -0.254) (xy 0.5334 -0.2794)
				(xy -0.5334 -0.2794) (xy -0.5334 -0.254) (xy -0.635 -0.254) (xy -0.635 0.254) (xy -0.5334 0.254)
				(xy -0.5334 0.2794)
			)
			(stroke
				(width 0)
				(type default)
			)
			(fill no)
			(layer "B.CrtYd")
		)
		(pad "1" smd rect
			(at -0.40005 0 180)
			(size 0.4572 0.508)
			(layers "B.Cu" "B.Mask" "B.Paste")
			(net "M_DDR3_NODE1_MON2P")
		)
		(pad "2" smd rect
			(at 0.40005 0 180)
			(size 0.4572 0.508)
			(layers "B.Cu" "B.Mask" "B.Paste")
			(net "M_DDR3_NODE1_MON2N")
		)
	)
	(footprint ""
		(layer "B.Cu")
		(at 76.408534 -20.939506 90)
		(property "Reference" "C175"
			(at -4.176014 -0.339852 270)
			(unlocked yes)
			(layer "B.SilkS")
			(effects
				(font
					(size 0.7874 0.5842)
					(thickness 0.1524)
				)
				(justify mirror)
			)
		)
		(property "Value" ""
			(at 0 0 90)
			(layer "B.Fab")
			(effects
				(font
					(size 1.27 1.27)
				)
				(justify mirror)
			)
		)
		(duplicate_pad_numbers_are_jumpers no)
		(fp_line
			(start 1.2954 -0.5842)
			(end -1.2954 -0.5842)
			(stroke
				(width 0.1524)
				(type default)
			)
			(layer "B.SilkS")
		)
		(fp_line
			(start 0 -0.5842)
			(end 0 0.5842)
			(stroke
				(width 0.1524)
				(type default)
			)
			(layer "B.SilkS")
		)
		(fp_line
			(start -1.2954 -0.5842)
			(end -1.2954 0.5842)
			(stroke
				(width 0.1524)
				(type default)
			)
			(layer "B.SilkS")
		)
		(fp_line
			(start 1.2954 0.5842)
			(end 1.2954 -0.5842)
			(stroke
				(width 0.1524)
				(type default)
			)
			(layer "B.SilkS")
		)
		(fp_line
			(start -1.2954 0.5842)
			(end 1.2954 0.5842)
			(stroke
				(width 0.1524)
				(type default)
			)
			(layer "B.SilkS")
		)
		(fp_poly
			(pts
				(xy -0.8636 -0.4572) (xy -0.8636 -0.3556) (xy -1.143 -0.3556) (xy -1.143 0.3556) (xy -0.8636 0.3556)
				(xy -0.8636 0.4572) (xy 0.8636 0.4572) (xy 0.8636 0.3556) (xy 1.143 0.3556) (xy 1.143 -0.3556) (xy 0.8636 -0.3556)
				(xy 0.8636 -0.4572)
			)
			(stroke
				(width 0)
				(type default)
			)
			(fill no)
			(layer "B.CrtYd")
		)
		(fp_line
			(start 0.884936 -0.504952)
			(end -0.884936 -0.504952)
			(stroke
				(width 0.1)
				(type default)
			)
			(layer "B.Fab")
		)
		(fp_line
			(start -0.884936 -0.504952)
			(end -0.884936 0.504952)
			(stroke
				(width 0.1)
				(type default)
			)
			(layer "B.Fab")
		)
		(fp_line
			(start 0.884936 0.504952)
			(end 0.884936 -0.504952)
			(stroke
				(width 0.1)
				(type default)
			)
			(layer "B.Fab")
		)
		(fp_line
			(start -0.884936 0.504952)
			(end 0.884936 0.504952)
			(stroke
				(width 0.1)
				(type default)
			)
			(layer "B.Fab")
		)
		(pad "1" smd rect
			(at -0.7366 0 180)
			(size 0.7112 0.8128)
			(layers "B.Cu" "B.Mask" "B.Paste")
			(net "PV_VDDR_NODE1")
		)
		(pad "2" smd rect
			(at 0.7366 0 180)
			(size 0.7112 0.8128)
			(layers "B.Cu" "B.Mask" "B.Paste")
			(net "GND")
		)
	)
	(footprint ""
		(layer "B.Cu")
		(at 126.069852 -141.56055 -90)
		(property "Reference" "C878"
			(at 1.561084 -0.400558 0)
			(unlocked yes)
			(layer "B.SilkS")
			(effects
				(font
					(size 0.7874 0.5842)
					(thickness 0.1524)
				)
				(justify left mirror)
			)
		)
		(property "Value" ""
			(at 0 0 90)
			(layer "B.Fab")
			(effects
				(font
					(size 1.27 1.27)
				)
				(justify mirror)
			)
		)
		(duplicate_pad_numbers_are_jumpers no)
		(fp_line
			(start -0.7874 0.4064)
			(end 0.7874 0.4064)
			(stroke
				(width 0.1524)
				(type default)
			)
			(layer "B.SilkS")
		)
		(fp_line
			(start 0.7874 0.4064)
			(end 0.7874 -0.4064)
			(stroke
				(width 0.1524)
				(type default)
			)
			(layer "B.SilkS")
		)
		(fp_line
			(start 0 0.381)
			(end 0 -0.381)
			(stroke
				(width 0.1524)
				(type default)
			)
			(layer "B.SilkS")
		)
		(fp_line
			(start -0.7874 -0.4064)
			(end -0.7874 0.4064)
			(stroke
				(width 0.1524)
				(type default)
			)
			(layer "B.SilkS")
		)
		(fp_line
			(start 0.7874 -0.4064)
			(end -0.7874 -0.4064)
			(stroke
				(width 0.1524)
				(type default)
			)
			(layer "B.SilkS")
		)
		(fp_poly
			(pts
				(xy 0.5334 0.254) (xy 0.635 0.254) (xy 0.635 0.2286) (xy 0.635 -0.254) (xy 0.5334 -0.254) (xy 0.5334 -0.2794)
				(xy -0.5334 -0.2794) (xy -0.5334 -0.254) (xy -0.635 -0.254) (xy -0.635 0.254) (xy -0.5334 0.254)
				(xy -0.5334 0.2794) (xy 0.508 0.2794) (xy 0.5334 0.2794)
			)
			(stroke
				(width 0)
				(type default)
			)
			(fill no)
			(layer "B.CrtYd")
		)
		(pad "1" smd rect
			(at -0.40005 0 90)
			(size 0.4572 0.508)
			(layers "B.Cu" "B.Mask" "B.Paste")
			(net "P1V0_NODE1")
		)
		(pad "2" smd rect
			(at 0.40005 0 90)
			(size 0.4572 0.508)
			(layers "B.Cu" "B.Mask" "B.Paste")
			(net "GND")
		)
	)
	(footprint ""
		(layer "B.Cu")
		(at 142.07236 -174.029624 180)
		(property "Reference" "R731"
			(at 1.287272 0.298196 0)
			(unlocked yes)
			(layer "B.SilkS")
			(effects
				(font
					(size 0.7874 0.5842)
					(thickness 0.1524)
				)
				(justify left mirror)
			)
		)
		(property "Value" ""
			(at 0 0 0)
			(layer "B.Fab")
			(effects
				(font
					(size 1.27 1.27)
				)
				(justify mirror)
			)
		)
		(duplicate_pad_numbers_are_jumpers no)
		(fp_line
			(start 0.7874 0.4064)
			(end 0.7874 -0.4064)
			(stroke
				(width 0.1524)
				(type default)
			)
			(layer "B.SilkS")
		)
		(fp_line
			(start 0.7874 -0.4064)
			(end -0.7874 -0.4064)
			(stroke
				(width 0.1524)
				(type default)
			)
			(layer "B.SilkS")
		)
		(fp_line
			(start -0.7874 0.4064)
			(end 0.7874 0.4064)
			(stroke
				(width 0.1524)
				(type default)
			)
			(layer "B.SilkS")
		)
		(fp_line
			(start -0.7874 -0.4064)
			(end -0.7874 0.4064)
			(stroke
				(width 0.1524)
				(type default)
			)
			(layer "B.SilkS")
		)
		(fp_poly
			(pts
				(xy 0.508 0.2794) (xy 0.508 0.2286) (xy 0.635 0.2286) (xy 0.635 -0.254) (xy 0.5334 -0.254) (xy 0.5334 -0.2794)
				(xy -0.5334 -0.2794) (xy -0.5334 -0.254) (xy -0.635 -0.254) (xy -0.635 0.254) (xy -0.5334 0.254)
				(xy -0.5334 0.2794)
			)
			(stroke
				(width 0)
				(type default)
			)
			(fill no)
			(layer "B.CrtYd")
		)
		(pad "1" smd rect
			(at -0.40005 0)
			(size 0.4572 0.508)
			(layers "B.Cu" "B.Mask" "B.Paste")
			(net "T9_NODE4_EN")
		)
		(pad "2" smd rect
			(at 0.40005 0)
			(size 0.4572 0.508)
			(layers "B.Cu" "B.Mask" "B.Paste")
			(net "P5V_NODE1")
		)
	)
	(footprint ""
		(layer "B.Cu")
		(at 63.922656 -142.710662)
		(property "Reference" "C258"
			(at -2.386584 0.182118 0)
			(unlocked yes)
			(layer "B.SilkS")
			(effects
				(font
					(size 0.7874 0.5842)
					(thickness 0.1524)
				)
				(justify left mirror)
			)
		)
		(property "Value" ""
			(at 0 0 0)
			(layer "B.Fab")
			(effects
				(font
					(size 1.27 1.27)
				)
				(justify mirror)
			)
		)
		(duplicate_pad_numbers_are_jumpers no)
		(fp_line
			(start -0.7874 -0.4064)
			(end -0.7874 0.4064)
			(stroke
				(width 0.1524)
				(type default)
			)
			(layer "B.SilkS")
		)
		(fp_line
			(start -0.7874 0.4064)
			(end 0.7874 0.4064)
			(stroke
				(width 0.1524)
				(type default)
			)
			(layer "B.SilkS")
		)
		(fp_line
			(start 0 0.381)
			(end 0 -0.381)
			(stroke
				(width 0.1524)
				(type default)
			)
			(layer "B.SilkS")
		)
		(fp_line
			(start 0.7874 -0.4064)
			(end -0.7874 -0.4064)
			(stroke
				(width 0.1524)
				(type default)
			)
			(layer "B.SilkS")
		)
		(fp_line
			(start 0.7874 0.4064)
			(end 0.7874 -0.4064)
			(stroke
				(width 0.1524)
				(type default)
			)
			(layer "B.SilkS")
		)
		(fp_poly
			(pts
				(xy 0.5334 0.254) (xy 0.635 0.254) (xy 0.635 0.2286) (xy 0.635 -0.254) (xy 0.5334 -0.254) (xy 0.5334 -0.2794)
				(xy -0.5334 -0.2794) (xy -0.5334 -0.254) (xy -0.635 -0.254) (xy -0.635 0.254) (xy -0.5334 0.254)
				(xy -0.5334 0.2794) (xy 0.508 0.2794) (xy 0.5334 0.2794)
			)
			(stroke
				(width 0)
				(type default)
			)
			(fill no)
			(layer "B.CrtYd")
		)
		(pad "1" smd rect
			(at -0.40005 0 180)
			(size 0.4572 0.508)
			(layers "B.Cu" "B.Mask" "B.Paste")
			(net "BMC_NODE1_ADCAV33")
		)
		(pad "2" smd rect
			(at 0.40005 0 180)
			(size 0.4572 0.508)
			(layers "B.Cu" "B.Mask" "B.Paste")
			(net "GND")
		)
	)
	(footprint ""
		(layer "B.Cu")
		(at 105.191814 -106.89082)
		(property "Reference" "PC114"
			(at -3.119374 0.200406 0)
			(unlocked yes)
			(layer "B.SilkS")
			(effects
				(font
					(size 0.7874 0.5842)
					(thickness 0.1524)
				)
				(justify left mirror)
			)
		)
		(property "Value" ""
			(at 0 0 0)
			(layer "B.Fab")
			(effects
				(font
					(size 1.27 1.27)
				)
				(justify mirror)
			)
		)
		(duplicate_pad_numbers_are_jumpers no)
		(fp_line
			(start -1.905 -0.8636)
			(end -1.905 0.8636)
			(stroke
				(width 0.1524)
				(type default)
			)
			(layer "B.SilkS")
		)
		(fp_line
			(start -1.905 0.8636)
			(end 1.905 0.8636)
			(stroke
				(width 0.1524)
				(type default)
			)
			(layer "B.SilkS")
		)
		(fp_line
			(start 0 0.8382)
			(end 0 -0.8382)
			(stroke
				(width 0.1524)
				(type default)
			)
			(layer "B.SilkS")
		)
		(fp_line
			(start 1.905 -0.8636)
			(end -1.905 -0.8636)
			(stroke
				(width 0.1524)
				(type default)
			)
			(layer "B.SilkS")
		)
		(fp_line
			(start 1.905 0.8636)
			(end 1.905 -0.8636)
			(stroke
				(width 0.1524)
				(type default)
			)
			(layer "B.SilkS")
		)
		(fp_rect
			(start 1.524 0.7366)
			(end -1.524 -0.7366)
			(stroke
				(width 0)
				(type default)
			)
			(fill no)
			(layer "B.CrtYd")
		)
		(pad "1" smd rect
			(at -0.94996 0 180)
			(size 1.1176 1.3716)
			(layers "B.Cu" "B.Mask" "B.Paste")
			(net "GND")
		)
		(pad "2" smd rect
			(at 0.94996 0 180)
			(size 1.1176 1.3716)
			(layers "B.Cu" "B.Mask" "B.Paste")
			(net "PV_VCCP_NODE1")
		)
	)
	(footprint ""
		(layer "B.Cu")
		(at 151.546814 -67.232022 90)
		(property "Reference" "C362"
			(at 0.02159 5.157724 270)
			(unlocked yes)
			(layer "B.SilkS")
			(effects
				(font
					(size 0.7874 0.5842)
					(thickness 0.1524)
				)
				(justify left mirror)
			)
		)
		(property "Value" ""
			(at 0 0 90)
			(layer "B.Fab")
			(effects
				(font
					(size 1.27 1.27)
				)
				(justify mirror)
			)
		)
		(duplicate_pad_numbers_are_jumpers no)
		(fp_line
			(start 0.7874 -0.4064)
			(end -0.7874 -0.4064)
			(stroke
				(width 0.1524)
				(type default)
			)
			(layer "B.SilkS")
		)
		(fp_line
			(start -0.7874 -0.4064)
			(end -0.7874 0.4064)
			(stroke
				(width 0.1524)
				(type default)
			)
			(layer "B.SilkS")
		)
		(fp_line
			(start 0 0.381)
			(end 0 -0.381)
			(stroke
				(width 0.1524)
				(type default)
			)
			(layer "B.SilkS")
		)
		(fp_line
			(start 0.7874 0.4064)
			(end 0.7874 -0.4064)
			(stroke
				(width 0.1524)
				(type default)
			)
			(layer "B.SilkS")
		)
		(fp_line
			(start -0.7874 0.4064)
			(end 0.7874 0.4064)
			(stroke
				(width 0.1524)
				(type default)
			)
			(layer "B.SilkS")
		)
		(fp_poly
			(pts
				(xy 0.5334 0.254) (xy 0.635 0.254) (xy 0.635 0.2286) (xy 0.635 -0.254) (xy 0.5334 -0.254) (xy 0.5334 -0.2794)
				(xy -0.5334 -0.2794) (xy -0.5334 -0.254) (xy -0.635 -0.254) (xy -0.635 0.254) (xy -0.5334 0.254)
				(xy -0.5334 0.2794) (xy 0.508 0.2794) (xy 0.5334 0.2794)
			)
			(stroke
				(width 0)
				(type default)
			)
			(fill no)
			(layer "B.CrtYd")
		)
		(pad "1" smd rect
			(at -0.40005 0 270)
			(size 0.4572 0.508)
			(layers "B.Cu" "B.Mask" "B.Paste")
			(net "P1V8_SATA_VAA1_NODE1")
		)
		(pad "2" smd rect
			(at 0.40005 0 270)
			(size 0.4572 0.508)
			(layers "B.Cu" "B.Mask" "B.Paste")
			(net "GND")
		)
	)
	(footprint ""
		(layer "B.Cu")
		(at 100.712524 -166.201852 -90)
		(property "Reference" "U71"
			(at 3.591814 -0.305054 0)
			(unlocked yes)
			(layer "B.SilkS")
			(effects
				(font
					(size 0.7874 0.5842)
					(thickness 0.1524)
				)
				(justify mirror)
			)
		)
		(property "Value" ""
			(at 0 0 90)
			(layer "B.Fab")
			(effects
				(font
					(size 1.27 1.27)
				)
				(justify mirror)
			)
		)
		(duplicate_pad_numbers_are_jumpers no)
		(fp_line
			(start -1.651 2.0574)
			(end 1.651 2.0574)
			(stroke
				(width 0.1524)
				(type default)
			)
			(layer "B.SilkS")
		)
		(fp_line
			(start 1.651 2.0574)
			(end 1.651 0.381)
			(stroke
				(width 0.1524)
				(type default)
			)
			(layer "B.SilkS")
		)
		(fp_line
			(start 1.651 0.381)
			(end 1.016 0)
			(stroke
				(width 0.1524)
				(type default)
			)
			(layer "B.SilkS")
		)
		(fp_line
			(start 1.016 0)
			(end 1.651 -0.381)
			(stroke
				(width 0.1524)
				(type default)
			)
			(layer "B.SilkS")
		)
		(fp_line
			(start 1.651 -0.381)
			(end 1.651 -2.0574)
			(stroke
				(width 0.1524)
				(type default)
			)
			(layer "B.SilkS")
		)
		(fp_line
			(start -1.651 -2.0574)
			(end -1.651 2.0574)
			(stroke
				(width 0.1524)
				(type default)
			)
			(layer "B.SilkS")
		)
		(fp_line
			(start 1.651 -2.0574)
			(end -1.651 -2.0574)
			(stroke
				(width 0.1524)
				(type default)
			)
			(layer "B.SilkS")
		)
		(fp_rect
			(start 1.524 1.905)
			(end -1.524 -1.905)
			(stroke
				(width 0)
				(type default)
			)
			(fill no)
			(layer "B.CrtYd")
		)
		(pad "1" smd rect
			(at 0.94996 1.225042 90)
			(size 0.5588 1.3462)
			(layers "B.Cu" "B.Mask" "B.Paste")
			(net "FNACTRL2_TMP_IN")
		)
		(pad "2" smd rect
			(at 0 1.225042 90)
			(size 0.5588 1.3462)
			(layers "B.Cu" "B.Mask" "B.Paste")
			(net "FNACTRL2_T_ST")
		)
		(pad "3" smd rect
			(at -0.94996 1.225042 90)
			(size 0.5588 1.3462)
			(layers "B.Cu" "B.Mask" "B.Paste")
			(net "TMP05_FUNC2")
		)
		(pad "4" smd rect
			(at -0.94996 -1.225042 90)
			(size 0.5588 1.3462)
			(layers "B.Cu" "B.Mask" "B.Paste")
			(net "GND")
		)
		(pad "5" smd rect
			(at 0.94996 -1.225042 90)
			(size 0.5588 1.3462)
			(layers "B.Cu" "B.Mask" "B.Paste")
			(net "P3V3_NODE1")
		)
	)
	(footprint ""
		(layer "B.Cu")
		(at 142.22476 -187.999624 90)
		(property "Reference" "R975"
			(at 4.438396 -1.614678 270)
			(unlocked yes)
			(layer "B.SilkS")
			(effects
				(font
					(size 0.7874 0.5842)
					(thickness 0.1524)
				)
				(justify left mirror)
			)
		)
		(property "Value" ""
			(at 0 0 90)
			(layer "B.Fab")
			(effects
				(font
					(size 1.27 1.27)
				)
				(justify mirror)
			)
		)
		(duplicate_pad_numbers_are_jumpers no)
		(fp_line
			(start 0.7874 -0.4064)
			(end -0.7874 -0.4064)
			(stroke
				(width 0.1524)
				(type default)
			)
			(layer "B.SilkS")
		)
		(fp_line
			(start -0.7874 -0.4064)
			(end -0.7874 0.4064)
			(stroke
				(width 0.1524)
				(type default)
			)
			(layer "B.SilkS")
		)
		(fp_line
			(start 0.7874 0.4064)
			(end 0.7874 -0.4064)
			(stroke
				(width 0.1524)
				(type default)
			)
			(layer "B.SilkS")
		)
		(fp_line
			(start -0.7874 0.4064)
			(end 0.7874 0.4064)
			(stroke
				(width 0.1524)
				(type default)
			)
			(layer "B.SilkS")
		)
		(fp_poly
			(pts
				(xy 0.508 0.2794) (xy 0.508 0.2286) (xy 0.635 0.2286) (xy 0.635 -0.254) (xy 0.5334 -0.254) (xy 0.5334 -0.2794)
				(xy -0.5334 -0.2794) (xy -0.5334 -0.254) (xy -0.635 -0.254) (xy -0.635 0.254) (xy -0.5334 0.254)
				(xy -0.5334 0.2794)
			)
			(stroke
				(width 0)
				(type default)
			)
			(fill no)
			(layer "B.CrtYd")
		)
		(pad "1" smd rect
			(at -0.40005 0 270)
			(size 0.4572 0.508)
			(layers "B.Cu" "B.Mask" "B.Paste")
			(net "UART_T11_NODE4_RXD")
		)
		(pad "2" smd rect
			(at 0.40005 0 270)
			(size 0.4572 0.508)
			(layers "B.Cu" "B.Mask" "B.Paste")
			(net "UART_T11_NODE4_RXD_R")
		)
	)
	(footprint ""
		(layer "B.Cu")
		(at 130.183382 -159.604964 -90)
		(property "Reference" "R1069"
			(at 5.080254 -0.167894 270)
			(unlocked yes)
			(layer "B.SilkS")
			(effects
				(font
					(size 0.7874 0.5842)
					(thickness 0.1524)
				)
				(justify left mirror)
			)
		)
		(property "Value" ""
			(at 0 0 90)
			(layer "B.Fab")
			(effects
				(font
					(size 1.27 1.27)
				)
				(justify mirror)
			)
		)
		(duplicate_pad_numbers_are_jumpers no)
		(fp_line
			(start -0.7874 0.4064)
			(end 0.7874 0.4064)
			(stroke
				(width 0.1524)
				(type default)
			)
			(layer "B.SilkS")
		)
		(fp_line
			(start 0.7874 0.4064)
			(end 0.7874 -0.4064)
			(stroke
				(width 0.1524)
				(type default)
			)
			(layer "B.SilkS")
		)
		(fp_line
			(start -0.7874 -0.4064)
			(end -0.7874 0.4064)
			(stroke
				(width 0.1524)
				(type default)
			)
			(layer "B.SilkS")
		)
		(fp_line
			(start 0.7874 -0.4064)
			(end -0.7874 -0.4064)
			(stroke
				(width 0.1524)
				(type default)
			)
			(layer "B.SilkS")
		)
		(fp_poly
			(pts
				(xy 0.508 0.2794) (xy 0.508 0.2286) (xy 0.635 0.2286) (xy 0.635 -0.254) (xy 0.5334 -0.254) (xy 0.5334 -0.2794)
				(xy -0.5334 -0.2794) (xy -0.5334 -0.254) (xy -0.635 -0.254) (xy -0.635 0.254) (xy -0.5334 0.254)
				(xy -0.5334 0.2794)
			)
			(stroke
				(width 0)
				(type default)
			)
			(fill no)
			(layer "B.CrtYd")
		)
		(pad "1" smd rect
			(at -0.40005 0 90)
			(size 0.4572 0.508)
			(layers "B.Cu" "B.Mask" "B.Paste")
			(net "UART_RI_P6_LS_N")
		)
		(pad "2" smd rect
			(at 0.40005 0 90)
			(size 0.4572 0.508)
			(layers "B.Cu" "B.Mask" "B.Paste")
			(net "UART_RI_P6_N")
		)
	)
	(footprint ""
		(layer "B.Cu")
		(at 76.6953 -87.463884 180)
		(property "Reference" "R144"
			(at -1.2827 1.512062 0)
			(unlocked yes)
			(layer "B.SilkS")
			(effects
				(font
					(size 0.7874 0.5842)
					(thickness 0.1524)
				)
				(justify left mirror)
			)
		)
		(property "Value" ""
			(at 0 0 0)
			(layer "B.Fab")
			(effects
				(font
					(size 1.27 1.27)
				)
				(justify mirror)
			)
		)
		(duplicate_pad_numbers_are_jumpers no)
		(fp_line
			(start 0.7874 0.4064)
			(end 0.7874 -0.4064)
			(stroke
				(width 0.1524)
				(type default)
			)
			(layer "B.SilkS")
		)
		(fp_line
			(start 0.7874 -0.4064)
			(end -0.7874 -0.4064)
			(stroke
				(width 0.1524)
				(type default)
			)
			(layer "B.SilkS")
		)
		(fp_line
			(start -0.7874 0.4064)
			(end 0.7874 0.4064)
			(stroke
				(width 0.1524)
				(type default)
			)
			(layer "B.SilkS")
		)
		(fp_line
			(start -0.7874 -0.4064)
			(end -0.7874 0.4064)
			(stroke
				(width 0.1524)
				(type default)
			)
			(layer "B.SilkS")
		)
		(fp_poly
			(pts
				(xy 0.508 0.2794) (xy 0.508 0.2286) (xy 0.635 0.2286) (xy 0.635 -0.254) (xy 0.5334 -0.254) (xy 0.5334 -0.2794)
				(xy -0.5334 -0.2794) (xy -0.5334 -0.254) (xy -0.635 -0.254) (xy -0.635 0.254) (xy -0.5334 0.254)
				(xy -0.5334 0.2794)
			)
			(stroke
				(width 0)
				(type default)
			)
			(fill no)
			(layer "B.CrtYd")
		)
		(pad "1" smd rect
			(at -0.40005 0)
			(size 0.4572 0.508)
			(layers "B.Cu" "B.Mask" "B.Paste")
			(net "IRQ_LVC3_CPU_NODE1_WAKE_L")
		)
		(pad "2" smd rect
			(at 0.40005 0)
			(size 0.4572 0.508)
			(layers "B.Cu" "B.Mask" "B.Paste")
			(net "P3V3_SUS_NODE1")
		)
	)
	(footprint ""
		(layer "B.Cu")
		(at 90.81262 -171.990512)
		(property "Reference" "R707"
			(at 24.902414 20.163028 0)
			(unlocked yes)
			(layer "B.SilkS")
			(effects
				(font
					(size 0.7874 0.5842)
					(thickness 0.1524)
				)
				(justify left mirror)
			)
		)
		(property "Value" ""
			(at 0 0 0)
			(layer "B.Fab")
			(effects
				(font
					(size 1.27 1.27)
				)
				(justify mirror)
			)
		)
		(duplicate_pad_numbers_are_jumpers no)
		(fp_line
			(start -0.7874 -0.4064)
			(end -0.7874 0.4064)
			(stroke
				(width 0.1524)
				(type default)
			)
			(layer "B.SilkS")
		)
		(fp_line
			(start -0.7874 0.4064)
			(end 0.7874 0.4064)
			(stroke
				(width 0.1524)
				(type default)
			)
			(layer "B.SilkS")
		)
		(fp_line
			(start 0.7874 -0.4064)
			(end -0.7874 -0.4064)
			(stroke
				(width 0.1524)
				(type default)
			)
			(layer "B.SilkS")
		)
		(fp_line
			(start 0.7874 0.4064)
			(end 0.7874 -0.4064)
			(stroke
				(width 0.1524)
				(type default)
			)
			(layer "B.SilkS")
		)
		(fp_poly
			(pts
				(xy 0.508 0.2794) (xy 0.508 0.2286) (xy 0.635 0.2286) (xy 0.635 -0.254) (xy 0.5334 -0.254) (xy 0.5334 -0.2794)
				(xy -0.5334 -0.2794) (xy -0.5334 -0.254) (xy -0.635 -0.254) (xy -0.635 0.254) (xy -0.5334 0.254)
				(xy -0.5334 0.2794)
			)
			(stroke
				(width 0)
				(type default)
			)
			(fill no)
			(layer "B.CrtYd")
		)
		(pad "1" smd rect
			(at -0.40005 0 180)
			(size 0.4572 0.508)
			(layers "B.Cu" "B.Mask" "B.Paste")
			(net "T4_NODE3_EN")
		)
		(pad "2" smd rect
			(at 0.40005 0 180)
			(size 0.4572 0.508)
			(layers "B.Cu" "B.Mask" "B.Paste")
			(net "P5V_NODE1")
		)
	)
	(footprint ""
		(layer "B.Cu")
		(at 167.217852 -104.84739 90)
		(property "Reference" "C372"
			(at 1.423416 6.288278 270)
			(unlocked yes)
			(layer "B.SilkS")
			(effects
				(font
					(size 0.7874 0.5842)
					(thickness 0.1524)
				)
				(justify left mirror)
			)
		)
		(property "Value" ""
			(at 0 0 90)
			(layer "B.Fab")
			(effects
				(font
					(size 1.27 1.27)
				)
				(justify mirror)
			)
		)
		(duplicate_pad_numbers_are_jumpers no)
		(fp_line
			(start 0.7874 -0.4064)
			(end -0.7874 -0.4064)
			(stroke
				(width 0.1524)
				(type default)
			)
			(layer "B.SilkS")
		)
		(fp_line
			(start -0.7874 -0.4064)
			(end -0.7874 0.4064)
			(stroke
				(width 0.1524)
				(type default)
			)
			(layer "B.SilkS")
		)
		(fp_line
			(start 0 0.381)
			(end 0 -0.381)
			(stroke
				(width 0.1524)
				(type default)
			)
			(layer "B.SilkS")
		)
		(fp_line
			(start 0.7874 0.4064)
			(end 0.7874 -0.4064)
			(stroke
				(width 0.1524)
				(type default)
			)
			(layer "B.SilkS")
		)
		(fp_line
			(start -0.7874 0.4064)
			(end 0.7874 0.4064)
			(stroke
				(width 0.1524)
				(type default)
			)
			(layer "B.SilkS")
		)
		(fp_poly
			(pts
				(xy 0.5334 0.254) (xy 0.635 0.254) (xy 0.635 0.2286) (xy 0.635 -0.254) (xy 0.5334 -0.254) (xy 0.5334 -0.2794)
				(xy -0.5334 -0.2794) (xy -0.5334 -0.254) (xy -0.635 -0.254) (xy -0.635 0.254) (xy -0.5334 0.254)
				(xy -0.5334 0.2794) (xy 0.508 0.2794) (xy 0.5334 0.2794)
			)
			(stroke
				(width 0)
				(type default)
			)
			(fill no)
			(layer "B.CrtYd")
		)
		(pad "1" smd rect
			(at -0.40005 0 270)
			(size 0.4572 0.508)
			(layers "B.Cu" "B.Mask" "B.Paste")
			(net "GND")
		)
		(pad "2" smd rect
			(at 0.40005 0 270)
			(size 0.4572 0.508)
			(layers "B.Cu" "B.Mask" "B.Paste")
			(net "P1V05_NODE1")
		)
	)
	(footprint ""
		(layer "B.Cu")
		(at 51.67376 -181.984142 -90)
		(property "Reference" "C603"
			(at 3.610356 10.609072 270)
			(unlocked yes)
			(layer "B.SilkS")
			(effects
				(font
					(size 0.7874 0.5842)
					(thickness 0.1524)
				)
				(justify left mirror)
			)
		)
		(property "Value" ""
			(at 0 0 90)
			(layer "B.Fab")
			(effects
				(font
					(size 1.27 1.27)
				)
				(justify mirror)
			)
		)
		(duplicate_pad_numbers_are_jumpers no)
		(fp_line
			(start -0.7874 0.4064)
			(end 0.7874 0.4064)
			(stroke
				(width 0.1524)
				(type default)
			)
			(layer "B.SilkS")
		)
		(fp_line
			(start 0.7874 0.4064)
			(end 0.7874 -0.4064)
			(stroke
				(width 0.1524)
				(type default)
			)
			(layer "B.SilkS")
		)
		(fp_line
			(start 0 0.381)
			(end 0 -0.381)
			(stroke
				(width 0.1524)
				(type default)
			)
			(layer "B.SilkS")
		)
		(fp_line
			(start -0.7874 -0.4064)
			(end -0.7874 0.4064)
			(stroke
				(width 0.1524)
				(type default)
			)
			(layer "B.SilkS")
		)
		(fp_line
			(start 0.7874 -0.4064)
			(end -0.7874 -0.4064)
			(stroke
				(width 0.1524)
				(type default)
			)
			(layer "B.SilkS")
		)
		(fp_poly
			(pts
				(xy 0.5334 0.254) (xy 0.635 0.254) (xy 0.635 0.2286) (xy 0.635 -0.254) (xy 0.5334 -0.254) (xy 0.5334 -0.2794)
				(xy -0.5334 -0.2794) (xy -0.5334 -0.254) (xy -0.635 -0.254) (xy -0.635 0.254) (xy -0.5334 0.254)
				(xy -0.5334 0.2794) (xy 0.508 0.2794) (xy 0.5334 0.2794)
			)
			(stroke
				(width 0)
				(type default)
			)
			(fill no)
			(layer "B.CrtYd")
		)
		(pad "1" smd rect
			(at -0.40005 0 90)
			(size 0.4572 0.508)
			(layers "B.Cu" "B.Mask" "B.Paste")
			(net "PSU2_DC_OK_R_BUF")
		)
		(pad "2" smd rect
			(at 0.40005 0 90)
			(size 0.4572 0.508)
			(layers "B.Cu" "B.Mask" "B.Paste")
			(net "GND")
		)
	)
	(footprint ""
		(layer "B.Cu")
		(at 53.95976 -185.205624 90)
		(property "Reference" "R910"
			(at 4.15163 0.120904 270)
			(unlocked yes)
			(layer "B.SilkS")
			(effects
				(font
					(size 0.7874 0.5842)
					(thickness 0.1524)
				)
				(justify left mirror)
			)
		)
		(property "Value" ""
			(at 0 0 90)
			(layer "B.Fab")
			(effects
				(font
					(size 1.27 1.27)
				)
				(justify mirror)
			)
		)
		(duplicate_pad_numbers_are_jumpers no)
		(fp_line
			(start 0.7874 -0.4064)
			(end -0.7874 -0.4064)
			(stroke
				(width 0.1524)
				(type default)
			)
			(layer "B.SilkS")
		)
		(fp_line
			(start -0.7874 -0.4064)
			(end -0.7874 0.4064)
			(stroke
				(width 0.1524)
				(type default)
			)
			(layer "B.SilkS")
		)
		(fp_line
			(start 0.7874 0.4064)
			(end 0.7874 -0.4064)
			(stroke
				(width 0.1524)
				(type default)
			)
			(layer "B.SilkS")
		)
		(fp_line
			(start -0.7874 0.4064)
			(end 0.7874 0.4064)
			(stroke
				(width 0.1524)
				(type default)
			)
			(layer "B.SilkS")
		)
		(fp_poly
			(pts
				(xy 0.508 0.2794) (xy 0.508 0.2286) (xy 0.635 0.2286) (xy 0.635 -0.254) (xy 0.5334 -0.254) (xy 0.5334 -0.2794)
				(xy -0.5334 -0.2794) (xy -0.5334 -0.254) (xy -0.635 -0.254) (xy -0.635 0.254) (xy -0.5334 0.254)
				(xy -0.5334 0.2794)
			)
			(stroke
				(width 0)
				(type default)
			)
			(fill no)
			(layer "B.CrtYd")
		)
		(pad "1" smd rect
			(at -0.40005 0 270)
			(size 0.4572 0.508)
			(layers "B.Cu" "B.Mask" "B.Paste")
			(net "UART_T1_NODE1_TXD")
		)
		(pad "2" smd rect
			(at 0.40005 0 270)
			(size 0.4572 0.508)
			(layers "B.Cu" "B.Mask" "B.Paste")
			(net "UART_T1_NODE1_TXD_R")
		)
	)
	(footprint ""
		(layer "B.Cu")
		(at 101.6508 -169.452798 90)
		(property "Reference" "U133"
			(at -1.65227 4.93522 0)
			(unlocked yes)
			(layer "B.SilkS")
			(effects
				(font
					(size 0.7874 0.5842)
					(thickness 0.1524)
				)
				(justify mirror)
			)
		)
		(property "Value" ""
			(at 0 0 90)
			(layer "B.Fab")
			(effects
				(font
					(size 1.27 1.27)
				)
				(justify mirror)
			)
		)
		(duplicate_pad_numbers_are_jumpers no)
		(fp_line
			(start 1.1176 -1.7018)
			(end -1.1176 -1.7018)
			(stroke
				(width 0.1524)
				(type default)
			)
			(layer "B.SilkS")
		)
		(fp_line
			(start 1.1176 -1.7018)
			(end 1.1176 -0.254)
			(stroke
				(width 0.1524)
				(type default)
			)
			(layer "B.SilkS")
		)
		(fp_line
			(start -1.1176 -1.7018)
			(end -1.1176 1.7018)
			(stroke
				(width 0.1524)
				(type default)
			)
			(layer "B.SilkS")
		)
		(fp_line
			(start 1.1176 -0.254)
			(end 0.7112 0)
			(stroke
				(width 0.1524)
				(type default)
			)
			(layer "B.SilkS")
		)
		(fp_line
			(start 0.7112 0)
			(end 1.1176 0.254)
			(stroke
				(width 0.1524)
				(type default)
			)
			(layer "B.SilkS")
		)
		(fp_line
			(start 1.1176 0.254)
			(end 1.1176 1.7018)
			(stroke
				(width 0.1524)
				(type default)
			)
			(layer "B.SilkS")
		)
		(fp_line
			(start -1.1176 1.7018)
			(end 1.1176 1.7018)
			(stroke
				(width 0.1524)
				(type default)
			)
			(layer "B.SilkS")
		)
		(fp_poly
			(pts
				(xy 0.675386 1.8161) (xy 0.446786 2.4003) (xy 0.878586 2.4003)
			)
			(stroke
				(width 0)
				(type default)
			)
			(fill yes)
			(layer "B.SilkS")
		)
		(fp_rect
			(start 1.1176 1.5494)
			(end -1.1176 -1.5494)
			(stroke
				(width 0)
				(type default)
			)
			(fill no)
			(layer "B.CrtYd")
		)
		(fp_line
			(start 1.1176 -1.5494)
			(end -1.1176 -1.5494)
			(stroke
				(width 0.1)
				(type default)
			)
			(layer "B.Fab")
		)
		(fp_line
			(start 1.1176 -1.5494)
			(end 1.1176 -0.254)
			(stroke
				(width 0.1)
				(type default)
			)
			(layer "B.Fab")
		)
		(fp_line
			(start -1.1176 -1.5494)
			(end -1.1176 1.5494)
			(stroke
				(width 0.1)
				(type default)
			)
			(layer "B.Fab")
		)
		(fp_line
			(start 1.1176 -0.254)
			(end 1.1176 0.254)
			(stroke
				(width 0.1)
				(type default)
			)
			(layer "B.Fab")
		)
		(fp_line
			(start 1.1176 0.254)
			(end 1.1176 1.5494)
			(stroke
				(width 0.1)
				(type default)
			)
			(layer "B.Fab")
		)
		(fp_line
			(start -1.1176 1.5494)
			(end 1.1176 1.5494)
			(stroke
				(width 0.1)
				(type default)
			)
			(layer "B.Fab")
		)
		(fp_poly
			(pts
				(xy 0.675386 1.8161) (xy 0.446786 2.4003) (xy 0.878586 2.4003)
			)
			(stroke
				(width 0)
				(type default)
			)
			(fill yes)
			(layer "B.Fab")
		)
		(pad "1" smd rect
			(at 0.649986 0.962406 270)
			(size 0.3302 1.1684)
			(layers "B.Cu" "B.Mask" "B.Paste")
			(net "Net_2267")
		)
		(pad "2" smd rect
			(at 0 0.962406 270)
			(size 0.3302 1.1684)
			(layers "B.Cu" "B.Mask" "B.Paste")
			(net "FAN_PWM_BUF")
		)
		(pad "3" smd rect
			(at -0.649986 0.962406 270)
			(size 0.3302 1.1684)
			(layers "B.Cu" "B.Mask" "B.Paste")
			(net "GND")
		)
		(pad "4" smd rect
			(at -0.649986 -0.962406 270)
			(size 0.3302 1.1684)
			(layers "B.Cu" "B.Mask" "B.Paste")
			(net "FAN_PWM")
		)
		(pad "5" smd rect
			(at 0.649986 -0.962406 270)
			(size 0.3302 1.1684)
			(layers "B.Cu" "B.Mask" "B.Paste")
			(net "P3V3_NODE1")
		)
	)
	(footprint ""
		(layer "B.Cu")
		(at 133.294628 -161.035492)
		(property "Reference" "U140"
			(at 0.30099 3.573526 0)
			(unlocked yes)
			(layer "B.SilkS")
			(effects
				(font
					(size 0.635 0.4064)
					(thickness 0.1524)
				)
				(justify mirror)
			)
		)
		(property "Value" ""
			(at 0 0 0)
			(layer "B.Fab")
			(effects
				(font
					(size 1.27 1.27)
				)
				(justify mirror)
			)
		)
		(duplicate_pad_numbers_are_jumpers no)
		(fp_line
			(start -1.651 -1.905)
			(end -1.651 1.905)
			(stroke
				(width 0.1524)
				(type default)
			)
			(layer "B.SilkS")
		)
		(fp_line
			(start -1.651 1.905)
			(end 1.651 1.905)
			(stroke
				(width 0.1524)
				(type default)
			)
			(layer "B.SilkS")
		)
		(fp_line
			(start 1.651 -1.905)
			(end -1.651 -1.905)
			(stroke
				(width 0.1524)
				(type default)
			)
			(layer "B.SilkS")
		)
		(fp_line
			(start 1.651 1.905)
			(end 1.651 -1.905)
			(stroke
				(width 0.1524)
				(type default)
			)
			(layer "B.SilkS")
		)
		(fp_poly
			(pts
				(xy 1.524 0.7112) (xy 1.524 1.7526) (xy 0.508 1.7526) (xy 0.508 0.6985) (xy -0.508 0.6985) (xy -0.508 1.7526)
				(xy -1.524 1.7526) (xy -1.524 0.6985) (xy -1.524 -0.6985) (xy -0.508 -0.6985) (xy -0.508 -1.7526)
				(xy 0.508 -1.7526) (xy 0.508 -0.6985) (xy 1.524 -0.6985) (xy 1.524 0.6985)
			)
			(stroke
				(width 0)
				(type default)
			)
			(fill no)
			(layer "B.CrtYd")
		)
		(fp_text user "S"
			(at -2.055622 1.362202 180)
			(unlocked yes)
			(layer "B.SilkS")
			(effects
				(font
					(size 0.635 0.4064)
					(thickness 0.1524)
				)
				(justify mirror)
			)
		)
		(fp_text user "D"
			(at -1.275334 -2.379472 180)
			(unlocked yes)
			(layer "B.SilkS")
			(effects
				(font
					(size 0.635 0.4064)
					(thickness 0.1524)
				)
				(justify mirror)
			)
		)
		(fp_text user "G"
			(at 2.132076 1.45288 0)
			(unlocked yes)
			(layer "B.SilkS")
			(effects
				(font
					(size 0.635 0.4064)
					(thickness 0.1524)
				)
				(justify mirror)
			)
		)
		(pad "D" smd rect
			(at 0 -1.1176 180)
			(size 1.016 1.27)
			(layers "B.Cu" "B.Mask" "B.Paste")
			(net "TACKOVER_EN")
		)
		(pad "G" smd rect
			(at 1.016 1.1176 180)
			(size 1.016 1.27)
			(layers "B.Cu" "B.Mask" "B.Paste")
			(net "TACKOVER_EN_N")
		)
		(pad "S" smd rect
			(at -1.016 1.1176 180)
			(size 1.016 1.27)
			(layers "B.Cu" "B.Mask" "B.Paste")
			(net "GND")
		)
	)
	(footprint ""
		(layer "B.Cu")
		(at 160.406588 -198.841614)
		(property "Reference" "TP10"
			(at 0 0 0)
			(layer "B.SilkS")
			(hide yes)
			(effects
				(font
					(size 1.27 1.27)
				)
				(justify mirror)
			)
		)
		(property "Value" ""
			(at 0 0 0)
			(layer "B.Fab")
			(effects
				(font
					(size 1.27 1.27)
				)
				(justify mirror)
			)
		)
		(duplicate_pad_numbers_are_jumpers no)
		(fp_poly
			(pts
				(arc
					(start 0.381 0)
					(mid -0.381 0)
					(end 0.381 0)
				)
			)
			(stroke
				(width 0)
				(type default)
			)
			(fill no)
			(layer "B.CrtYd")
		)
		(pad "1" smd circle
			(at 0 0 180)
			(size 0.762 0.762)
			(layers "B.Cu" "B.Mask" "B.Paste")
			(net "UART_CTS_RP5_L_N")
		)
	)
	(footprint ""
		(layer "B.Cu")
		(at 62.18047 -134.045198)
		(property "Reference" "C289"
			(at -40.632888 52.982368 0)
			(unlocked yes)
			(layer "B.SilkS")
			(effects
				(font
					(size 0.7874 0.5842)
					(thickness 0.1524)
				)
				(justify left mirror)
			)
		)
		(property "Value" ""
			(at 0 0 0)
			(layer "B.Fab")
			(effects
				(font
					(size 1.27 1.27)
				)
				(justify mirror)
			)
		)
		(duplicate_pad_numbers_are_jumpers no)
		(fp_line
			(start -0.7874 -0.4064)
			(end -0.7874 0.4064)
			(stroke
				(width 0.1524)
				(type default)
			)
			(layer "B.SilkS")
		)
		(fp_line
			(start -0.7874 0.4064)
			(end 0.7874 0.4064)
			(stroke
				(width 0.1524)
				(type default)
			)
			(layer "B.SilkS")
		)
		(fp_line
			(start 0 0.381)
			(end 0 -0.381)
			(stroke
				(width 0.1524)
				(type default)
			)
			(layer "B.SilkS")
		)
		(fp_line
			(start 0.7874 -0.4064)
			(end -0.7874 -0.4064)
			(stroke
				(width 0.1524)
				(type default)
			)
			(layer "B.SilkS")
		)
		(fp_line
			(start 0.7874 0.4064)
			(end 0.7874 -0.4064)
			(stroke
				(width 0.1524)
				(type default)
			)
			(layer "B.SilkS")
		)
		(fp_poly
			(pts
				(xy 0.5334 0.254) (xy 0.635 0.254) (xy 0.635 0.2286) (xy 0.635 -0.254) (xy 0.5334 -0.254) (xy 0.5334 -0.2794)
				(xy -0.5334 -0.2794) (xy -0.5334 -0.254) (xy -0.635 -0.254) (xy -0.635 0.254) (xy -0.5334 0.254)
				(xy -0.5334 0.2794) (xy 0.508 0.2794) (xy 0.5334 0.2794)
			)
			(stroke
				(width 0)
				(type default)
			)
			(fill no)
			(layer "B.CrtYd")
		)
		(pad "1" smd rect
			(at -0.40005 0 180)
			(size 0.4572 0.508)
			(layers "B.Cu" "B.Mask" "B.Paste")
			(net "P1V26_BMC_NODE1")
		)
		(pad "2" smd rect
			(at 0.40005 0 180)
			(size 0.4572 0.508)
			(layers "B.Cu" "B.Mask" "B.Paste")
			(net "GND")
		)
	)
	(footprint ""
		(layer "B.Cu")
		(at 64.24676 -185.205624 90)
		(property "Reference" "R865"
			(at 4.15163 0.125984 270)
			(unlocked yes)
			(layer "B.SilkS")
			(effects
				(font
					(size 0.7874 0.5842)
					(thickness 0.1524)
				)
				(justify left mirror)
			)
		)
		(property "Value" ""
			(at 0 0 90)
			(layer "B.Fab")
			(effects
				(font
					(size 1.27 1.27)
				)
				(justify mirror)
			)
		)
		(duplicate_pad_numbers_are_jumpers no)
		(fp_line
			(start 0.7874 -0.4064)
			(end -0.7874 -0.4064)
			(stroke
				(width 0.1524)
				(type default)
			)
			(layer "B.SilkS")
		)
		(fp_line
			(start -0.7874 -0.4064)
			(end -0.7874 0.4064)
			(stroke
				(width 0.1524)
				(type default)
			)
			(layer "B.SilkS")
		)
		(fp_line
			(start 0.7874 0.4064)
			(end 0.7874 -0.4064)
			(stroke
				(width 0.1524)
				(type default)
			)
			(layer "B.SilkS")
		)
		(fp_line
			(start -0.7874 0.4064)
			(end 0.7874 0.4064)
			(stroke
				(width 0.1524)
				(type default)
			)
			(layer "B.SilkS")
		)
		(fp_poly
			(pts
				(xy 0.508 0.2794) (xy 0.508 0.2286) (xy 0.635 0.2286) (xy 0.635 -0.254) (xy 0.5334 -0.254) (xy 0.5334 -0.2794)
				(xy -0.5334 -0.2794) (xy -0.5334 -0.254) (xy -0.635 -0.254) (xy -0.635 0.254) (xy -0.5334 0.254)
				(xy -0.5334 0.2794)
			)
			(stroke
				(width 0)
				(type default)
			)
			(fill no)
			(layer "B.CrtYd")
		)
		(pad "1" smd rect
			(at -0.40005 0 270)
			(size 0.4572 0.508)
			(layers "B.Cu" "B.Mask" "B.Paste")
			(net "T1_NODE3_EN")
		)
		(pad "2" smd rect
			(at 0.40005 0 270)
			(size 0.4572 0.508)
			(layers "B.Cu" "B.Mask" "B.Paste")
			(net "T1_NODE3_EN_R")
		)
	)
	(footprint ""
		(layer "B.Cu")
		(at 77.098652 -179.990242 -90)
		(property "Reference" "R1166"
			(at 5.402834 3.002788 270)
			(unlocked yes)
			(layer "B.SilkS")
			(effects
				(font
					(size 0.7874 0.5842)
					(thickness 0.1524)
				)
				(justify left mirror)
			)
		)
		(property "Value" ""
			(at 0 0 90)
			(layer "B.Fab")
			(effects
				(font
					(size 1.27 1.27)
				)
				(justify mirror)
			)
		)
		(duplicate_pad_numbers_are_jumpers no)
		(fp_line
			(start -0.7874 0.4064)
			(end 0.7874 0.4064)
			(stroke
				(width 0.1524)
				(type default)
			)
			(layer "B.SilkS")
		)
		(fp_line
			(start 0.7874 0.4064)
			(end 0.7874 -0.4064)
			(stroke
				(width 0.1524)
				(type default)
			)
			(layer "B.SilkS")
		)
		(fp_line
			(start -0.7874 -0.4064)
			(end -0.7874 0.4064)
			(stroke
				(width 0.1524)
				(type default)
			)
			(layer "B.SilkS")
		)
		(fp_line
			(start 0.7874 -0.4064)
			(end -0.7874 -0.4064)
			(stroke
				(width 0.1524)
				(type default)
			)
			(layer "B.SilkS")
		)
		(fp_poly
			(pts
				(xy 0.508 0.2794) (xy 0.508 0.2286) (xy 0.635 0.2286) (xy 0.635 -0.254) (xy 0.5334 -0.254) (xy 0.5334 -0.2794)
				(xy -0.5334 -0.2794) (xy -0.5334 -0.254) (xy -0.635 -0.254) (xy -0.635 0.254) (xy -0.5334 0.254)
				(xy -0.5334 0.2794)
			)
			(stroke
				(width 0)
				(type default)
			)
			(fill no)
			(layer "B.CrtYd")
		)
		(pad "1" smd rect
			(at -0.40005 0 90)
			(size 0.4572 0.508)
			(layers "B.Cu" "B.Mask" "B.Paste")
			(net "UART_DTR_P4_N")
		)
		(pad "2" smd rect
			(at 0.40005 0 90)
			(size 0.4572 0.508)
			(layers "B.Cu" "B.Mask" "B.Paste")
			(net "GND")
		)
	)
	(footprint ""
		(layer "B.Cu")
		(at 69.143372 -80.514698 90)
		(property "Reference" "C67"
			(at -32.158686 -14.55039 270)
			(unlocked yes)
			(layer "B.SilkS")
			(effects
				(font
					(size 0.7874 0.5842)
					(thickness 0.1524)
				)
				(justify left mirror)
			)
		)
		(property "Value" ""
			(at 0 0 90)
			(layer "B.Fab")
			(effects
				(font
					(size 1.27 1.27)
				)
				(justify mirror)
			)
		)
		(duplicate_pad_numbers_are_jumpers no)
		(fp_line
			(start 0.7874 -0.4064)
			(end -0.7874 -0.4064)
			(stroke
				(width 0.1524)
				(type default)
			)
			(layer "B.SilkS")
		)
		(fp_line
			(start -0.7874 -0.4064)
			(end -0.7874 0.4064)
			(stroke
				(width 0.1524)
				(type default)
			)
			(layer "B.SilkS")
		)
		(fp_line
			(start 0 0.381)
			(end 0 -0.381)
			(stroke
				(width 0.1524)
				(type default)
			)
			(layer "B.SilkS")
		)
		(fp_line
			(start 0.7874 0.4064)
			(end 0.7874 -0.4064)
			(stroke
				(width 0.1524)
				(type default)
			)
			(layer "B.SilkS")
		)
		(fp_line
			(start -0.7874 0.4064)
			(end 0.7874 0.4064)
			(stroke
				(width 0.1524)
				(type default)
			)
			(layer "B.SilkS")
		)
		(fp_poly
			(pts
				(xy 0.5334 0.254) (xy 0.635 0.254) (xy 0.635 0.2286) (xy 0.635 -0.254) (xy 0.5334 -0.254) (xy 0.5334 -0.2794)
				(xy -0.5334 -0.2794) (xy -0.5334 -0.254) (xy -0.635 -0.254) (xy -0.635 0.254) (xy -0.5334 0.254)
				(xy -0.5334 0.2794) (xy 0.508 0.2794) (xy 0.5334 0.2794)
			)
			(stroke
				(width 0)
				(type default)
			)
			(fill no)
			(layer "B.CrtYd")
		)
		(pad "1" smd rect
			(at -0.40005 0 270)
			(size 0.4572 0.508)
			(layers "B.Cu" "B.Mask" "B.Paste")
			(net "PV_VCCP_NODE1")
		)
		(pad "2" smd rect
			(at 0.40005 0 270)
			(size 0.4572 0.508)
			(layers "B.Cu" "B.Mask" "B.Paste")
			(net "GND")
		)
	)
	(footprint ""
		(layer "B.Cu")
		(at 91.47302 -73.740518)
		(property "Reference" "R158"
			(at 4.07797 0.606044 0)
			(unlocked yes)
			(layer "B.SilkS")
			(effects
				(font
					(size 0.7874 0.5842)
					(thickness 0.1524)
				)
				(justify left mirror)
			)
		)
		(property "Value" ""
			(at 0 0 0)
			(layer "B.Fab")
			(effects
				(font
					(size 1.27 1.27)
				)
				(justify mirror)
			)
		)
		(duplicate_pad_numbers_are_jumpers no)
		(fp_line
			(start -0.7874 -0.4064)
			(end -0.7874 0.4064)
			(stroke
				(width 0.1524)
				(type default)
			)
			(layer "B.SilkS")
		)
		(fp_line
			(start -0.7874 0.4064)
			(end 0.7874 0.4064)
			(stroke
				(width 0.1524)
				(type default)
			)
			(layer "B.SilkS")
		)
		(fp_line
			(start 0.7874 -0.4064)
			(end -0.7874 -0.4064)
			(stroke
				(width 0.1524)
				(type default)
			)
			(layer "B.SilkS")
		)
		(fp_line
			(start 0.7874 0.4064)
			(end 0.7874 -0.4064)
			(stroke
				(width 0.1524)
				(type default)
			)
			(layer "B.SilkS")
		)
		(fp_poly
			(pts
				(xy 0.508 0.2794) (xy 0.508 0.2286) (xy 0.635 0.2286) (xy 0.635 -0.254) (xy 0.5334 -0.254) (xy 0.5334 -0.2794)
				(xy -0.5334 -0.2794) (xy -0.5334 -0.254) (xy -0.635 -0.254) (xy -0.635 0.254) (xy -0.5334 0.254)
				(xy -0.5334 0.2794)
			)
			(stroke
				(width 0)
				(type default)
			)
			(fill no)
			(layer "B.CrtYd")
		)
		(pad "1" smd rect
			(at -0.40005 0 180)
			(size 0.4572 0.508)
			(layers "B.Cu" "B.Mask" "B.Paste")
			(net "PD_CPU_NODE1_SPD_EN_L")
		)
		(pad "2" smd rect
			(at 0.40005 0 180)
			(size 0.4572 0.508)
			(layers "B.Cu" "B.Mask" "B.Paste")
			(net "P1V05_SUS_NODE1")
		)
	)
	(footprint ""
		(layer "B.Cu")
		(at 46.33722 -159.21609 -90)
		(property "Reference" "C421"
			(at -7.02437 7.212076 270)
			(unlocked yes)
			(layer "B.SilkS")
			(effects
				(font
					(size 0.7874 0.5842)
					(thickness 0.1524)
				)
				(justify left mirror)
			)
		)
		(property "Value" ""
			(at 0 0 90)
			(layer "B.Fab")
			(effects
				(font
					(size 1.27 1.27)
				)
				(justify mirror)
			)
		)
		(duplicate_pad_numbers_are_jumpers no)
		(fp_line
			(start -0.7874 0.4064)
			(end 0.7874 0.4064)
			(stroke
				(width 0.1524)
				(type default)
			)
			(layer "B.SilkS")
		)
		(fp_line
			(start 0.7874 0.4064)
			(end 0.7874 -0.4064)
			(stroke
				(width 0.1524)
				(type default)
			)
			(layer "B.SilkS")
		)
		(fp_line
			(start 0 0.381)
			(end 0 -0.381)
			(stroke
				(width 0.1524)
				(type default)
			)
			(layer "B.SilkS")
		)
		(fp_line
			(start -0.7874 -0.4064)
			(end -0.7874 0.4064)
			(stroke
				(width 0.1524)
				(type default)
			)
			(layer "B.SilkS")
		)
		(fp_line
			(start 0.7874 -0.4064)
			(end -0.7874 -0.4064)
			(stroke
				(width 0.1524)
				(type default)
			)
			(layer "B.SilkS")
		)
		(fp_poly
			(pts
				(xy 0.5334 0.254) (xy 0.635 0.254) (xy 0.635 0.2286) (xy 0.635 -0.254) (xy 0.5334 -0.254) (xy 0.5334 -0.2794)
				(xy -0.5334 -0.2794) (xy -0.5334 -0.254) (xy -0.635 -0.254) (xy -0.635 0.254) (xy -0.5334 0.254)
				(xy -0.5334 0.2794) (xy 0.508 0.2794) (xy 0.5334 0.2794)
			)
			(stroke
				(width 0)
				(type default)
			)
			(fill no)
			(layer "B.CrtYd")
		)
		(pad "1" smd rect
			(at -0.40005 0 90)
			(size 0.4572 0.508)
			(layers "B.Cu" "B.Mask" "B.Paste")
			(net "P1V05_LAN1")
		)
		(pad "2" smd rect
			(at 0.40005 0 90)
			(size 0.4572 0.508)
			(layers "B.Cu" "B.Mask" "B.Paste")
			(net "GND")
		)
	)
	(footprint ""
		(layer "B.Cu")
		(at 162.80638 -148.880322 90)
		(property "Reference" "C452"
			(at -8.513318 0.318262 270)
			(unlocked yes)
			(layer "B.SilkS")
			(effects
				(font
					(size 0.7874 0.5842)
					(thickness 0.1524)
				)
				(justify left mirror)
			)
		)
		(property "Value" ""
			(at 0 0 90)
			(layer "B.Fab")
			(effects
				(font
					(size 1.27 1.27)
				)
				(justify mirror)
			)
		)
		(duplicate_pad_numbers_are_jumpers no)
		(fp_line
			(start 0.7874 -0.4064)
			(end -0.7874 -0.4064)
			(stroke
				(width 0.1524)
				(type default)
			)
			(layer "B.SilkS")
		)
		(fp_line
			(start -0.7874 -0.4064)
			(end -0.7874 0.4064)
			(stroke
				(width 0.1524)
				(type default)
			)
			(layer "B.SilkS")
		)
		(fp_line
			(start 0 0.381)
			(end 0 -0.381)
			(stroke
				(width 0.1524)
				(type default)
			)
			(layer "B.SilkS")
		)
		(fp_line
			(start 0.7874 0.4064)
			(end 0.7874 -0.4064)
			(stroke
				(width 0.1524)
				(type default)
			)
			(layer "B.SilkS")
		)
		(fp_line
			(start -0.7874 0.4064)
			(end 0.7874 0.4064)
			(stroke
				(width 0.1524)
				(type default)
			)
			(layer "B.SilkS")
		)
		(fp_poly
			(pts
				(xy 0.5334 0.254) (xy 0.635 0.254) (xy 0.635 0.2286) (xy 0.635 -0.254) (xy 0.5334 -0.254) (xy 0.5334 -0.2794)
				(xy -0.5334 -0.2794) (xy -0.5334 -0.254) (xy -0.635 -0.254) (xy -0.635 0.254) (xy -0.5334 0.254)
				(xy -0.5334 0.2794) (xy 0.508 0.2794) (xy 0.5334 0.2794)
			)
			(stroke
				(width 0)
				(type default)
			)
			(fill no)
			(layer "B.CrtYd")
		)
		(pad "1" smd rect
			(at -0.40005 0 270)
			(size 0.4572 0.508)
			(layers "B.Cu" "B.Mask" "B.Paste")
			(net "P1V9_LAN2")
		)
		(pad "2" smd rect
			(at 0.40005 0 270)
			(size 0.4572 0.508)
			(layers "B.Cu" "B.Mask" "B.Paste")
			(net "GND")
		)
	)
	(footprint ""
		(layer "B.Cu")
		(at 40.39362 -156.65069)
		(property "Reference" "C411"
			(at -6.504178 -9.453372 0)
			(unlocked yes)
			(layer "B.SilkS")
			(effects
				(font
					(size 0.7874 0.5842)
					(thickness 0.1524)
				)
				(justify left mirror)
			)
		)
		(property "Value" ""
			(at 0 0 0)
			(layer "B.Fab")
			(effects
				(font
					(size 1.27 1.27)
				)
				(justify mirror)
			)
		)
		(duplicate_pad_numbers_are_jumpers no)
		(fp_line
			(start -0.7874 -0.4064)
			(end -0.7874 0.4064)
			(stroke
				(width 0.1524)
				(type default)
			)
			(layer "B.SilkS")
		)
		(fp_line
			(start -0.7874 0.4064)
			(end 0.7874 0.4064)
			(stroke
				(width 0.1524)
				(type default)
			)
			(layer "B.SilkS")
		)
		(fp_line
			(start 0 0.381)
			(end 0 -0.381)
			(stroke
				(width 0.1524)
				(type default)
			)
			(layer "B.SilkS")
		)
		(fp_line
			(start 0.7874 -0.4064)
			(end -0.7874 -0.4064)
			(stroke
				(width 0.1524)
				(type default)
			)
			(layer "B.SilkS")
		)
		(fp_line
			(start 0.7874 0.4064)
			(end 0.7874 -0.4064)
			(stroke
				(width 0.1524)
				(type default)
			)
			(layer "B.SilkS")
		)
		(fp_poly
			(pts
				(xy 0.5334 0.254) (xy 0.635 0.254) (xy 0.635 0.2286) (xy 0.635 -0.254) (xy 0.5334 -0.254) (xy 0.5334 -0.2794)
				(xy -0.5334 -0.2794) (xy -0.5334 -0.254) (xy -0.635 -0.254) (xy -0.635 0.254) (xy -0.5334 0.254)
				(xy -0.5334 0.2794) (xy 0.508 0.2794) (xy 0.5334 0.2794)
			)
			(stroke
				(width 0)
				(type default)
			)
			(fill no)
			(layer "B.CrtYd")
		)
		(pad "1" smd rect
			(at -0.40005 0 180)
			(size 0.4572 0.508)
			(layers "B.Cu" "B.Mask" "B.Paste")
			(net "P1V9_LAN1")
		)
		(pad "2" smd rect
			(at 0.40005 0 180)
			(size 0.4572 0.508)
			(layers "B.Cu" "B.Mask" "B.Paste")
			(net "GND")
		)
	)
	(footprint ""
		(layer "B.Cu")
		(at 59.997086 -146.419062 90)
		(property "Reference" "R291"
			(at 0.94742 -0.289306 270)
			(unlocked yes)
			(layer "B.SilkS")
			(effects
				(font
					(size 0.7874 0.5842)
					(thickness 0.1524)
				)
				(justify left mirror)
			)
		)
		(property "Value" ""
			(at 0 0 90)
			(layer "B.Fab")
			(effects
				(font
					(size 1.27 1.27)
				)
				(justify mirror)
			)
		)
		(duplicate_pad_numbers_are_jumpers no)
		(fp_line
			(start 0.7874 -0.4064)
			(end -0.7874 -0.4064)
			(stroke
				(width 0.1524)
				(type default)
			)
			(layer "B.SilkS")
		)
		(fp_line
			(start -0.7874 -0.4064)
			(end -0.7874 0.4064)
			(stroke
				(width 0.1524)
				(type default)
			)
			(layer "B.SilkS")
		)
		(fp_line
			(start 0.7874 0.4064)
			(end 0.7874 -0.4064)
			(stroke
				(width 0.1524)
				(type default)
			)
			(layer "B.SilkS")
		)
		(fp_line
			(start -0.7874 0.4064)
			(end 0.7874 0.4064)
			(stroke
				(width 0.1524)
				(type default)
			)
			(layer "B.SilkS")
		)
		(fp_poly
			(pts
				(xy 0.508 0.2794) (xy 0.508 0.2286) (xy 0.635 0.2286) (xy 0.635 -0.254) (xy 0.5334 -0.254) (xy 0.5334 -0.2794)
				(xy -0.5334 -0.2794) (xy -0.5334 -0.254) (xy -0.635 -0.254) (xy -0.635 0.254) (xy -0.5334 0.254)
				(xy -0.5334 0.2794)
			)
			(stroke
				(width 0)
				(type default)
			)
			(fill no)
			(layer "B.CrtYd")
		)
		(pad "1" smd rect
			(at -0.40005 0 270)
			(size 0.4572 0.508)
			(layers "B.Cu" "B.Mask" "B.Paste")
			(net "BMC_NODE1_GFX_GREEN")
		)
		(pad "2" smd rect
			(at 0.40005 0 270)
			(size 0.4572 0.508)
			(layers "B.Cu" "B.Mask" "B.Paste")
			(net "GND")
		)
	)
	(footprint ""
		(layer "B.Cu")
		(at 42.551858 -72.478138 180)
		(property "Reference" "R37"
			(at 0.923036 -1.577848 0)
			(unlocked yes)
			(layer "B.SilkS")
			(effects
				(font
					(size 0.7874 0.5842)
					(thickness 0.1524)
				)
				(justify left mirror)
			)
		)
		(property "Value" ""
			(at 0 0 0)
			(layer "B.Fab")
			(effects
				(font
					(size 1.27 1.27)
				)
				(justify mirror)
			)
		)
		(duplicate_pad_numbers_are_jumpers no)
		(fp_line
			(start 0.7874 0.4064)
			(end 0.7874 -0.4064)
			(stroke
				(width 0.1524)
				(type default)
			)
			(layer "B.SilkS")
		)
		(fp_line
			(start 0.7874 -0.4064)
			(end -0.7874 -0.4064)
			(stroke
				(width 0.1524)
				(type default)
			)
			(layer "B.SilkS")
		)
		(fp_line
			(start -0.7874 0.4064)
			(end 0.7874 0.4064)
			(stroke
				(width 0.1524)
				(type default)
			)
			(layer "B.SilkS")
		)
		(fp_line
			(start -0.7874 -0.4064)
			(end -0.7874 0.4064)
			(stroke
				(width 0.1524)
				(type default)
			)
			(layer "B.SilkS")
		)
		(fp_poly
			(pts
				(xy 0.508 0.2794) (xy 0.508 0.2286) (xy 0.635 0.2286) (xy 0.635 -0.254) (xy 0.5334 -0.254) (xy 0.5334 -0.2794)
				(xy -0.5334 -0.2794) (xy -0.5334 -0.254) (xy -0.635 -0.254) (xy -0.635 0.254) (xy -0.5334 0.254)
				(xy -0.5334 0.2794)
			)
			(stroke
				(width 0)
				(type default)
			)
			(fill no)
			(layer "B.CrtYd")
		)
		(pad "1" smd rect
			(at -0.40005 0)
			(size 0.4572 0.508)
			(layers "B.Cu" "B.Mask" "B.Paste")
			(net "PD_CPU_NODE1_AN5")
		)
		(pad "2" smd rect
			(at 0.40005 0)
			(size 0.4572 0.508)
			(layers "B.Cu" "B.Mask" "B.Paste")
			(net "GND")
		)
	)
	(footprint ""
		(layer "B.Cu")
		(at 147.305014 -71.651622)
		(property "Reference" "C349"
			(at 4.93522 -0.616458 0)
			(unlocked yes)
			(layer "B.SilkS")
			(effects
				(font
					(size 0.7874 0.5842)
					(thickness 0.1524)
				)
				(justify left mirror)
			)
		)
		(property "Value" ""
			(at 0 0 0)
			(layer "B.Fab")
			(effects
				(font
					(size 1.27 1.27)
				)
				(justify mirror)
			)
		)
		(duplicate_pad_numbers_are_jumpers no)
		(fp_line
			(start -0.7874 -0.4064)
			(end -0.7874 0.4064)
			(stroke
				(width 0.1524)
				(type default)
			)
			(layer "B.SilkS")
		)
		(fp_line
			(start -0.7874 0.4064)
			(end 0.7874 0.4064)
			(stroke
				(width 0.1524)
				(type default)
			)
			(layer "B.SilkS")
		)
		(fp_line
			(start 0 0.381)
			(end 0 -0.381)
			(stroke
				(width 0.1524)
				(type default)
			)
			(layer "B.SilkS")
		)
		(fp_line
			(start 0.7874 -0.4064)
			(end -0.7874 -0.4064)
			(stroke
				(width 0.1524)
				(type default)
			)
			(layer "B.SilkS")
		)
		(fp_line
			(start 0.7874 0.4064)
			(end 0.7874 -0.4064)
			(stroke
				(width 0.1524)
				(type default)
			)
			(layer "B.SilkS")
		)
		(fp_poly
			(pts
				(xy 0.5334 0.254) (xy 0.635 0.254) (xy 0.635 0.2286) (xy 0.635 -0.254) (xy 0.5334 -0.254) (xy 0.5334 -0.2794)
				(xy -0.5334 -0.2794) (xy -0.5334 -0.254) (xy -0.635 -0.254) (xy -0.635 0.254) (xy -0.5334 0.254)
				(xy -0.5334 0.2794) (xy 0.508 0.2794) (xy 0.5334 0.2794)
			)
			(stroke
				(width 0)
				(type default)
			)
			(fill no)
			(layer "B.CrtYd")
		)
		(pad "1" smd rect
			(at -0.40005 0 180)
			(size 0.4572 0.508)
			(layers "B.Cu" "B.Mask" "B.Paste")
			(net "GND")
		)
		(pad "2" smd rect
			(at 0.40005 0 180)
			(size 0.4572 0.508)
			(layers "B.Cu" "B.Mask" "B.Paste")
			(net "P1V8_SATA_AVDD_NODE1")
		)
	)
	(footprint ""
		(layer "B.Cu")
		(at 144.51076 -187.999624 90)
		(property "Reference" "R969"
			(at 4.438396 -1.775206 270)
			(unlocked yes)
			(layer "B.SilkS")
			(effects
				(font
					(size 0.7874 0.5842)
					(thickness 0.1524)
				)
				(justify left mirror)
			)
		)
		(property "Value" ""
			(at 0 0 90)
			(layer "B.Fab")
			(effects
				(font
					(size 1.27 1.27)
				)
				(justify mirror)
			)
		)
		(duplicate_pad_numbers_are_jumpers no)
		(fp_line
			(start 0.7874 -0.4064)
			(end -0.7874 -0.4064)
			(stroke
				(width 0.1524)
				(type default)
			)
			(layer "B.SilkS")
		)
		(fp_line
			(start -0.7874 -0.4064)
			(end -0.7874 0.4064)
			(stroke
				(width 0.1524)
				(type default)
			)
			(layer "B.SilkS")
		)
		(fp_line
			(start 0.7874 0.4064)
			(end 0.7874 -0.4064)
			(stroke
				(width 0.1524)
				(type default)
			)
			(layer "B.SilkS")
		)
		(fp_line
			(start -0.7874 0.4064)
			(end 0.7874 0.4064)
			(stroke
				(width 0.1524)
				(type default)
			)
			(layer "B.SilkS")
		)
		(fp_poly
			(pts
				(xy 0.508 0.2794) (xy 0.508 0.2286) (xy 0.635 0.2286) (xy 0.635 -0.254) (xy 0.5334 -0.254) (xy 0.5334 -0.2794)
				(xy -0.5334 -0.2794) (xy -0.5334 -0.254) (xy -0.635 -0.254) (xy -0.635 0.254) (xy -0.5334 0.254)
				(xy -0.5334 0.2794)
			)
			(stroke
				(width 0)
				(type default)
			)
			(fill no)
			(layer "B.CrtYd")
		)
		(pad "1" smd rect
			(at -0.40005 0 270)
			(size 0.4572 0.508)
			(layers "B.Cu" "B.Mask" "B.Paste")
			(net "UART_T11_NODE3_RXD")
		)
		(pad "2" smd rect
			(at 0.40005 0 270)
			(size 0.4572 0.508)
			(layers "B.Cu" "B.Mask" "B.Paste")
			(net "UART_T11_NODE3_RXD_R")
		)
	)
	(footprint ""
		(layer "B.Cu")
		(at 91.47302 -74.756518)
		(property "Reference" "R159"
			(at 4.07797 0.606044 0)
			(unlocked yes)
			(layer "B.SilkS")
			(effects
				(font
					(size 0.7874 0.5842)
					(thickness 0.1524)
				)
				(justify left mirror)
			)
		)
		(property "Value" ""
			(at 0 0 0)
			(layer "B.Fab")
			(effects
				(font
					(size 1.27 1.27)
				)
				(justify mirror)
			)
		)
		(duplicate_pad_numbers_are_jumpers no)
		(fp_line
			(start -0.7874 -0.4064)
			(end -0.7874 0.4064)
			(stroke
				(width 0.1524)
				(type default)
			)
			(layer "B.SilkS")
		)
		(fp_line
			(start -0.7874 0.4064)
			(end 0.7874 0.4064)
			(stroke
				(width 0.1524)
				(type default)
			)
			(layer "B.SilkS")
		)
		(fp_line
			(start 0.7874 -0.4064)
			(end -0.7874 -0.4064)
			(stroke
				(width 0.1524)
				(type default)
			)
			(layer "B.SilkS")
		)
		(fp_line
			(start 0.7874 0.4064)
			(end 0.7874 -0.4064)
			(stroke
				(width 0.1524)
				(type default)
			)
			(layer "B.SilkS")
		)
		(fp_poly
			(pts
				(xy 0.508 0.2794) (xy 0.508 0.2286) (xy 0.635 0.2286) (xy 0.635 -0.254) (xy 0.5334 -0.254) (xy 0.5334 -0.2794)
				(xy -0.5334 -0.2794) (xy -0.5334 -0.254) (xy -0.635 -0.254) (xy -0.635 0.254) (xy -0.5334 0.254)
				(xy -0.5334 0.2794)
			)
			(stroke
				(width 0)
				(type default)
			)
			(fill no)
			(layer "B.CrtYd")
		)
		(pad "1" smd rect
			(at -0.40005 0 180)
			(size 0.4572 0.508)
			(layers "B.Cu" "B.Mask" "B.Paste")
			(net "PD_CPU_NODE1_HVMGEAR_SEL")
		)
		(pad "2" smd rect
			(at 0.40005 0 180)
			(size 0.4572 0.508)
			(layers "B.Cu" "B.Mask" "B.Paste")
			(net "P1V05_SUS_NODE1")
		)
	)
	(footprint ""
		(layer "B.Cu")
		(at 108.5342 -137.415778)
		(property "Reference" "PR41"
			(at 1.000252 1.800606 0)
			(unlocked yes)
			(layer "B.SilkS")
			(effects
				(font
					(size 0.7874 0.5842)
					(thickness 0.1524)
				)
				(justify mirror)
			)
		)
		(property "Value" ""
			(at 0 0 0)
			(layer "B.Fab")
			(effects
				(font
					(size 1.27 1.27)
				)
				(justify mirror)
			)
		)
		(duplicate_pad_numbers_are_jumpers no)
		(fp_line
			(start -1.2954 -0.5842)
			(end -1.2954 0.5842)
			(stroke
				(width 0.1524)
				(type default)
			)
			(layer "B.SilkS")
		)
		(fp_line
			(start -1.2954 0.5842)
			(end 1.2954 0.5842)
			(stroke
				(width 0.1524)
				(type default)
			)
			(layer "B.SilkS")
		)
		(fp_line
			(start 1.2954 -0.5842)
			(end -1.2954 -0.5842)
			(stroke
				(width 0.1524)
				(type default)
			)
			(layer "B.SilkS")
		)
		(fp_line
			(start 1.2954 0.5842)
			(end 1.2954 -0.5842)
			(stroke
				(width 0.1524)
				(type default)
			)
			(layer "B.SilkS")
		)
		(fp_poly
			(pts
				(xy -1.143 -0.3556) (xy -1.143 0.3556) (xy -0.8636 0.3556) (xy -0.8636 0.4572) (xy 0.8636 0.4572)
				(xy 0.8636 0.4318) (xy 0.8636 0.3556) (xy 1.143 0.3556) (xy 1.143 -0.3556) (xy 0.8636 -0.3556) (xy 0.8636 -0.4572)
				(xy -0.8636 -0.4572) (xy -0.8636 -0.3556)
			)
			(stroke
				(width 0)
				(type default)
			)
			(fill no)
			(layer "B.CrtYd")
		)
		(pad "1" smd rect
			(at -0.7366 0 90)
			(size 0.7112 0.8128)
			(layers "B.Cu" "B.Mask" "B.Paste")
			(net "P5V_STB_NODE1")
		)
		(pad "2" smd rect
			(at 0.7366 0 90)
			(size 0.7112 0.8128)
			(layers "B.Cu" "B.Mask" "B.Paste")
			(net "VR_PVCCP_NODE1_VCC")
		)
	)
	(footprint ""
		(layer "B.Cu")
		(at 77.396086 -125.438662)
		(property "Reference" "C285"
			(at 3.903472 0.243078 0)
			(unlocked yes)
			(layer "B.SilkS")
			(effects
				(font
					(size 0.7874 0.5842)
					(thickness 0.1524)
				)
				(justify left mirror)
			)
		)
		(property "Value" ""
			(at 0 0 0)
			(layer "B.Fab")
			(effects
				(font
					(size 1.27 1.27)
				)
				(justify mirror)
			)
		)
		(duplicate_pad_numbers_are_jumpers no)
		(fp_line
			(start -0.7874 -0.4064)
			(end -0.7874 0.4064)
			(stroke
				(width 0.1524)
				(type default)
			)
			(layer "B.SilkS")
		)
		(fp_line
			(start -0.7874 0.4064)
			(end 0.7874 0.4064)
			(stroke
				(width 0.1524)
				(type default)
			)
			(layer "B.SilkS")
		)
		(fp_line
			(start 0 0.381)
			(end 0 -0.381)
			(stroke
				(width 0.1524)
				(type default)
			)
			(layer "B.SilkS")
		)
		(fp_line
			(start 0.7874 -0.4064)
			(end -0.7874 -0.4064)
			(stroke
				(width 0.1524)
				(type default)
			)
			(layer "B.SilkS")
		)
		(fp_line
			(start 0.7874 0.4064)
			(end 0.7874 -0.4064)
			(stroke
				(width 0.1524)
				(type default)
			)
			(layer "B.SilkS")
		)
		(fp_poly
			(pts
				(xy 0.5334 0.254) (xy 0.635 0.254) (xy 0.635 0.2286) (xy 0.635 -0.254) (xy 0.5334 -0.254) (xy 0.5334 -0.2794)
				(xy -0.5334 -0.2794) (xy -0.5334 -0.254) (xy -0.635 -0.254) (xy -0.635 0.254) (xy -0.5334 0.254)
				(xy -0.5334 0.2794) (xy 0.508 0.2794) (xy 0.5334 0.2794)
			)
			(stroke
				(width 0)
				(type default)
			)
			(fill no)
			(layer "B.CrtYd")
		)
		(pad "1" smd rect
			(at -0.40005 0 180)
			(size 0.4572 0.508)
			(layers "B.Cu" "B.Mask" "B.Paste")
			(net "BMC_NODE1_VCC_1V8_PCIEA")
		)
		(pad "2" smd rect
			(at 0.40005 0 180)
			(size 0.4572 0.508)
			(layers "B.Cu" "B.Mask" "B.Paste")
			(net "GND")
		)
	)
	(footprint ""
		(layer "B.Cu")
		(at 144.51076 -184.951624 -90)
		(property "Reference" "C732"
			(at -4.357624 2.41427 270)
			(unlocked yes)
			(layer "B.SilkS")
			(effects
				(font
					(size 0.7874 0.5842)
					(thickness 0.1524)
				)
				(justify left mirror)
			)
		)
		(property "Value" ""
			(at 0 0 90)
			(layer "B.Fab")
			(effects
				(font
					(size 1.27 1.27)
				)
				(justify mirror)
			)
		)
		(duplicate_pad_numbers_are_jumpers no)
		(fp_line
			(start -0.7874 0.4064)
			(end 0.7874 0.4064)
			(stroke
				(width 0.1524)
				(type default)
			)
			(layer "B.SilkS")
		)
		(fp_line
			(start 0.7874 0.4064)
			(end 0.7874 -0.4064)
			(stroke
				(width 0.1524)
				(type default)
			)
			(layer "B.SilkS")
		)
		(fp_line
			(start 0 0.381)
			(end 0 -0.381)
			(stroke
				(width 0.1524)
				(type default)
			)
			(layer "B.SilkS")
		)
		(fp_line
			(start -0.7874 -0.4064)
			(end -0.7874 0.4064)
			(stroke
				(width 0.1524)
				(type default)
			)
			(layer "B.SilkS")
		)
		(fp_line
			(start 0.7874 -0.4064)
			(end -0.7874 -0.4064)
			(stroke
				(width 0.1524)
				(type default)
			)
			(layer "B.SilkS")
		)
		(fp_poly
			(pts
				(xy 0.5334 0.254) (xy 0.635 0.254) (xy 0.635 0.2286) (xy 0.635 -0.254) (xy 0.5334 -0.254) (xy 0.5334 -0.2794)
				(xy -0.5334 -0.2794) (xy -0.5334 -0.254) (xy -0.635 -0.254) (xy -0.635 0.254) (xy -0.5334 0.254)
				(xy -0.5334 0.2794) (xy 0.508 0.2794) (xy 0.5334 0.2794)
			)
			(stroke
				(width 0)
				(type default)
			)
			(fill no)
			(layer "B.CrtYd")
		)
		(pad "1" smd rect
			(at -0.40005 0 90)
			(size 0.4572 0.508)
			(layers "B.Cu" "B.Mask" "B.Paste")
			(net "UART_T11_NODE3_RXD")
		)
		(pad "2" smd rect
			(at 0.40005 0 90)
			(size 0.4572 0.508)
			(layers "B.Cu" "B.Mask" "B.Paste")
			(net "GND")
		)
	)
	(footprint ""
		(layer "B.Cu")
		(at 139.252452 -139.57935 -90)
		(property "Reference" "C867"
			(at -0.451866 0.585216 0)
			(unlocked yes)
			(layer "B.SilkS")
			(effects
				(font
					(size 0.7874 0.5842)
					(thickness 0.1524)
				)
				(justify left mirror)
			)
		)
		(property "Value" ""
			(at 0 0 90)
			(layer "B.Fab")
			(effects
				(font
					(size 1.27 1.27)
				)
				(justify mirror)
			)
		)
		(duplicate_pad_numbers_are_jumpers no)
		(fp_line
			(start -0.7874 0.4064)
			(end 0.7874 0.4064)
			(stroke
				(width 0.1524)
				(type default)
			)
			(layer "B.SilkS")
		)
		(fp_line
			(start 0.7874 0.4064)
			(end 0.7874 -0.4064)
			(stroke
				(width 0.1524)
				(type default)
			)
			(layer "B.SilkS")
		)
		(fp_line
			(start 0 0.381)
			(end 0 -0.381)
			(stroke
				(width 0.1524)
				(type default)
			)
			(layer "B.SilkS")
		)
		(fp_line
			(start -0.7874 -0.4064)
			(end -0.7874 0.4064)
			(stroke
				(width 0.1524)
				(type default)
			)
			(layer "B.SilkS")
		)
		(fp_line
			(start 0.7874 -0.4064)
			(end -0.7874 -0.4064)
			(stroke
				(width 0.1524)
				(type default)
			)
			(layer "B.SilkS")
		)
		(fp_poly
			(pts
				(xy 0.5334 0.254) (xy 0.635 0.254) (xy 0.635 0.2286) (xy 0.635 -0.254) (xy 0.5334 -0.254) (xy 0.5334 -0.2794)
				(xy -0.5334 -0.2794) (xy -0.5334 -0.254) (xy -0.635 -0.254) (xy -0.635 0.254) (xy -0.5334 0.254)
				(xy -0.5334 0.2794) (xy 0.508 0.2794) (xy 0.5334 0.2794)
			)
			(stroke
				(width 0)
				(type default)
			)
			(fill no)
			(layer "B.CrtYd")
		)
		(pad "1" smd rect
			(at -0.40005 0 90)
			(size 0.4572 0.508)
			(layers "B.Cu" "B.Mask" "B.Paste")
			(net "P3V3_NODE1")
		)
		(pad "2" smd rect
			(at 0.40005 0 90)
			(size 0.4572 0.508)
			(layers "B.Cu" "B.Mask" "B.Paste")
			(net "GND")
		)
	)
	(footprint ""
		(layer "B.Cu")
		(at 141.08176 -187.948824 -90)
		(property "Reference" "C741"
			(at -4.544568 1.490472 270)
			(unlocked yes)
			(layer "B.SilkS")
			(effects
				(font
					(size 0.7874 0.5842)
					(thickness 0.1524)
				)
				(justify left mirror)
			)
		)
		(property "Value" ""
			(at 0 0 90)
			(layer "B.Fab")
			(effects
				(font
					(size 1.27 1.27)
				)
				(justify mirror)
			)
		)
		(duplicate_pad_numbers_are_jumpers no)
		(fp_line
			(start -0.7874 0.4064)
			(end 0.7874 0.4064)
			(stroke
				(width 0.1524)
				(type default)
			)
			(layer "B.SilkS")
		)
		(fp_line
			(start 0.7874 0.4064)
			(end 0.7874 -0.4064)
			(stroke
				(width 0.1524)
				(type default)
			)
			(layer "B.SilkS")
		)
		(fp_line
			(start 0 0.381)
			(end 0 -0.381)
			(stroke
				(width 0.1524)
				(type default)
			)
			(layer "B.SilkS")
		)
		(fp_line
			(start -0.7874 -0.4064)
			(end -0.7874 0.4064)
			(stroke
				(width 0.1524)
				(type default)
			)
			(layer "B.SilkS")
		)
		(fp_line
			(start 0.7874 -0.4064)
			(end -0.7874 -0.4064)
			(stroke
				(width 0.1524)
				(type default)
			)
			(layer "B.SilkS")
		)
		(fp_poly
			(pts
				(xy 0.5334 0.254) (xy 0.635 0.254) (xy 0.635 0.2286) (xy 0.635 -0.254) (xy 0.5334 -0.254) (xy 0.5334 -0.2794)
				(xy -0.5334 -0.2794) (xy -0.5334 -0.254) (xy -0.635 -0.254) (xy -0.635 0.254) (xy -0.5334 0.254)
				(xy -0.5334 0.2794) (xy 0.508 0.2794) (xy 0.5334 0.2794)
			)
			(stroke
				(width 0)
				(type default)
			)
			(fill no)
			(layer "B.CrtYd")
		)
		(pad "1" smd rect
			(at -0.40005 0 90)
			(size 0.4572 0.508)
			(layers "B.Cu" "B.Mask" "B.Paste")
			(net "UART_T11_NODE4_TXD_R")
		)
		(pad "2" smd rect
			(at 0.40005 0 90)
			(size 0.4572 0.508)
			(layers "B.Cu" "B.Mask" "B.Paste")
			(net "GND")
		)
	)
	(footprint ""
		(layer "B.Cu")
		(at 56.519572 -70.354698)
		(property "Reference" "C80"
			(at -13.618972 31.441136 0)
			(unlocked yes)
			(layer "B.SilkS")
			(effects
				(font
					(size 0.7874 0.5842)
					(thickness 0.1524)
				)
				(justify left mirror)
			)
		)
		(property "Value" ""
			(at 0 0 0)
			(layer "B.Fab")
			(effects
				(font
					(size 1.27 1.27)
				)
				(justify mirror)
			)
		)
		(duplicate_pad_numbers_are_jumpers no)
		(fp_line
			(start -0.7874 -0.4064)
			(end -0.7874 0.4064)
			(stroke
				(width 0.1524)
				(type default)
			)
			(layer "B.SilkS")
		)
		(fp_line
			(start -0.7874 0.4064)
			(end 0.7874 0.4064)
			(stroke
				(width 0.1524)
				(type default)
			)
			(layer "B.SilkS")
		)
		(fp_line
			(start 0 0.381)
			(end 0 -0.381)
			(stroke
				(width 0.1524)
				(type default)
			)
			(layer "B.SilkS")
		)
		(fp_line
			(start 0.7874 -0.4064)
			(end -0.7874 -0.4064)
			(stroke
				(width 0.1524)
				(type default)
			)
			(layer "B.SilkS")
		)
		(fp_line
			(start 0.7874 0.4064)
			(end 0.7874 -0.4064)
			(stroke
				(width 0.1524)
				(type default)
			)
			(layer "B.SilkS")
		)
		(fp_poly
			(pts
				(xy 0.5334 0.254) (xy 0.635 0.254) (xy 0.635 0.2286) (xy 0.635 -0.254) (xy 0.5334 -0.254) (xy 0.5334 -0.2794)
				(xy -0.5334 -0.2794) (xy -0.5334 -0.254) (xy -0.635 -0.254) (xy -0.635 0.254) (xy -0.5334 0.254)
				(xy -0.5334 0.2794) (xy 0.508 0.2794) (xy 0.5334 0.2794)
			)
			(stroke
				(width 0)
				(type default)
			)
			(fill no)
			(layer "B.CrtYd")
		)
		(pad "1" smd rect
			(at -0.40005 0 180)
			(size 0.4572 0.508)
			(layers "B.Cu" "B.Mask" "B.Paste")
			(net "P1V05_VCCACLK_DDR3_NODE1")
		)
		(pad "2" smd rect
			(at 0.40005 0 180)
			(size 0.4572 0.508)
			(layers "B.Cu" "B.Mask" "B.Paste")
			(net "GND")
		)
	)
	(footprint ""
		(layer "B.Cu")
		(at 141.005052 -144.76095 -90)
		(property "Reference" "C866"
			(at -0.031242 1.143762 0)
			(unlocked yes)
			(layer "B.SilkS")
			(effects
				(font
					(size 0.7874 0.5842)
					(thickness 0.1524)
				)
				(justify left mirror)
			)
		)
		(property "Value" ""
			(at 0 0 90)
			(layer "B.Fab")
			(effects
				(font
					(size 1.27 1.27)
				)
				(justify mirror)
			)
		)
		(duplicate_pad_numbers_are_jumpers no)
		(fp_line
			(start -0.7874 0.4064)
			(end 0.7874 0.4064)
			(stroke
				(width 0.1524)
				(type default)
			)
			(layer "B.SilkS")
		)
		(fp_line
			(start 0.7874 0.4064)
			(end 0.7874 -0.4064)
			(stroke
				(width 0.1524)
				(type default)
			)
			(layer "B.SilkS")
		)
		(fp_line
			(start 0 0.381)
			(end 0 -0.381)
			(stroke
				(width 0.1524)
				(type default)
			)
			(layer "B.SilkS")
		)
		(fp_line
			(start -0.7874 -0.4064)
			(end -0.7874 0.4064)
			(stroke
				(width 0.1524)
				(type default)
			)
			(layer "B.SilkS")
		)
		(fp_line
			(start 0.7874 -0.4064)
			(end -0.7874 -0.4064)
			(stroke
				(width 0.1524)
				(type default)
			)
			(layer "B.SilkS")
		)
		(fp_poly
			(pts
				(xy 0.5334 0.254) (xy 0.635 0.254) (xy 0.635 0.2286) (xy 0.635 -0.254) (xy 0.5334 -0.254) (xy 0.5334 -0.2794)
				(xy -0.5334 -0.2794) (xy -0.5334 -0.254) (xy -0.635 -0.254) (xy -0.635 0.254) (xy -0.5334 0.254)
				(xy -0.5334 0.2794) (xy 0.508 0.2794) (xy 0.5334 0.2794)
			)
			(stroke
				(width 0)
				(type default)
			)
			(fill no)
			(layer "B.CrtYd")
		)
		(pad "1" smd rect
			(at -0.40005 0 90)
			(size 0.4572 0.508)
			(layers "B.Cu" "B.Mask" "B.Paste")
			(net "P3V3_NODE1")
		)
		(pad "2" smd rect
			(at 0.40005 0 90)
			(size 0.4572 0.508)
			(layers "B.Cu" "B.Mask" "B.Paste")
			(net "GND")
		)
	)
	(footprint ""
		(layer "B.Cu")
		(at 37.90442 -151.92629 180)
		(property "Reference" "C406"
			(at 6.961378 10.661396 0)
			(unlocked yes)
			(layer "B.SilkS")
			(effects
				(font
					(size 0.7874 0.5842)
					(thickness 0.1524)
				)
				(justify left mirror)
			)
		)
		(property "Value" ""
			(at 0 0 0)
			(layer "B.Fab")
			(effects
				(font
					(size 1.27 1.27)
				)
				(justify mirror)
			)
		)
		(duplicate_pad_numbers_are_jumpers no)
		(fp_line
			(start 0.7874 0.4064)
			(end 0.7874 -0.4064)
			(stroke
				(width 0.1524)
				(type default)
			)
			(layer "B.SilkS")
		)
		(fp_line
			(start 0.7874 -0.4064)
			(end -0.7874 -0.4064)
			(stroke
				(width 0.1524)
				(type default)
			)
			(layer "B.SilkS")
		)
		(fp_line
			(start 0 0.381)
			(end 0 -0.381)
			(stroke
				(width 0.1524)
				(type default)
			)
			(layer "B.SilkS")
		)
		(fp_line
			(start -0.7874 0.4064)
			(end 0.7874 0.4064)
			(stroke
				(width 0.1524)
				(type default)
			)
			(layer "B.SilkS")
		)
		(fp_line
			(start -0.7874 -0.4064)
			(end -0.7874 0.4064)
			(stroke
				(width 0.1524)
				(type default)
			)
			(layer "B.SilkS")
		)
		(fp_poly
			(pts
				(xy 0.5334 0.254) (xy 0.635 0.254) (xy 0.635 0.2286) (xy 0.635 -0.254) (xy 0.5334 -0.254) (xy 0.5334 -0.2794)
				(xy -0.5334 -0.2794) (xy -0.5334 -0.254) (xy -0.635 -0.254) (xy -0.635 0.254) (xy -0.5334 0.254)
				(xy -0.5334 0.2794) (xy 0.508 0.2794) (xy 0.5334 0.2794)
			)
			(stroke
				(width 0)
				(type default)
			)
			(fill no)
			(layer "B.CrtYd")
		)
		(pad "1" smd rect
			(at -0.40005 0)
			(size 0.4572 0.508)
			(layers "B.Cu" "B.Mask" "B.Paste")
			(net "P1V9_LAN1")
		)
		(pad "2" smd rect
			(at 0.40005 0)
			(size 0.4572 0.508)
			(layers "B.Cu" "B.Mask" "B.Paste")
			(net "GND")
		)
	)
	(footprint ""
		(layer "B.Cu")
		(at 51.849782 -70.512686)
		(property "Reference" "R36"
			(at -13.538962 31.434024 0)
			(unlocked yes)
			(layer "B.SilkS")
			(effects
				(font
					(size 0.7874 0.5842)
					(thickness 0.1524)
				)
				(justify left mirror)
			)
		)
		(property "Value" ""
			(at 0 0 0)
			(layer "B.Fab")
			(effects
				(font
					(size 1.27 1.27)
				)
				(justify mirror)
			)
		)
		(duplicate_pad_numbers_are_jumpers no)
		(fp_line
			(start -0.7874 -0.4064)
			(end -0.7874 0.4064)
			(stroke
				(width 0.1524)
				(type default)
			)
			(layer "B.SilkS")
		)
		(fp_line
			(start -0.7874 0.4064)
			(end 0.7874 0.4064)
			(stroke
				(width 0.1524)
				(type default)
			)
			(layer "B.SilkS")
		)
		(fp_line
			(start 0.7874 -0.4064)
			(end -0.7874 -0.4064)
			(stroke
				(width 0.1524)
				(type default)
			)
			(layer "B.SilkS")
		)
		(fp_line
			(start 0.7874 0.4064)
			(end 0.7874 -0.4064)
			(stroke
				(width 0.1524)
				(type default)
			)
			(layer "B.SilkS")
		)
		(fp_poly
			(pts
				(xy 0.508 0.2794) (xy 0.508 0.2286) (xy 0.635 0.2286) (xy 0.635 -0.254) (xy 0.5334 -0.254) (xy 0.5334 -0.2794)
				(xy -0.5334 -0.2794) (xy -0.5334 -0.254) (xy -0.635 -0.254) (xy -0.635 0.254) (xy -0.5334 0.254)
				(xy -0.5334 0.2794)
			)
			(stroke
				(width 0)
				(type default)
			)
			(fill no)
			(layer "B.CrtYd")
		)
		(pad "1" smd rect
			(at -0.40005 0 180)
			(size 0.4572 0.508)
			(layers "B.Cu" "B.Mask" "B.Paste")
			(net "P1V5_NODE1")
		)
		(pad "2" smd rect
			(at 0.40005 0 180)
			(size 0.4572 0.508)
			(layers "B.Cu" "B.Mask" "B.Paste")
			(net "A_NODE1_RP0_RCOMP")
		)
	)
	(footprint ""
		(layer "B.Cu")
		(at 129.54 -59.436 90)
		(property "Reference" "R1330"
			(at 1.27 0.10033 270)
			(unlocked yes)
			(layer "B.SilkS")
			(effects
				(font
					(size 0.7874 0.5842)
					(thickness 0.1524)
				)
				(justify left mirror)
			)
		)
		(property "Value" ""
			(at 0 0 90)
			(layer "B.Fab")
			(effects
				(font
					(size 1.27 1.27)
				)
				(justify mirror)
			)
		)
		(duplicate_pad_numbers_are_jumpers no)
		(fp_line
			(start 0.7874 -0.4064)
			(end -0.7874 -0.4064)
			(stroke
				(width 0.1524)
				(type default)
			)
			(layer "B.SilkS")
		)
		(fp_line
			(start -0.7874 -0.4064)
			(end -0.7874 0.4064)
			(stroke
				(width 0.1524)
				(type default)
			)
			(layer "B.SilkS")
		)
		(fp_line
			(start 0.7874 0.4064)
			(end 0.7874 -0.4064)
			(stroke
				(width 0.1524)
				(type default)
			)
			(layer "B.SilkS")
		)
		(fp_line
			(start -0.7874 0.4064)
			(end 0.7874 0.4064)
			(stroke
				(width 0.1524)
				(type default)
			)
			(layer "B.SilkS")
		)
		(fp_poly
			(pts
				(xy 0.508 0.2794) (xy 0.508 0.2286) (xy 0.635 0.2286) (xy 0.635 -0.254) (xy 0.5334 -0.254) (xy 0.5334 -0.2794)
				(xy -0.5334 -0.2794) (xy -0.5334 -0.254) (xy -0.635 -0.254) (xy -0.635 0.254) (xy -0.5334 0.254)
				(xy -0.5334 0.2794)
			)
			(stroke
				(width 0)
				(type default)
			)
			(fill no)
			(layer "B.CrtYd")
		)
		(pad "1" smd rect
			(at -0.40005 0 270)
			(size 0.4572 0.508)
			(layers "B.Cu" "B.Mask" "B.Paste")
			(net "UART_RI_P3_BUFFER_N")
		)
		(pad "2" smd rect
			(at 0.40005 0 270)
			(size 0.4572 0.508)
			(layers "B.Cu" "B.Mask" "B.Paste")
			(net "P3V3_NODE1")
		)
	)
	(footprint ""
		(layer "B.Cu")
		(at 36.964874 -133.45287 90)
		(property "Reference" "R261"
			(at -1.92659 -2.218436 270)
			(unlocked yes)
			(layer "B.SilkS")
			(effects
				(font
					(size 0.7874 0.5842)
					(thickness 0.1524)
				)
				(justify left mirror)
			)
		)
		(property "Value" ""
			(at 0 0 90)
			(layer "B.Fab")
			(effects
				(font
					(size 1.27 1.27)
				)
				(justify mirror)
			)
		)
		(duplicate_pad_numbers_are_jumpers no)
		(fp_line
			(start 0.7874 -0.4064)
			(end -0.7874 -0.4064)
			(stroke
				(width 0.1524)
				(type default)
			)
			(layer "B.SilkS")
		)
		(fp_line
			(start -0.7874 -0.4064)
			(end -0.7874 0.4064)
			(stroke
				(width 0.1524)
				(type default)
			)
			(layer "B.SilkS")
		)
		(fp_line
			(start 0.7874 0.4064)
			(end 0.7874 -0.4064)
			(stroke
				(width 0.1524)
				(type default)
			)
			(layer "B.SilkS")
		)
		(fp_line
			(start -0.7874 0.4064)
			(end 0.7874 0.4064)
			(stroke
				(width 0.1524)
				(type default)
			)
			(layer "B.SilkS")
		)
		(fp_poly
			(pts
				(xy 0.508 0.2794) (xy 0.508 0.2286) (xy 0.635 0.2286) (xy 0.635 -0.254) (xy 0.5334 -0.254) (xy 0.5334 -0.2794)
				(xy -0.5334 -0.2794) (xy -0.5334 -0.254) (xy -0.635 -0.254) (xy -0.635 0.254) (xy -0.5334 0.254)
				(xy -0.5334 0.2794)
			)
			(stroke
				(width 0)
				(type default)
			)
			(fill no)
			(layer "B.CrtYd")
		)
		(pad "1" smd rect
			(at -0.40005 0 270)
			(size 0.4572 0.508)
			(layers "B.Cu" "B.Mask" "B.Paste")
			(net "P1V538_BMC_NODE1")
		)
		(pad "2" smd rect
			(at 0.40005 0 270)
			(size 0.4572 0.508)
			(layers "B.Cu" "B.Mask" "B.Paste")
			(net "P0V75_BMC_VTTREF_NODE1")
		)
	)
	(footprint ""
		(layer "B.Cu")
		(at 52.81676 -181.992524 -90)
		(property "Reference" "C601"
			(at 3.618738 10.725912 270)
			(unlocked yes)
			(layer "B.SilkS")
			(effects
				(font
					(size 0.7874 0.5842)
					(thickness 0.1524)
				)
				(justify left mirror)
			)
		)
		(property "Value" ""
			(at 0 0 90)
			(layer "B.Fab")
			(effects
				(font
					(size 1.27 1.27)
				)
				(justify mirror)
			)
		)
		(duplicate_pad_numbers_are_jumpers no)
		(fp_line
			(start -0.7874 0.4064)
			(end 0.7874 0.4064)
			(stroke
				(width 0.1524)
				(type default)
			)
			(layer "B.SilkS")
		)
		(fp_line
			(start 0.7874 0.4064)
			(end 0.7874 -0.4064)
			(stroke
				(width 0.1524)
				(type default)
			)
			(layer "B.SilkS")
		)
		(fp_line
			(start 0 0.381)
			(end 0 -0.381)
			(stroke
				(width 0.1524)
				(type default)
			)
			(layer "B.SilkS")
		)
		(fp_line
			(start -0.7874 -0.4064)
			(end -0.7874 0.4064)
			(stroke
				(width 0.1524)
				(type default)
			)
			(layer "B.SilkS")
		)
		(fp_line
			(start 0.7874 -0.4064)
			(end -0.7874 -0.4064)
			(stroke
				(width 0.1524)
				(type default)
			)
			(layer "B.SilkS")
		)
		(fp_poly
			(pts
				(xy 0.5334 0.254) (xy 0.635 0.254) (xy 0.635 0.2286) (xy 0.635 -0.254) (xy 0.5334 -0.254) (xy 0.5334 -0.2794)
				(xy -0.5334 -0.2794) (xy -0.5334 -0.254) (xy -0.635 -0.254) (xy -0.635 0.254) (xy -0.5334 0.254)
				(xy -0.5334 0.2794) (xy 0.508 0.2794) (xy 0.5334 0.2794)
			)
			(stroke
				(width 0)
				(type default)
			)
			(fill no)
			(layer "B.CrtYd")
		)
		(pad "1" smd rect
			(at -0.40005 0 90)
			(size 0.4572 0.508)
			(layers "B.Cu" "B.Mask" "B.Paste")
			(net "PSU1_DC_OK_R_BUF")
		)
		(pad "2" smd rect
			(at 0.40005 0 90)
			(size 0.4572 0.508)
			(layers "B.Cu" "B.Mask" "B.Paste")
			(net "GND")
		)
	)
	(footprint ""
		(layer "B.Cu")
		(at 176.487582 -118.67896 90)
		(property "Reference" "C791"
			(at -4.32816 0.041148 270)
			(unlocked yes)
			(layer "B.SilkS")
			(effects
				(font
					(size 0.7874 0.5842)
					(thickness 0.1524)
				)
				(justify mirror)
			)
		)
		(property "Value" ""
			(at 0 0 90)
			(layer "B.Fab")
			(effects
				(font
					(size 1.27 1.27)
				)
				(justify mirror)
			)
		)
		(duplicate_pad_numbers_are_jumpers no)
		(fp_line
			(start 1.2954 -0.5842)
			(end -1.2954 -0.5842)
			(stroke
				(width 0.1524)
				(type default)
			)
			(layer "B.SilkS")
		)
		(fp_line
			(start 0 -0.5842)
			(end 0 0.5842)
			(stroke
				(width 0.1524)
				(type default)
			)
			(layer "B.SilkS")
		)
		(fp_line
			(start -1.2954 -0.5842)
			(end -1.2954 0.5842)
			(stroke
				(width 0.1524)
				(type default)
			)
			(layer "B.SilkS")
		)
		(fp_line
			(start 1.2954 0.5842)
			(end 1.2954 -0.5842)
			(stroke
				(width 0.1524)
				(type default)
			)
			(layer "B.SilkS")
		)
		(fp_line
			(start -1.2954 0.5842)
			(end 1.2954 0.5842)
			(stroke
				(width 0.1524)
				(type default)
			)
			(layer "B.SilkS")
		)
		(fp_poly
			(pts
				(xy -0.8636 -0.4572) (xy -0.8636 -0.3556) (xy -1.143 -0.3556) (xy -1.143 0.3556) (xy -0.8636 0.3556)
				(xy -0.8636 0.4572) (xy 0.8636 0.4572) (xy 0.8636 0.3556) (xy 1.143 0.3556) (xy 1.143 -0.3556) (xy 0.8636 -0.3556)
				(xy 0.8636 -0.4572)
			)
			(stroke
				(width 0)
				(type default)
			)
			(fill no)
			(layer "B.CrtYd")
		)
		(fp_line
			(start 0.884936 -0.504952)
			(end -0.884936 -0.504952)
			(stroke
				(width 0.1)
				(type default)
			)
			(layer "B.Fab")
		)
		(fp_line
			(start -0.884936 -0.504952)
			(end -0.884936 0.504952)
			(stroke
				(width 0.1)
				(type default)
			)
			(layer "B.Fab")
		)
		(fp_line
			(start 0.884936 0.504952)
			(end 0.884936 -0.504952)
			(stroke
				(width 0.1)
				(type default)
			)
			(layer "B.Fab")
		)
		(fp_line
			(start -0.884936 0.504952)
			(end 0.884936 0.504952)
			(stroke
				(width 0.1)
				(type default)
			)
			(layer "B.Fab")
		)
		(pad "1" smd rect
			(at -0.7366 0 180)
			(size 0.7112 0.8128)
			(layers "B.Cu" "B.Mask" "B.Paste")
			(net "P3V3_STB_NODE1")
		)
		(pad "2" smd rect
			(at 0.7366 0 180)
			(size 0.7112 0.8128)
			(layers "B.Cu" "B.Mask" "B.Paste")
			(net "GND")
		)
	)
	(footprint ""
		(layer "B.Cu")
		(at 110.44936 -176.569624 180)
		(property "Reference" "R712"
			(at 21.356828 -32.269176 0)
			(unlocked yes)
			(layer "B.SilkS")
			(effects
				(font
					(size 0.7874 0.5842)
					(thickness 0.1524)
				)
				(justify left mirror)
			)
		)
		(property "Value" ""
			(at 0 0 0)
			(layer "B.Fab")
			(effects
				(font
					(size 1.27 1.27)
				)
				(justify mirror)
			)
		)
		(duplicate_pad_numbers_are_jumpers no)
		(fp_line
			(start 0.7874 0.4064)
			(end 0.7874 -0.4064)
			(stroke
				(width 0.1524)
				(type default)
			)
			(layer "B.SilkS")
		)
		(fp_line
			(start 0.7874 -0.4064)
			(end -0.7874 -0.4064)
			(stroke
				(width 0.1524)
				(type default)
			)
			(layer "B.SilkS")
		)
		(fp_line
			(start -0.7874 0.4064)
			(end 0.7874 0.4064)
			(stroke
				(width 0.1524)
				(type default)
			)
			(layer "B.SilkS")
		)
		(fp_line
			(start -0.7874 -0.4064)
			(end -0.7874 0.4064)
			(stroke
				(width 0.1524)
				(type default)
			)
			(layer "B.SilkS")
		)
		(fp_poly
			(pts
				(xy 0.508 0.2794) (xy 0.508 0.2286) (xy 0.635 0.2286) (xy 0.635 -0.254) (xy 0.5334 -0.254) (xy 0.5334 -0.2794)
				(xy -0.5334 -0.2794) (xy -0.5334 -0.254) (xy -0.635 -0.254) (xy -0.635 0.254) (xy -0.5334 0.254)
				(xy -0.5334 0.2794)
			)
			(stroke
				(width 0)
				(type default)
			)
			(fill no)
			(layer "B.CrtYd")
		)
		(pad "1" smd rect
			(at -0.40005 0)
			(size 0.4572 0.508)
			(layers "B.Cu" "B.Mask" "B.Paste")
			(net "T5_NODE3_EN")
		)
		(pad "2" smd rect
			(at 0.40005 0)
			(size 0.4572 0.508)
			(layers "B.Cu" "B.Mask" "B.Paste")
			(net "P5V_NODE1")
		)
	)
	(footprint ""
		(layer "B.Cu")
		(at 159.25038 -148.804122 90)
		(property "Reference" "C461"
			(at -8.469122 -0.061722 270)
			(unlocked yes)
			(layer "B.SilkS")
			(effects
				(font
					(size 0.7874 0.5842)
					(thickness 0.1524)
				)
				(justify left mirror)
			)
		)
		(property "Value" ""
			(at 0 0 90)
			(layer "B.Fab")
			(effects
				(font
					(size 1.27 1.27)
				)
				(justify mirror)
			)
		)
		(duplicate_pad_numbers_are_jumpers no)
		(fp_line
			(start 0.7874 -0.4064)
			(end -0.7874 -0.4064)
			(stroke
				(width 0.1524)
				(type default)
			)
			(layer "B.SilkS")
		)
		(fp_line
			(start -0.7874 -0.4064)
			(end -0.7874 0.4064)
			(stroke
				(width 0.1524)
				(type default)
			)
			(layer "B.SilkS")
		)
		(fp_line
			(start 0 0.381)
			(end 0 -0.381)
			(stroke
				(width 0.1524)
				(type default)
			)
			(layer "B.SilkS")
		)
		(fp_line
			(start 0.7874 0.4064)
			(end 0.7874 -0.4064)
			(stroke
				(width 0.1524)
				(type default)
			)
			(layer "B.SilkS")
		)
		(fp_line
			(start -0.7874 0.4064)
			(end 0.7874 0.4064)
			(stroke
				(width 0.1524)
				(type default)
			)
			(layer "B.SilkS")
		)
		(fp_poly
			(pts
				(xy 0.5334 0.254) (xy 0.635 0.254) (xy 0.635 0.2286) (xy 0.635 -0.254) (xy 0.5334 -0.254) (xy 0.5334 -0.2794)
				(xy -0.5334 -0.2794) (xy -0.5334 -0.254) (xy -0.635 -0.254) (xy -0.635 0.254) (xy -0.5334 0.254)
				(xy -0.5334 0.2794) (xy 0.508 0.2794) (xy 0.5334 0.2794)
			)
			(stroke
				(width 0)
				(type default)
			)
			(fill no)
			(layer "B.CrtYd")
		)
		(pad "1" smd rect
			(at -0.40005 0 270)
			(size 0.4572 0.508)
			(layers "B.Cu" "B.Mask" "B.Paste")
			(net "P1V05_LAN2")
		)
		(pad "2" smd rect
			(at 0.40005 0 270)
			(size 0.4572 0.508)
			(layers "B.Cu" "B.Mask" "B.Paste")
			(net "GND")
		)
	)
	(footprint ""
		(layer "B.Cu")
		(at 47.551086 -137.376662 180)
		(property "Reference" "C233"
			(at -3.853434 0.612648 0)
			(unlocked yes)
			(layer "B.SilkS")
			(effects
				(font
					(size 0.7874 0.5842)
					(thickness 0.1524)
				)
				(justify left mirror)
			)
		)
		(property "Value" ""
			(at 0 0 0)
			(layer "B.Fab")
			(effects
				(font
					(size 1.27 1.27)
				)
				(justify mirror)
			)
		)
		(duplicate_pad_numbers_are_jumpers no)
		(fp_line
			(start 0.7874 0.4064)
			(end 0.7874 -0.4064)
			(stroke
				(width 0.1524)
				(type default)
			)
			(layer "B.SilkS")
		)
		(fp_line
			(start 0.7874 -0.4064)
			(end -0.7874 -0.4064)
			(stroke
				(width 0.1524)
				(type default)
			)
			(layer "B.SilkS")
		)
		(fp_line
			(start 0 0.381)
			(end 0 -0.381)
			(stroke
				(width 0.1524)
				(type default)
			)
			(layer "B.SilkS")
		)
		(fp_line
			(start -0.7874 0.4064)
			(end 0.7874 0.4064)
			(stroke
				(width 0.1524)
				(type default)
			)
			(layer "B.SilkS")
		)
		(fp_line
			(start -0.7874 -0.4064)
			(end -0.7874 0.4064)
			(stroke
				(width 0.1524)
				(type default)
			)
			(layer "B.SilkS")
		)
		(fp_poly
			(pts
				(xy 0.5334 0.254) (xy 0.635 0.254) (xy 0.635 0.2286) (xy 0.635 -0.254) (xy 0.5334 -0.254) (xy 0.5334 -0.2794)
				(xy -0.5334 -0.2794) (xy -0.5334 -0.254) (xy -0.635 -0.254) (xy -0.635 0.254) (xy -0.5334 0.254)
				(xy -0.5334 0.2794) (xy 0.508 0.2794) (xy 0.5334 0.2794)
			)
			(stroke
				(width 0)
				(type default)
			)
			(fill no)
			(layer "B.CrtYd")
		)
		(pad "1" smd rect
			(at -0.40005 0)
			(size 0.4572 0.508)
			(layers "B.Cu" "B.Mask" "B.Paste")
			(net "P1V538_BMC_NODE1")
		)
		(pad "2" smd rect
			(at 0.40005 0)
			(size 0.4572 0.508)
			(layers "B.Cu" "B.Mask" "B.Paste")
			(net "GND")
		)
	)
	(footprint ""
		(layer "B.Cu")
		(at 48.75022 -151.06269 180)
		(property "Reference" "C420"
			(at 11.81354 5.6134 0)
			(unlocked yes)
			(layer "B.SilkS")
			(effects
				(font
					(size 0.7874 0.5842)
					(thickness 0.1524)
				)
				(justify left mirror)
			)
		)
		(property "Value" ""
			(at 0 0 0)
			(layer "B.Fab")
			(effects
				(font
					(size 1.27 1.27)
				)
				(justify mirror)
			)
		)
		(duplicate_pad_numbers_are_jumpers no)
		(fp_line
			(start 0.7874 0.4064)
			(end 0.7874 -0.4064)
			(stroke
				(width 0.1524)
				(type default)
			)
			(layer "B.SilkS")
		)
		(fp_line
			(start 0.7874 -0.4064)
			(end -0.7874 -0.4064)
			(stroke
				(width 0.1524)
				(type default)
			)
			(layer "B.SilkS")
		)
		(fp_line
			(start 0 0.381)
			(end 0 -0.381)
			(stroke
				(width 0.1524)
				(type default)
			)
			(layer "B.SilkS")
		)
		(fp_line
			(start -0.7874 0.4064)
			(end 0.7874 0.4064)
			(stroke
				(width 0.1524)
				(type default)
			)
			(layer "B.SilkS")
		)
		(fp_line
			(start -0.7874 -0.4064)
			(end -0.7874 0.4064)
			(stroke
				(width 0.1524)
				(type default)
			)
			(layer "B.SilkS")
		)
		(fp_poly
			(pts
				(xy 0.5334 0.254) (xy 0.635 0.254) (xy 0.635 0.2286) (xy 0.635 -0.254) (xy 0.5334 -0.254) (xy 0.5334 -0.2794)
				(xy -0.5334 -0.2794) (xy -0.5334 -0.254) (xy -0.635 -0.254) (xy -0.635 0.254) (xy -0.5334 0.254)
				(xy -0.5334 0.2794) (xy 0.508 0.2794) (xy 0.5334 0.2794)
			)
			(stroke
				(width 0)
				(type default)
			)
			(fill no)
			(layer "B.CrtYd")
		)
		(pad "1" smd rect
			(at -0.40005 0)
			(size 0.4572 0.508)
			(layers "B.Cu" "B.Mask" "B.Paste")
			(net "P1V05_LAN1")
		)
		(pad "2" smd rect
			(at 0.40005 0)
			(size 0.4572 0.508)
			(layers "B.Cu" "B.Mask" "B.Paste")
			(net "GND")
		)
	)
	(footprint ""
		(layer "B.Cu")
		(at 69.987668 -21.171662 90)
		(property "Reference" "C158"
			(at -5.88137 -0.810006 270)
			(unlocked yes)
			(layer "B.SilkS")
			(effects
				(font
					(size 0.7874 0.5842)
					(thickness 0.1524)
				)
				(justify left mirror)
			)
		)
		(property "Value" ""
			(at 0 0 90)
			(layer "B.Fab")
			(effects
				(font
					(size 1.27 1.27)
				)
				(justify mirror)
			)
		)
		(duplicate_pad_numbers_are_jumpers no)
		(fp_line
			(start 0.7874 -0.4064)
			(end -0.7874 -0.4064)
			(stroke
				(width 0.1524)
				(type default)
			)
			(layer "B.SilkS")
		)
		(fp_line
			(start -0.7874 -0.4064)
			(end -0.7874 0.4064)
			(stroke
				(width 0.1524)
				(type default)
			)
			(layer "B.SilkS")
		)
		(fp_line
			(start 0 0.381)
			(end 0 -0.381)
			(stroke
				(width 0.1524)
				(type default)
			)
			(layer "B.SilkS")
		)
		(fp_line
			(start 0.7874 0.4064)
			(end 0.7874 -0.4064)
			(stroke
				(width 0.1524)
				(type default)
			)
			(layer "B.SilkS")
		)
		(fp_line
			(start -0.7874 0.4064)
			(end 0.7874 0.4064)
			(stroke
				(width 0.1524)
				(type default)
			)
			(layer "B.SilkS")
		)
		(fp_poly
			(pts
				(xy 0.5334 0.254) (xy 0.635 0.254) (xy 0.635 0.2286) (xy 0.635 -0.254) (xy 0.5334 -0.254) (xy 0.5334 -0.2794)
				(xy -0.5334 -0.2794) (xy -0.5334 -0.254) (xy -0.635 -0.254) (xy -0.635 0.254) (xy -0.5334 0.254)
				(xy -0.5334 0.2794) (xy 0.508 0.2794) (xy 0.5334 0.2794)
			)
			(stroke
				(width 0)
				(type default)
			)
			(fill no)
			(layer "B.CrtYd")
		)
		(pad "1" smd rect
			(at -0.40005 0 270)
			(size 0.4572 0.508)
			(layers "B.Cu" "B.Mask" "B.Paste")
			(net "PV_VDDR_NODE1")
		)
		(pad "2" smd rect
			(at 0.40005 0 270)
			(size 0.4572 0.508)
			(layers "B.Cu" "B.Mask" "B.Paste")
			(net "GND")
		)
	)
	(footprint ""
		(layer "B.Cu")
		(at 77.86243 -84.93252)
		(property "Reference" "R143"
			(at -13.49121 31.479744 0)
			(unlocked yes)
			(layer "B.SilkS")
			(effects
				(font
					(size 0.7874 0.5842)
					(thickness 0.1524)
				)
				(justify left mirror)
			)
		)
		(property "Value" ""
			(at 0 0 0)
			(layer "B.Fab")
			(effects
				(font
					(size 1.27 1.27)
				)
				(justify mirror)
			)
		)
		(duplicate_pad_numbers_are_jumpers no)
		(fp_line
			(start -0.7874 -0.4064)
			(end -0.7874 0.4064)
			(stroke
				(width 0.1524)
				(type default)
			)
			(layer "B.SilkS")
		)
		(fp_line
			(start -0.7874 0.4064)
			(end 0.7874 0.4064)
			(stroke
				(width 0.1524)
				(type default)
			)
			(layer "B.SilkS")
		)
		(fp_line
			(start 0.7874 -0.4064)
			(end -0.7874 -0.4064)
			(stroke
				(width 0.1524)
				(type default)
			)
			(layer "B.SilkS")
		)
		(fp_line
			(start 0.7874 0.4064)
			(end 0.7874 -0.4064)
			(stroke
				(width 0.1524)
				(type default)
			)
			(layer "B.SilkS")
		)
		(fp_poly
			(pts
				(xy 0.508 0.2794) (xy 0.508 0.2286) (xy 0.635 0.2286) (xy 0.635 -0.254) (xy 0.5334 -0.254) (xy 0.5334 -0.2794)
				(xy -0.5334 -0.2794) (xy -0.5334 -0.254) (xy -0.635 -0.254) (xy -0.635 0.254) (xy -0.5334 0.254)
				(xy -0.5334 0.2794)
			)
			(stroke
				(width 0)
				(type default)
			)
			(fill no)
			(layer "B.CrtYd")
		)
		(pad "1" smd rect
			(at -0.40005 0 180)
			(size 0.4572 0.508)
			(layers "B.Cu" "B.Mask" "B.Paste")
			(net "N32265582")
		)
		(pad "2" smd rect
			(at 0.40005 0 180)
			(size 0.4572 0.508)
			(layers "B.Cu" "B.Mask" "B.Paste")
			(net "P3V3_RTC_NODE1")
		)
	)
	(footprint ""
		(layer "B.Cu")
		(at 169.779188 -94.36354 90)
		(property "Reference" "C384"
			(at -2.781554 2.10185 270)
			(unlocked yes)
			(layer "B.SilkS")
			(effects
				(font
					(size 0.7874 0.5842)
					(thickness 0.1524)
				)
				(justify left mirror)
			)
		)
		(property "Value" ""
			(at 0 0 90)
			(layer "B.Fab")
			(effects
				(font
					(size 1.27 1.27)
				)
				(justify mirror)
			)
		)
		(duplicate_pad_numbers_are_jumpers no)
		(fp_line
			(start 0.7874 -0.4064)
			(end -0.7874 -0.4064)
			(stroke
				(width 0.1524)
				(type default)
			)
			(layer "B.SilkS")
		)
		(fp_line
			(start -0.7874 -0.4064)
			(end -0.7874 0.4064)
			(stroke
				(width 0.1524)
				(type default)
			)
			(layer "B.SilkS")
		)
		(fp_line
			(start 0 0.381)
			(end 0 -0.381)
			(stroke
				(width 0.1524)
				(type default)
			)
			(layer "B.SilkS")
		)
		(fp_line
			(start 0.7874 0.4064)
			(end 0.7874 -0.4064)
			(stroke
				(width 0.1524)
				(type default)
			)
			(layer "B.SilkS")
		)
		(fp_line
			(start -0.7874 0.4064)
			(end 0.7874 0.4064)
			(stroke
				(width 0.1524)
				(type default)
			)
			(layer "B.SilkS")
		)
		(fp_poly
			(pts
				(xy 0.5334 0.254) (xy 0.635 0.254) (xy 0.635 0.2286) (xy 0.635 -0.254) (xy 0.5334 -0.254) (xy 0.5334 -0.2794)
				(xy -0.5334 -0.2794) (xy -0.5334 -0.254) (xy -0.635 -0.254) (xy -0.635 0.254) (xy -0.5334 0.254)
				(xy -0.5334 0.2794) (xy 0.508 0.2794) (xy 0.5334 0.2794)
			)
			(stroke
				(width 0)
				(type default)
			)
			(fill no)
			(layer "B.CrtYd")
		)
		(pad "1" smd rect
			(at -0.40005 0 270)
			(size 0.4572 0.508)
			(layers "B.Cu" "B.Mask" "B.Paste")
			(net "GND")
		)
		(pad "2" smd rect
			(at 0.40005 0 270)
			(size 0.4572 0.508)
			(layers "B.Cu" "B.Mask" "B.Paste")
			(net "P3V3_USB_NODE1")
		)
	)
	(footprint ""
		(layer "B.Cu")
		(at 63.959486 -140.805662 90)
		(property "Reference" "C242"
			(at -54.612794 -41.514776 270)
			(unlocked yes)
			(layer "B.SilkS")
			(effects
				(font
					(size 0.7874 0.5842)
					(thickness 0.1524)
				)
				(justify left mirror)
			)
		)
		(property "Value" ""
			(at 0 0 90)
			(layer "B.Fab")
			(effects
				(font
					(size 1.27 1.27)
				)
				(justify mirror)
			)
		)
		(duplicate_pad_numbers_are_jumpers no)
		(fp_line
			(start 0.7874 -0.4064)
			(end -0.7874 -0.4064)
			(stroke
				(width 0.1524)
				(type default)
			)
			(layer "B.SilkS")
		)
		(fp_line
			(start -0.7874 -0.4064)
			(end -0.7874 0.4064)
			(stroke
				(width 0.1524)
				(type default)
			)
			(layer "B.SilkS")
		)
		(fp_line
			(start 0 0.381)
			(end 0 -0.381)
			(stroke
				(width 0.1524)
				(type default)
			)
			(layer "B.SilkS")
		)
		(fp_line
			(start 0.7874 0.4064)
			(end 0.7874 -0.4064)
			(stroke
				(width 0.1524)
				(type default)
			)
			(layer "B.SilkS")
		)
		(fp_line
			(start -0.7874 0.4064)
			(end 0.7874 0.4064)
			(stroke
				(width 0.1524)
				(type default)
			)
			(layer "B.SilkS")
		)
		(fp_poly
			(pts
				(xy 0.5334 0.254) (xy 0.635 0.254) (xy 0.635 0.2286) (xy 0.635 -0.254) (xy 0.5334 -0.254) (xy 0.5334 -0.2794)
				(xy -0.5334 -0.2794) (xy -0.5334 -0.254) (xy -0.635 -0.254) (xy -0.635 0.254) (xy -0.5334 0.254)
				(xy -0.5334 0.2794) (xy 0.508 0.2794) (xy 0.5334 0.2794)
			)
			(stroke
				(width 0)
				(type default)
			)
			(fill no)
			(layer "B.CrtYd")
		)
		(pad "1" smd rect
			(at -0.40005 0 270)
			(size 0.4572 0.508)
			(layers "B.Cu" "B.Mask" "B.Paste")
			(net "P3V3_NODE1")
		)
		(pad "2" smd rect
			(at 0.40005 0 270)
			(size 0.4572 0.508)
			(layers "B.Cu" "B.Mask" "B.Paste")
			(net "GND")
		)
	)
	(footprint ""
		(layer "B.Cu")
		(at 67.286886 -121.044462 90)
		(property "Reference" "R335"
			(at -7.37235 9.88314 270)
			(unlocked yes)
			(layer "B.SilkS")
			(effects
				(font
					(size 0.7874 0.5842)
					(thickness 0.1524)
				)
				(justify left mirror)
			)
		)
		(property "Value" ""
			(at 0 0 90)
			(layer "B.Fab")
			(effects
				(font
					(size 1.27 1.27)
				)
				(justify mirror)
			)
		)
		(duplicate_pad_numbers_are_jumpers no)
		(fp_line
			(start 0.7874 -0.4064)
			(end -0.7874 -0.4064)
			(stroke
				(width 0.1524)
				(type default)
			)
			(layer "B.SilkS")
		)
		(fp_line
			(start -0.7874 -0.4064)
			(end -0.7874 0.4064)
			(stroke
				(width 0.1524)
				(type default)
			)
			(layer "B.SilkS")
		)
		(fp_line
			(start 0.7874 0.4064)
			(end 0.7874 -0.4064)
			(stroke
				(width 0.1524)
				(type default)
			)
			(layer "B.SilkS")
		)
		(fp_line
			(start -0.7874 0.4064)
			(end 0.7874 0.4064)
			(stroke
				(width 0.1524)
				(type default)
			)
			(layer "B.SilkS")
		)
		(fp_poly
			(pts
				(xy 0.508 0.2794) (xy 0.508 0.2286) (xy 0.635 0.2286) (xy 0.635 -0.254) (xy 0.5334 -0.254) (xy 0.5334 -0.2794)
				(xy -0.5334 -0.2794) (xy -0.5334 -0.254) (xy -0.635 -0.254) (xy -0.635 0.254) (xy -0.5334 0.254)
				(xy -0.5334 0.2794)
			)
			(stroke
				(width 0)
				(type default)
			)
			(fill no)
			(layer "B.CrtYd")
		)
		(pad "1" smd rect
			(at -0.40005 0 270)
			(size 0.4572 0.508)
			(layers "B.Cu" "B.Mask" "B.Paste")
			(net "P3V3_NODE1")
		)
		(pad "2" smd rect
			(at 0.40005 0 270)
			(size 0.4572 0.508)
			(layers "B.Cu" "B.Mask" "B.Paste")
			(net "BMC_ROMA19")
		)
	)
	(footprint ""
		(layer "B.Cu")
		(at 63.15075 -69.200268 90)
		(property "Reference" "C132"
			(at -34.07156 -14.28242 270)
			(unlocked yes)
			(layer "B.SilkS")
			(effects
				(font
					(size 0.7874 0.5842)
					(thickness 0.1524)
				)
				(justify left mirror)
			)
		)
		(property "Value" ""
			(at 0 0 90)
			(layer "B.Fab")
			(effects
				(font
					(size 1.27 1.27)
				)
				(justify mirror)
			)
		)
		(duplicate_pad_numbers_are_jumpers no)
		(fp_line
			(start 0.7874 -0.4064)
			(end -0.7874 -0.4064)
			(stroke
				(width 0.1524)
				(type default)
			)
			(layer "B.SilkS")
		)
		(fp_line
			(start -0.7874 -0.4064)
			(end -0.7874 0.4064)
			(stroke
				(width 0.1524)
				(type default)
			)
			(layer "B.SilkS")
		)
		(fp_line
			(start 0 0.381)
			(end 0 -0.381)
			(stroke
				(width 0.1524)
				(type default)
			)
			(layer "B.SilkS")
		)
		(fp_line
			(start 0.7874 0.4064)
			(end 0.7874 -0.4064)
			(stroke
				(width 0.1524)
				(type default)
			)
			(layer "B.SilkS")
		)
		(fp_line
			(start -0.7874 0.4064)
			(end 0.7874 0.4064)
			(stroke
				(width 0.1524)
				(type default)
			)
			(layer "B.SilkS")
		)
		(fp_poly
			(pts
				(xy 0.5334 0.254) (xy 0.635 0.254) (xy 0.635 0.2286) (xy 0.635 -0.254) (xy 0.5334 -0.254) (xy 0.5334 -0.2794)
				(xy -0.5334 -0.2794) (xy -0.5334 -0.254) (xy -0.635 -0.254) (xy -0.635 0.254) (xy -0.5334 0.254)
				(xy -0.5334 0.2794) (xy 0.508 0.2794) (xy 0.5334 0.2794)
			)
			(stroke
				(width 0)
				(type default)
			)
			(fill no)
			(layer "B.CrtYd")
		)
		(pad "1" smd rect
			(at -0.40005 0 270)
			(size 0.4572 0.508)
			(layers "B.Cu" "B.Mask" "B.Paste")
			(net "PV_VDDR_VCCCLK_DDR3_NODE1")
		)
		(pad "2" smd rect
			(at 0.40005 0 270)
			(size 0.4572 0.508)
			(layers "B.Cu" "B.Mask" "B.Paste")
			(net "GND")
		)
	)
	(footprint ""
		(layer "B.Cu")
		(at 141.259052 -139.22375)
		(property "Reference" "C888"
			(at 3.924046 -3.314954 0)
			(unlocked yes)
			(layer "B.SilkS")
			(effects
				(font
					(size 0.7874 0.5842)
					(thickness 0.1524)
				)
				(justify left mirror)
			)
		)
		(property "Value" ""
			(at 0 0 0)
			(layer "B.Fab")
			(effects
				(font
					(size 1.27 1.27)
				)
				(justify mirror)
			)
		)
		(duplicate_pad_numbers_are_jumpers no)
		(fp_line
			(start -0.7874 -0.4064)
			(end -0.7874 0.4064)
			(stroke
				(width 0.1524)
				(type default)
			)
			(layer "B.SilkS")
		)
		(fp_line
			(start -0.7874 0.4064)
			(end 0.7874 0.4064)
			(stroke
				(width 0.1524)
				(type default)
			)
			(layer "B.SilkS")
		)
		(fp_line
			(start 0 0.381)
			(end 0 -0.381)
			(stroke
				(width 0.1524)
				(type default)
			)
			(layer "B.SilkS")
		)
		(fp_line
			(start 0.7874 -0.4064)
			(end -0.7874 -0.4064)
			(stroke
				(width 0.1524)
				(type default)
			)
			(layer "B.SilkS")
		)
		(fp_line
			(start 0.7874 0.4064)
			(end 0.7874 -0.4064)
			(stroke
				(width 0.1524)
				(type default)
			)
			(layer "B.SilkS")
		)
		(fp_poly
			(pts
				(xy 0.5334 0.254) (xy 0.635 0.254) (xy 0.635 0.2286) (xy 0.635 -0.254) (xy 0.5334 -0.254) (xy 0.5334 -0.2794)
				(xy -0.5334 -0.2794) (xy -0.5334 -0.254) (xy -0.635 -0.254) (xy -0.635 0.254) (xy -0.5334 0.254)
				(xy -0.5334 0.2794) (xy 0.508 0.2794) (xy 0.5334 0.2794)
			)
			(stroke
				(width 0)
				(type default)
			)
			(fill no)
			(layer "B.CrtYd")
		)
		(pad "1" smd rect
			(at -0.40005 0 180)
			(size 0.4572 0.508)
			(layers "B.Cu" "B.Mask" "B.Paste")
			(net "P3V3_NODE1")
		)
		(pad "2" smd rect
			(at 0.40005 0 180)
			(size 0.4572 0.508)
			(layers "B.Cu" "B.Mask" "B.Paste")
			(net "GND")
		)
	)
	(footprint ""
		(layer "B.Cu")
		(at 154.06116 -174.537624)
		(property "Reference" "R747"
			(at -1.323086 12.476226 0)
			(unlocked yes)
			(layer "B.SilkS")
			(effects
				(font
					(size 0.7874 0.5842)
					(thickness 0.1524)
				)
				(justify left mirror)
			)
		)
		(property "Value" ""
			(at 0 0 0)
			(layer "B.Fab")
			(effects
				(font
					(size 1.27 1.27)
				)
				(justify mirror)
			)
		)
		(duplicate_pad_numbers_are_jumpers no)
		(fp_line
			(start -0.7874 -0.4064)
			(end -0.7874 0.4064)
			(stroke
				(width 0.1524)
				(type default)
			)
			(layer "B.SilkS")
		)
		(fp_line
			(start -0.7874 0.4064)
			(end 0.7874 0.4064)
			(stroke
				(width 0.1524)
				(type default)
			)
			(layer "B.SilkS")
		)
		(fp_line
			(start 0.7874 -0.4064)
			(end -0.7874 -0.4064)
			(stroke
				(width 0.1524)
				(type default)
			)
			(layer "B.SilkS")
		)
		(fp_line
			(start 0.7874 0.4064)
			(end 0.7874 -0.4064)
			(stroke
				(width 0.1524)
				(type default)
			)
			(layer "B.SilkS")
		)
		(fp_poly
			(pts
				(xy 0.508 0.2794) (xy 0.508 0.2286) (xy 0.635 0.2286) (xy 0.635 -0.254) (xy 0.5334 -0.254) (xy 0.5334 -0.2794)
				(xy -0.5334 -0.2794) (xy -0.5334 -0.254) (xy -0.635 -0.254) (xy -0.635 0.254) (xy -0.5334 0.254)
				(xy -0.5334 0.2794)
			)
			(stroke
				(width 0)
				(type default)
			)
			(fill no)
			(layer "B.CrtYd")
		)
		(pad "1" smd rect
			(at -0.40005 0 180)
			(size 0.4572 0.508)
			(layers "B.Cu" "B.Mask" "B.Paste")
			(net "T12_NODE2_EN")
		)
		(pad "2" smd rect
			(at 0.40005 0 180)
			(size 0.4572 0.508)
			(layers "B.Cu" "B.Mask" "B.Paste")
			(net "P5V_NODE1")
		)
	)
	(footprint ""
		(layer "B.Cu")
		(at 69.732652 -142.880842)
		(property "Reference" "TP8"
			(at -0.10287 -0.4826 270)
			(unlocked yes)
			(layer "B.SilkS")
			(effects
				(font
					(size 0.7874 0.5842)
					(thickness 0.1524)
				)
				(justify left mirror)
			)
		)
		(property "Value" ""
			(at 0 0 0)
			(layer "B.Fab")
			(effects
				(font
					(size 1.27 1.27)
				)
				(justify mirror)
			)
		)
		(duplicate_pad_numbers_are_jumpers no)
		(fp_poly
			(pts
				(arc
					(start 0 -0.381)
					(mid 0 0.381)
					(end 0 -0.381)
				)
			)
			(stroke
				(width 0)
				(type default)
			)
			(fill no)
			(layer "B.CrtYd")
		)
		(pad "1" smd circle
			(at 0 0 180)
			(size 0.762 0.762)
			(layers "B.Cu" "B.Mask" "B.Paste")
			(net "N3975090755")
		)
	)
	(footprint ""
		(layer "B.Cu")
		(at 65.194942 -28.091638)
		(property "Reference" "R204"
			(at -0.948182 -0.09271 0)
			(unlocked yes)
			(layer "B.SilkS")
			(effects
				(font
					(size 0.7874 0.5842)
					(thickness 0.1524)
				)
				(justify left mirror)
			)
		)
		(property "Value" ""
			(at 0 0 0)
			(layer "B.Fab")
			(effects
				(font
					(size 1.27 1.27)
				)
				(justify mirror)
			)
		)
		(duplicate_pad_numbers_are_jumpers no)
		(fp_line
			(start -0.7874 -0.4064)
			(end -0.7874 0.4064)
			(stroke
				(width 0.1524)
				(type default)
			)
			(layer "B.SilkS")
		)
		(fp_line
			(start -0.7874 0.4064)
			(end 0.7874 0.4064)
			(stroke
				(width 0.1524)
				(type default)
			)
			(layer "B.SilkS")
		)
		(fp_line
			(start 0.7874 -0.4064)
			(end -0.7874 -0.4064)
			(stroke
				(width 0.1524)
				(type default)
			)
			(layer "B.SilkS")
		)
		(fp_line
			(start 0.7874 0.4064)
			(end 0.7874 -0.4064)
			(stroke
				(width 0.1524)
				(type default)
			)
			(layer "B.SilkS")
		)
		(fp_poly
			(pts
				(xy 0.508 0.2794) (xy 0.508 0.2286) (xy 0.635 0.2286) (xy 0.635 -0.254) (xy 0.5334 -0.254) (xy 0.5334 -0.2794)
				(xy -0.5334 -0.2794) (xy -0.5334 -0.254) (xy -0.635 -0.254) (xy -0.635 0.254) (xy -0.5334 0.254)
				(xy -0.5334 0.2794)
			)
			(stroke
				(width 0)
				(type default)
			)
			(fill no)
			(layer "B.CrtYd")
		)
		(pad "1" smd rect
			(at -0.40005 0 180)
			(size 0.4572 0.508)
			(layers "B.Cu" "B.Mask" "B.Paste")
			(net "GND")
		)
		(pad "2" smd rect
			(at 0.40005 0 180)
			(size 0.4572 0.508)
			(layers "B.Cu" "B.Mask" "B.Paste")
			(net "PD_NODE1_DM8")
		)
	)
	(footprint ""
		(layer "B.Cu")
		(at 149.33676 -184.951624 90)
		(property "Reference" "R960"
			(at 4.357624 -3.09245 270)
			(unlocked yes)
			(layer "B.SilkS")
			(effects
				(font
					(size 0.7874 0.5842)
					(thickness 0.1524)
				)
				(justify left mirror)
			)
		)
		(property "Value" ""
			(at 0 0 90)
			(layer "B.Fab")
			(effects
				(font
					(size 1.27 1.27)
				)
				(justify mirror)
			)
		)
		(duplicate_pad_numbers_are_jumpers no)
		(fp_line
			(start 0.7874 -0.4064)
			(end -0.7874 -0.4064)
			(stroke
				(width 0.1524)
				(type default)
			)
			(layer "B.SilkS")
		)
		(fp_line
			(start -0.7874 -0.4064)
			(end -0.7874 0.4064)
			(stroke
				(width 0.1524)
				(type default)
			)
			(layer "B.SilkS")
		)
		(fp_line
			(start 0.7874 0.4064)
			(end 0.7874 -0.4064)
			(stroke
				(width 0.1524)
				(type default)
			)
			(layer "B.SilkS")
		)
		(fp_line
			(start -0.7874 0.4064)
			(end 0.7874 0.4064)
			(stroke
				(width 0.1524)
				(type default)
			)
			(layer "B.SilkS")
		)
		(fp_poly
			(pts
				(xy 0.508 0.2794) (xy 0.508 0.2286) (xy 0.635 0.2286) (xy 0.635 -0.254) (xy 0.5334 -0.254) (xy 0.5334 -0.2794)
				(xy -0.5334 -0.2794) (xy -0.5334 -0.254) (xy -0.635 -0.254) (xy -0.635 0.254) (xy -0.5334 0.254)
				(xy -0.5334 0.2794)
			)
			(stroke
				(width 0)
				(type default)
			)
			(fill no)
			(layer "B.CrtYd")
		)
		(pad "1" smd rect
			(at -0.40005 0 270)
			(size 0.4572 0.508)
			(layers "B.Cu" "B.Mask" "B.Paste")
			(net "UART_T11_NODE1_TXD")
		)
		(pad "2" smd rect
			(at 0.40005 0 270)
			(size 0.4572 0.508)
			(layers "B.Cu" "B.Mask" "B.Paste")
			(net "UART_T11_NODE1_TXD_R")
		)
	)
	(footprint ""
		(layer "B.Cu")
		(at 111.87176 -188.126624 90)
		(property "Reference" "R967"
			(at 4.080256 0.69596 270)
			(unlocked yes)
			(layer "B.SilkS")
			(effects
				(font
					(size 0.7874 0.5842)
					(thickness 0.1524)
				)
				(justify left mirror)
			)
		)
		(property "Value" ""
			(at 0 0 90)
			(layer "B.Fab")
			(effects
				(font
					(size 1.27 1.27)
				)
				(justify mirror)
			)
		)
		(duplicate_pad_numbers_are_jumpers no)
		(fp_line
			(start 0.7874 -0.4064)
			(end -0.7874 -0.4064)
			(stroke
				(width 0.1524)
				(type default)
			)
			(layer "B.SilkS")
		)
		(fp_line
			(start -0.7874 -0.4064)
			(end -0.7874 0.4064)
			(stroke
				(width 0.1524)
				(type default)
			)
			(layer "B.SilkS")
		)
		(fp_line
			(start 0.7874 0.4064)
			(end 0.7874 -0.4064)
			(stroke
				(width 0.1524)
				(type default)
			)
			(layer "B.SilkS")
		)
		(fp_line
			(start -0.7874 0.4064)
			(end 0.7874 0.4064)
			(stroke
				(width 0.1524)
				(type default)
			)
			(layer "B.SilkS")
		)
		(fp_poly
			(pts
				(xy 0.508 0.2794) (xy 0.508 0.2286) (xy 0.635 0.2286) (xy 0.635 -0.254) (xy 0.5334 -0.254) (xy 0.5334 -0.2794)
				(xy -0.5334 -0.2794) (xy -0.5334 -0.254) (xy -0.635 -0.254) (xy -0.635 0.254) (xy -0.5334 0.254)
				(xy -0.5334 0.2794)
			)
			(stroke
				(width 0)
				(type default)
			)
			(fill no)
			(layer "B.CrtYd")
		)
		(pad "1" smd rect
			(at -0.40005 0 270)
			(size 0.4572 0.508)
			(layers "B.Cu" "B.Mask" "B.Paste")
			(net "UART_T7_NODE3_RXD")
		)
		(pad "2" smd rect
			(at 0.40005 0 270)
			(size 0.4572 0.508)
			(layers "B.Cu" "B.Mask" "B.Paste")
			(net "UART_T7_NODE3_RXD_R")
		)
	)
	(footprint ""
		(layer "B.Cu")
		(at 43.702732 -94.40037 90)
		(property "Reference" "R128"
			(at -4.703318 -4.548378 270)
			(unlocked yes)
			(layer "B.SilkS")
			(effects
				(font
					(size 0.7874 0.5842)
					(thickness 0.1524)
				)
				(justify left mirror)
			)
		)
		(property "Value" ""
			(at 0 0 90)
			(layer "B.Fab")
			(effects
				(font
					(size 1.27 1.27)
				)
				(justify mirror)
			)
		)
		(duplicate_pad_numbers_are_jumpers no)
		(fp_line
			(start 0.7874 -0.4064)
			(end -0.7874 -0.4064)
			(stroke
				(width 0.1524)
				(type default)
			)
			(layer "B.SilkS")
		)
		(fp_line
			(start -0.7874 -0.4064)
			(end -0.7874 0.4064)
			(stroke
				(width 0.1524)
				(type default)
			)
			(layer "B.SilkS")
		)
		(fp_line
			(start 0.7874 0.4064)
			(end 0.7874 -0.4064)
			(stroke
				(width 0.1524)
				(type default)
			)
			(layer "B.SilkS")
		)
		(fp_line
			(start -0.7874 0.4064)
			(end 0.7874 0.4064)
			(stroke
				(width 0.1524)
				(type default)
			)
			(layer "B.SilkS")
		)
		(fp_poly
			(pts
				(xy 0.508 0.2794) (xy 0.508 0.2286) (xy 0.635 0.2286) (xy 0.635 -0.254) (xy 0.5334 -0.254) (xy 0.5334 -0.2794)
				(xy -0.5334 -0.2794) (xy -0.5334 -0.254) (xy -0.635 -0.254) (xy -0.635 0.254) (xy -0.5334 0.254)
				(xy -0.5334 0.2794)
			)
			(stroke
				(width 0)
				(type default)
			)
			(fill no)
			(layer "B.CrtYd")
		)
		(pad "1" smd rect
			(at -0.40005 0 270)
			(size 0.4572 0.508)
			(layers "B.Cu" "B.Mask" "B.Paste")
			(net "SMB_CPU_NODE1_MEM_ICS_DAT_R")
		)
		(pad "2" smd rect
			(at 0.40005 0 270)
			(size 0.4572 0.508)
			(layers "B.Cu" "B.Mask" "B.Paste")
			(net "SMB_MUX_CPU_ICS_NODE1_DAT")
		)
	)
	(footprint ""
		(layer "B.Cu")
		(at 90.81262 -175.038512)
		(property "Reference" "R700"
			(at 24.902414 20.083272 0)
			(unlocked yes)
			(layer "B.SilkS")
			(effects
				(font
					(size 0.7874 0.5842)
					(thickness 0.1524)
				)
				(justify left mirror)
			)
		)
		(property "Value" ""
			(at 0 0 0)
			(layer "B.Fab")
			(effects
				(font
					(size 1.27 1.27)
				)
				(justify mirror)
			)
		)
		(duplicate_pad_numbers_are_jumpers no)
		(fp_line
			(start -0.7874 -0.4064)
			(end -0.7874 0.4064)
			(stroke
				(width 0.1524)
				(type default)
			)
			(layer "B.SilkS")
		)
		(fp_line
			(start -0.7874 0.4064)
			(end 0.7874 0.4064)
			(stroke
				(width 0.1524)
				(type default)
			)
			(layer "B.SilkS")
		)
		(fp_line
			(start 0.7874 -0.4064)
			(end -0.7874 -0.4064)
			(stroke
				(width 0.1524)
				(type default)
			)
			(layer "B.SilkS")
		)
		(fp_line
			(start 0.7874 0.4064)
			(end 0.7874 -0.4064)
			(stroke
				(width 0.1524)
				(type default)
			)
			(layer "B.SilkS")
		)
		(fp_poly
			(pts
				(xy 0.508 0.2794) (xy 0.508 0.2286) (xy 0.635 0.2286) (xy 0.635 -0.254) (xy 0.5334 -0.254) (xy 0.5334 -0.2794)
				(xy -0.5334 -0.2794) (xy -0.5334 -0.254) (xy -0.635 -0.254) (xy -0.635 0.254) (xy -0.5334 0.254)
				(xy -0.5334 0.2794)
			)
			(stroke
				(width 0)
				(type default)
			)
			(fill no)
			(layer "B.CrtYd")
		)
		(pad "1" smd rect
			(at -0.40005 0 180)
			(size 0.4572 0.508)
			(layers "B.Cu" "B.Mask" "B.Paste")
			(net "T3_NODE4_EN")
		)
		(pad "2" smd rect
			(at 0.40005 0 180)
			(size 0.4572 0.508)
			(layers "B.Cu" "B.Mask" "B.Paste")
			(net "P5V_NODE1")
		)
	)
	(footprint ""
		(layer "B.Cu")
		(at 55.552086 -128.740662 180)
		(property "Reference" "C266"
			(at 41.609518 -53.38191 0)
			(unlocked yes)
			(layer "B.SilkS")
			(effects
				(font
					(size 0.7874 0.5842)
					(thickness 0.1524)
				)
				(justify left mirror)
			)
		)
		(property "Value" ""
			(at 0 0 0)
			(layer "B.Fab")
			(effects
				(font
					(size 1.27 1.27)
				)
				(justify mirror)
			)
		)
		(duplicate_pad_numbers_are_jumpers no)
		(fp_line
			(start 0.7874 0.4064)
			(end 0.7874 -0.4064)
			(stroke
				(width 0.1524)
				(type default)
			)
			(layer "B.SilkS")
		)
		(fp_line
			(start 0.7874 -0.4064)
			(end -0.7874 -0.4064)
			(stroke
				(width 0.1524)
				(type default)
			)
			(layer "B.SilkS")
		)
		(fp_line
			(start 0 0.381)
			(end 0 -0.381)
			(stroke
				(width 0.1524)
				(type default)
			)
			(layer "B.SilkS")
		)
		(fp_line
			(start -0.7874 0.4064)
			(end 0.7874 0.4064)
			(stroke
				(width 0.1524)
				(type default)
			)
			(layer "B.SilkS")
		)
		(fp_line
			(start -0.7874 -0.4064)
			(end -0.7874 0.4064)
			(stroke
				(width 0.1524)
				(type default)
			)
			(layer "B.SilkS")
		)
		(fp_poly
			(pts
				(xy 0.5334 0.254) (xy 0.635 0.254) (xy 0.635 0.2286) (xy 0.635 -0.254) (xy 0.5334 -0.254) (xy 0.5334 -0.2794)
				(xy -0.5334 -0.2794) (xy -0.5334 -0.254) (xy -0.635 -0.254) (xy -0.635 0.254) (xy -0.5334 0.254)
				(xy -0.5334 0.2794) (xy 0.508 0.2794) (xy 0.5334 0.2794)
			)
			(stroke
				(width 0)
				(type default)
			)
			(fill no)
			(layer "B.CrtYd")
		)
		(pad "1" smd rect
			(at -0.40005 0)
			(size 0.4572 0.508)
			(layers "B.Cu" "B.Mask" "B.Paste")
			(net "BMC_NODE1_MPLLAV33")
		)
		(pad "2" smd rect
			(at 0.40005 0)
			(size 0.4572 0.508)
			(layers "B.Cu" "B.Mask" "B.Paste")
			(net "GND")
		)
	)
	(footprint ""
		(layer "B.Cu")
		(at 130.521202 -34.973768)
		(property "Reference" "R1209"
			(at 5.29971 3.420618 0)
			(unlocked yes)
			(layer "B.SilkS")
			(effects
				(font
					(size 0.7874 0.5842)
					(thickness 0.1524)
				)
				(justify left mirror)
			)
		)
		(property "Value" ""
			(at 0 0 0)
			(layer "B.Fab")
			(effects
				(font
					(size 1.27 1.27)
				)
				(justify mirror)
			)
		)
		(duplicate_pad_numbers_are_jumpers no)
		(fp_line
			(start -0.7874 -0.4064)
			(end -0.7874 0.4064)
			(stroke
				(width 0.1524)
				(type default)
			)
			(layer "B.SilkS")
		)
		(fp_line
			(start -0.7874 0.4064)
			(end 0.7874 0.4064)
			(stroke
				(width 0.1524)
				(type default)
			)
			(layer "B.SilkS")
		)
		(fp_line
			(start 0.7874 -0.4064)
			(end -0.7874 -0.4064)
			(stroke
				(width 0.1524)
				(type default)
			)
			(layer "B.SilkS")
		)
		(fp_line
			(start 0.7874 0.4064)
			(end 0.7874 -0.4064)
			(stroke
				(width 0.1524)
				(type default)
			)
			(layer "B.SilkS")
		)
		(fp_poly
			(pts
				(xy 0.508 0.2794) (xy 0.508 0.2286) (xy 0.635 0.2286) (xy 0.635 -0.254) (xy 0.5334 -0.254) (xy 0.5334 -0.2794)
				(xy -0.5334 -0.2794) (xy -0.5334 -0.254) (xy -0.635 -0.254) (xy -0.635 0.254) (xy -0.5334 0.254)
				(xy -0.5334 0.2794)
			)
			(stroke
				(width 0)
				(type default)
			)
			(fill no)
			(layer "B.CrtYd")
		)
		(pad "1" smd rect
			(at -0.40005 0 180)
			(size 0.4572 0.508)
			(layers "B.Cu" "B.Mask" "B.Paste")
			(net "SIO_JTAG_CPLD3_TMS")
		)
		(pad "2" smd rect
			(at 0.40005 0 180)
			(size 0.4572 0.508)
			(layers "B.Cu" "B.Mask" "B.Paste")
			(net "GND")
		)
	)
	(footprint ""
		(layer "B.Cu")
		(at 52.301648 -125.133354)
		(property "Reference" "C286"
			(at -42.066464 53.341524 0)
			(unlocked yes)
			(layer "B.SilkS")
			(effects
				(font
					(size 0.7874 0.5842)
					(thickness 0.1524)
				)
				(justify mirror)
			)
		)
		(property "Value" ""
			(at 0 0 0)
			(layer "B.Fab")
			(effects
				(font
					(size 1.27 1.27)
				)
				(justify mirror)
			)
		)
		(duplicate_pad_numbers_are_jumpers no)
		(fp_line
			(start -1.2954 -0.5842)
			(end -1.2954 0.5842)
			(stroke
				(width 0.1524)
				(type default)
			)
			(layer "B.SilkS")
		)
		(fp_line
			(start -1.2954 0.5842)
			(end 1.2954 0.5842)
			(stroke
				(width 0.1524)
				(type default)
			)
			(layer "B.SilkS")
		)
		(fp_line
			(start 0 -0.5842)
			(end 0 0.5842)
			(stroke
				(width 0.1524)
				(type default)
			)
			(layer "B.SilkS")
		)
		(fp_line
			(start 1.2954 -0.5842)
			(end -1.2954 -0.5842)
			(stroke
				(width 0.1524)
				(type default)
			)
			(layer "B.SilkS")
		)
		(fp_line
			(start 1.2954 0.5842)
			(end 1.2954 -0.5842)
			(stroke
				(width 0.1524)
				(type default)
			)
			(layer "B.SilkS")
		)
		(fp_poly
			(pts
				(xy -0.8636 -0.4572) (xy -0.8636 -0.3556) (xy -1.143 -0.3556) (xy -1.143 0.3556) (xy -0.8636 0.3556)
				(xy -0.8636 0.4572) (xy 0.8636 0.4572) (xy 0.8636 0.3556) (xy 1.143 0.3556) (xy 1.143 -0.3556) (xy 0.8636 -0.3556)
				(xy 0.8636 -0.4572)
			)
			(stroke
				(width 0)
				(type default)
			)
			(fill no)
			(layer "B.CrtYd")
		)
		(fp_line
			(start -0.884936 -0.504952)
			(end -0.884936 0.504952)
			(stroke
				(width 0.1)
				(type default)
			)
			(layer "B.Fab")
		)
		(fp_line
			(start -0.884936 0.504952)
			(end 0.884936 0.504952)
			(stroke
				(width 0.1)
				(type default)
			)
			(layer "B.Fab")
		)
		(fp_line
			(start 0.884936 -0.504952)
			(end -0.884936 -0.504952)
			(stroke
				(width 0.1)
				(type default)
			)
			(layer "B.Fab")
		)
		(fp_line
			(start 0.884936 0.504952)
			(end 0.884936 -0.504952)
			(stroke
				(width 0.1)
				(type default)
			)
			(layer "B.Fab")
		)
		(pad "1" smd rect
			(at -0.7366 0 90)
			(size 0.7112 0.8128)
			(layers "B.Cu" "B.Mask" "B.Paste")
			(net "P1V26_BMC_NODE1")
		)
		(pad "2" smd rect
			(at 0.7366 0 90)
			(size 0.7112 0.8128)
			(layers "B.Cu" "B.Mask" "B.Paste")
			(net "GND")
		)
	)
	(footprint ""
		(layer "B.Cu")
		(at 163.890198 -148.85543 90)
		(property "Reference" "C459"
			(at -8.488426 0.2413 270)
			(unlocked yes)
			(layer "B.SilkS")
			(effects
				(font
					(size 0.7874 0.5842)
					(thickness 0.1524)
				)
				(justify left mirror)
			)
		)
		(property "Value" ""
			(at 0 0 90)
			(layer "B.Fab")
			(effects
				(font
					(size 1.27 1.27)
				)
				(justify mirror)
			)
		)
		(duplicate_pad_numbers_are_jumpers no)
		(fp_line
			(start 0.7874 -0.4064)
			(end -0.7874 -0.4064)
			(stroke
				(width 0.1524)
				(type default)
			)
			(layer "B.SilkS")
		)
		(fp_line
			(start -0.7874 -0.4064)
			(end -0.7874 0.4064)
			(stroke
				(width 0.1524)
				(type default)
			)
			(layer "B.SilkS")
		)
		(fp_line
			(start 0 0.381)
			(end 0 -0.381)
			(stroke
				(width 0.1524)
				(type default)
			)
			(layer "B.SilkS")
		)
		(fp_line
			(start 0.7874 0.4064)
			(end 0.7874 -0.4064)
			(stroke
				(width 0.1524)
				(type default)
			)
			(layer "B.SilkS")
		)
		(fp_line
			(start -0.7874 0.4064)
			(end 0.7874 0.4064)
			(stroke
				(width 0.1524)
				(type default)
			)
			(layer "B.SilkS")
		)
		(fp_poly
			(pts
				(xy 0.5334 0.254) (xy 0.635 0.254) (xy 0.635 0.2286) (xy 0.635 -0.254) (xy 0.5334 -0.254) (xy 0.5334 -0.2794)
				(xy -0.5334 -0.2794) (xy -0.5334 -0.254) (xy -0.635 -0.254) (xy -0.635 0.254) (xy -0.5334 0.254)
				(xy -0.5334 0.2794) (xy 0.508 0.2794) (xy 0.5334 0.2794)
			)
			(stroke
				(width 0)
				(type default)
			)
			(fill no)
			(layer "B.CrtYd")
		)
		(pad "1" smd rect
			(at -0.40005 0 270)
			(size 0.4572 0.508)
			(layers "B.Cu" "B.Mask" "B.Paste")
			(net "P1V9_LAN2")
		)
		(pad "2" smd rect
			(at 0.40005 0 270)
			(size 0.4572 0.508)
			(layers "B.Cu" "B.Mask" "B.Paste")
			(net "GND")
		)
	)
	(footprint ""
		(layer "B.Cu")
		(at 152.76576 -187.872624 -90)
		(property "Reference" "C654"
			(at -4.565396 3.44043 270)
			(unlocked yes)
			(layer "B.SilkS")
			(effects
				(font
					(size 0.7874 0.5842)
					(thickness 0.1524)
				)
				(justify left mirror)
			)
		)
		(property "Value" ""
			(at 0 0 90)
			(layer "B.Fab")
			(effects
				(font
					(size 1.27 1.27)
				)
				(justify mirror)
			)
		)
		(duplicate_pad_numbers_are_jumpers no)
		(fp_line
			(start -0.7874 0.4064)
			(end 0.7874 0.4064)
			(stroke
				(width 0.1524)
				(type default)
			)
			(layer "B.SilkS")
		)
		(fp_line
			(start 0.7874 0.4064)
			(end 0.7874 -0.4064)
			(stroke
				(width 0.1524)
				(type default)
			)
			(layer "B.SilkS")
		)
		(fp_line
			(start 0 0.381)
			(end 0 -0.381)
			(stroke
				(width 0.1524)
				(type default)
			)
			(layer "B.SilkS")
		)
		(fp_line
			(start -0.7874 -0.4064)
			(end -0.7874 0.4064)
			(stroke
				(width 0.1524)
				(type default)
			)
			(layer "B.SilkS")
		)
		(fp_line
			(start 0.7874 -0.4064)
			(end -0.7874 -0.4064)
			(stroke
				(width 0.1524)
				(type default)
			)
			(layer "B.SilkS")
		)
		(fp_poly
			(pts
				(xy 0.5334 0.254) (xy 0.635 0.254) (xy 0.635 0.2286) (xy 0.635 -0.254) (xy 0.5334 -0.254) (xy 0.5334 -0.2794)
				(xy -0.5334 -0.2794) (xy -0.5334 -0.254) (xy -0.635 -0.254) (xy -0.635 0.254) (xy -0.5334 0.254)
				(xy -0.5334 0.2794) (xy 0.508 0.2794) (xy 0.5334 0.2794)
			)
			(stroke
				(width 0)
				(type default)
			)
			(fill no)
			(layer "B.CrtYd")
		)
		(pad "1" smd rect
			(at -0.40005 0 90)
			(size 0.4572 0.508)
			(layers "B.Cu" "B.Mask" "B.Paste")
			(net "T11_NODE3_EN_R")
		)
		(pad "2" smd rect
			(at 0.40005 0 90)
			(size 0.4572 0.508)
			(layers "B.Cu" "B.Mask" "B.Paste")
			(net "GND")
		)
	)
	(footprint ""
		(layer "B.Cu")
		(at 127.416814 -124.224796 -90)
		(property "Reference" "L3"
			(at -2.121408 -0.1651 270)
			(unlocked yes)
			(layer "B.SilkS")
			(effects
				(font
					(size 0.7874 0.5842)
					(thickness 0.1524)
				)
				(justify left mirror)
			)
		)
		(property "Value" ""
			(at 0 0 90)
			(layer "B.Fab")
			(effects
				(font
					(size 1.27 1.27)
				)
				(justify mirror)
			)
		)
		(duplicate_pad_numbers_are_jumpers no)
		(fp_line
			(start -1.905 0.8636)
			(end 1.905 0.8636)
			(stroke
				(width 0.1524)
				(type default)
			)
			(layer "B.SilkS")
		)
		(fp_line
			(start -1.905 0.8382)
			(end -1.905 -0.8382)
			(stroke
				(width 0.1524)
				(type default)
			)
			(layer "B.SilkS")
		)
		(fp_line
			(start -0.127 0.8382)
			(end -0.127 -0.8382)
			(stroke
				(width 0.1524)
				(type default)
			)
			(layer "B.SilkS")
		)
		(fp_line
			(start 0.127 0.8382)
			(end 0.127 -0.8382)
			(stroke
				(width 0.1524)
				(type default)
			)
			(layer "B.SilkS")
		)
		(fp_line
			(start 1.905 0.8382)
			(end 1.905 -0.8382)
			(stroke
				(width 0.1524)
				(type default)
			)
			(layer "B.SilkS")
		)
		(fp_line
			(start 1.905 -0.8636)
			(end -1.905 -0.8636)
			(stroke
				(width 0.1524)
				(type default)
			)
			(layer "B.SilkS")
		)
		(fp_rect
			(start 1.524 0.7112)
			(end -1.524 -0.7366)
			(stroke
				(width 0)
				(type default)
			)
			(fill no)
			(layer "B.CrtYd")
		)
		(pad "1" smd rect
			(at -0.94996 0 90)
			(size 1.1176 1.3716)
			(layers "B.Cu" "B.Mask" "B.Paste")
			(net "P1V05_CLK_NODE1_R")
		)
		(pad "2" smd rect
			(at 0.94996 0 90)
			(size 1.1176 1.3716)
			(layers "B.Cu" "B.Mask" "B.Paste")
			(net "P1V05_CLK_NODE1")
		)
	)
	(footprint ""
		(layer "B.Cu")
		(at 78.83144 -177.585624 180)
		(property "Reference" "R696"
			(at -30.562296 -20.108164 0)
			(unlocked yes)
			(layer "B.SilkS")
			(effects
				(font
					(size 0.7874 0.5842)
					(thickness 0.1524)
				)
				(justify left mirror)
			)
		)
		(property "Value" ""
			(at 0 0 0)
			(layer "B.Fab")
			(effects
				(font
					(size 1.27 1.27)
				)
				(justify mirror)
			)
		)
		(duplicate_pad_numbers_are_jumpers no)
		(fp_line
			(start 0.7874 0.4064)
			(end 0.7874 -0.4064)
			(stroke
				(width 0.1524)
				(type default)
			)
			(layer "B.SilkS")
		)
		(fp_line
			(start 0.7874 -0.4064)
			(end -0.7874 -0.4064)
			(stroke
				(width 0.1524)
				(type default)
			)
			(layer "B.SilkS")
		)
		(fp_line
			(start -0.7874 0.4064)
			(end 0.7874 0.4064)
			(stroke
				(width 0.1524)
				(type default)
			)
			(layer "B.SilkS")
		)
		(fp_line
			(start -0.7874 -0.4064)
			(end -0.7874 0.4064)
			(stroke
				(width 0.1524)
				(type default)
			)
			(layer "B.SilkS")
		)
		(fp_poly
			(pts
				(xy 0.508 0.2794) (xy 0.508 0.2286) (xy 0.635 0.2286) (xy 0.635 -0.254) (xy 0.5334 -0.254) (xy 0.5334 -0.2794)
				(xy -0.5334 -0.2794) (xy -0.5334 -0.254) (xy -0.635 -0.254) (xy -0.635 0.254) (xy -0.5334 0.254)
				(xy -0.5334 0.2794)
			)
			(stroke
				(width 0)
				(type default)
			)
			(fill no)
			(layer "B.CrtYd")
		)
		(pad "1" smd rect
			(at -0.40005 0)
			(size 0.4572 0.508)
			(layers "B.Cu" "B.Mask" "B.Paste")
			(net "T2_NODE4_EN")
		)
		(pad "2" smd rect
			(at 0.40005 0)
			(size 0.4572 0.508)
			(layers "B.Cu" "B.Mask" "B.Paste")
			(net "P5V_NODE1")
		)
	)
	(footprint ""
		(layer "B.Cu")
		(at 90.81262 -161.830512)
		(property "Reference" "R912"
			(at 24.774144 20.104354 0)
			(unlocked yes)
			(layer "B.SilkS")
			(effects
				(font
					(size 0.7874 0.5842)
					(thickness 0.1524)
				)
				(justify left mirror)
			)
		)
		(property "Value" ""
			(at 0 0 0)
			(layer "B.Fab")
			(effects
				(font
					(size 1.27 1.27)
				)
				(justify mirror)
			)
		)
		(duplicate_pad_numbers_are_jumpers no)
		(fp_line
			(start -0.7874 -0.4064)
			(end -0.7874 0.4064)
			(stroke
				(width 0.1524)
				(type default)
			)
			(layer "B.SilkS")
		)
		(fp_line
			(start -0.7874 0.4064)
			(end 0.7874 0.4064)
			(stroke
				(width 0.1524)
				(type default)
			)
			(layer "B.SilkS")
		)
		(fp_line
			(start 0.7874 -0.4064)
			(end -0.7874 -0.4064)
			(stroke
				(width 0.1524)
				(type default)
			)
			(layer "B.SilkS")
		)
		(fp_line
			(start 0.7874 0.4064)
			(end 0.7874 -0.4064)
			(stroke
				(width 0.1524)
				(type default)
			)
			(layer "B.SilkS")
		)
		(fp_poly
			(pts
				(xy 0.508 0.2794) (xy 0.508 0.2286) (xy 0.635 0.2286) (xy 0.635 -0.254) (xy 0.5334 -0.254) (xy 0.5334 -0.2794)
				(xy -0.5334 -0.2794) (xy -0.5334 -0.254) (xy -0.635 -0.254) (xy -0.635 0.254) (xy -0.5334 0.254)
				(xy -0.5334 0.2794)
			)
			(stroke
				(width 0)
				(type default)
			)
			(fill no)
			(layer "B.CrtYd")
		)
		(pad "1" smd rect
			(at -0.40005 0 180)
			(size 0.4572 0.508)
			(layers "B.Cu" "B.Mask" "B.Paste")
			(net "UART_T5_NODE1_TXD")
		)
		(pad "2" smd rect
			(at 0.40005 0 180)
			(size 0.4572 0.508)
			(layers "B.Cu" "B.Mask" "B.Paste")
			(net "UART_T5_NODE1_TXD_R")
		)
	)
	(footprint ""
		(layer "B.Cu")
		(at 90.81262 -174.022512)
		(property "Reference" "R703"
			(at 24.902414 20.163028 0)
			(unlocked yes)
			(layer "B.SilkS")
			(effects
				(font
					(size 0.7874 0.5842)
					(thickness 0.1524)
				)
				(justify left mirror)
			)
		)
		(property "Value" ""
			(at 0 0 0)
			(layer "B.Fab")
			(effects
				(font
					(size 1.27 1.27)
				)
				(justify mirror)
			)
		)
		(duplicate_pad_numbers_are_jumpers no)
		(fp_line
			(start -0.7874 -0.4064)
			(end -0.7874 0.4064)
			(stroke
				(width 0.1524)
				(type default)
			)
			(layer "B.SilkS")
		)
		(fp_line
			(start -0.7874 0.4064)
			(end 0.7874 0.4064)
			(stroke
				(width 0.1524)
				(type default)
			)
			(layer "B.SilkS")
		)
		(fp_line
			(start 0.7874 -0.4064)
			(end -0.7874 -0.4064)
			(stroke
				(width 0.1524)
				(type default)
			)
			(layer "B.SilkS")
		)
		(fp_line
			(start 0.7874 0.4064)
			(end 0.7874 -0.4064)
			(stroke
				(width 0.1524)
				(type default)
			)
			(layer "B.SilkS")
		)
		(fp_poly
			(pts
				(xy 0.508 0.2794) (xy 0.508 0.2286) (xy 0.635 0.2286) (xy 0.635 -0.254) (xy 0.5334 -0.254) (xy 0.5334 -0.2794)
				(xy -0.5334 -0.2794) (xy -0.5334 -0.254) (xy -0.635 -0.254) (xy -0.635 0.254) (xy -0.5334 0.254)
				(xy -0.5334 0.2794)
			)
			(stroke
				(width 0)
				(type default)
			)
			(fill no)
			(layer "B.CrtYd")
		)
		(pad "1" smd rect
			(at -0.40005 0 180)
			(size 0.4572 0.508)
			(layers "B.Cu" "B.Mask" "B.Paste")
			(net "T4_NODE1_EN")
		)
		(pad "2" smd rect
			(at 0.40005 0 180)
			(size 0.4572 0.508)
			(layers "B.Cu" "B.Mask" "B.Paste")
			(net "P5V_NODE1")
		)
	)
	(footprint ""
		(layer "B.Cu")
		(at 55.552086 -129.756662 180)
		(property "Reference" "C267"
			(at 41.609518 -53.368702 0)
			(unlocked yes)
			(layer "B.SilkS")
			(effects
				(font
					(size 0.7874 0.5842)
					(thickness 0.1524)
				)
				(justify left mirror)
			)
		)
		(property "Value" ""
			(at 0 0 0)
			(layer "B.Fab")
			(effects
				(font
					(size 1.27 1.27)
				)
				(justify mirror)
			)
		)
		(duplicate_pad_numbers_are_jumpers no)
		(fp_line
			(start 0.7874 0.4064)
			(end 0.7874 -0.4064)
			(stroke
				(width 0.1524)
				(type default)
			)
			(layer "B.SilkS")
		)
		(fp_line
			(start 0.7874 -0.4064)
			(end -0.7874 -0.4064)
			(stroke
				(width 0.1524)
				(type default)
			)
			(layer "B.SilkS")
		)
		(fp_line
			(start 0 0.381)
			(end 0 -0.381)
			(stroke
				(width 0.1524)
				(type default)
			)
			(layer "B.SilkS")
		)
		(fp_line
			(start -0.7874 0.4064)
			(end 0.7874 0.4064)
			(stroke
				(width 0.1524)
				(type default)
			)
			(layer "B.SilkS")
		)
		(fp_line
			(start -0.7874 -0.4064)
			(end -0.7874 0.4064)
			(stroke
				(width 0.1524)
				(type default)
			)
			(layer "B.SilkS")
		)
		(fp_poly
			(pts
				(xy 0.5334 0.254) (xy 0.635 0.254) (xy 0.635 0.2286) (xy 0.635 -0.254) (xy 0.5334 -0.254) (xy 0.5334 -0.2794)
				(xy -0.5334 -0.2794) (xy -0.5334 -0.254) (xy -0.635 -0.254) (xy -0.635 0.254) (xy -0.5334 0.254)
				(xy -0.5334 0.2794) (xy 0.508 0.2794) (xy 0.5334 0.2794)
			)
			(stroke
				(width 0)
				(type default)
			)
			(fill no)
			(layer "B.CrtYd")
		)
		(pad "1" smd rect
			(at -0.40005 0)
			(size 0.4572 0.508)
			(layers "B.Cu" "B.Mask" "B.Paste")
			(net "BMC_NODE1_MPLLAV33")
		)
		(pad "2" smd rect
			(at 0.40005 0)
			(size 0.4572 0.508)
			(layers "B.Cu" "B.Mask" "B.Paste")
			(net "GND")
		)
	)
	(footprint ""
		(layer "B.Cu")
		(at 69.326252 -136.505188 180)
		(property "Reference" "C282"
			(at 35.998912 -52.704746 0)
			(unlocked yes)
			(layer "B.SilkS")
			(effects
				(font
					(size 0.7874 0.5842)
					(thickness 0.1524)
				)
				(justify left mirror)
			)
		)
		(property "Value" ""
			(at 0 0 0)
			(layer "B.Fab")
			(effects
				(font
					(size 1.27 1.27)
				)
				(justify mirror)
			)
		)
		(duplicate_pad_numbers_are_jumpers no)
		(fp_line
			(start 0.7874 0.4064)
			(end 0.7874 -0.4064)
			(stroke
				(width 0.1524)
				(type default)
			)
			(layer "B.SilkS")
		)
		(fp_line
			(start 0.7874 -0.4064)
			(end -0.7874 -0.4064)
			(stroke
				(width 0.1524)
				(type default)
			)
			(layer "B.SilkS")
		)
		(fp_line
			(start 0 0.381)
			(end 0 -0.381)
			(stroke
				(width 0.1524)
				(type default)
			)
			(layer "B.SilkS")
		)
		(fp_line
			(start -0.7874 0.4064)
			(end 0.7874 0.4064)
			(stroke
				(width 0.1524)
				(type default)
			)
			(layer "B.SilkS")
		)
		(fp_line
			(start -0.7874 -0.4064)
			(end -0.7874 0.4064)
			(stroke
				(width 0.1524)
				(type default)
			)
			(layer "B.SilkS")
		)
		(fp_poly
			(pts
				(xy 0.5334 0.254) (xy 0.635 0.254) (xy 0.635 0.2286) (xy 0.635 -0.254) (xy 0.5334 -0.254) (xy 0.5334 -0.2794)
				(xy -0.5334 -0.2794) (xy -0.5334 -0.254) (xy -0.635 -0.254) (xy -0.635 0.254) (xy -0.5334 0.254)
				(xy -0.5334 0.2794) (xy 0.508 0.2794) (xy 0.5334 0.2794)
			)
			(stroke
				(width 0)
				(type default)
			)
			(fill no)
			(layer "B.CrtYd")
		)
		(pad "1" smd rect
			(at -0.40005 0)
			(size 0.4572 0.508)
			(layers "B.Cu" "B.Mask" "B.Paste")
			(net "P3V3_NODE1")
		)
		(pad "2" smd rect
			(at 0.40005 0)
			(size 0.4572 0.508)
			(layers "B.Cu" "B.Mask" "B.Paste")
			(net "GND")
		)
	)
	(footprint ""
		(layer "B.Cu")
		(at 48.452278 -77.678026 180)
		(property "Reference" "C35"
			(at 14.723618 -31.527242 0)
			(unlocked yes)
			(layer "B.SilkS")
			(effects
				(font
					(size 0.7874 0.5842)
					(thickness 0.1524)
				)
				(justify left mirror)
			)
		)
		(property "Value" ""
			(at 0 0 0)
			(layer "B.Fab")
			(effects
				(font
					(size 1.27 1.27)
				)
				(justify mirror)
			)
		)
		(duplicate_pad_numbers_are_jumpers no)
		(fp_line
			(start 0.7874 0.4064)
			(end 0.7874 -0.4064)
			(stroke
				(width 0.1524)
				(type default)
			)
			(layer "B.SilkS")
		)
		(fp_line
			(start 0.7874 -0.4064)
			(end -0.7874 -0.4064)
			(stroke
				(width 0.1524)
				(type default)
			)
			(layer "B.SilkS")
		)
		(fp_line
			(start 0 0.381)
			(end 0 -0.381)
			(stroke
				(width 0.1524)
				(type default)
			)
			(layer "B.SilkS")
		)
		(fp_line
			(start -0.7874 0.4064)
			(end 0.7874 0.4064)
			(stroke
				(width 0.1524)
				(type default)
			)
			(layer "B.SilkS")
		)
		(fp_line
			(start -0.7874 -0.4064)
			(end -0.7874 0.4064)
			(stroke
				(width 0.1524)
				(type default)
			)
			(layer "B.SilkS")
		)
		(fp_poly
			(pts
				(xy 0.5334 0.254) (xy 0.635 0.254) (xy 0.635 0.2286) (xy 0.635 -0.254) (xy 0.5334 -0.254) (xy 0.5334 -0.2794)
				(xy -0.5334 -0.2794) (xy -0.5334 -0.254) (xy -0.635 -0.254) (xy -0.635 0.254) (xy -0.5334 0.254)
				(xy -0.5334 0.2794) (xy 0.508 0.2794) (xy 0.5334 0.2794)
			)
			(stroke
				(width 0)
				(type default)
			)
			(fill no)
			(layer "B.CrtYd")
		)
		(pad "1" smd rect
			(at -0.40005 0)
			(size 0.4572 0.508)
			(layers "B.Cu" "B.Mask" "B.Paste")
			(net "GND")
		)
		(pad "2" smd rect
			(at 0.40005 0)
			(size 0.4572 0.508)
			(layers "B.Cu" "B.Mask" "B.Paste")
			(net "P1V05_NODE1")
		)
	)
	(footprint ""
		(layer "B.Cu")
		(at 65.598802 -62.857634 -90)
		(property "Reference" "C120"
			(at 5.118862 -0.922782 270)
			(unlocked yes)
			(layer "B.SilkS")
			(effects
				(font
					(size 0.7874 0.5842)
					(thickness 0.1524)
				)
				(justify left mirror)
			)
		)
		(property "Value" ""
			(at 0 0 90)
			(layer "B.Fab")
			(effects
				(font
					(size 1.27 1.27)
				)
				(justify mirror)
			)
		)
		(duplicate_pad_numbers_are_jumpers no)
		(fp_line
			(start -0.7874 0.4064)
			(end 0.7874 0.4064)
			(stroke
				(width 0.1524)
				(type default)
			)
			(layer "B.SilkS")
		)
		(fp_line
			(start 0.7874 0.4064)
			(end 0.7874 -0.4064)
			(stroke
				(width 0.1524)
				(type default)
			)
			(layer "B.SilkS")
		)
		(fp_line
			(start 0 0.381)
			(end 0 -0.381)
			(stroke
				(width 0.1524)
				(type default)
			)
			(layer "B.SilkS")
		)
		(fp_line
			(start -0.7874 -0.4064)
			(end -0.7874 0.4064)
			(stroke
				(width 0.1524)
				(type default)
			)
			(layer "B.SilkS")
		)
		(fp_line
			(start 0.7874 -0.4064)
			(end -0.7874 -0.4064)
			(stroke
				(width 0.1524)
				(type default)
			)
			(layer "B.SilkS")
		)
		(fp_poly
			(pts
				(xy 0.5334 0.254) (xy 0.635 0.254) (xy 0.635 0.2286) (xy 0.635 -0.254) (xy 0.5334 -0.254) (xy 0.5334 -0.2794)
				(xy -0.5334 -0.2794) (xy -0.5334 -0.254) (xy -0.635 -0.254) (xy -0.635 0.254) (xy -0.5334 0.254)
				(xy -0.5334 0.2794) (xy 0.508 0.2794) (xy 0.5334 0.2794)
			)
			(stroke
				(width 0)
				(type default)
			)
			(fill no)
			(layer "B.CrtYd")
		)
		(pad "1" smd rect
			(at -0.40005 0 90)
			(size 0.4572 0.508)
			(layers "B.Cu" "B.Mask" "B.Paste")
			(net "PV_VDDR_NODE1")
		)
		(pad "2" smd rect
			(at 0.40005 0 90)
			(size 0.4572 0.508)
			(layers "B.Cu" "B.Mask" "B.Paste")
			(net "GND")
		)
	)
	(footprint ""
		(layer "B.Cu")
		(at 123.70816 -176.442624)
		(property "Reference" "R725"
			(at -28.598876 31.521146 0)
			(unlocked yes)
			(layer "B.SilkS")
			(effects
				(font
					(size 0.7874 0.5842)
					(thickness 0.1524)
				)
				(justify left mirror)
			)
		)
		(property "Value" ""
			(at 0 0 0)
			(layer "B.Fab")
			(effects
				(font
					(size 1.27 1.27)
				)
				(justify mirror)
			)
		)
		(duplicate_pad_numbers_are_jumpers no)
		(fp_line
			(start -0.7874 -0.4064)
			(end -0.7874 0.4064)
			(stroke
				(width 0.1524)
				(type default)
			)
			(layer "B.SilkS")
		)
		(fp_line
			(start -0.7874 0.4064)
			(end 0.7874 0.4064)
			(stroke
				(width 0.1524)
				(type default)
			)
			(layer "B.SilkS")
		)
		(fp_line
			(start 0.7874 -0.4064)
			(end -0.7874 -0.4064)
			(stroke
				(width 0.1524)
				(type default)
			)
			(layer "B.SilkS")
		)
		(fp_line
			(start 0.7874 0.4064)
			(end 0.7874 -0.4064)
			(stroke
				(width 0.1524)
				(type default)
			)
			(layer "B.SilkS")
		)
		(fp_poly
			(pts
				(xy 0.508 0.2794) (xy 0.508 0.2286) (xy 0.635 0.2286) (xy 0.635 -0.254) (xy 0.5334 -0.254) (xy 0.5334 -0.2794)
				(xy -0.5334 -0.2794) (xy -0.5334 -0.254) (xy -0.635 -0.254) (xy -0.635 0.254) (xy -0.5334 0.254)
				(xy -0.5334 0.2794)
			)
			(stroke
				(width 0)
				(type default)
			)
			(fill no)
			(layer "B.CrtYd")
		)
		(pad "1" smd rect
			(at -0.40005 0 180)
			(size 0.4572 0.508)
			(layers "B.Cu" "B.Mask" "B.Paste")
			(net "T8_NODE2_EN")
		)
		(pad "2" smd rect
			(at 0.40005 0 180)
			(size 0.4572 0.508)
			(layers "B.Cu" "B.Mask" "B.Paste")
			(net "P5V_NODE1")
		)
	)
	(footprint ""
		(layer "B.Cu")
		(at 136.483852 -114.915442 180)
		(property "Reference" "C5"
			(at -0.739902 0.95504 0)
			(unlocked yes)
			(layer "B.SilkS")
			(effects
				(font
					(size 0.7874 0.5842)
					(thickness 0.1524)
				)
				(justify left mirror)
			)
		)
		(property "Value" ""
			(at 0 0 0)
			(layer "B.Fab")
			(effects
				(font
					(size 1.27 1.27)
				)
				(justify mirror)
			)
		)
		(duplicate_pad_numbers_are_jumpers no)
		(fp_line
			(start 0.7874 0.4064)
			(end 0.7874 -0.4064)
			(stroke
				(width 0.1524)
				(type default)
			)
			(layer "B.SilkS")
		)
		(fp_line
			(start 0.7874 -0.4064)
			(end -0.7874 -0.4064)
			(stroke
				(width 0.1524)
				(type default)
			)
			(layer "B.SilkS")
		)
		(fp_line
			(start 0 0.381)
			(end 0 -0.381)
			(stroke
				(width 0.1524)
				(type default)
			)
			(layer "B.SilkS")
		)
		(fp_line
			(start -0.7874 0.4064)
			(end 0.7874 0.4064)
			(stroke
				(width 0.1524)
				(type default)
			)
			(layer "B.SilkS")
		)
		(fp_line
			(start -0.7874 -0.4064)
			(end -0.7874 0.4064)
			(stroke
				(width 0.1524)
				(type default)
			)
			(layer "B.SilkS")
		)
		(fp_poly
			(pts
				(xy 0.5334 0.254) (xy 0.635 0.254) (xy 0.635 0.2286) (xy 0.635 -0.254) (xy 0.5334 -0.254) (xy 0.5334 -0.2794)
				(xy -0.5334 -0.2794) (xy -0.5334 -0.254) (xy -0.635 -0.254) (xy -0.635 0.254) (xy -0.5334 0.254)
				(xy -0.5334 0.2794) (xy 0.508 0.2794) (xy 0.5334 0.2794)
			)
			(stroke
				(width 0)
				(type default)
			)
			(fill no)
			(layer "B.CrtYd")
		)
		(pad "1" smd rect
			(at -0.40005 0)
			(size 0.4572 0.508)
			(layers "B.Cu" "B.Mask" "B.Paste")
			(net "P3V3_CLK_NODE1")
		)
		(pad "2" smd rect
			(at 0.40005 0)
			(size 0.4572 0.508)
			(layers "B.Cu" "B.Mask" "B.Paste")
			(net "GND")
		)
	)
	(footprint ""
		(layer "B.Cu")
		(at 138.684 -46.952154 90)
		(property "Reference" "R1264"
			(at 3.238246 11.93673 270)
			(unlocked yes)
			(layer "B.SilkS")
			(effects
				(font
					(size 0.7874 0.5842)
					(thickness 0.1524)
				)
				(justify left mirror)
			)
		)
		(property "Value" ""
			(at 0 0 90)
			(layer "B.Fab")
			(effects
				(font
					(size 1.27 1.27)
				)
				(justify mirror)
			)
		)
		(duplicate_pad_numbers_are_jumpers no)
		(fp_line
			(start 0.7874 -0.4064)
			(end -0.7874 -0.4064)
			(stroke
				(width 0.1524)
				(type default)
			)
			(layer "B.SilkS")
		)
		(fp_line
			(start -0.7874 -0.4064)
			(end -0.7874 0.4064)
			(stroke
				(width 0.1524)
				(type default)
			)
			(layer "B.SilkS")
		)
		(fp_line
			(start 0.7874 0.4064)
			(end 0.7874 -0.4064)
			(stroke
				(width 0.1524)
				(type default)
			)
			(layer "B.SilkS")
		)
		(fp_line
			(start -0.7874 0.4064)
			(end 0.7874 0.4064)
			(stroke
				(width 0.1524)
				(type default)
			)
			(layer "B.SilkS")
		)
		(fp_poly
			(pts
				(xy 0.508 0.2794) (xy 0.508 0.2286) (xy 0.635 0.2286) (xy 0.635 -0.254) (xy 0.5334 -0.254) (xy 0.5334 -0.2794)
				(xy -0.5334 -0.2794) (xy -0.5334 -0.254) (xy -0.635 -0.254) (xy -0.635 0.254) (xy -0.5334 0.254)
				(xy -0.5334 0.2794)
			)
			(stroke
				(width 0)
				(type default)
			)
			(fill no)
			(layer "B.CrtYd")
		)
		(pad "1" smd rect
			(at -0.40005 0 270)
			(size 0.4572 0.508)
			(layers "B.Cu" "B.Mask" "B.Paste")
			(net "P5V_NODE1")
		)
		(pad "2" smd rect
			(at 0.40005 0 270)
			(size 0.4572 0.508)
			(layers "B.Cu" "B.Mask" "B.Paste")
			(net "UART_DCD_P3_N")
		)
	)
	(footprint ""
		(layer "B.Cu")
		(at 156.77769 -173.809914 -90)
		(property "Reference" "C917"
			(at 1.045972 -1.034288 270)
			(unlocked yes)
			(layer "B.SilkS")
			(effects
				(font
					(size 0.7874 0.5842)
					(thickness 0.1524)
				)
				(justify left mirror)
			)
		)
		(property "Value" ""
			(at 0 0 90)
			(layer "B.Fab")
			(effects
				(font
					(size 1.27 1.27)
				)
				(justify mirror)
			)
		)
		(duplicate_pad_numbers_are_jumpers no)
		(fp_line
			(start -0.7874 0.4064)
			(end 0.7874 0.4064)
			(stroke
				(width 0.1524)
				(type default)
			)
			(layer "B.SilkS")
		)
		(fp_line
			(start 0.7874 0.4064)
			(end 0.7874 -0.4064)
			(stroke
				(width 0.1524)
				(type default)
			)
			(layer "B.SilkS")
		)
		(fp_line
			(start 0 0.381)
			(end 0 -0.381)
			(stroke
				(width 0.1524)
				(type default)
			)
			(layer "B.SilkS")
		)
		(fp_line
			(start -0.7874 -0.4064)
			(end -0.7874 0.4064)
			(stroke
				(width 0.1524)
				(type default)
			)
			(layer "B.SilkS")
		)
		(fp_line
			(start 0.7874 -0.4064)
			(end -0.7874 -0.4064)
			(stroke
				(width 0.1524)
				(type default)
			)
			(layer "B.SilkS")
		)
		(fp_poly
			(pts
				(xy 0.5334 0.254) (xy 0.635 0.254) (xy 0.635 0.2286) (xy 0.635 -0.254) (xy 0.5334 -0.254) (xy 0.5334 -0.2794)
				(xy -0.5334 -0.2794) (xy -0.5334 -0.254) (xy -0.635 -0.254) (xy -0.635 0.254) (xy -0.5334 0.254)
				(xy -0.5334 0.2794) (xy 0.508 0.2794) (xy 0.5334 0.2794)
			)
			(stroke
				(width 0)
				(type default)
			)
			(fill no)
			(layer "B.CrtYd")
		)
		(pad "1" smd rect
			(at -0.40005 0 90)
			(size 0.4572 0.508)
			(layers "B.Cu" "B.Mask" "B.Paste")
			(net "GND")
		)
		(pad "2" smd rect
			(at 0.40005 0 90)
			(size 0.4572 0.508)
			(layers "B.Cu" "B.Mask" "B.Paste")
			(net "N54365837")
		)
	)
	(footprint ""
		(layer "B.Cu")
		(at 47.74438 -97.104454 -90)
		(property "Reference" "R124"
			(at -0.960374 -0.484378 270)
			(unlocked yes)
			(layer "B.SilkS")
			(effects
				(font
					(size 0.7874 0.5842)
					(thickness 0.1524)
				)
				(justify left mirror)
			)
		)
		(property "Value" ""
			(at 0 0 90)
			(layer "B.Fab")
			(effects
				(font
					(size 1.27 1.27)
				)
				(justify mirror)
			)
		)
		(duplicate_pad_numbers_are_jumpers no)
		(fp_line
			(start -0.7874 0.4064)
			(end 0.7874 0.4064)
			(stroke
				(width 0.1524)
				(type default)
			)
			(layer "B.SilkS")
		)
		(fp_line
			(start 0.7874 0.4064)
			(end 0.7874 -0.4064)
			(stroke
				(width 0.1524)
				(type default)
			)
			(layer "B.SilkS")
		)
		(fp_line
			(start -0.7874 -0.4064)
			(end -0.7874 0.4064)
			(stroke
				(width 0.1524)
				(type default)
			)
			(layer "B.SilkS")
		)
		(fp_line
			(start 0.7874 -0.4064)
			(end -0.7874 -0.4064)
			(stroke
				(width 0.1524)
				(type default)
			)
			(layer "B.SilkS")
		)
		(fp_poly
			(pts
				(xy 0.508 0.2794) (xy 0.508 0.2286) (xy 0.635 0.2286) (xy 0.635 -0.254) (xy 0.5334 -0.254) (xy 0.5334 -0.2794)
				(xy -0.5334 -0.2794) (xy -0.5334 -0.254) (xy -0.635 -0.254) (xy -0.635 0.254) (xy -0.5334 0.254)
				(xy -0.5334 0.2794)
			)
			(stroke
				(width 0)
				(type default)
			)
			(fill no)
			(layer "B.CrtYd")
		)
		(pad "1" smd rect
			(at -0.40005 0 90)
			(size 0.4572 0.508)
			(layers "B.Cu" "B.Mask" "B.Paste")
			(net "P3V3_NODE1")
		)
		(pad "2" smd rect
			(at 0.40005 0 90)
			(size 0.4572 0.508)
			(layers "B.Cu" "B.Mask" "B.Paste")
			(net "SMB_CPU_NODE1_XDP_DAT")
		)
	)
	(footprint ""
		(layer "B.Cu")
		(at 121.40184 -142.404592 180)
		(property "Reference" "C188"
			(at 2.075942 -0.005334 0)
			(unlocked yes)
			(layer "B.SilkS")
			(effects
				(font
					(size 0.7874 0.5842)
					(thickness 0.1524)
				)
				(justify left mirror)
			)
		)
		(property "Value" ""
			(at 0 0 0)
			(layer "B.Fab")
			(effects
				(font
					(size 1.27 1.27)
				)
				(justify mirror)
			)
		)
		(duplicate_pad_numbers_are_jumpers no)
		(fp_line
			(start 0.7874 0.4064)
			(end 0.7874 -0.4064)
			(stroke
				(width 0.1524)
				(type default)
			)
			(layer "B.SilkS")
		)
		(fp_line
			(start 0.7874 -0.4064)
			(end -0.7874 -0.4064)
			(stroke
				(width 0.1524)
				(type default)
			)
			(layer "B.SilkS")
		)
		(fp_line
			(start 0 0.381)
			(end 0 -0.381)
			(stroke
				(width 0.1524)
				(type default)
			)
			(layer "B.SilkS")
		)
		(fp_line
			(start -0.7874 0.4064)
			(end 0.7874 0.4064)
			(stroke
				(width 0.1524)
				(type default)
			)
			(layer "B.SilkS")
		)
		(fp_line
			(start -0.7874 -0.4064)
			(end -0.7874 0.4064)
			(stroke
				(width 0.1524)
				(type default)
			)
			(layer "B.SilkS")
		)
		(fp_poly
			(pts
				(xy 0.5334 0.254) (xy 0.635 0.254) (xy 0.635 0.2286) (xy 0.635 -0.254) (xy 0.5334 -0.254) (xy 0.5334 -0.2794)
				(xy -0.5334 -0.2794) (xy -0.5334 -0.254) (xy -0.635 -0.254) (xy -0.635 0.254) (xy -0.5334 0.254)
				(xy -0.5334 0.2794) (xy 0.508 0.2794) (xy 0.5334 0.2794)
			)
			(stroke
				(width 0)
				(type default)
			)
			(fill no)
			(layer "B.CrtYd")
		)
		(pad "1" smd rect
			(at -0.40005 0)
			(size 0.4572 0.508)
			(layers "B.Cu" "B.Mask" "B.Paste")
			(net "P2E_CPU_BMC_NODE1_TX_C_DN")
		)
		(pad "2" smd rect
			(at 0.40005 0)
			(size 0.4572 0.508)
			(layers "B.Cu" "B.Mask" "B.Paste")
			(net "P2E_CPU_BMC_NODE1_TX_DN")
		)
	)
	(footprint ""
		(layer "B.Cu")
		(at 35.847274 -67.576192 180)
		(property "Reference" "C17"
			(at 2.062734 -0.060452 0)
			(unlocked yes)
			(layer "B.SilkS")
			(effects
				(font
					(size 0.7874 0.5842)
					(thickness 0.1524)
				)
				(justify left mirror)
			)
		)
		(property "Value" ""
			(at 0 0 0)
			(layer "B.Fab")
			(effects
				(font
					(size 1.27 1.27)
				)
				(justify mirror)
			)
		)
		(duplicate_pad_numbers_are_jumpers no)
		(fp_line
			(start 0.7874 0.4064)
			(end 0.7874 -0.4064)
			(stroke
				(width 0.1524)
				(type default)
			)
			(layer "B.SilkS")
		)
		(fp_line
			(start 0.7874 -0.4064)
			(end -0.7874 -0.4064)
			(stroke
				(width 0.1524)
				(type default)
			)
			(layer "B.SilkS")
		)
		(fp_line
			(start 0 0.381)
			(end 0 -0.381)
			(stroke
				(width 0.1524)
				(type default)
			)
			(layer "B.SilkS")
		)
		(fp_line
			(start -0.7874 0.4064)
			(end 0.7874 0.4064)
			(stroke
				(width 0.1524)
				(type default)
			)
			(layer "B.SilkS")
		)
		(fp_line
			(start -0.7874 -0.4064)
			(end -0.7874 0.4064)
			(stroke
				(width 0.1524)
				(type default)
			)
			(layer "B.SilkS")
		)
		(fp_poly
			(pts
				(xy 0.5334 0.254) (xy 0.635 0.254) (xy 0.635 0.2286) (xy 0.635 -0.254) (xy 0.5334 -0.254) (xy 0.5334 -0.2794)
				(xy -0.5334 -0.2794) (xy -0.5334 -0.254) (xy -0.635 -0.254) (xy -0.635 0.254) (xy -0.5334 0.254)
				(xy -0.5334 0.2794) (xy 0.508 0.2794) (xy 0.5334 0.2794)
			)
			(stroke
				(width 0)
				(type default)
			)
			(fill no)
			(layer "B.CrtYd")
		)
		(pad "1" smd rect
			(at -0.40005 0)
			(size 0.4572 0.508)
			(layers "B.Cu" "B.Mask" "B.Paste")
			(net "P2E_CPU_NIC2_NODE1_TX_C_DP")
		)
		(pad "2" smd rect
			(at 0.40005 0)
			(size 0.4572 0.508)
			(layers "B.Cu" "B.Mask" "B.Paste")
			(net "P2E_CPU_NIC2_NODE1_TX_DP")
		)
	)
	(footprint ""
		(layer "B.Cu")
		(at 156.83738 -156.957522)
		(property "Reference" "C466"
			(at -3.502406 -0.096012 0)
			(unlocked yes)
			(layer "B.SilkS")
			(effects
				(font
					(size 0.7874 0.5842)
					(thickness 0.1524)
				)
				(justify left mirror)
			)
		)
		(property "Value" ""
			(at 0 0 0)
			(layer "B.Fab")
			(effects
				(font
					(size 1.27 1.27)
				)
				(justify mirror)
			)
		)
		(duplicate_pad_numbers_are_jumpers no)
		(fp_line
			(start -0.7874 -0.4064)
			(end -0.7874 0.4064)
			(stroke
				(width 0.1524)
				(type default)
			)
			(layer "B.SilkS")
		)
		(fp_line
			(start -0.7874 0.4064)
			(end 0.7874 0.4064)
			(stroke
				(width 0.1524)
				(type default)
			)
			(layer "B.SilkS")
		)
		(fp_line
			(start 0 0.381)
			(end 0 -0.381)
			(stroke
				(width 0.1524)
				(type default)
			)
			(layer "B.SilkS")
		)
		(fp_line
			(start 0.7874 -0.4064)
			(end -0.7874 -0.4064)
			(stroke
				(width 0.1524)
				(type default)
			)
			(layer "B.SilkS")
		)
		(fp_line
			(start 0.7874 0.4064)
			(end 0.7874 -0.4064)
			(stroke
				(width 0.1524)
				(type default)
			)
			(layer "B.SilkS")
		)
		(fp_poly
			(pts
				(xy 0.5334 0.254) (xy 0.635 0.254) (xy 0.635 0.2286) (xy 0.635 -0.254) (xy 0.5334 -0.254) (xy 0.5334 -0.2794)
				(xy -0.5334 -0.2794) (xy -0.5334 -0.254) (xy -0.635 -0.254) (xy -0.635 0.254) (xy -0.5334 0.254)
				(xy -0.5334 0.2794) (xy 0.508 0.2794) (xy 0.5334 0.2794)
			)
			(stroke
				(width 0)
				(type default)
			)
			(fill no)
			(layer "B.CrtYd")
		)
		(pad "1" smd rect
			(at -0.40005 0 180)
			(size 0.4572 0.508)
			(layers "B.Cu" "B.Mask" "B.Paste")
			(net "P1V05_LAN2")
		)
		(pad "2" smd rect
			(at 0.40005 0 180)
			(size 0.4572 0.508)
			(layers "B.Cu" "B.Mask" "B.Paste")
			(net "GND")
		)
	)
	(footprint ""
		(layer "B.Cu")
		(at 149.390354 -178.784504 90)
		(property "Reference" "R741"
			(at -0.32004 2.22631 270)
			(unlocked yes)
			(layer "B.SilkS")
			(effects
				(font
					(size 0.7874 0.5842)
					(thickness 0.1524)
				)
				(justify left mirror)
			)
		)
		(property "Value" ""
			(at 0 0 90)
			(layer "B.Fab")
			(effects
				(font
					(size 1.27 1.27)
				)
				(justify mirror)
			)
		)
		(duplicate_pad_numbers_are_jumpers no)
		(fp_line
			(start 0.7874 -0.4064)
			(end -0.7874 -0.4064)
			(stroke
				(width 0.1524)
				(type default)
			)
			(layer "B.SilkS")
		)
		(fp_line
			(start -0.7874 -0.4064)
			(end -0.7874 0.4064)
			(stroke
				(width 0.1524)
				(type default)
			)
			(layer "B.SilkS")
		)
		(fp_line
			(start 0.7874 0.4064)
			(end 0.7874 -0.4064)
			(stroke
				(width 0.1524)
				(type default)
			)
			(layer "B.SilkS")
		)
		(fp_line
			(start -0.7874 0.4064)
			(end 0.7874 0.4064)
			(stroke
				(width 0.1524)
				(type default)
			)
			(layer "B.SilkS")
		)
		(fp_poly
			(pts
				(xy 0.508 0.2794) (xy 0.508 0.2286) (xy 0.635 0.2286) (xy 0.635 -0.254) (xy 0.5334 -0.254) (xy 0.5334 -0.2794)
				(xy -0.5334 -0.2794) (xy -0.5334 -0.254) (xy -0.635 -0.254) (xy -0.635 0.254) (xy -0.5334 0.254)
				(xy -0.5334 0.2794)
			)
			(stroke
				(width 0)
				(type default)
			)
			(fill no)
			(layer "B.CrtYd")
		)
		(pad "1" smd rect
			(at -0.40005 0 270)
			(size 0.4572 0.508)
			(layers "B.Cu" "B.Mask" "B.Paste")
			(net "T11_NODE1_EN")
		)
		(pad "2" smd rect
			(at 0.40005 0 270)
			(size 0.4572 0.508)
			(layers "B.Cu" "B.Mask" "B.Paste")
			(net "P5V_NODE1")
		)
	)
	(footprint ""
		(layer "B.Cu")
		(at 163.128452 -103.094282 180)
		(property "Reference" "C386"
			(at -4.541012 -0.07366 0)
			(unlocked yes)
			(layer "B.SilkS")
			(effects
				(font
					(size 0.7874 0.5842)
					(thickness 0.1524)
				)
				(justify left mirror)
			)
		)
		(property "Value" ""
			(at 0 0 0)
			(layer "B.Fab")
			(effects
				(font
					(size 1.27 1.27)
				)
				(justify mirror)
			)
		)
		(duplicate_pad_numbers_are_jumpers no)
		(fp_line
			(start 0.7874 0.4064)
			(end 0.7874 -0.4064)
			(stroke
				(width 0.1524)
				(type default)
			)
			(layer "B.SilkS")
		)
		(fp_line
			(start 0.7874 -0.4064)
			(end -0.7874 -0.4064)
			(stroke
				(width 0.1524)
				(type default)
			)
			(layer "B.SilkS")
		)
		(fp_line
			(start 0 0.381)
			(end 0 -0.381)
			(stroke
				(width 0.1524)
				(type default)
			)
			(layer "B.SilkS")
		)
		(fp_line
			(start -0.7874 0.4064)
			(end 0.7874 0.4064)
			(stroke
				(width 0.1524)
				(type default)
			)
			(layer "B.SilkS")
		)
		(fp_line
			(start -0.7874 -0.4064)
			(end -0.7874 0.4064)
			(stroke
				(width 0.1524)
				(type default)
			)
			(layer "B.SilkS")
		)
		(fp_poly
			(pts
				(xy 0.5334 0.254) (xy 0.635 0.254) (xy 0.635 0.2286) (xy 0.635 -0.254) (xy 0.5334 -0.254) (xy 0.5334 -0.2794)
				(xy -0.5334 -0.2794) (xy -0.5334 -0.254) (xy -0.635 -0.254) (xy -0.635 0.254) (xy -0.5334 0.254)
				(xy -0.5334 0.2794) (xy 0.508 0.2794) (xy 0.5334 0.2794)
			)
			(stroke
				(width 0)
				(type default)
			)
			(fill no)
			(layer "B.CrtYd")
		)
		(pad "1" smd rect
			(at -0.40005 0)
			(size 0.4572 0.508)
			(layers "B.Cu" "B.Mask" "B.Paste")
			(net "GND")
		)
		(pad "2" smd rect
			(at 0.40005 0)
			(size 0.4572 0.508)
			(layers "B.Cu" "B.Mask" "B.Paste")
			(net "P3V3_USB_NODE1")
		)
	)
	(footprint ""
		(layer "B.Cu")
		(at 171.180252 -100.98659)
		(property "Reference" "C371"
			(at 7.670038 0.253492 0)
			(unlocked yes)
			(layer "B.SilkS")
			(effects
				(font
					(size 0.7874 0.5842)
					(thickness 0.1524)
				)
				(justify left mirror)
			)
		)
		(property "Value" ""
			(at 0 0 0)
			(layer "B.Fab")
			(effects
				(font
					(size 1.27 1.27)
				)
				(justify mirror)
			)
		)
		(duplicate_pad_numbers_are_jumpers no)
		(fp_line
			(start -0.7874 -0.4064)
			(end -0.7874 0.4064)
			(stroke
				(width 0.1524)
				(type default)
			)
			(layer "B.SilkS")
		)
		(fp_line
			(start -0.7874 0.4064)
			(end 0.7874 0.4064)
			(stroke
				(width 0.1524)
				(type default)
			)
			(layer "B.SilkS")
		)
		(fp_line
			(start 0 0.381)
			(end 0 -0.381)
			(stroke
				(width 0.1524)
				(type default)
			)
			(layer "B.SilkS")
		)
		(fp_line
			(start 0.7874 -0.4064)
			(end -0.7874 -0.4064)
			(stroke
				(width 0.1524)
				(type default)
			)
			(layer "B.SilkS")
		)
		(fp_line
			(start 0.7874 0.4064)
			(end 0.7874 -0.4064)
			(stroke
				(width 0.1524)
				(type default)
			)
			(layer "B.SilkS")
		)
		(fp_poly
			(pts
				(xy 0.5334 0.254) (xy 0.635 0.254) (xy 0.635 0.2286) (xy 0.635 -0.254) (xy 0.5334 -0.254) (xy 0.5334 -0.2794)
				(xy -0.5334 -0.2794) (xy -0.5334 -0.254) (xy -0.635 -0.254) (xy -0.635 0.254) (xy -0.5334 0.254)
				(xy -0.5334 0.2794) (xy 0.508 0.2794) (xy 0.5334 0.2794)
			)
			(stroke
				(width 0)
				(type default)
			)
			(fill no)
			(layer "B.CrtYd")
		)
		(pad "1" smd rect
			(at -0.40005 0 180)
			(size 0.4572 0.508)
			(layers "B.Cu" "B.Mask" "B.Paste")
			(net "GND")
		)
		(pad "2" smd rect
			(at 0.40005 0 180)
			(size 0.4572 0.508)
			(layers "B.Cu" "B.Mask" "B.Paste")
			(net "P1V05_NODE1")
		)
	)
	(footprint ""
		(layer "B.Cu")
		(at 145.001996 -68.73113 -90)
		(property "Reference" "C337"
			(at -1.050036 -0.550926 270)
			(unlocked yes)
			(layer "B.SilkS")
			(effects
				(font
					(size 0.7874 0.5842)
					(thickness 0.1524)
				)
				(justify left mirror)
			)
		)
		(property "Value" ""
			(at 0 0 90)
			(layer "B.Fab")
			(effects
				(font
					(size 1.27 1.27)
				)
				(justify mirror)
			)
		)
		(duplicate_pad_numbers_are_jumpers no)
		(fp_line
			(start -0.7874 0.4064)
			(end 0.7874 0.4064)
			(stroke
				(width 0.1524)
				(type default)
			)
			(layer "B.SilkS")
		)
		(fp_line
			(start 0.7874 0.4064)
			(end 0.7874 -0.4064)
			(stroke
				(width 0.1524)
				(type default)
			)
			(layer "B.SilkS")
		)
		(fp_line
			(start 0 0.381)
			(end 0 -0.381)
			(stroke
				(width 0.1524)
				(type default)
			)
			(layer "B.SilkS")
		)
		(fp_line
			(start -0.7874 -0.4064)
			(end -0.7874 0.4064)
			(stroke
				(width 0.1524)
				(type default)
			)
			(layer "B.SilkS")
		)
		(fp_line
			(start 0.7874 -0.4064)
			(end -0.7874 -0.4064)
			(stroke
				(width 0.1524)
				(type default)
			)
			(layer "B.SilkS")
		)
		(fp_poly
			(pts
				(xy 0.5334 0.254) (xy 0.635 0.254) (xy 0.635 0.2286) (xy 0.635 -0.254) (xy 0.5334 -0.254) (xy 0.5334 -0.2794)
				(xy -0.5334 -0.2794) (xy -0.5334 -0.254) (xy -0.635 -0.254) (xy -0.635 0.254) (xy -0.5334 0.254)
				(xy -0.5334 0.2794) (xy 0.508 0.2794) (xy 0.5334 0.2794)
			)
			(stroke
				(width 0)
				(type default)
			)
			(fill no)
			(layer "B.CrtYd")
		)
		(pad "1" smd rect
			(at -0.40005 0 90)
			(size 0.4572 0.508)
			(layers "B.Cu" "B.Mask" "B.Paste")
			(net "P1V0_SATA")
		)
		(pad "2" smd rect
			(at 0.40005 0 90)
			(size 0.4572 0.508)
			(layers "B.Cu" "B.Mask" "B.Paste")
			(net "GND")
		)
	)
	(footprint ""
		(layer "B.Cu")
		(at 72.008492 -92.920058 90)
		(property "Reference" "R89"
			(at -1.399286 2.039874 270)
			(unlocked yes)
			(layer "B.SilkS")
			(effects
				(font
					(size 0.7874 0.5842)
					(thickness 0.1524)
				)
				(justify left mirror)
			)
		)
		(property "Value" ""
			(at 0 0 90)
			(layer "B.Fab")
			(effects
				(font
					(size 1.27 1.27)
				)
				(justify mirror)
			)
		)
		(duplicate_pad_numbers_are_jumpers no)
		(fp_line
			(start 0.7874 -0.4064)
			(end -0.7874 -0.4064)
			(stroke
				(width 0.1524)
				(type default)
			)
			(layer "B.SilkS")
		)
		(fp_line
			(start -0.7874 -0.4064)
			(end -0.7874 0.4064)
			(stroke
				(width 0.1524)
				(type default)
			)
			(layer "B.SilkS")
		)
		(fp_line
			(start 0.7874 0.4064)
			(end 0.7874 -0.4064)
			(stroke
				(width 0.1524)
				(type default)
			)
			(layer "B.SilkS")
		)
		(fp_line
			(start -0.7874 0.4064)
			(end 0.7874 0.4064)
			(stroke
				(width 0.1524)
				(type default)
			)
			(layer "B.SilkS")
		)
		(fp_poly
			(pts
				(xy 0.508 0.2794) (xy 0.508 0.2286) (xy 0.635 0.2286) (xy 0.635 -0.254) (xy 0.5334 -0.254) (xy 0.5334 -0.2794)
				(xy -0.5334 -0.2794) (xy -0.5334 -0.254) (xy -0.635 -0.254) (xy -0.635 0.254) (xy -0.5334 0.254)
				(xy -0.5334 0.2794)
			)
			(stroke
				(width 0)
				(type default)
			)
			(fill no)
			(layer "B.CrtYd")
		)
		(pad "1" smd rect
			(at -0.40005 0 270)
			(size 0.4572 0.508)
			(layers "B.Cu" "B.Mask" "B.Paste")
			(net "H_CPU_NODE1_ERR0")
		)
		(pad "2" smd rect
			(at 0.40005 0 270)
			(size 0.4572 0.508)
			(layers "B.Cu" "B.Mask" "B.Paste")
			(net "H_CPU_NODE1_ERR0_R")
		)
	)
	(footprint ""
		(layer "B.Cu")
		(at 180.213 -188.468 -90)
		(property "Reference" "C592"
			(at -1.4986 0.05207 270)
			(unlocked yes)
			(layer "B.SilkS")
			(effects
				(font
					(size 0.7874 0.5842)
					(thickness 0.1524)
				)
				(justify left mirror)
			)
		)
		(property "Value" ""
			(at 0 0 90)
			(layer "B.Fab")
			(effects
				(font
					(size 1.27 1.27)
				)
				(justify mirror)
			)
		)
		(duplicate_pad_numbers_are_jumpers no)
		(fp_line
			(start -0.7874 0.4064)
			(end 0.7874 0.4064)
			(stroke
				(width 0.1524)
				(type default)
			)
			(layer "B.SilkS")
		)
		(fp_line
			(start 0.7874 0.4064)
			(end 0.7874 -0.4064)
			(stroke
				(width 0.1524)
				(type default)
			)
			(layer "B.SilkS")
		)
		(fp_line
			(start 0 0.381)
			(end 0 -0.381)
			(stroke
				(width 0.1524)
				(type default)
			)
			(layer "B.SilkS")
		)
		(fp_line
			(start -0.7874 -0.4064)
			(end -0.7874 0.4064)
			(stroke
				(width 0.1524)
				(type default)
			)
			(layer "B.SilkS")
		)
		(fp_line
			(start 0.7874 -0.4064)
			(end -0.7874 -0.4064)
			(stroke
				(width 0.1524)
				(type default)
			)
			(layer "B.SilkS")
		)
		(fp_poly
			(pts
				(xy 0.5334 0.254) (xy 0.635 0.254) (xy 0.635 0.2286) (xy 0.635 -0.254) (xy 0.5334 -0.254) (xy 0.5334 -0.2794)
				(xy -0.5334 -0.2794) (xy -0.5334 -0.254) (xy -0.635 -0.254) (xy -0.635 0.254) (xy -0.5334 0.254)
				(xy -0.5334 0.2794) (xy 0.508 0.2794) (xy 0.5334 0.2794)
			)
			(stroke
				(width 0)
				(type default)
			)
			(fill no)
			(layer "B.CrtYd")
		)
		(pad "1" smd rect
			(at -0.40005 0 90)
			(size 0.4572 0.508)
			(layers "B.Cu" "B.Mask" "B.Paste")
			(net "POWER_SW1_PWR_CTR_12V_R")
		)
		(pad "2" smd rect
			(at 0.40005 0 90)
			(size 0.4572 0.508)
			(layers "B.Cu" "B.Mask" "B.Paste")
			(net "GND")
		)
	)
	(footprint ""
		(layer "B.Cu")
		(at 53.006498 -96.696784 90)
		(property "Reference" "R51"
			(at 6.405118 -4.4577 270)
			(unlocked yes)
			(layer "B.SilkS")
			(effects
				(font
					(size 0.7874 0.5842)
					(thickness 0.1524)
				)
				(justify left mirror)
			)
		)
		(property "Value" ""
			(at 0 0 90)
			(layer "B.Fab")
			(effects
				(font
					(size 1.27 1.27)
				)
				(justify mirror)
			)
		)
		(duplicate_pad_numbers_are_jumpers no)
		(fp_line
			(start 0.7874 -0.4064)
			(end -0.7874 -0.4064)
			(stroke
				(width 0.1524)
				(type default)
			)
			(layer "B.SilkS")
		)
		(fp_line
			(start -0.7874 -0.4064)
			(end -0.7874 0.4064)
			(stroke
				(width 0.1524)
				(type default)
			)
			(layer "B.SilkS")
		)
		(fp_line
			(start 0.7874 0.4064)
			(end 0.7874 -0.4064)
			(stroke
				(width 0.1524)
				(type default)
			)
			(layer "B.SilkS")
		)
		(fp_line
			(start -0.7874 0.4064)
			(end 0.7874 0.4064)
			(stroke
				(width 0.1524)
				(type default)
			)
			(layer "B.SilkS")
		)
		(fp_poly
			(pts
				(xy 0.508 0.2794) (xy 0.508 0.2286) (xy 0.635 0.2286) (xy 0.635 -0.254) (xy 0.5334 -0.254) (xy 0.5334 -0.2794)
				(xy -0.5334 -0.2794) (xy -0.5334 -0.254) (xy -0.635 -0.254) (xy -0.635 0.254) (xy -0.5334 0.254)
				(xy -0.5334 0.2794)
			)
			(stroke
				(width 0)
				(type default)
			)
			(fill no)
			(layer "B.CrtYd")
		)
		(pad "1" smd rect
			(at -0.40005 0 270)
			(size 0.4572 0.508)
			(layers "B.Cu" "B.Mask" "B.Paste")
			(net "PU_CPU_NODE1_DFX_GPIO_GRP1_5")
		)
		(pad "2" smd rect
			(at 0.40005 0 270)
			(size 0.4572 0.508)
			(layers "B.Cu" "B.Mask" "B.Paste")
			(net "P1V8_NODE1")
		)
	)
	(footprint ""
		(layer "B.Cu")
		(at 73.964546 -124.940568 -90)
		(property "Reference" "L18"
			(at 2.67081 -7.64286 270)
			(unlocked yes)
			(layer "B.SilkS")
			(effects
				(font
					(size 0.7874 0.5842)
					(thickness 0.1524)
				)
				(justify mirror)
			)
		)
		(property "Value" ""
			(at 0 0 90)
			(layer "B.Fab")
			(effects
				(font
					(size 1.27 1.27)
				)
				(justify mirror)
			)
		)
		(duplicate_pad_numbers_are_jumpers no)
		(fp_line
			(start -1.2954 0.635)
			(end 1.2954 0.635)
			(stroke
				(width 0.1524)
				(type default)
			)
			(layer "B.SilkS")
		)
		(fp_line
			(start -0.127 -0.5842)
			(end -0.127 0.5842)
			(stroke
				(width 0.1524)
				(type default)
			)
			(layer "B.SilkS")
		)
		(fp_line
			(start 0.127 -0.5842)
			(end 0.127 0.5842)
			(stroke
				(width 0.1524)
				(type default)
			)
			(layer "B.SilkS")
		)
		(fp_line
			(start -1.2954 -0.635)
			(end -1.2954 0.635)
			(stroke
				(width 0.1524)
				(type default)
			)
			(layer "B.SilkS")
		)
		(fp_line
			(start 1.2954 -0.635)
			(end 1.2954 0.635)
			(stroke
				(width 0.1524)
				(type default)
			)
			(layer "B.SilkS")
		)
		(fp_line
			(start 1.2954 -0.635)
			(end -1.2954 -0.635)
			(stroke
				(width 0.1524)
				(type default)
			)
			(layer "B.SilkS")
		)
		(fp_poly
			(pts
				(xy 0.9144 0.508) (xy 0.9144 0.3556) (xy 1.143 0.3556) (xy 1.143 -0.3556) (xy 0.9144 -0.3556) (xy 0.9144 -0.508)
				(xy -0.9144 -0.508) (xy -0.9144 -0.3556) (xy -1.143 -0.3556) (xy -1.143 0.3556) (xy -0.9144 0.3556)
				(xy -0.9144 0.508)
			)
			(stroke
				(width 0)
				(type default)
			)
			(fill no)
			(layer "B.CrtYd")
		)
		(pad "1" smd rect
			(at -0.7366 0)
			(size 0.7112 0.8128)
			(layers "B.Cu" "B.Mask" "B.Paste")
			(net "BMC_NODE1_VCC_1V8_PCIEA")
		)
		(pad "2" smd rect
			(at 0.7366 0)
			(size 0.7112 0.8128)
			(layers "B.Cu" "B.Mask" "B.Paste")
			(net "P1V8_NODE1")
		)
	)
	(footprint ""
		(layer "B.Cu")
		(at 13.05814 -125.632972 180)
		(property "Reference" "PC54"
			(at 1.418844 0.116586 0)
			(unlocked yes)
			(layer "B.SilkS")
			(effects
				(font
					(size 0.7874 0.5842)
					(thickness 0.1524)
				)
				(justify left mirror)
			)
		)
		(property "Value" ""
			(at 0 0 0)
			(layer "B.Fab")
			(effects
				(font
					(size 1.27 1.27)
				)
				(justify mirror)
			)
		)
		(duplicate_pad_numbers_are_jumpers no)
		(fp_line
			(start 0.7874 0.4064)
			(end 0.7874 -0.4064)
			(stroke
				(width 0.1524)
				(type default)
			)
			(layer "B.SilkS")
		)
		(fp_line
			(start 0.7874 -0.4064)
			(end -0.7874 -0.4064)
			(stroke
				(width 0.1524)
				(type default)
			)
			(layer "B.SilkS")
		)
		(fp_line
			(start 0 0.381)
			(end 0 -0.381)
			(stroke
				(width 0.1524)
				(type default)
			)
			(layer "B.SilkS")
		)
		(fp_line
			(start -0.7874 0.4064)
			(end 0.7874 0.4064)
			(stroke
				(width 0.1524)
				(type default)
			)
			(layer "B.SilkS")
		)
		(fp_line
			(start -0.7874 -0.4064)
			(end -0.7874 0.4064)
			(stroke
				(width 0.1524)
				(type default)
			)
			(layer "B.SilkS")
		)
		(fp_poly
			(pts
				(xy 0.5334 0.254) (xy 0.635 0.254) (xy 0.635 0.2286) (xy 0.635 -0.254) (xy 0.5334 -0.254) (xy 0.5334 -0.2794)
				(xy -0.5334 -0.2794) (xy -0.5334 -0.254) (xy -0.635 -0.254) (xy -0.635 0.254) (xy -0.5334 0.254)
				(xy -0.5334 0.2794) (xy 0.508 0.2794) (xy 0.5334 0.2794)
			)
			(stroke
				(width 0)
				(type default)
			)
			(fill no)
			(layer "B.CrtYd")
		)
		(pad "1" smd rect
			(at -0.40005 0)
			(size 0.4572 0.508)
			(layers "B.Cu" "B.Mask" "B.Paste")
			(net "SW_P1V05_NODE1_VIN_FLT")
		)
		(pad "2" smd rect
			(at 0.40005 0)
			(size 0.4572 0.508)
			(layers "B.Cu" "B.Mask" "B.Paste")
			(net "GND")
		)
	)
	(footprint ""
		(layer "B.Cu")
		(at 76.108052 -179.990242 -90)
		(property "Reference" "R1165"
			(at 5.482082 3.401822 270)
			(unlocked yes)
			(layer "B.SilkS")
			(effects
				(font
					(size 0.7874 0.5842)
					(thickness 0.1524)
				)
				(justify left mirror)
			)
		)
		(property "Value" ""
			(at 0 0 90)
			(layer "B.Fab")
			(effects
				(font
					(size 1.27 1.27)
				)
				(justify mirror)
			)
		)
		(duplicate_pad_numbers_are_jumpers no)
		(fp_line
			(start -0.7874 0.4064)
			(end 0.7874 0.4064)
			(stroke
				(width 0.1524)
				(type default)
			)
			(layer "B.SilkS")
		)
		(fp_line
			(start 0.7874 0.4064)
			(end 0.7874 -0.4064)
			(stroke
				(width 0.1524)
				(type default)
			)
			(layer "B.SilkS")
		)
		(fp_line
			(start -0.7874 -0.4064)
			(end -0.7874 0.4064)
			(stroke
				(width 0.1524)
				(type default)
			)
			(layer "B.SilkS")
		)
		(fp_line
			(start 0.7874 -0.4064)
			(end -0.7874 -0.4064)
			(stroke
				(width 0.1524)
				(type default)
			)
			(layer "B.SilkS")
		)
		(fp_poly
			(pts
				(xy 0.508 0.2794) (xy 0.508 0.2286) (xy 0.635 0.2286) (xy 0.635 -0.254) (xy 0.5334 -0.254) (xy 0.5334 -0.2794)
				(xy -0.5334 -0.2794) (xy -0.5334 -0.254) (xy -0.635 -0.254) (xy -0.635 0.254) (xy -0.5334 0.254)
				(xy -0.5334 0.2794)
			)
			(stroke
				(width 0)
				(type default)
			)
			(fill no)
			(layer "B.CrtYd")
		)
		(pad "1" smd rect
			(at -0.40005 0 90)
			(size 0.4572 0.508)
			(layers "B.Cu" "B.Mask" "B.Paste")
			(net "UART_RTS_P4_N")
		)
		(pad "2" smd rect
			(at 0.40005 0 90)
			(size 0.4572 0.508)
			(layers "B.Cu" "B.Mask" "B.Paste")
			(net "GND")
		)
	)
	(footprint ""
		(layer "B.Cu")
		(at 48.24476 -181.992524 -90)
		(property "Reference" "C612"
			(at 3.618738 10.367772 270)
			(unlocked yes)
			(layer "B.SilkS")
			(effects
				(font
					(size 0.7874 0.5842)
					(thickness 0.1524)
				)
				(justify left mirror)
			)
		)
		(property "Value" ""
			(at 0 0 90)
			(layer "B.Fab")
			(effects
				(font
					(size 1.27 1.27)
				)
				(justify mirror)
			)
		)
		(duplicate_pad_numbers_are_jumpers no)
		(fp_line
			(start -0.7874 0.4064)
			(end 0.7874 0.4064)
			(stroke
				(width 0.1524)
				(type default)
			)
			(layer "B.SilkS")
		)
		(fp_line
			(start 0.7874 0.4064)
			(end 0.7874 -0.4064)
			(stroke
				(width 0.1524)
				(type default)
			)
			(layer "B.SilkS")
		)
		(fp_line
			(start 0 0.381)
			(end 0 -0.381)
			(stroke
				(width 0.1524)
				(type default)
			)
			(layer "B.SilkS")
		)
		(fp_line
			(start -0.7874 -0.4064)
			(end -0.7874 0.4064)
			(stroke
				(width 0.1524)
				(type default)
			)
			(layer "B.SilkS")
		)
		(fp_line
			(start 0.7874 -0.4064)
			(end -0.7874 -0.4064)
			(stroke
				(width 0.1524)
				(type default)
			)
			(layer "B.SilkS")
		)
		(fp_poly
			(pts
				(xy 0.5334 0.254) (xy 0.635 0.254) (xy 0.635 0.2286) (xy 0.635 -0.254) (xy 0.5334 -0.254) (xy 0.5334 -0.2794)
				(xy -0.5334 -0.2794) (xy -0.5334 -0.254) (xy -0.635 -0.254) (xy -0.635 0.254) (xy -0.5334 0.254)
				(xy -0.5334 0.2794) (xy 0.508 0.2794) (xy 0.5334 0.2794)
			)
			(stroke
				(width 0)
				(type default)
			)
			(fill no)
			(layer "B.CrtYd")
		)
		(pad "1" smd rect
			(at -0.40005 0 90)
			(size 0.4572 0.508)
			(layers "B.Cu" "B.Mask" "B.Paste")
			(net "PSU5_DC_OK_R_BUF")
		)
		(pad "2" smd rect
			(at 0.40005 0 90)
			(size 0.4572 0.508)
			(layers "B.Cu" "B.Mask" "B.Paste")
			(net "GND")
		)
	)
	(footprint ""
		(layer "B.Cu")
		(at 61.444886 -121.044462 90)
		(property "Reference" "R342"
			(at -7.37235 10.216642 270)
			(unlocked yes)
			(layer "B.SilkS")
			(effects
				(font
					(size 0.7874 0.5842)
					(thickness 0.1524)
				)
				(justify left mirror)
			)
		)
		(property "Value" ""
			(at 0 0 90)
			(layer "B.Fab")
			(effects
				(font
					(size 1.27 1.27)
				)
				(justify mirror)
			)
		)
		(duplicate_pad_numbers_are_jumpers no)
		(fp_line
			(start 0.7874 -0.4064)
			(end -0.7874 -0.4064)
			(stroke
				(width 0.1524)
				(type default)
			)
			(layer "B.SilkS")
		)
		(fp_line
			(start -0.7874 -0.4064)
			(end -0.7874 0.4064)
			(stroke
				(width 0.1524)
				(type default)
			)
			(layer "B.SilkS")
		)
		(fp_line
			(start 0.7874 0.4064)
			(end 0.7874 -0.4064)
			(stroke
				(width 0.1524)
				(type default)
			)
			(layer "B.SilkS")
		)
		(fp_line
			(start -0.7874 0.4064)
			(end 0.7874 0.4064)
			(stroke
				(width 0.1524)
				(type default)
			)
			(layer "B.SilkS")
		)
		(fp_poly
			(pts
				(xy 0.508 0.2794) (xy 0.508 0.2286) (xy 0.635 0.2286) (xy 0.635 -0.254) (xy 0.5334 -0.254) (xy 0.5334 -0.2794)
				(xy -0.5334 -0.2794) (xy -0.5334 -0.254) (xy -0.635 -0.254) (xy -0.635 0.254) (xy -0.5334 0.254)
				(xy -0.5334 0.2794)
			)
			(stroke
				(width 0)
				(type default)
			)
			(fill no)
			(layer "B.CrtYd")
		)
		(pad "1" smd rect
			(at -0.40005 0 270)
			(size 0.4572 0.508)
			(layers "B.Cu" "B.Mask" "B.Paste")
			(net "P3V3_NODE1")
		)
		(pad "2" smd rect
			(at 0.40005 0 270)
			(size 0.4572 0.508)
			(layers "B.Cu" "B.Mask" "B.Paste")
			(net "BMC_ROMD2")
		)
	)
	(footprint ""
		(layer "B.Cu")
		(at 129.578862 -169.264838)
		(property "Reference" "R994"
			(at 0.745998 1.016762 0)
			(unlocked yes)
			(layer "B.SilkS")
			(effects
				(font
					(size 0.7874 0.5842)
					(thickness 0.1524)
				)
				(justify left mirror)
			)
		)
		(property "Value" ""
			(at 0 0 0)
			(layer "B.Fab")
			(effects
				(font
					(size 1.27 1.27)
				)
				(justify mirror)
			)
		)
		(duplicate_pad_numbers_are_jumpers no)
		(fp_line
			(start -0.7874 -0.4064)
			(end -0.7874 0.4064)
			(stroke
				(width 0.1524)
				(type default)
			)
			(layer "B.SilkS")
		)
		(fp_line
			(start -0.7874 0.4064)
			(end 0.7874 0.4064)
			(stroke
				(width 0.1524)
				(type default)
			)
			(layer "B.SilkS")
		)
		(fp_line
			(start 0.7874 -0.4064)
			(end -0.7874 -0.4064)
			(stroke
				(width 0.1524)
				(type default)
			)
			(layer "B.SilkS")
		)
		(fp_line
			(start 0.7874 0.4064)
			(end 0.7874 -0.4064)
			(stroke
				(width 0.1524)
				(type default)
			)
			(layer "B.SilkS")
		)
		(fp_poly
			(pts
				(xy 0.508 0.2794) (xy 0.508 0.2286) (xy 0.635 0.2286) (xy 0.635 -0.254) (xy 0.5334 -0.254) (xy 0.5334 -0.2794)
				(xy -0.5334 -0.2794) (xy -0.5334 -0.254) (xy -0.635 -0.254) (xy -0.635 0.254) (xy -0.5334 0.254)
				(xy -0.5334 0.2794)
			)
			(stroke
				(width 0)
				(type default)
			)
			(fill no)
			(layer "B.CrtYd")
		)
		(pad "1" smd rect
			(at -0.40005 0 180)
			(size 0.4572 0.508)
			(layers "B.Cu" "B.Mask" "B.Paste")
			(net "UART_T8_NODE3_TXD")
		)
		(pad "2" smd rect
			(at 0.40005 0 180)
			(size 0.4572 0.508)
			(layers "B.Cu" "B.Mask" "B.Paste")
			(net "UART_T8_NODE3_TXD_R")
		)
	)
	(footprint ""
		(layer "B.Cu")
		(at 168.783762 -170.320716 90)
		(property "Reference" "C916"
			(at -4.199636 0.052324 270)
			(unlocked yes)
			(layer "B.SilkS")
			(effects
				(font
					(size 0.7874 0.5842)
					(thickness 0.1524)
				)
				(justify left mirror)
			)
		)
		(property "Value" ""
			(at 0 0 90)
			(layer "B.Fab")
			(effects
				(font
					(size 1.27 1.27)
				)
				(justify mirror)
			)
		)
		(duplicate_pad_numbers_are_jumpers no)
		(fp_line
			(start 0.7874 -0.406146)
			(end -0.7874 -0.406146)
			(stroke
				(width 0.1524)
				(type default)
			)
			(layer "B.SilkS")
		)
		(fp_line
			(start -0.7874 -0.406146)
			(end -0.7874 0.406146)
			(stroke
				(width 0.1524)
				(type default)
			)
			(layer "B.SilkS")
		)
		(fp_line
			(start 0 0.381)
			(end 0 -0.381)
			(stroke
				(width 0.1524)
				(type default)
			)
			(layer "B.SilkS")
		)
		(fp_line
			(start 0.7874 0.406146)
			(end 0.7874 -0.406146)
			(stroke
				(width 0.1524)
				(type default)
			)
			(layer "B.SilkS")
		)
		(fp_line
			(start -0.7874 0.406146)
			(end 0.7874 0.406146)
			(stroke
				(width 0.1524)
				(type default)
			)
			(layer "B.SilkS")
		)
		(fp_poly
			(pts
				(xy 0.5334 0.254) (xy 0.635 0.254) (xy 0.635 0.2286) (xy 0.635 -0.254) (xy 0.5334 -0.254) (xy 0.5334 -0.2794)
				(xy -0.5334 -0.2794) (xy -0.5334 -0.254) (xy -0.635 -0.254) (xy -0.635 0.254) (xy -0.5334 0.254)
				(xy -0.5334 0.2794) (xy 0.508 0.2794) (xy 0.5334 0.2794)
			)
			(stroke
				(width 0)
				(type default)
			)
			(fill no)
			(layer "B.CrtYd")
		)
		(pad "1" smd rect
			(at -0.40005 0 270)
			(size 0.4572 0.508)
			(layers "B.Cu" "B.Mask" "B.Paste")
			(net "N54365821")
		)
		(pad "2" smd rect
			(at 0.40005 0 270)
			(size 0.4572 0.508)
			(layers "B.Cu" "B.Mask" "B.Paste")
			(net "N54365823")
		)
	)
	(footprint ""
		(layer "B.Cu")
		(at 48.24476 -188.126624 -90)
		(property "Reference" "R857"
			(at -4.318254 0.408432 270)
			(unlocked yes)
			(layer "B.SilkS")
			(effects
				(font
					(size 0.7874 0.5842)
					(thickness 0.1524)
				)
				(justify left mirror)
			)
		)
		(property "Value" ""
			(at 0 0 90)
			(layer "B.Fab")
			(effects
				(font
					(size 1.27 1.27)
				)
				(justify mirror)
			)
		)
		(duplicate_pad_numbers_are_jumpers no)
		(fp_line
			(start -0.7874 0.4064)
			(end 0.7874 0.4064)
			(stroke
				(width 0.1524)
				(type default)
			)
			(layer "B.SilkS")
		)
		(fp_line
			(start 0.7874 0.4064)
			(end 0.7874 -0.4064)
			(stroke
				(width 0.1524)
				(type default)
			)
			(layer "B.SilkS")
		)
		(fp_line
			(start -0.7874 -0.4064)
			(end -0.7874 0.4064)
			(stroke
				(width 0.1524)
				(type default)
			)
			(layer "B.SilkS")
		)
		(fp_line
			(start 0.7874 -0.4064)
			(end -0.7874 -0.4064)
			(stroke
				(width 0.1524)
				(type default)
			)
			(layer "B.SilkS")
		)
		(fp_poly
			(pts
				(xy 0.508 0.2794) (xy 0.508 0.2286) (xy 0.635 0.2286) (xy 0.635 -0.254) (xy 0.5334 -0.254) (xy 0.5334 -0.2794)
				(xy -0.5334 -0.2794) (xy -0.5334 -0.254) (xy -0.635 -0.254) (xy -0.635 0.254) (xy -0.5334 0.254)
				(xy -0.5334 0.2794)
			)
			(stroke
				(width 0)
				(type default)
			)
			(fill no)
			(layer "B.CrtYd")
		)
		(pad "1" smd rect
			(at -0.40005 0 90)
			(size 0.4572 0.508)
			(layers "B.Cu" "B.Mask" "B.Paste")
			(net "PSU5_DC_OK_R")
		)
		(pad "2" smd rect
			(at 0.40005 0 90)
			(size 0.4572 0.508)
			(layers "B.Cu" "B.Mask" "B.Paste")
			(net "GND")
		)
	)
	(footprint ""
		(layer "B.Cu")
		(at 67.286886 -118.758462 -90)
		(property "Reference" "R324"
			(at 5.064506 0.457962 270)
			(unlocked yes)
			(layer "B.SilkS")
			(effects
				(font
					(size 0.7874 0.5842)
					(thickness 0.1524)
				)
				(justify left mirror)
			)
		)
		(property "Value" ""
			(at 0 0 90)
			(layer "B.Fab")
			(effects
				(font
					(size 1.27 1.27)
				)
				(justify mirror)
			)
		)
		(duplicate_pad_numbers_are_jumpers no)
		(fp_line
			(start -0.7874 0.4064)
			(end 0.7874 0.4064)
			(stroke
				(width 0.1524)
				(type default)
			)
			(layer "B.SilkS")
		)
		(fp_line
			(start 0.7874 0.4064)
			(end 0.7874 -0.4064)
			(stroke
				(width 0.1524)
				(type default)
			)
			(layer "B.SilkS")
		)
		(fp_line
			(start -0.7874 -0.4064)
			(end -0.7874 0.4064)
			(stroke
				(width 0.1524)
				(type default)
			)
			(layer "B.SilkS")
		)
		(fp_line
			(start 0.7874 -0.4064)
			(end -0.7874 -0.4064)
			(stroke
				(width 0.1524)
				(type default)
			)
			(layer "B.SilkS")
		)
		(fp_poly
			(pts
				(xy 0.508 0.2794) (xy 0.508 0.2286) (xy 0.635 0.2286) (xy 0.635 -0.254) (xy 0.5334 -0.254) (xy 0.5334 -0.2794)
				(xy -0.5334 -0.2794) (xy -0.5334 -0.254) (xy -0.635 -0.254) (xy -0.635 0.254) (xy -0.5334 0.254)
				(xy -0.5334 0.2794)
			)
			(stroke
				(width 0)
				(type default)
			)
			(fill no)
			(layer "B.CrtYd")
		)
		(pad "1" smd rect
			(at -0.40005 0 90)
			(size 0.4572 0.508)
			(layers "B.Cu" "B.Mask" "B.Paste")
			(net "P3V3_NODE1")
		)
		(pad "2" smd rect
			(at 0.40005 0 90)
			(size 0.4572 0.508)
			(layers "B.Cu" "B.Mask" "B.Paste")
			(net "BMC_ROMA8")
		)
	)
	(footprint ""
		(layer "B.Cu")
		(at 58.8264 -77.401928 -90)
		(property "Reference" "C102"
			(at 32.15894 14.43355 270)
			(unlocked yes)
			(layer "B.SilkS")
			(effects
				(font
					(size 0.7874 0.5842)
					(thickness 0.1524)
				)
				(justify left mirror)
			)
		)
		(property "Value" ""
			(at 0 0 90)
			(layer "B.Fab")
			(effects
				(font
					(size 1.27 1.27)
				)
				(justify mirror)
			)
		)
		(duplicate_pad_numbers_are_jumpers no)
		(fp_line
			(start -0.7874 0.4064)
			(end 0.7874 0.4064)
			(stroke
				(width 0.1524)
				(type default)
			)
			(layer "B.SilkS")
		)
		(fp_line
			(start 0.7874 0.4064)
			(end 0.7874 -0.4064)
			(stroke
				(width 0.1524)
				(type default)
			)
			(layer "B.SilkS")
		)
		(fp_line
			(start 0 0.381)
			(end 0 -0.381)
			(stroke
				(width 0.1524)
				(type default)
			)
			(layer "B.SilkS")
		)
		(fp_line
			(start -0.7874 -0.4064)
			(end -0.7874 0.4064)
			(stroke
				(width 0.1524)
				(type default)
			)
			(layer "B.SilkS")
		)
		(fp_line
			(start 0.7874 -0.4064)
			(end -0.7874 -0.4064)
			(stroke
				(width 0.1524)
				(type default)
			)
			(layer "B.SilkS")
		)
		(fp_poly
			(pts
				(xy 0.5334 0.254) (xy 0.635 0.254) (xy 0.635 0.2286) (xy 0.635 -0.254) (xy 0.5334 -0.254) (xy 0.5334 -0.2794)
				(xy -0.5334 -0.2794) (xy -0.5334 -0.254) (xy -0.635 -0.254) (xy -0.635 0.254) (xy -0.5334 0.254)
				(xy -0.5334 0.2794) (xy 0.508 0.2794) (xy 0.5334 0.2794)
			)
			(stroke
				(width 0)
				(type default)
			)
			(fill no)
			(layer "B.CrtYd")
		)
		(pad "1" smd rect
			(at -0.40005 0 90)
			(size 0.4572 0.508)
			(layers "B.Cu" "B.Mask" "B.Paste")
			(net "P1V05_NODE1")
		)
		(pad "2" smd rect
			(at 0.40005 0 90)
			(size 0.4572 0.508)
			(layers "B.Cu" "B.Mask" "B.Paste")
			(net "GND")
		)
	)
	(footprint ""
		(layer "B.Cu")
		(at 121.72061 -36.414456 180)
		(property "Reference" "R1202"
			(at 3.310636 -0.941578 0)
			(unlocked yes)
			(layer "B.SilkS")
			(effects
				(font
					(size 0.7874 0.5842)
					(thickness 0.1524)
				)
				(justify left mirror)
			)
		)
		(property "Value" ""
			(at 0 0 0)
			(layer "B.Fab")
			(effects
				(font
					(size 1.27 1.27)
				)
				(justify mirror)
			)
		)
		(duplicate_pad_numbers_are_jumpers no)
		(fp_line
			(start 0.7874 0.4064)
			(end 0.7874 -0.4064)
			(stroke
				(width 0.1524)
				(type default)
			)
			(layer "B.SilkS")
		)
		(fp_line
			(start 0.7874 -0.4064)
			(end -0.7874 -0.4064)
			(stroke
				(width 0.1524)
				(type default)
			)
			(layer "B.SilkS")
		)
		(fp_line
			(start -0.7874 0.4064)
			(end 0.7874 0.4064)
			(stroke
				(width 0.1524)
				(type default)
			)
			(layer "B.SilkS")
		)
		(fp_line
			(start -0.7874 -0.4064)
			(end -0.7874 0.4064)
			(stroke
				(width 0.1524)
				(type default)
			)
			(layer "B.SilkS")
		)
		(fp_poly
			(pts
				(xy 0.508 0.2794) (xy 0.508 0.2286) (xy 0.635 0.2286) (xy 0.635 -0.254) (xy 0.5334 -0.254) (xy 0.5334 -0.2794)
				(xy -0.5334 -0.2794) (xy -0.5334 -0.254) (xy -0.635 -0.254) (xy -0.635 0.254) (xy -0.5334 0.254)
				(xy -0.5334 0.2794)
			)
			(stroke
				(width 0)
				(type default)
			)
			(fill no)
			(layer "B.CrtYd")
		)
		(pad "1" smd rect
			(at -0.40005 0)
			(size 0.4572 0.508)
			(layers "B.Cu" "B.Mask" "B.Paste")
			(net "SIO_JTAG_CPLD3_TDI_R")
		)
		(pad "2" smd rect
			(at 0.40005 0)
			(size 0.4572 0.508)
			(layers "B.Cu" "B.Mask" "B.Paste")
			(net "P3V3_NODE1")
		)
	)
	(footprint ""
		(layer "B.Cu")
		(at 70.346062 -29.394658 90)
		(property "Reference" "R202"
			(at 1.302766 -0.213106 270)
			(unlocked yes)
			(layer "B.SilkS")
			(effects
				(font
					(size 0.7874 0.5842)
					(thickness 0.1524)
				)
				(justify left mirror)
			)
		)
		(property "Value" ""
			(at 0 0 90)
			(layer "B.Fab")
			(effects
				(font
					(size 1.27 1.27)
				)
				(justify mirror)
			)
		)
		(duplicate_pad_numbers_are_jumpers no)
		(fp_line
			(start 0.7874 -0.4064)
			(end -0.7874 -0.4064)
			(stroke
				(width 0.1524)
				(type default)
			)
			(layer "B.SilkS")
		)
		(fp_line
			(start -0.7874 -0.4064)
			(end -0.7874 0.4064)
			(stroke
				(width 0.1524)
				(type default)
			)
			(layer "B.SilkS")
		)
		(fp_line
			(start 0.7874 0.4064)
			(end 0.7874 -0.4064)
			(stroke
				(width 0.1524)
				(type default)
			)
			(layer "B.SilkS")
		)
		(fp_line
			(start -0.7874 0.4064)
			(end 0.7874 0.4064)
			(stroke
				(width 0.1524)
				(type default)
			)
			(layer "B.SilkS")
		)
		(fp_poly
			(pts
				(xy 0.508 0.2794) (xy 0.508 0.2286) (xy 0.635 0.2286) (xy 0.635 -0.254) (xy 0.5334 -0.254) (xy 0.5334 -0.2794)
				(xy -0.5334 -0.2794) (xy -0.5334 -0.254) (xy -0.635 -0.254) (xy -0.635 0.254) (xy -0.5334 0.254)
				(xy -0.5334 0.2794)
			)
			(stroke
				(width 0)
				(type default)
			)
			(fill no)
			(layer "B.CrtYd")
		)
		(pad "1" smd rect
			(at -0.40005 0 270)
			(size 0.4572 0.508)
			(layers "B.Cu" "B.Mask" "B.Paste")
			(net "PV_VDDR_NODE1")
		)
		(pad "2" smd rect
			(at 0.40005 0 270)
			(size 0.4572 0.508)
			(layers "B.Cu" "B.Mask" "B.Paste")
			(net "P1V5_NODE1_DDR3_VREF_A_A")
		)
	)
	(footprint ""
		(layer "B.Cu")
		(at 65.786 -131.554474 90)
		(property "Reference" "C254"
			(at -54.867048 -41.245282 270)
			(unlocked yes)
			(layer "B.SilkS")
			(effects
				(font
					(size 0.7874 0.5842)
					(thickness 0.1524)
				)
				(justify left mirror)
			)
		)
		(property "Value" ""
			(at 0 0 90)
			(layer "B.Fab")
			(effects
				(font
					(size 1.27 1.27)
				)
				(justify mirror)
			)
		)
		(duplicate_pad_numbers_are_jumpers no)
		(fp_line
			(start 0.7874 -0.4064)
			(end -0.7874 -0.4064)
			(stroke
				(width 0.1524)
				(type default)
			)
			(layer "B.SilkS")
		)
		(fp_line
			(start -0.7874 -0.4064)
			(end -0.7874 0.4064)
			(stroke
				(width 0.1524)
				(type default)
			)
			(layer "B.SilkS")
		)
		(fp_line
			(start 0 0.381)
			(end 0 -0.381)
			(stroke
				(width 0.1524)
				(type default)
			)
			(layer "B.SilkS")
		)
		(fp_line
			(start 0.7874 0.4064)
			(end 0.7874 -0.4064)
			(stroke
				(width 0.1524)
				(type default)
			)
			(layer "B.SilkS")
		)
		(fp_line
			(start -0.7874 0.4064)
			(end 0.7874 0.4064)
			(stroke
				(width 0.1524)
				(type default)
			)
			(layer "B.SilkS")
		)
		(fp_poly
			(pts
				(xy 0.5334 0.254) (xy 0.635 0.254) (xy 0.635 0.2286) (xy 0.635 -0.254) (xy 0.5334 -0.254) (xy 0.5334 -0.2794)
				(xy -0.5334 -0.2794) (xy -0.5334 -0.254) (xy -0.635 -0.254) (xy -0.635 0.254) (xy -0.5334 0.254)
				(xy -0.5334 0.2794) (xy 0.508 0.2794) (xy 0.5334 0.2794)
			)
			(stroke
				(width 0)
				(type default)
			)
			(fill no)
			(layer "B.CrtYd")
		)
		(pad "1" smd rect
			(at -0.40005 0 270)
			(size 0.4572 0.508)
			(layers "B.Cu" "B.Mask" "B.Paste")
			(net "P3V3_NODE1")
		)
		(pad "2" smd rect
			(at 0.40005 0 270)
			(size 0.4572 0.508)
			(layers "B.Cu" "B.Mask" "B.Paste")
			(net "GND")
		)
	)
	(footprint ""
		(layer "B.Cu")
		(at 53.199538 -74.959718 90)
		(property "Reference" "C50"
			(at -32.304228 -14.331188 270)
			(unlocked yes)
			(layer "B.SilkS")
			(effects
				(font
					(size 0.7874 0.5842)
					(thickness 0.1524)
				)
				(justify left mirror)
			)
		)
		(property "Value" ""
			(at 0 0 90)
			(layer "B.Fab")
			(effects
				(font
					(size 1.27 1.27)
				)
				(justify mirror)
			)
		)
		(duplicate_pad_numbers_are_jumpers no)
		(fp_line
			(start 0.7874 -0.4064)
			(end -0.7874 -0.4064)
			(stroke
				(width 0.1524)
				(type default)
			)
			(layer "B.SilkS")
		)
		(fp_line
			(start -0.7874 -0.4064)
			(end -0.7874 0.4064)
			(stroke
				(width 0.1524)
				(type default)
			)
			(layer "B.SilkS")
		)
		(fp_line
			(start 0 0.381)
			(end 0 -0.381)
			(stroke
				(width 0.1524)
				(type default)
			)
			(layer "B.SilkS")
		)
		(fp_line
			(start 0.7874 0.4064)
			(end 0.7874 -0.4064)
			(stroke
				(width 0.1524)
				(type default)
			)
			(layer "B.SilkS")
		)
		(fp_line
			(start -0.7874 0.4064)
			(end 0.7874 0.4064)
			(stroke
				(width 0.1524)
				(type default)
			)
			(layer "B.SilkS")
		)
		(fp_poly
			(pts
				(xy 0.5334 0.254) (xy 0.635 0.254) (xy 0.635 0.2286) (xy 0.635 -0.254) (xy 0.5334 -0.254) (xy 0.5334 -0.2794)
				(xy -0.5334 -0.2794) (xy -0.5334 -0.254) (xy -0.635 -0.254) (xy -0.635 0.254) (xy -0.5334 0.254)
				(xy -0.5334 0.2794) (xy 0.508 0.2794) (xy 0.5334 0.2794)
			)
			(stroke
				(width 0)
				(type default)
			)
			(fill no)
			(layer "B.CrtYd")
		)
		(pad "1" smd rect
			(at -0.40005 0 270)
			(size 0.4572 0.508)
			(layers "B.Cu" "B.Mask" "B.Paste")
			(net "P1V05_NODE1")
		)
		(pad "2" smd rect
			(at 0.40005 0 270)
			(size 0.4572 0.508)
			(layers "B.Cu" "B.Mask" "B.Paste")
			(net "GND")
		)
	)
	(footprint ""
		(layer "B.Cu")
		(at 154.06116 -172.505624)
		(property "Reference" "R749"
			(at -1.545844 12.970002 0)
			(unlocked yes)
			(layer "B.SilkS")
			(effects
				(font
					(size 0.7874 0.5842)
					(thickness 0.1524)
				)
				(justify left mirror)
			)
		)
		(property "Value" ""
			(at 0 0 0)
			(layer "B.Fab")
			(effects
				(font
					(size 1.27 1.27)
				)
				(justify mirror)
			)
		)
		(duplicate_pad_numbers_are_jumpers no)
		(fp_line
			(start -0.7874 -0.4064)
			(end -0.7874 0.4064)
			(stroke
				(width 0.1524)
				(type default)
			)
			(layer "B.SilkS")
		)
		(fp_line
			(start -0.7874 0.4064)
			(end 0.7874 0.4064)
			(stroke
				(width 0.1524)
				(type default)
			)
			(layer "B.SilkS")
		)
		(fp_line
			(start 0.7874 -0.4064)
			(end -0.7874 -0.4064)
			(stroke
				(width 0.1524)
				(type default)
			)
			(layer "B.SilkS")
		)
		(fp_line
			(start 0.7874 0.4064)
			(end 0.7874 -0.4064)
			(stroke
				(width 0.1524)
				(type default)
			)
			(layer "B.SilkS")
		)
		(fp_poly
			(pts
				(xy 0.508 0.2794) (xy 0.508 0.2286) (xy 0.635 0.2286) (xy 0.635 -0.254) (xy 0.5334 -0.254) (xy 0.5334 -0.2794)
				(xy -0.5334 -0.2794) (xy -0.5334 -0.254) (xy -0.635 -0.254) (xy -0.635 0.254) (xy -0.5334 0.254)
				(xy -0.5334 0.2794)
			)
			(stroke
				(width 0)
				(type default)
			)
			(fill no)
			(layer "B.CrtYd")
		)
		(pad "1" smd rect
			(at -0.40005 0 180)
			(size 0.4572 0.508)
			(layers "B.Cu" "B.Mask" "B.Paste")
			(net "T12_NODE4_EN")
		)
		(pad "2" smd rect
			(at 0.40005 0 180)
			(size 0.4572 0.508)
			(layers "B.Cu" "B.Mask" "B.Paste")
			(net "P5V_NODE1")
		)
	)
	(footprint ""
		(layer "B.Cu")
		(at 75.269852 -139.385802)
		(property "Reference" "TP5"
			(at 0 0 0)
			(layer "B.SilkS")
			(hide yes)
			(effects
				(font
					(size 1.27 1.27)
				)
				(justify mirror)
			)
		)
		(property "Value" ""
			(at 0 0 0)
			(layer "B.Fab")
			(effects
				(font
					(size 1.27 1.27)
				)
				(justify mirror)
			)
		)
		(duplicate_pad_numbers_are_jumpers no)
		(fp_poly
			(pts
				(arc
					(start 0 -0.381)
					(mid 0 0.381)
					(end 0 -0.381)
				)
			)
			(stroke
				(width 0)
				(type default)
			)
			(fill no)
			(layer "B.CrtYd")
		)
		(pad "1" smd circle
			(at 0 0 180)
			(size 0.762 0.762)
			(layers "B.Cu" "B.Mask" "B.Paste")
			(net "N3975090765")
		)
	)
	(footprint ""
		(layer "B.Cu")
		(at 120.370092 -165.410642 -90)
		(property "Reference" "R1225"
			(at 2.96418 -2.73431 270)
			(unlocked yes)
			(layer "B.SilkS")
			(effects
				(font
					(size 0.7874 0.5842)
					(thickness 0.1524)
				)
				(justify left mirror)
			)
		)
		(property "Value" ""
			(at 0 0 90)
			(layer "B.Fab")
			(effects
				(font
					(size 1.27 1.27)
				)
				(justify mirror)
			)
		)
		(duplicate_pad_numbers_are_jumpers no)
		(fp_line
			(start -0.7874 0.4064)
			(end 0.7874 0.4064)
			(stroke
				(width 0.1524)
				(type default)
			)
			(layer "B.SilkS")
		)
		(fp_line
			(start 0.7874 0.4064)
			(end 0.7874 -0.4064)
			(stroke
				(width 0.1524)
				(type default)
			)
			(layer "B.SilkS")
		)
		(fp_line
			(start -0.7874 -0.4064)
			(end -0.7874 0.4064)
			(stroke
				(width 0.1524)
				(type default)
			)
			(layer "B.SilkS")
		)
		(fp_line
			(start 0.7874 -0.4064)
			(end -0.7874 -0.4064)
			(stroke
				(width 0.1524)
				(type default)
			)
			(layer "B.SilkS")
		)
		(fp_poly
			(pts
				(xy 0.508 0.2794) (xy 0.508 0.2286) (xy 0.635 0.2286) (xy 0.635 -0.254) (xy 0.5334 -0.254) (xy 0.5334 -0.2794)
				(xy -0.5334 -0.2794) (xy -0.5334 -0.254) (xy -0.635 -0.254) (xy -0.635 0.254) (xy -0.5334 0.254)
				(xy -0.5334 0.2794)
			)
			(stroke
				(width 0)
				(type default)
			)
			(fill no)
			(layer "B.CrtYd")
		)
		(pad "1" smd rect
			(at -0.40005 0 90)
			(size 0.4572 0.508)
			(layers "B.Cu" "B.Mask" "B.Paste")
			(net "FAN_MAX_CTRL")
		)
		(pad "2" smd rect
			(at 0.40005 0 90)
			(size 0.4572 0.508)
			(layers "B.Cu" "B.Mask" "B.Paste")
			(net "GND")
		)
	)
	(footprint ""
		(layer "B.Cu")
		(at 63.10376 -188.126624 -90)
		(property "Reference" "C631"
			(at -4.276598 0.212598 270)
			(unlocked yes)
			(layer "B.SilkS")
			(effects
				(font
					(size 0.7874 0.5842)
					(thickness 0.1524)
				)
				(justify left mirror)
			)
		)
		(property "Value" ""
			(at 0 0 90)
			(layer "B.Fab")
			(effects
				(font
					(size 1.27 1.27)
				)
				(justify mirror)
			)
		)
		(duplicate_pad_numbers_are_jumpers no)
		(fp_line
			(start -0.7874 0.4064)
			(end 0.7874 0.4064)
			(stroke
				(width 0.1524)
				(type default)
			)
			(layer "B.SilkS")
		)
		(fp_line
			(start 0.7874 0.4064)
			(end 0.7874 -0.4064)
			(stroke
				(width 0.1524)
				(type default)
			)
			(layer "B.SilkS")
		)
		(fp_line
			(start 0 0.381)
			(end 0 -0.381)
			(stroke
				(width 0.1524)
				(type default)
			)
			(layer "B.SilkS")
		)
		(fp_line
			(start -0.7874 -0.4064)
			(end -0.7874 0.4064)
			(stroke
				(width 0.1524)
				(type default)
			)
			(layer "B.SilkS")
		)
		(fp_line
			(start 0.7874 -0.4064)
			(end -0.7874 -0.4064)
			(stroke
				(width 0.1524)
				(type default)
			)
			(layer "B.SilkS")
		)
		(fp_poly
			(pts
				(xy 0.5334 0.254) (xy 0.635 0.254) (xy 0.635 0.2286) (xy 0.635 -0.254) (xy 0.5334 -0.254) (xy 0.5334 -0.2794)
				(xy -0.5334 -0.2794) (xy -0.5334 -0.254) (xy -0.635 -0.254) (xy -0.635 0.254) (xy -0.5334 0.254)
				(xy -0.5334 0.2794) (xy 0.508 0.2794) (xy 0.5334 0.2794)
			)
			(stroke
				(width 0)
				(type default)
			)
			(fill no)
			(layer "B.CrtYd")
		)
		(pad "1" smd rect
			(at -0.40005 0 90)
			(size 0.4572 0.508)
			(layers "B.Cu" "B.Mask" "B.Paste")
			(net "T1_NODE4_EN_R")
		)
		(pad "2" smd rect
			(at 0.40005 0 90)
			(size 0.4572 0.508)
			(layers "B.Cu" "B.Mask" "B.Paste")
			(net "GND")
		)
	)
	(footprint ""
		(layer "B.Cu")
		(at 48.274732 -88.473026 90)
		(property "Reference" "R97"
			(at 0.913892 -0.1397 270)
			(unlocked yes)
			(layer "B.SilkS")
			(effects
				(font
					(size 0.7874 0.5842)
					(thickness 0.1524)
				)
				(justify left mirror)
			)
		)
		(property "Value" ""
			(at 0 0 90)
			(layer "B.Fab")
			(effects
				(font
					(size 1.27 1.27)
				)
				(justify mirror)
			)
		)
		(duplicate_pad_numbers_are_jumpers no)
		(fp_line
			(start 0.7874 -0.4064)
			(end -0.7874 -0.4064)
			(stroke
				(width 0.1524)
				(type default)
			)
			(layer "B.SilkS")
		)
		(fp_line
			(start -0.7874 -0.4064)
			(end -0.7874 0.4064)
			(stroke
				(width 0.1524)
				(type default)
			)
			(layer "B.SilkS")
		)
		(fp_line
			(start 0.7874 0.4064)
			(end 0.7874 -0.4064)
			(stroke
				(width 0.1524)
				(type default)
			)
			(layer "B.SilkS")
		)
		(fp_line
			(start -0.7874 0.4064)
			(end 0.7874 0.4064)
			(stroke
				(width 0.1524)
				(type default)
			)
			(layer "B.SilkS")
		)
		(fp_poly
			(pts
				(xy 0.508 0.2794) (xy 0.508 0.2286) (xy 0.635 0.2286) (xy 0.635 -0.254) (xy 0.5334 -0.254) (xy 0.5334 -0.2794)
				(xy -0.5334 -0.2794) (xy -0.5334 -0.254) (xy -0.635 -0.254) (xy -0.635 0.254) (xy -0.5334 0.254)
				(xy -0.5334 0.2794)
			)
			(stroke
				(width 0)
				(type default)
			)
			(fill no)
			(layer "B.CrtYd")
		)
		(pad "1" smd rect
			(at -0.40005 0 270)
			(size 0.4572 0.508)
			(layers "B.Cu" "B.Mask" "B.Paste")
			(net "PD_NODE1_NTB_CLKINP")
		)
		(pad "2" smd rect
			(at 0.40005 0 270)
			(size 0.4572 0.508)
			(layers "B.Cu" "B.Mask" "B.Paste")
			(net "GND")
		)
	)
	(footprint ""
		(layer "B.Cu")
		(at 28.240736 -117.301772)
		(property "Reference" "C96"
			(at -2.455926 0.028448 0)
			(unlocked yes)
			(layer "B.SilkS")
			(effects
				(font
					(size 0.7874 0.5842)
					(thickness 0.1524)
				)
				(justify left mirror)
			)
		)
		(property "Value" ""
			(at 0 0 0)
			(layer "B.Fab")
			(effects
				(font
					(size 1.27 1.27)
				)
				(justify mirror)
			)
		)
		(duplicate_pad_numbers_are_jumpers no)
		(fp_line
			(start -2.2098 -0.9398)
			(end -2.2098 0.9398)
			(stroke
				(width 0.1524)
				(type default)
			)
			(layer "B.SilkS")
		)
		(fp_line
			(start -2.2098 0.9398)
			(end 2.2098 0.9398)
			(stroke
				(width 0.1524)
				(type default)
			)
			(layer "B.SilkS")
		)
		(fp_line
			(start 0 -0.9398)
			(end 0 0.9398)
			(stroke
				(width 0.1524)
				(type default)
			)
			(layer "B.SilkS")
		)
		(fp_line
			(start 2.2098 -0.9398)
			(end -2.2098 -0.9398)
			(stroke
				(width 0.1524)
				(type default)
			)
			(layer "B.SilkS")
		)
		(fp_line
			(start 2.2098 0.9398)
			(end 2.2098 -0.9398)
			(stroke
				(width 0.1524)
				(type default)
			)
			(layer "B.SilkS")
		)
		(fp_poly
			(pts
				(xy 1.6764 0.889) (xy 1.6764 0.7874) (xy 2.0574 0.7874) (xy 2.0574 -0.7874) (xy 1.6764 -0.7874)
				(xy 1.6764 -0.9398) (xy -1.6764 -0.9398) (xy -1.6764 -0.7874) (xy -2.0574 -0.7874) (xy -2.0574 0.7874)
				(xy -1.6764 0.7874) (xy -1.6764 0.9398) (xy 1.6764 0.9398)
			)
			(stroke
				(width 0)
				(type default)
			)
			(fill no)
			(layer "B.CrtYd")
		)
		(fp_line
			(start -1.700022 -0.899922)
			(end -1.700022 0.899922)
			(stroke
				(width 0.1)
				(type default)
			)
			(layer "B.Fab")
		)
		(fp_line
			(start -1.700022 0.899922)
			(end 1.700022 0.899922)
			(stroke
				(width 0.1)
				(type default)
			)
			(layer "B.Fab")
		)
		(fp_line
			(start 1.700022 -0.899922)
			(end -1.700022 -0.899922)
			(stroke
				(width 0.1)
				(type default)
			)
			(layer "B.Fab")
		)
		(fp_line
			(start 1.700022 0.899922)
			(end 1.700022 -0.899922)
			(stroke
				(width 0.1)
				(type default)
			)
			(layer "B.Fab")
		)
		(pad "1" smd rect
			(at -1.4732 0 180)
			(size 1.1684 1.5748)
			(layers "B.Cu" "B.Mask" "B.Paste")
			(net "P1V05_NODE1")
		)
		(pad "2" smd rect
			(at 1.4732 0 180)
			(size 1.1684 1.5748)
			(layers "B.Cu" "B.Mask" "B.Paste")
			(net "GND")
		)
	)
	(footprint ""
		(layer "B.Cu")
		(at 140.749274 -60.833254)
		(property "Reference" "C352"
			(at -4.939792 0.007874 0)
			(unlocked yes)
			(layer "B.SilkS")
			(effects
				(font
					(size 0.7874 0.5842)
					(thickness 0.1524)
				)
				(justify left mirror)
			)
		)
		(property "Value" ""
			(at 0 0 0)
			(layer "B.Fab")
			(effects
				(font
					(size 1.27 1.27)
				)
				(justify mirror)
			)
		)
		(duplicate_pad_numbers_are_jumpers no)
		(fp_line
			(start -0.7874 -0.4064)
			(end -0.7874 0.4064)
			(stroke
				(width 0.1524)
				(type default)
			)
			(layer "B.SilkS")
		)
		(fp_line
			(start -0.7874 0.4064)
			(end 0.7874 0.4064)
			(stroke
				(width 0.1524)
				(type default)
			)
			(layer "B.SilkS")
		)
		(fp_line
			(start 0 0.381)
			(end 0 -0.381)
			(stroke
				(width 0.1524)
				(type default)
			)
			(layer "B.SilkS")
		)
		(fp_line
			(start 0.7874 -0.4064)
			(end -0.7874 -0.4064)
			(stroke
				(width 0.1524)
				(type default)
			)
			(layer "B.SilkS")
		)
		(fp_line
			(start 0.7874 0.4064)
			(end 0.7874 -0.4064)
			(stroke
				(width 0.1524)
				(type default)
			)
			(layer "B.SilkS")
		)
		(fp_poly
			(pts
				(xy 0.5334 0.254) (xy 0.635 0.254) (xy 0.635 0.2286) (xy 0.635 -0.254) (xy 0.5334 -0.254) (xy 0.5334 -0.2794)
				(xy -0.5334 -0.2794) (xy -0.5334 -0.254) (xy -0.635 -0.254) (xy -0.635 0.254) (xy -0.5334 0.254)
				(xy -0.5334 0.2794) (xy 0.508 0.2794) (xy 0.5334 0.2794)
			)
			(stroke
				(width 0)
				(type default)
			)
			(fill no)
			(layer "B.CrtYd")
		)
		(pad "1" smd rect
			(at -0.40005 0 180)
			(size 0.4572 0.508)
			(layers "B.Cu" "B.Mask" "B.Paste")
			(net "P3V3_NODE1")
		)
		(pad "2" smd rect
			(at 0.40005 0 180)
			(size 0.4572 0.508)
			(layers "B.Cu" "B.Mask" "B.Paste")
			(net "GND")
		)
	)
	(footprint ""
		(layer "B.Cu")
		(at 129.600452 -117.658642)
		(property "Reference" "C10"
			(at 3.208274 0.117856 0)
			(unlocked yes)
			(layer "B.SilkS")
			(effects
				(font
					(size 0.7874 0.5842)
					(thickness 0.1524)
				)
				(justify left mirror)
			)
		)
		(property "Value" ""
			(at 0 0 0)
			(layer "B.Fab")
			(effects
				(font
					(size 1.27 1.27)
				)
				(justify mirror)
			)
		)
		(duplicate_pad_numbers_are_jumpers no)
		(fp_line
			(start -0.7874 -0.4064)
			(end -0.7874 0.4064)
			(stroke
				(width 0.1524)
				(type default)
			)
			(layer "B.SilkS")
		)
		(fp_line
			(start -0.7874 0.4064)
			(end 0.7874 0.4064)
			(stroke
				(width 0.1524)
				(type default)
			)
			(layer "B.SilkS")
		)
		(fp_line
			(start 0 0.381)
			(end 0 -0.381)
			(stroke
				(width 0.1524)
				(type default)
			)
			(layer "B.SilkS")
		)
		(fp_line
			(start 0.7874 -0.4064)
			(end -0.7874 -0.4064)
			(stroke
				(width 0.1524)
				(type default)
			)
			(layer "B.SilkS")
		)
		(fp_line
			(start 0.7874 0.4064)
			(end 0.7874 -0.4064)
			(stroke
				(width 0.1524)
				(type default)
			)
			(layer "B.SilkS")
		)
		(fp_poly
			(pts
				(xy 0.5334 0.254) (xy 0.635 0.254) (xy 0.635 0.2286) (xy 0.635 -0.254) (xy 0.5334 -0.254) (xy 0.5334 -0.2794)
				(xy -0.5334 -0.2794) (xy -0.5334 -0.254) (xy -0.635 -0.254) (xy -0.635 0.254) (xy -0.5334 0.254)
				(xy -0.5334 0.2794) (xy 0.508 0.2794) (xy 0.5334 0.2794)
			)
			(stroke
				(width 0)
				(type default)
			)
			(fill no)
			(layer "B.CrtYd")
		)
		(pad "1" smd rect
			(at -0.40005 0 180)
			(size 0.4572 0.508)
			(layers "B.Cu" "B.Mask" "B.Paste")
			(net "P1V05_CLK_NODE1")
		)
		(pad "2" smd rect
			(at 0.40005 0 180)
			(size 0.4572 0.508)
			(layers "B.Cu" "B.Mask" "B.Paste")
			(net "GND")
		)
	)
	(footprint ""
		(layer "B.Cu")
		(at 75.0062 -30.71114 180)
		(property "Reference" "C153"
			(at -1.788922 -2.09804 0)
			(unlocked yes)
			(layer "B.SilkS")
			(effects
				(font
					(size 0.7874 0.5842)
					(thickness 0.1524)
				)
				(justify left mirror)
			)
		)
		(property "Value" ""
			(at 0 0 0)
			(layer "B.Fab")
			(effects
				(font
					(size 1.27 1.27)
				)
				(justify mirror)
			)
		)
		(duplicate_pad_numbers_are_jumpers no)
		(fp_line
			(start 0.7874 0.4064)
			(end 0.7874 -0.4064)
			(stroke
				(width 0.1524)
				(type default)
			)
			(layer "B.SilkS")
		)
		(fp_line
			(start 0.7874 -0.4064)
			(end -0.7874 -0.4064)
			(stroke
				(width 0.1524)
				(type default)
			)
			(layer "B.SilkS")
		)
		(fp_line
			(start 0 0.381)
			(end 0 -0.381)
			(stroke
				(width 0.1524)
				(type default)
			)
			(layer "B.SilkS")
		)
		(fp_line
			(start -0.7874 0.4064)
			(end 0.7874 0.4064)
			(stroke
				(width 0.1524)
				(type default)
			)
			(layer "B.SilkS")
		)
		(fp_line
			(start -0.7874 -0.4064)
			(end -0.7874 0.4064)
			(stroke
				(width 0.1524)
				(type default)
			)
			(layer "B.SilkS")
		)
		(fp_poly
			(pts
				(xy 0.5334 0.254) (xy 0.635 0.254) (xy 0.635 0.2286) (xy 0.635 -0.254) (xy 0.5334 -0.254) (xy 0.5334 -0.2794)
				(xy -0.5334 -0.2794) (xy -0.5334 -0.254) (xy -0.635 -0.254) (xy -0.635 0.254) (xy -0.5334 0.254)
				(xy -0.5334 0.2794) (xy 0.508 0.2794) (xy 0.5334 0.2794)
			)
			(stroke
				(width 0)
				(type default)
			)
			(fill no)
			(layer "B.CrtYd")
		)
		(pad "1" smd rect
			(at -0.40005 0)
			(size 0.4572 0.508)
			(layers "B.Cu" "B.Mask" "B.Paste")
			(net "PV_VDDR_NODE1")
		)
		(pad "2" smd rect
			(at 0.40005 0)
			(size 0.4572 0.508)
			(layers "B.Cu" "B.Mask" "B.Paste")
			(net "GND")
		)
	)
	(footprint ""
		(layer "B.Cu")
		(at 131.464558 -113.912904 90)
		(property "Reference" "C2"
			(at 1.36398 0.478028 270)
			(unlocked yes)
			(layer "B.SilkS")
			(effects
				(font
					(size 0.7874 0.5842)
					(thickness 0.1524)
				)
				(justify left mirror)
			)
		)
		(property "Value" ""
			(at 0 0 90)
			(layer "B.Fab")
			(effects
				(font
					(size 1.27 1.27)
				)
				(justify mirror)
			)
		)
		(duplicate_pad_numbers_are_jumpers no)
		(fp_line
			(start 0.7874 -0.4064)
			(end -0.7874 -0.4064)
			(stroke
				(width 0.1524)
				(type default)
			)
			(layer "B.SilkS")
		)
		(fp_line
			(start -0.7874 -0.4064)
			(end -0.7874 0.4064)
			(stroke
				(width 0.1524)
				(type default)
			)
			(layer "B.SilkS")
		)
		(fp_line
			(start 0 0.381)
			(end 0 -0.381)
			(stroke
				(width 0.1524)
				(type default)
			)
			(layer "B.SilkS")
		)
		(fp_line
			(start 0.7874 0.4064)
			(end 0.7874 -0.4064)
			(stroke
				(width 0.1524)
				(type default)
			)
			(layer "B.SilkS")
		)
		(fp_line
			(start -0.7874 0.4064)
			(end 0.7874 0.4064)
			(stroke
				(width 0.1524)
				(type default)
			)
			(layer "B.SilkS")
		)
		(fp_poly
			(pts
				(xy 0.5334 0.254) (xy 0.635 0.254) (xy 0.635 0.2286) (xy 0.635 -0.254) (xy 0.5334 -0.254) (xy 0.5334 -0.2794)
				(xy -0.5334 -0.2794) (xy -0.5334 -0.254) (xy -0.635 -0.254) (xy -0.635 0.254) (xy -0.5334 0.254)
				(xy -0.5334 0.2794) (xy 0.508 0.2794) (xy 0.5334 0.2794)
			)
			(stroke
				(width 0)
				(type default)
			)
			(fill no)
			(layer "B.CrtYd")
		)
		(pad "1" smd rect
			(at -0.40005 0 270)
			(size 0.4572 0.508)
			(layers "B.Cu" "B.Mask" "B.Paste")
			(net "P3V3_CLK_NODE1")
		)
		(pad "2" smd rect
			(at 0.40005 0 270)
			(size 0.4572 0.508)
			(layers "B.Cu" "B.Mask" "B.Paste")
			(net "GND")
		)
	)
	(footprint ""
		(layer "B.Cu")
		(at 62.724538 -71.022718 -90)
		(property "Reference" "C124"
			(at 33.088326 14.768068 270)
			(unlocked yes)
			(layer "B.SilkS")
			(effects
				(font
					(size 0.7874 0.5842)
					(thickness 0.1524)
				)
				(justify left mirror)
			)
		)
		(property "Value" ""
			(at 0 0 90)
			(layer "B.Fab")
			(effects
				(font
					(size 1.27 1.27)
				)
				(justify mirror)
			)
		)
		(duplicate_pad_numbers_are_jumpers no)
		(fp_line
			(start -0.7874 0.4064)
			(end 0.7874 0.4064)
			(stroke
				(width 0.1524)
				(type default)
			)
			(layer "B.SilkS")
		)
		(fp_line
			(start 0.7874 0.4064)
			(end 0.7874 -0.4064)
			(stroke
				(width 0.1524)
				(type default)
			)
			(layer "B.SilkS")
		)
		(fp_line
			(start 0 0.381)
			(end 0 -0.381)
			(stroke
				(width 0.1524)
				(type default)
			)
			(layer "B.SilkS")
		)
		(fp_line
			(start -0.7874 -0.4064)
			(end -0.7874 0.4064)
			(stroke
				(width 0.1524)
				(type default)
			)
			(layer "B.SilkS")
		)
		(fp_line
			(start 0.7874 -0.4064)
			(end -0.7874 -0.4064)
			(stroke
				(width 0.1524)
				(type default)
			)
			(layer "B.SilkS")
		)
		(fp_poly
			(pts
				(xy 0.5334 0.254) (xy 0.635 0.254) (xy 0.635 0.2286) (xy 0.635 -0.254) (xy 0.5334 -0.254) (xy 0.5334 -0.2794)
				(xy -0.5334 -0.2794) (xy -0.5334 -0.254) (xy -0.635 -0.254) (xy -0.635 0.254) (xy -0.5334 0.254)
				(xy -0.5334 0.2794) (xy 0.508 0.2794) (xy 0.5334 0.2794)
			)
			(stroke
				(width 0)
				(type default)
			)
			(fill no)
			(layer "B.CrtYd")
		)
		(pad "1" smd rect
			(at -0.40005 0 90)
			(size 0.4572 0.508)
			(layers "B.Cu" "B.Mask" "B.Paste")
			(net "P1V05_NODE1")
		)
		(pad "2" smd rect
			(at 0.40005 0 90)
			(size 0.4572 0.508)
			(layers "B.Cu" "B.Mask" "B.Paste")
			(net "GND")
		)
	)
	(footprint ""
		(layer "B.Cu")
		(at 61.037978 -79.74965 90)
		(property "Reference" "C100"
			(at -32.526478 -14.402308 270)
			(unlocked yes)
			(layer "B.SilkS")
			(effects
				(font
					(size 0.7874 0.5842)
					(thickness 0.1524)
				)
				(justify left mirror)
			)
		)
		(property "Value" ""
			(at 0 0 90)
			(layer "B.Fab")
			(effects
				(font
					(size 1.27 1.27)
				)
				(justify mirror)
			)
		)
		(duplicate_pad_numbers_are_jumpers no)
		(fp_line
			(start 0.7874 -0.4064)
			(end -0.7874 -0.4064)
			(stroke
				(width 0.1524)
				(type default)
			)
			(layer "B.SilkS")
		)
		(fp_line
			(start -0.7874 -0.4064)
			(end -0.7874 0.4064)
			(stroke
				(width 0.1524)
				(type default)
			)
			(layer "B.SilkS")
		)
		(fp_line
			(start 0 0.381)
			(end 0 -0.381)
			(stroke
				(width 0.1524)
				(type default)
			)
			(layer "B.SilkS")
		)
		(fp_line
			(start 0.7874 0.4064)
			(end 0.7874 -0.4064)
			(stroke
				(width 0.1524)
				(type default)
			)
			(layer "B.SilkS")
		)
		(fp_line
			(start -0.7874 0.4064)
			(end 0.7874 0.4064)
			(stroke
				(width 0.1524)
				(type default)
			)
			(layer "B.SilkS")
		)
		(fp_poly
			(pts
				(xy 0.5334 0.254) (xy 0.635 0.254) (xy 0.635 0.2286) (xy 0.635 -0.254) (xy 0.5334 -0.254) (xy 0.5334 -0.2794)
				(xy -0.5334 -0.2794) (xy -0.5334 -0.254) (xy -0.635 -0.254) (xy -0.635 0.254) (xy -0.5334 0.254)
				(xy -0.5334 0.2794) (xy 0.508 0.2794) (xy 0.5334 0.2794)
			)
			(stroke
				(width 0)
				(type default)
			)
			(fill no)
			(layer "B.CrtYd")
		)
		(pad "1" smd rect
			(at -0.40005 0 270)
			(size 0.4572 0.508)
			(layers "B.Cu" "B.Mask" "B.Paste")
			(net "P1V05_NODE1")
		)
		(pad "2" smd rect
			(at 0.40005 0 270)
			(size 0.4572 0.508)
			(layers "B.Cu" "B.Mask" "B.Paste")
			(net "GND")
		)
	)
	(footprint ""
		(layer "B.Cu")
		(at 167.63238 -151.496522)
		(property "Reference" "C451"
			(at 4.681728 0.02159 0)
			(unlocked yes)
			(layer "B.SilkS")
			(effects
				(font
					(size 0.7874 0.5842)
					(thickness 0.1524)
				)
				(justify left mirror)
			)
		)
		(property "Value" ""
			(at 0 0 0)
			(layer "B.Fab")
			(effects
				(font
					(size 1.27 1.27)
				)
				(justify mirror)
			)
		)
		(duplicate_pad_numbers_are_jumpers no)
		(fp_line
			(start -0.7874 -0.4064)
			(end -0.7874 0.4064)
			(stroke
				(width 0.1524)
				(type default)
			)
			(layer "B.SilkS")
		)
		(fp_line
			(start -0.7874 0.4064)
			(end 0.7874 0.4064)
			(stroke
				(width 0.1524)
				(type default)
			)
			(layer "B.SilkS")
		)
		(fp_line
			(start 0 0.381)
			(end 0 -0.381)
			(stroke
				(width 0.1524)
				(type default)
			)
			(layer "B.SilkS")
		)
		(fp_line
			(start 0.7874 -0.4064)
			(end -0.7874 -0.4064)
			(stroke
				(width 0.1524)
				(type default)
			)
			(layer "B.SilkS")
		)
		(fp_line
			(start 0.7874 0.4064)
			(end 0.7874 -0.4064)
			(stroke
				(width 0.1524)
				(type default)
			)
			(layer "B.SilkS")
		)
		(fp_poly
			(pts
				(xy 0.5334 0.254) (xy 0.635 0.254) (xy 0.635 0.2286) (xy 0.635 -0.254) (xy 0.5334 -0.254) (xy 0.5334 -0.2794)
				(xy -0.5334 -0.2794) (xy -0.5334 -0.254) (xy -0.635 -0.254) (xy -0.635 0.254) (xy -0.5334 0.254)
				(xy -0.5334 0.2794) (xy 0.508 0.2794) (xy 0.5334 0.2794)
			)
			(stroke
				(width 0)
				(type default)
			)
			(fill no)
			(layer "B.CrtYd")
		)
		(pad "1" smd rect
			(at -0.40005 0 180)
			(size 0.4572 0.508)
			(layers "B.Cu" "B.Mask" "B.Paste")
			(net "P1V9_LAN2")
		)
		(pad "2" smd rect
			(at 0.40005 0 180)
			(size 0.4572 0.508)
			(layers "B.Cu" "B.Mask" "B.Paste")
			(net "GND")
		)
	)
	(footprint ""
		(layer "B.Cu")
		(at 78.241906 -83.923124)
		(property "Reference" "R1216"
			(at -12.435586 31.674816 0)
			(unlocked yes)
			(layer "B.SilkS")
			(effects
				(font
					(size 0.7874 0.5842)
					(thickness 0.1524)
				)
				(justify left mirror)
			)
		)
		(property "Value" ""
			(at 0 0 0)
			(layer "B.Fab")
			(effects
				(font
					(size 1.27 1.27)
				)
				(justify mirror)
			)
		)
		(duplicate_pad_numbers_are_jumpers no)
		(fp_line
			(start -0.7874 -0.4064)
			(end -0.7874 0.4064)
			(stroke
				(width 0.1524)
				(type default)
			)
			(layer "B.SilkS")
		)
		(fp_line
			(start -0.7874 0.4064)
			(end 0.7874 0.4064)
			(stroke
				(width 0.1524)
				(type default)
			)
			(layer "B.SilkS")
		)
		(fp_line
			(start 0.7874 -0.4064)
			(end -0.7874 -0.4064)
			(stroke
				(width 0.1524)
				(type default)
			)
			(layer "B.SilkS")
		)
		(fp_line
			(start 0.7874 0.4064)
			(end 0.7874 -0.4064)
			(stroke
				(width 0.1524)
				(type default)
			)
			(layer "B.SilkS")
		)
		(fp_poly
			(pts
				(xy 0.508 0.2794) (xy 0.508 0.2286) (xy 0.635 0.2286) (xy 0.635 -0.254) (xy 0.5334 -0.254) (xy 0.5334 -0.2794)
				(xy -0.5334 -0.2794) (xy -0.5334 -0.254) (xy -0.635 -0.254) (xy -0.635 0.254) (xy -0.5334 0.254)
				(xy -0.5334 0.2794)
			)
			(stroke
				(width 0)
				(type default)
			)
			(fill no)
			(layer "B.CrtYd")
		)
		(pad "1" smd rect
			(at -0.40005 0 180)
			(size 0.4572 0.508)
			(layers "B.Cu" "B.Mask" "B.Paste")
			(net "CPU_NODE1_PROCHOT_N")
		)
		(pad "2" smd rect
			(at 0.40005 0 180)
			(size 0.4572 0.508)
			(layers "B.Cu" "B.Mask" "B.Paste")
			(net "P3V3_NODE1")
		)
	)
	(footprint ""
		(layer "B.Cu")
		(at 155.661614 -62.075822 90)
		(property "Reference" "L32"
			(at -2.829814 6.138418 270)
			(unlocked yes)
			(layer "B.SilkS")
			(effects
				(font
					(size 0.7874 0.5842)
					(thickness 0.1524)
				)
				(justify left mirror)
			)
		)
		(property "Value" ""
			(at 0 0 90)
			(layer "B.Fab")
			(effects
				(font
					(size 1.27 1.27)
				)
				(justify mirror)
			)
		)
		(duplicate_pad_numbers_are_jumpers no)
		(fp_line
			(start 0.7874 -0.4064)
			(end -0.7874 -0.4064)
			(stroke
				(width 0.1524)
				(type default)
			)
			(layer "B.SilkS")
		)
		(fp_line
			(start -0.7874 -0.4064)
			(end -0.7874 0.4064)
			(stroke
				(width 0.1524)
				(type default)
			)
			(layer "B.SilkS")
		)
		(fp_line
			(start 0.7874 0.4064)
			(end 0.7874 -0.4064)
			(stroke
				(width 0.1524)
				(type default)
			)
			(layer "B.SilkS")
		)
		(fp_line
			(start 0.0889 0.4064)
			(end 0.0889 -0.4064)
			(stroke
				(width 0.1524)
				(type default)
			)
			(layer "B.SilkS")
		)
		(fp_line
			(start -0.0889 0.4064)
			(end -0.0889 -0.4064)
			(stroke
				(width 0.1524)
				(type default)
			)
			(layer "B.SilkS")
		)
		(fp_line
			(start -0.7874 0.4064)
			(end 0.7874 0.4064)
			(stroke
				(width 0.1524)
				(type default)
			)
			(layer "B.SilkS")
		)
		(fp_poly
			(pts
				(xy 0.5334 0.254) (xy 0.635 0.254) (xy 0.635 0.2286) (xy 0.635 -0.254) (xy 0.5334 -0.254) (xy 0.5334 -0.2794)
				(xy -0.5334 -0.2794) (xy -0.5334 -0.254) (xy -0.635 -0.254) (xy -0.635 0.254) (xy -0.5334 0.254)
				(xy -0.5334 0.2794) (xy 0.508 0.2794) (xy 0.5334 0.2794)
			)
			(stroke
				(width 0)
				(type default)
			)
			(fill no)
			(layer "B.CrtYd")
		)
		(pad "1" smd rect
			(at -0.40005 0 270)
			(size 0.4572 0.508)
			(layers "B.Cu" "B.Mask" "B.Paste")
			(net "P1V8_NODE1")
		)
		(pad "2" smd rect
			(at 0.40005 0 270)
			(size 0.4572 0.508)
			(layers "B.Cu" "B.Mask" "B.Paste")
			(net "P1V8_SATA_VAA2_1_NODE1")
		)
	)
	(footprint ""
		(layer "B.Cu")
		(at 63.0555 -79.166466 -90)
		(property "Reference" "C68"
			(at 32.206946 14.38783 270)
			(unlocked yes)
			(layer "B.SilkS")
			(effects
				(font
					(size 0.7874 0.5842)
					(thickness 0.1524)
				)
				(justify left mirror)
			)
		)
		(property "Value" ""
			(at 0 0 90)
			(layer "B.Fab")
			(effects
				(font
					(size 1.27 1.27)
				)
				(justify mirror)
			)
		)
		(duplicate_pad_numbers_are_jumpers no)
		(fp_line
			(start -0.7874 0.4064)
			(end 0.7874 0.4064)
			(stroke
				(width 0.1524)
				(type default)
			)
			(layer "B.SilkS")
		)
		(fp_line
			(start 0.7874 0.4064)
			(end 0.7874 -0.4064)
			(stroke
				(width 0.1524)
				(type default)
			)
			(layer "B.SilkS")
		)
		(fp_line
			(start 0 0.381)
			(end 0 -0.381)
			(stroke
				(width 0.1524)
				(type default)
			)
			(layer "B.SilkS")
		)
		(fp_line
			(start -0.7874 -0.4064)
			(end -0.7874 0.4064)
			(stroke
				(width 0.1524)
				(type default)
			)
			(layer "B.SilkS")
		)
		(fp_line
			(start 0.7874 -0.4064)
			(end -0.7874 -0.4064)
			(stroke
				(width 0.1524)
				(type default)
			)
			(layer "B.SilkS")
		)
		(fp_poly
			(pts
				(xy 0.5334 0.254) (xy 0.635 0.254) (xy 0.635 0.2286) (xy 0.635 -0.254) (xy 0.5334 -0.254) (xy 0.5334 -0.2794)
				(xy -0.5334 -0.2794) (xy -0.5334 -0.254) (xy -0.635 -0.254) (xy -0.635 0.254) (xy -0.5334 0.254)
				(xy -0.5334 0.2794) (xy 0.508 0.2794) (xy 0.5334 0.2794)
			)
			(stroke
				(width 0)
				(type default)
			)
			(fill no)
			(layer "B.CrtYd")
		)
		(pad "1" smd rect
			(at -0.40005 0 90)
			(size 0.4572 0.508)
			(layers "B.Cu" "B.Mask" "B.Paste")
			(net "PV_VCCP_NODE1")
		)
		(pad "2" smd rect
			(at 0.40005 0 90)
			(size 0.4572 0.508)
			(layers "B.Cu" "B.Mask" "B.Paste")
			(net "GND")
		)
	)
	(footprint ""
		(layer "B.Cu")
		(at 117.45976 -185.205624 90)
		(property "Reference" "R878"
			(at 3.957828 0.468122 270)
			(unlocked yes)
			(layer "B.SilkS")
			(effects
				(font
					(size 0.7874 0.5842)
					(thickness 0.1524)
				)
				(justify left mirror)
			)
		)
		(property "Value" ""
			(at 0 0 90)
			(layer "B.Fab")
			(effects
				(font
					(size 1.27 1.27)
				)
				(justify mirror)
			)
		)
		(duplicate_pad_numbers_are_jumpers no)
		(fp_line
			(start 0.7874 -0.406146)
			(end -0.7874 -0.406146)
			(stroke
				(width 0.1524)
				(type default)
			)
			(layer "B.SilkS")
		)
		(fp_line
			(start -0.7874 -0.406146)
			(end -0.7874 0.406146)
			(stroke
				(width 0.1524)
				(type default)
			)
			(layer "B.SilkS")
		)
		(fp_line
			(start 0.7874 0.406146)
			(end 0.7874 -0.406146)
			(stroke
				(width 0.1524)
				(type default)
			)
			(layer "B.SilkS")
		)
		(fp_line
			(start -0.7874 0.406146)
			(end 0.7874 0.406146)
			(stroke
				(width 0.1524)
				(type default)
			)
			(layer "B.SilkS")
		)
		(fp_poly
			(pts
				(xy 0.508 0.2794) (xy 0.508 0.2286) (xy 0.635 0.2286) (xy 0.635 -0.254) (xy 0.5334 -0.254) (xy 0.5334 -0.2794)
				(xy -0.5334 -0.2794) (xy -0.5334 -0.254) (xy -0.635 -0.254) (xy -0.635 0.254) (xy -0.5334 0.254)
				(xy -0.5334 0.2794)
			)
			(stroke
				(width 0)
				(type default)
			)
			(fill no)
			(layer "B.CrtYd")
		)
		(pad "1" smd rect
			(at -0.40005 0 270)
			(size 0.4572 0.508)
			(layers "B.Cu" "B.Mask" "B.Paste")
			(net "T7_NODE3_EN")
		)
		(pad "2" smd rect
			(at 0.40005 0 270)
			(size 0.4572 0.508)
			(layers "B.Cu" "B.Mask" "B.Paste")
			(net "T7_NODE3_EN_R")
		)
	)
	(footprint ""
		(layer "B.Cu")
		(at 52.72786 -76.312776)
		(property "Reference" "R42"
			(at -14.47038 31.371794 0)
			(unlocked yes)
			(layer "B.SilkS")
			(effects
				(font
					(size 0.7874 0.5842)
					(thickness 0.1524)
				)
				(justify left mirror)
			)
		)
		(property "Value" ""
			(at 0 0 0)
			(layer "B.Fab")
			(effects
				(font
					(size 1.27 1.27)
				)
				(justify mirror)
			)
		)
		(duplicate_pad_numbers_are_jumpers no)
		(fp_line
			(start -0.7874 -0.4064)
			(end -0.7874 0.4064)
			(stroke
				(width 0.1524)
				(type default)
			)
			(layer "B.SilkS")
		)
		(fp_line
			(start -0.7874 0.4064)
			(end 0.7874 0.4064)
			(stroke
				(width 0.1524)
				(type default)
			)
			(layer "B.SilkS")
		)
		(fp_line
			(start 0.7874 -0.4064)
			(end -0.7874 -0.4064)
			(stroke
				(width 0.1524)
				(type default)
			)
			(layer "B.SilkS")
		)
		(fp_line
			(start 0.7874 0.4064)
			(end 0.7874 -0.4064)
			(stroke
				(width 0.1524)
				(type default)
			)
			(layer "B.SilkS")
		)
		(fp_poly
			(pts
				(xy 0.508 0.2794) (xy 0.508 0.2286) (xy 0.635 0.2286) (xy 0.635 -0.254) (xy 0.5334 -0.254) (xy 0.5334 -0.2794)
				(xy -0.5334 -0.2794) (xy -0.5334 -0.254) (xy -0.635 -0.254) (xy -0.635 0.254) (xy -0.5334 0.254)
				(xy -0.5334 0.2794)
			)
			(stroke
				(width 0)
				(type default)
			)
			(fill no)
			(layer "B.CrtYd")
		)
		(pad "1" smd rect
			(at -0.40005 0 180)
			(size 0.4572 0.508)
			(layers "B.Cu" "B.Mask" "B.Paste")
			(net "PD_CPU_NODE1_AJ23")
		)
		(pad "2" smd rect
			(at 0.40005 0 180)
			(size 0.4572 0.508)
			(layers "B.Cu" "B.Mask" "B.Paste")
			(net "GND")
		)
	)
	(footprint ""
		(layer "B.Cu")
		(at 47.10176 -181.992524 -90)
		(property "Reference" "C615"
			(at 3.618738 10.238994 270)
			(unlocked yes)
			(layer "B.SilkS")
			(effects
				(font
					(size 0.7874 0.5842)
					(thickness 0.1524)
				)
				(justify left mirror)
			)
		)
		(property "Value" ""
			(at 0 0 90)
			(layer "B.Fab")
			(effects
				(font
					(size 1.27 1.27)
				)
				(justify mirror)
			)
		)
		(duplicate_pad_numbers_are_jumpers no)
		(fp_line
			(start -0.7874 0.4064)
			(end 0.7874 0.4064)
			(stroke
				(width 0.1524)
				(type default)
			)
			(layer "B.SilkS")
		)
		(fp_line
			(start 0.7874 0.4064)
			(end 0.7874 -0.4064)
			(stroke
				(width 0.1524)
				(type default)
			)
			(layer "B.SilkS")
		)
		(fp_line
			(start 0 0.381)
			(end 0 -0.381)
			(stroke
				(width 0.1524)
				(type default)
			)
			(layer "B.SilkS")
		)
		(fp_line
			(start -0.7874 -0.4064)
			(end -0.7874 0.4064)
			(stroke
				(width 0.1524)
				(type default)
			)
			(layer "B.SilkS")
		)
		(fp_line
			(start 0.7874 -0.4064)
			(end -0.7874 -0.4064)
			(stroke
				(width 0.1524)
				(type default)
			)
			(layer "B.SilkS")
		)
		(fp_poly
			(pts
				(xy 0.5334 0.254) (xy 0.635 0.254) (xy 0.635 0.2286) (xy 0.635 -0.254) (xy 0.5334 -0.254) (xy 0.5334 -0.2794)
				(xy -0.5334 -0.2794) (xy -0.5334 -0.254) (xy -0.635 -0.254) (xy -0.635 0.254) (xy -0.5334 0.254)
				(xy -0.5334 0.2794) (xy 0.508 0.2794) (xy 0.5334 0.2794)
			)
			(stroke
				(width 0)
				(type default)
			)
			(fill no)
			(layer "B.CrtYd")
		)
		(pad "1" smd rect
			(at -0.40005 0 90)
			(size 0.4572 0.508)
			(layers "B.Cu" "B.Mask" "B.Paste")
			(net "PSU6_DC_OK_R_BUF")
		)
		(pad "2" smd rect
			(at 0.40005 0 90)
			(size 0.4572 0.508)
			(layers "B.Cu" "B.Mask" "B.Paste")
			(net "GND")
		)
	)
	(footprint ""
		(layer "B.Cu")
		(at 135.36676 -187.872624 90)
		(property "Reference" "R956"
			(at 4.565396 -1.359154 270)
			(unlocked yes)
			(layer "B.SilkS")
			(effects
				(font
					(size 0.7874 0.5842)
					(thickness 0.1524)
				)
				(justify left mirror)
			)
		)
		(property "Value" ""
			(at 0 0 90)
			(layer "B.Fab")
			(effects
				(font
					(size 1.27 1.27)
				)
				(justify mirror)
			)
		)
		(duplicate_pad_numbers_are_jumpers no)
		(fp_line
			(start 0.7874 -0.4064)
			(end -0.7874 -0.4064)
			(stroke
				(width 0.1524)
				(type default)
			)
			(layer "B.SilkS")
		)
		(fp_line
			(start -0.7874 -0.4064)
			(end -0.7874 0.4064)
			(stroke
				(width 0.1524)
				(type default)
			)
			(layer "B.SilkS")
		)
		(fp_line
			(start 0.7874 0.4064)
			(end 0.7874 -0.4064)
			(stroke
				(width 0.1524)
				(type default)
			)
			(layer "B.SilkS")
		)
		(fp_line
			(start -0.7874 0.4064)
			(end 0.7874 0.4064)
			(stroke
				(width 0.1524)
				(type default)
			)
			(layer "B.SilkS")
		)
		(fp_poly
			(pts
				(xy 0.508 0.2794) (xy 0.508 0.2286) (xy 0.635 0.2286) (xy 0.635 -0.254) (xy 0.5334 -0.254) (xy 0.5334 -0.2794)
				(xy -0.5334 -0.2794) (xy -0.5334 -0.254) (xy -0.635 -0.254) (xy -0.635 0.254) (xy -0.5334 0.254)
				(xy -0.5334 0.2794)
			)
			(stroke
				(width 0)
				(type default)
			)
			(fill no)
			(layer "B.CrtYd")
		)
		(pad "1" smd rect
			(at -0.40005 0 270)
			(size 0.4572 0.508)
			(layers "B.Cu" "B.Mask" "B.Paste")
			(net "UART_T9_NODE1_RXD")
		)
		(pad "2" smd rect
			(at 0.40005 0 270)
			(size 0.4572 0.508)
			(layers "B.Cu" "B.Mask" "B.Paste")
			(net "UART_T9_NODE1_RXD_R")
		)
	)
	(footprint ""
		(layer "B.Cu")
		(at 62.22873 -137.106406)
		(property "Reference" "C280"
			(at -40.681148 52.897278 0)
			(unlocked yes)
			(layer "B.SilkS")
			(effects
				(font
					(size 0.7874 0.5842)
					(thickness 0.1524)
				)
				(justify left mirror)
			)
		)
		(property "Value" ""
			(at 0 0 0)
			(layer "B.Fab")
			(effects
				(font
					(size 1.27 1.27)
				)
				(justify mirror)
			)
		)
		(duplicate_pad_numbers_are_jumpers no)
		(fp_line
			(start -0.7874 -0.4064)
			(end -0.7874 0.4064)
			(stroke
				(width 0.1524)
				(type default)
			)
			(layer "B.SilkS")
		)
		(fp_line
			(start -0.7874 0.4064)
			(end 0.7874 0.4064)
			(stroke
				(width 0.1524)
				(type default)
			)
			(layer "B.SilkS")
		)
		(fp_line
			(start 0 0.381)
			(end 0 -0.381)
			(stroke
				(width 0.1524)
				(type default)
			)
			(layer "B.SilkS")
		)
		(fp_line
			(start 0.7874 -0.4064)
			(end -0.7874 -0.4064)
			(stroke
				(width 0.1524)
				(type default)
			)
			(layer "B.SilkS")
		)
		(fp_line
			(start 0.7874 0.4064)
			(end 0.7874 -0.4064)
			(stroke
				(width 0.1524)
				(type default)
			)
			(layer "B.SilkS")
		)
		(fp_poly
			(pts
				(xy 0.5334 0.254) (xy 0.635 0.254) (xy 0.635 0.2286) (xy 0.635 -0.254) (xy 0.5334 -0.254) (xy 0.5334 -0.2794)
				(xy -0.5334 -0.2794) (xy -0.5334 -0.254) (xy -0.635 -0.254) (xy -0.635 0.254) (xy -0.5334 0.254)
				(xy -0.5334 0.2794) (xy 0.508 0.2794) (xy 0.5334 0.2794)
			)
			(stroke
				(width 0)
				(type default)
			)
			(fill no)
			(layer "B.CrtYd")
		)
		(pad "1" smd rect
			(at -0.40005 0 180)
			(size 0.4572 0.508)
			(layers "B.Cu" "B.Mask" "B.Paste")
			(net "P3V3_NODE1")
		)
		(pad "2" smd rect
			(at 0.40005 0 180)
			(size 0.4572 0.508)
			(layers "B.Cu" "B.Mask" "B.Paste")
			(net "GND")
		)
	)
	(footprint ""
		(layer "B.Cu")
		(at 73.207372 -80.514698 90)
		(property "Reference" "C69"
			(at -32.276034 -14.610842 270)
			(unlocked yes)
			(layer "B.SilkS")
			(effects
				(font
					(size 0.7874 0.5842)
					(thickness 0.1524)
				)
				(justify left mirror)
			)
		)
		(property "Value" ""
			(at 0 0 90)
			(layer "B.Fab")
			(effects
				(font
					(size 1.27 1.27)
				)
				(justify mirror)
			)
		)
		(duplicate_pad_numbers_are_jumpers no)
		(fp_line
			(start 0.7874 -0.4064)
			(end -0.7874 -0.4064)
			(stroke
				(width 0.1524)
				(type default)
			)
			(layer "B.SilkS")
		)
		(fp_line
			(start -0.7874 -0.4064)
			(end -0.7874 0.4064)
			(stroke
				(width 0.1524)
				(type default)
			)
			(layer "B.SilkS")
		)
		(fp_line
			(start 0 0.381)
			(end 0 -0.381)
			(stroke
				(width 0.1524)
				(type default)
			)
			(layer "B.SilkS")
		)
		(fp_line
			(start 0.7874 0.4064)
			(end 0.7874 -0.4064)
			(stroke
				(width 0.1524)
				(type default)
			)
			(layer "B.SilkS")
		)
		(fp_line
			(start -0.7874 0.4064)
			(end 0.7874 0.4064)
			(stroke
				(width 0.1524)
				(type default)
			)
			(layer "B.SilkS")
		)
		(fp_poly
			(pts
				(xy 0.5334 0.254) (xy 0.635 0.254) (xy 0.635 0.2286) (xy 0.635 -0.254) (xy 0.5334 -0.254) (xy 0.5334 -0.2794)
				(xy -0.5334 -0.2794) (xy -0.5334 -0.254) (xy -0.635 -0.254) (xy -0.635 0.254) (xy -0.5334 0.254)
				(xy -0.5334 0.2794) (xy 0.508 0.2794) (xy 0.5334 0.2794)
			)
			(stroke
				(width 0)
				(type default)
			)
			(fill no)
			(layer "B.CrtYd")
		)
		(pad "1" smd rect
			(at -0.40005 0 270)
			(size 0.4572 0.508)
			(layers "B.Cu" "B.Mask" "B.Paste")
			(net "PV_VCCP_NODE1")
		)
		(pad "2" smd rect
			(at 0.40005 0 270)
			(size 0.4572 0.508)
			(layers "B.Cu" "B.Mask" "B.Paste")
			(net "GND")
		)
	)
	(footprint ""
		(layer "B.Cu")
		(at 88.77935 -77.749654)
		(property "Reference" "R171"
			(at -1.91516 9.670288 0)
			(unlocked yes)
			(layer "B.SilkS")
			(effects
				(font
					(size 0.7874 0.5842)
					(thickness 0.1524)
				)
				(justify left mirror)
			)
		)
		(property "Value" ""
			(at 0 0 0)
			(layer "B.Fab")
			(effects
				(font
					(size 1.27 1.27)
				)
				(justify mirror)
			)
		)
		(duplicate_pad_numbers_are_jumpers no)
		(fp_line
			(start -0.7874 -0.4064)
			(end -0.7874 0.4064)
			(stroke
				(width 0.1524)
				(type default)
			)
			(layer "B.SilkS")
		)
		(fp_line
			(start -0.7874 0.4064)
			(end 0.7874 0.4064)
			(stroke
				(width 0.1524)
				(type default)
			)
			(layer "B.SilkS")
		)
		(fp_line
			(start 0.7874 -0.4064)
			(end -0.7874 -0.4064)
			(stroke
				(width 0.1524)
				(type default)
			)
			(layer "B.SilkS")
		)
		(fp_line
			(start 0.7874 0.4064)
			(end 0.7874 -0.4064)
			(stroke
				(width 0.1524)
				(type default)
			)
			(layer "B.SilkS")
		)
		(fp_poly
			(pts
				(xy 0.508 0.2794) (xy 0.508 0.2286) (xy 0.635 0.2286) (xy 0.635 -0.254) (xy 0.5334 -0.254) (xy 0.5334 -0.2794)
				(xy -0.5334 -0.2794) (xy -0.5334 -0.254) (xy -0.635 -0.254) (xy -0.635 0.254) (xy -0.5334 0.254)
				(xy -0.5334 0.2794)
			)
			(stroke
				(width 0)
				(type default)
			)
			(fill no)
			(layer "B.CrtYd")
		)
		(pad "1" smd rect
			(at -0.40005 0 180)
			(size 0.4572 0.508)
			(layers "B.Cu" "B.Mask" "B.Paste")
			(net "PU_CPU_NODE1_MEM_SPEED0")
		)
		(pad "2" smd rect
			(at 0.40005 0 180)
			(size 0.4572 0.508)
			(layers "B.Cu" "B.Mask" "B.Paste")
			(net "P1V05_SUS_NODE1")
		)
	)
	(footprint ""
		(layer "B.Cu")
		(at 171.180252 -103.32339 180)
		(property "Reference" "C377"
			(at -7.681722 -0.220726 0)
			(unlocked yes)
			(layer "B.SilkS")
			(effects
				(font
					(size 0.7874 0.5842)
					(thickness 0.1524)
				)
				(justify left mirror)
			)
		)
		(property "Value" ""
			(at 0 0 0)
			(layer "B.Fab")
			(effects
				(font
					(size 1.27 1.27)
				)
				(justify mirror)
			)
		)
		(duplicate_pad_numbers_are_jumpers no)
		(fp_line
			(start 0.7874 0.4064)
			(end 0.7874 -0.4064)
			(stroke
				(width 0.1524)
				(type default)
			)
			(layer "B.SilkS")
		)
		(fp_line
			(start 0.7874 -0.4064)
			(end -0.7874 -0.4064)
			(stroke
				(width 0.1524)
				(type default)
			)
			(layer "B.SilkS")
		)
		(fp_line
			(start 0 0.381)
			(end 0 -0.381)
			(stroke
				(width 0.1524)
				(type default)
			)
			(layer "B.SilkS")
		)
		(fp_line
			(start -0.7874 0.4064)
			(end 0.7874 0.4064)
			(stroke
				(width 0.1524)
				(type default)
			)
			(layer "B.SilkS")
		)
		(fp_line
			(start -0.7874 -0.4064)
			(end -0.7874 0.4064)
			(stroke
				(width 0.1524)
				(type default)
			)
			(layer "B.SilkS")
		)
		(fp_poly
			(pts
				(xy 0.5334 0.254) (xy 0.635 0.254) (xy 0.635 0.2286) (xy 0.635 -0.254) (xy 0.5334 -0.254) (xy 0.5334 -0.2794)
				(xy -0.5334 -0.2794) (xy -0.5334 -0.254) (xy -0.635 -0.254) (xy -0.635 0.254) (xy -0.5334 0.254)
				(xy -0.5334 0.2794) (xy 0.508 0.2794) (xy 0.5334 0.2794)
			)
			(stroke
				(width 0)
				(type default)
			)
			(fill no)
			(layer "B.CrtYd")
		)
		(pad "1" smd rect
			(at -0.40005 0)
			(size 0.4572 0.508)
			(layers "B.Cu" "B.Mask" "B.Paste")
			(net "P3V3_NODE1")
		)
		(pad "2" smd rect
			(at 0.40005 0)
			(size 0.4572 0.508)
			(layers "B.Cu" "B.Mask" "B.Paste")
			(net "GND")
		)
	)
	(footprint ""
		(layer "B.Cu")
		(at 51.691286 -123.025662 90)
		(property "Reference" "L19"
			(at -53.17871 -42.41165 270)
			(unlocked yes)
			(layer "B.SilkS")
			(effects
				(font
					(size 0.7874 0.5842)
					(thickness 0.1524)
				)
				(justify mirror)
			)
		)
		(property "Value" ""
			(at 0 0 90)
			(layer "B.Fab")
			(effects
				(font
					(size 1.27 1.27)
				)
				(justify mirror)
			)
		)
		(duplicate_pad_numbers_are_jumpers no)
		(fp_line
			(start 1.2954 -0.635)
			(end -1.2954 -0.635)
			(stroke
				(width 0.1524)
				(type default)
			)
			(layer "B.SilkS")
		)
		(fp_line
			(start 1.2954 -0.635)
			(end 1.2954 0.635)
			(stroke
				(width 0.1524)
				(type default)
			)
			(layer "B.SilkS")
		)
		(fp_line
			(start -1.2954 -0.635)
			(end -1.2954 0.635)
			(stroke
				(width 0.1524)
				(type default)
			)
			(layer "B.SilkS")
		)
		(fp_line
			(start 0.127 -0.5842)
			(end 0.127 0.5842)
			(stroke
				(width 0.1524)
				(type default)
			)
			(layer "B.SilkS")
		)
		(fp_line
			(start -0.127 -0.5842)
			(end -0.127 0.5842)
			(stroke
				(width 0.1524)
				(type default)
			)
			(layer "B.SilkS")
		)
		(fp_line
			(start -1.2954 0.635)
			(end 1.2954 0.635)
			(stroke
				(width 0.1524)
				(type default)
			)
			(layer "B.SilkS")
		)
		(fp_poly
			(pts
				(xy 0.9144 0.508) (xy 0.9144 0.3556) (xy 1.143 0.3556) (xy 1.143 -0.3556) (xy 0.9144 -0.3556) (xy 0.9144 -0.508)
				(xy -0.9144 -0.508) (xy -0.9144 -0.3556) (xy -1.143 -0.3556) (xy -1.143 0.3556) (xy -0.9144 0.3556)
				(xy -0.9144 0.508)
			)
			(stroke
				(width 0)
				(type default)
			)
			(fill no)
			(layer "B.CrtYd")
		)
		(pad "1" smd rect
			(at -0.7366 0 180)
			(size 0.7112 0.8128)
			(layers "B.Cu" "B.Mask" "B.Paste")
			(net "BMC_NODE1_V1PLLAV12")
		)
		(pad "2" smd rect
			(at 0.7366 0 180)
			(size 0.7112 0.8128)
			(layers "B.Cu" "B.Mask" "B.Paste")
			(net "P1V26_BMC_NODE1")
		)
	)
	(footprint ""
		(layer "B.Cu")
		(at 141.522196 -68.73113 -90)
		(property "Reference" "C351"
			(at 0.8382 -1.029462 270)
			(unlocked yes)
			(layer "B.SilkS")
			(effects
				(font
					(size 0.7874 0.5842)
					(thickness 0.1524)
				)
				(justify left mirror)
			)
		)
		(property "Value" ""
			(at 0 0 90)
			(layer "B.Fab")
			(effects
				(font
					(size 1.27 1.27)
				)
				(justify mirror)
			)
		)
		(duplicate_pad_numbers_are_jumpers no)
		(fp_line
			(start -0.7874 0.4064)
			(end 0.7874 0.4064)
			(stroke
				(width 0.1524)
				(type default)
			)
			(layer "B.SilkS")
		)
		(fp_line
			(start 0.7874 0.4064)
			(end 0.7874 -0.4064)
			(stroke
				(width 0.1524)
				(type default)
			)
			(layer "B.SilkS")
		)
		(fp_line
			(start 0 0.381)
			(end 0 -0.381)
			(stroke
				(width 0.1524)
				(type default)
			)
			(layer "B.SilkS")
		)
		(fp_line
			(start -0.7874 -0.4064)
			(end -0.7874 0.4064)
			(stroke
				(width 0.1524)
				(type default)
			)
			(layer "B.SilkS")
		)
		(fp_line
			(start 0.7874 -0.4064)
			(end -0.7874 -0.4064)
			(stroke
				(width 0.1524)
				(type default)
			)
			(layer "B.SilkS")
		)
		(fp_poly
			(pts
				(xy 0.5334 0.254) (xy 0.635 0.254) (xy 0.635 0.2286) (xy 0.635 -0.254) (xy 0.5334 -0.254) (xy 0.5334 -0.2794)
				(xy -0.5334 -0.2794) (xy -0.5334 -0.254) (xy -0.635 -0.254) (xy -0.635 0.254) (xy -0.5334 0.254)
				(xy -0.5334 0.2794) (xy 0.508 0.2794) (xy 0.5334 0.2794)
			)
			(stroke
				(width 0)
				(type default)
			)
			(fill no)
			(layer "B.CrtYd")
		)
		(pad "1" smd rect
			(at -0.40005 0 90)
			(size 0.4572 0.508)
			(layers "B.Cu" "B.Mask" "B.Paste")
			(net "P3V3_NODE1")
		)
		(pad "2" smd rect
			(at 0.40005 0 90)
			(size 0.4572 0.508)
			(layers "B.Cu" "B.Mask" "B.Paste")
			(net "GND")
		)
	)
	(footprint ""
		(layer "B.Cu")
		(at 139.227052 -151.28875 90)
		(property "Reference" "C868"
			(at 1.03378 3.437382 270)
			(unlocked yes)
			(layer "B.SilkS")
			(effects
				(font
					(size 0.7874 0.5842)
					(thickness 0.1524)
				)
				(justify left mirror)
			)
		)
		(property "Value" ""
			(at 0 0 90)
			(layer "B.Fab")
			(effects
				(font
					(size 1.27 1.27)
				)
				(justify mirror)
			)
		)
		(duplicate_pad_numbers_are_jumpers no)
		(fp_line
			(start 0.7874 -0.4064)
			(end -0.7874 -0.4064)
			(stroke
				(width 0.1524)
				(type default)
			)
			(layer "B.SilkS")
		)
		(fp_line
			(start -0.7874 -0.4064)
			(end -0.7874 0.4064)
			(stroke
				(width 0.1524)
				(type default)
			)
			(layer "B.SilkS")
		)
		(fp_line
			(start 0 0.381)
			(end 0 -0.381)
			(stroke
				(width 0.1524)
				(type default)
			)
			(layer "B.SilkS")
		)
		(fp_line
			(start 0.7874 0.4064)
			(end 0.7874 -0.4064)
			(stroke
				(width 0.1524)
				(type default)
			)
			(layer "B.SilkS")
		)
		(fp_line
			(start -0.7874 0.4064)
			(end 0.7874 0.4064)
			(stroke
				(width 0.1524)
				(type default)
			)
			(layer "B.SilkS")
		)
		(fp_poly
			(pts
				(xy 0.5334 0.254) (xy 0.635 0.254) (xy 0.635 0.2286) (xy 0.635 -0.254) (xy 0.5334 -0.254) (xy 0.5334 -0.2794)
				(xy -0.5334 -0.2794) (xy -0.5334 -0.254) (xy -0.635 -0.254) (xy -0.635 0.254) (xy -0.5334 0.254)
				(xy -0.5334 0.2794) (xy 0.508 0.2794) (xy 0.5334 0.2794)
			)
			(stroke
				(width 0)
				(type default)
			)
			(fill no)
			(layer "B.CrtYd")
		)
		(pad "1" smd rect
			(at -0.40005 0 270)
			(size 0.4572 0.508)
			(layers "B.Cu" "B.Mask" "B.Paste")
			(net "P3V3_NODE1")
		)
		(pad "2" smd rect
			(at 0.40005 0 270)
			(size 0.4572 0.508)
			(layers "B.Cu" "B.Mask" "B.Paste")
			(net "GND")
		)
	)
	(footprint ""
		(layer "B.Cu")
		(at 128.524 -59.436 -90)
		(property "Reference" "R1327"
			(at -1.143 0.02667 270)
			(unlocked yes)
			(layer "B.SilkS")
			(effects
				(font
					(size 0.7874 0.5842)
					(thickness 0.1524)
				)
				(justify left mirror)
			)
		)
		(property "Value" ""
			(at 0 0 90)
			(layer "B.Fab")
			(effects
				(font
					(size 1.27 1.27)
				)
				(justify mirror)
			)
		)
		(duplicate_pad_numbers_are_jumpers no)
		(fp_line
			(start -0.7874 0.4064)
			(end 0.7874 0.4064)
			(stroke
				(width 0.1524)
				(type default)
			)
			(layer "B.SilkS")
		)
		(fp_line
			(start 0.7874 0.4064)
			(end 0.7874 -0.4064)
			(stroke
				(width 0.1524)
				(type default)
			)
			(layer "B.SilkS")
		)
		(fp_line
			(start -0.7874 -0.4064)
			(end -0.7874 0.4064)
			(stroke
				(width 0.1524)
				(type default)
			)
			(layer "B.SilkS")
		)
		(fp_line
			(start 0.7874 -0.4064)
			(end -0.7874 -0.4064)
			(stroke
				(width 0.1524)
				(type default)
			)
			(layer "B.SilkS")
		)
		(fp_poly
			(pts
				(xy 0.508 0.2794) (xy 0.508 0.2286) (xy 0.635 0.2286) (xy 0.635 -0.254) (xy 0.5334 -0.254) (xy 0.5334 -0.2794)
				(xy -0.5334 -0.2794) (xy -0.5334 -0.254) (xy -0.635 -0.254) (xy -0.635 0.254) (xy -0.5334 0.254)
				(xy -0.5334 0.2794)
			)
			(stroke
				(width 0)
				(type default)
			)
			(fill no)
			(layer "B.CrtYd")
		)
		(pad "1" smd rect
			(at -0.40005 0 90)
			(size 0.4572 0.508)
			(layers "B.Cu" "B.Mask" "B.Paste")
			(net "UART_RI_P3_BUFFER_N")
		)
		(pad "2" smd rect
			(at 0.40005 0 90)
			(size 0.4572 0.508)
			(layers "B.Cu" "B.Mask" "B.Paste")
			(net "UART_RI_P3_N")
		)
	)
	(footprint ""
		(layer "B.Cu")
		(at 76.5683 -184.85358 90)
		(property "Reference" "R892"
			(at 4.15163 0.12065 270)
			(unlocked yes)
			(layer "B.SilkS")
			(effects
				(font
					(size 0.7874 0.5842)
					(thickness 0.1524)
				)
				(justify left mirror)
			)
		)
		(property "Value" ""
			(at 0 0 90)
			(layer "B.Fab")
			(effects
				(font
					(size 1.27 1.27)
				)
				(justify mirror)
			)
		)
		(duplicate_pad_numbers_are_jumpers no)
		(fp_line
			(start 0.7874 -0.4064)
			(end -0.7874 -0.4064)
			(stroke
				(width 0.1524)
				(type default)
			)
			(layer "B.SilkS")
		)
		(fp_line
			(start -0.7874 -0.4064)
			(end -0.7874 0.4064)
			(stroke
				(width 0.1524)
				(type default)
			)
			(layer "B.SilkS")
		)
		(fp_line
			(start 0.7874 0.4064)
			(end 0.7874 -0.4064)
			(stroke
				(width 0.1524)
				(type default)
			)
			(layer "B.SilkS")
		)
		(fp_line
			(start -0.7874 0.4064)
			(end 0.7874 0.4064)
			(stroke
				(width 0.1524)
				(type default)
			)
			(layer "B.SilkS")
		)
		(fp_poly
			(pts
				(xy 0.508 0.2794) (xy 0.508 0.2286) (xy 0.635 0.2286) (xy 0.635 -0.254) (xy 0.5334 -0.254) (xy 0.5334 -0.2794)
				(xy -0.5334 -0.2794) (xy -0.5334 -0.254) (xy -0.635 -0.254) (xy -0.635 0.254) (xy -0.5334 0.254)
				(xy -0.5334 0.2794)
			)
			(stroke
				(width 0)
				(type default)
			)
			(fill no)
			(layer "B.CrtYd")
		)
		(pad "1" smd rect
			(at -0.40005 0 270)
			(size 0.4572 0.508)
			(layers "B.Cu" "B.Mask" "B.Paste")
			(net "T3_NODE4_EN")
		)
		(pad "2" smd rect
			(at 0.40005 0 270)
			(size 0.4572 0.508)
			(layers "B.Cu" "B.Mask" "B.Paste")
			(net "T3_NODE4_EN_R")
		)
	)
	(footprint ""
		(layer "B.Cu")
		(at 165.210998 -156.39923 180)
		(property "Reference" "C471"
			(at 1.075182 -0.301498 0)
			(unlocked yes)
			(layer "B.SilkS")
			(effects
				(font
					(size 0.7874 0.5842)
					(thickness 0.1524)
				)
				(justify left mirror)
			)
		)
		(property "Value" ""
			(at 0 0 0)
			(layer "B.Fab")
			(effects
				(font
					(size 1.27 1.27)
				)
				(justify mirror)
			)
		)
		(duplicate_pad_numbers_are_jumpers no)
		(fp_line
			(start 0.7874 0.4064)
			(end 0.7874 -0.4064)
			(stroke
				(width 0.1524)
				(type default)
			)
			(layer "B.SilkS")
		)
		(fp_line
			(start 0.7874 -0.4064)
			(end -0.7874 -0.4064)
			(stroke
				(width 0.1524)
				(type default)
			)
			(layer "B.SilkS")
		)
		(fp_line
			(start 0 0.381)
			(end 0 -0.381)
			(stroke
				(width 0.1524)
				(type default)
			)
			(layer "B.SilkS")
		)
		(fp_line
			(start -0.7874 0.4064)
			(end 0.7874 0.4064)
			(stroke
				(width 0.1524)
				(type default)
			)
			(layer "B.SilkS")
		)
		(fp_line
			(start -0.7874 -0.4064)
			(end -0.7874 0.4064)
			(stroke
				(width 0.1524)
				(type default)
			)
			(layer "B.SilkS")
		)
		(fp_poly
			(pts
				(xy 0.5334 0.254) (xy 0.635 0.254) (xy 0.635 0.2286) (xy 0.635 -0.254) (xy 0.5334 -0.254) (xy 0.5334 -0.2794)
				(xy -0.5334 -0.2794) (xy -0.5334 -0.254) (xy -0.635 -0.254) (xy -0.635 0.254) (xy -0.5334 0.254)
				(xy -0.5334 0.2794) (xy 0.508 0.2794) (xy 0.5334 0.2794)
			)
			(stroke
				(width 0)
				(type default)
			)
			(fill no)
			(layer "B.CrtYd")
		)
		(pad "1" smd rect
			(at -0.40005 0)
			(size 0.4572 0.508)
			(layers "B.Cu" "B.Mask" "B.Paste")
			(net "P1V9_LAN2")
		)
		(pad "2" smd rect
			(at 0.40005 0)
			(size 0.4572 0.508)
			(layers "B.Cu" "B.Mask" "B.Paste")
			(net "GND")
		)
	)
	(footprint ""
		(layer "B.Cu")
		(at 131.988052 -151.28875 90)
		(property "Reference" "C875"
			(at 1.704086 0.21844 270)
			(unlocked yes)
			(layer "B.SilkS")
			(effects
				(font
					(size 0.7874 0.5842)
					(thickness 0.1524)
				)
				(justify left mirror)
			)
		)
		(property "Value" ""
			(at 0 0 90)
			(layer "B.Fab")
			(effects
				(font
					(size 1.27 1.27)
				)
				(justify mirror)
			)
		)
		(duplicate_pad_numbers_are_jumpers no)
		(fp_line
			(start 0.7874 -0.4064)
			(end -0.7874 -0.4064)
			(stroke
				(width 0.1524)
				(type default)
			)
			(layer "B.SilkS")
		)
		(fp_line
			(start -0.7874 -0.4064)
			(end -0.7874 0.4064)
			(stroke
				(width 0.1524)
				(type default)
			)
			(layer "B.SilkS")
		)
		(fp_line
			(start 0 0.381)
			(end 0 -0.381)
			(stroke
				(width 0.1524)
				(type default)
			)
			(layer "B.SilkS")
		)
		(fp_line
			(start 0.7874 0.4064)
			(end 0.7874 -0.4064)
			(stroke
				(width 0.1524)
				(type default)
			)
			(layer "B.SilkS")
		)
		(fp_line
			(start -0.7874 0.4064)
			(end 0.7874 0.4064)
			(stroke
				(width 0.1524)
				(type default)
			)
			(layer "B.SilkS")
		)
		(fp_poly
			(pts
				(xy 0.5334 0.254) (xy 0.635 0.254) (xy 0.635 0.2286) (xy 0.635 -0.254) (xy 0.5334 -0.254) (xy 0.5334 -0.2794)
				(xy -0.5334 -0.2794) (xy -0.5334 -0.254) (xy -0.635 -0.254) (xy -0.635 0.254) (xy -0.5334 0.254)
				(xy -0.5334 0.2794) (xy 0.508 0.2794) (xy 0.5334 0.2794)
			)
			(stroke
				(width 0)
				(type default)
			)
			(fill no)
			(layer "B.CrtYd")
		)
		(pad "1" smd rect
			(at -0.40005 0 270)
			(size 0.4572 0.508)
			(layers "B.Cu" "B.Mask" "B.Paste")
			(net "P1V0_NODE1")
		)
		(pad "2" smd rect
			(at 0.40005 0 270)
			(size 0.4572 0.508)
			(layers "B.Cu" "B.Mask" "B.Paste")
			(net "GND")
		)
	)
	(footprint ""
		(layer "B.Cu")
		(at 163.427918 -144.51203 -90)
		(property "Reference" "TP3"
			(at 0 0 90)
			(layer "B.SilkS")
			(hide yes)
			(effects
				(font
					(size 1.27 1.27)
				)
				(justify mirror)
			)
		)
		(property "Value" ""
			(at 0 0 90)
			(layer "B.Fab")
			(effects
				(font
					(size 1.27 1.27)
				)
				(justify mirror)
			)
		)
		(duplicate_pad_numbers_are_jumpers no)
		(fp_poly
			(pts
				(arc
					(start 0 -0.381)
					(mid 0 0.381)
					(end 0 -0.381)
				)
			)
			(stroke
				(width 0)
				(type default)
			)
			(fill no)
			(layer "B.CrtYd")
		)
		(pad "1" smd circle
			(at 0 0 90)
			(size 0.762 0.762)
			(layers "B.Cu" "B.Mask" "B.Paste")
			(net "N21357353")
		)
	)
	(footprint ""
		(layer "B.Cu")
		(at 56.171338 -80.166718 180)
		(property "Reference" "C48"
			(at 13.628878 -30.096968 0)
			(unlocked yes)
			(layer "B.SilkS")
			(effects
				(font
					(size 0.7874 0.5842)
					(thickness 0.1524)
				)
				(justify left mirror)
			)
		)
		(property "Value" ""
			(at 0 0 0)
			(layer "B.Fab")
			(effects
				(font
					(size 1.27 1.27)
				)
				(justify mirror)
			)
		)
		(duplicate_pad_numbers_are_jumpers no)
		(fp_line
			(start 0.7874 0.4064)
			(end 0.7874 -0.4064)
			(stroke
				(width 0.1524)
				(type default)
			)
			(layer "B.SilkS")
		)
		(fp_line
			(start 0.7874 -0.4064)
			(end -0.7874 -0.4064)
			(stroke
				(width 0.1524)
				(type default)
			)
			(layer "B.SilkS")
		)
		(fp_line
			(start 0 0.381)
			(end 0 -0.381)
			(stroke
				(width 0.1524)
				(type default)
			)
			(layer "B.SilkS")
		)
		(fp_line
			(start -0.7874 0.4064)
			(end 0.7874 0.4064)
			(stroke
				(width 0.1524)
				(type default)
			)
			(layer "B.SilkS")
		)
		(fp_line
			(start -0.7874 -0.4064)
			(end -0.7874 0.4064)
			(stroke
				(width 0.1524)
				(type default)
			)
			(layer "B.SilkS")
		)
		(fp_poly
			(pts
				(xy 0.5334 0.254) (xy 0.635 0.254) (xy 0.635 0.2286) (xy 0.635 -0.254) (xy 0.5334 -0.254) (xy 0.5334 -0.2794)
				(xy -0.5334 -0.2794) (xy -0.5334 -0.254) (xy -0.635 -0.254) (xy -0.635 0.254) (xy -0.5334 0.254)
				(xy -0.5334 0.2794) (xy 0.508 0.2794) (xy 0.5334 0.2794)
			)
			(stroke
				(width 0)
				(type default)
			)
			(fill no)
			(layer "B.CrtYd")
		)
		(pad "1" smd rect
			(at -0.40005 0)
			(size 0.4572 0.508)
			(layers "B.Cu" "B.Mask" "B.Paste")
			(net "P1V05_NODE1")
		)
		(pad "2" smd rect
			(at 0.40005 0)
			(size 0.4572 0.508)
			(layers "B.Cu" "B.Mask" "B.Paste")
			(net "GND")
		)
	)
	(footprint ""
		(layer "B.Cu")
		(at 94.234762 -184.815988 180)
		(property "Reference" "C665"
			(at -1.292098 5.936234 0)
			(unlocked yes)
			(layer "B.SilkS")
			(effects
				(font
					(size 0.7874 0.5842)
					(thickness 0.1524)
				)
				(justify left mirror)
			)
		)
		(property "Value" ""
			(at 0 0 0)
			(layer "B.Fab")
			(effects
				(font
					(size 1.27 1.27)
				)
				(justify mirror)
			)
		)
		(duplicate_pad_numbers_are_jumpers no)
		(fp_line
			(start 0.7874 0.4064)
			(end 0.7874 -0.4064)
			(stroke
				(width 0.1524)
				(type default)
			)
			(layer "B.SilkS")
		)
		(fp_line
			(start 0.7874 -0.4064)
			(end -0.7874 -0.4064)
			(stroke
				(width 0.1524)
				(type default)
			)
			(layer "B.SilkS")
		)
		(fp_line
			(start 0 0.381)
			(end 0 -0.381)
			(stroke
				(width 0.1524)
				(type default)
			)
			(layer "B.SilkS")
		)
		(fp_line
			(start -0.7874 0.4064)
			(end 0.7874 0.4064)
			(stroke
				(width 0.1524)
				(type default)
			)
			(layer "B.SilkS")
		)
		(fp_line
			(start -0.7874 -0.4064)
			(end -0.7874 0.4064)
			(stroke
				(width 0.1524)
				(type default)
			)
			(layer "B.SilkS")
		)
		(fp_poly
			(pts
				(xy 0.5334 0.254) (xy 0.635 0.254) (xy 0.635 0.2286) (xy 0.635 -0.254) (xy 0.5334 -0.254) (xy 0.5334 -0.2794)
				(xy -0.5334 -0.2794) (xy -0.5334 -0.254) (xy -0.635 -0.254) (xy -0.635 0.254) (xy -0.5334 0.254)
				(xy -0.5334 0.2794) (xy 0.508 0.2794) (xy 0.5334 0.2794)
			)
			(stroke
				(width 0)
				(type default)
			)
			(fill no)
			(layer "B.CrtYd")
		)
		(pad "1" smd rect
			(at -0.40005 0)
			(size 0.4572 0.508)
			(layers "B.Cu" "B.Mask" "B.Paste")
			(net "T5_NODE3_EN_R")
		)
		(pad "2" smd rect
			(at 0.40005 0)
			(size 0.4572 0.508)
			(layers "B.Cu" "B.Mask" "B.Paste")
			(net "GND")
		)
	)
	(footprint ""
		(layer "B.Cu")
		(at 125.866652 -143.00835 180)
		(property "Reference" "C894"
			(at 3.235198 3.495294 0)
			(unlocked yes)
			(layer "B.SilkS")
			(effects
				(font
					(size 0.7874 0.5842)
					(thickness 0.1524)
				)
				(justify left mirror)
			)
		)
		(property "Value" ""
			(at 0 0 0)
			(layer "B.Fab")
			(effects
				(font
					(size 1.27 1.27)
				)
				(justify mirror)
			)
		)
		(duplicate_pad_numbers_are_jumpers no)
		(fp_line
			(start 0.7874 0.4064)
			(end 0.7874 -0.4064)
			(stroke
				(width 0.1524)
				(type default)
			)
			(layer "B.SilkS")
		)
		(fp_line
			(start 0.7874 -0.4064)
			(end -0.7874 -0.4064)
			(stroke
				(width 0.1524)
				(type default)
			)
			(layer "B.SilkS")
		)
		(fp_line
			(start 0 0.381)
			(end 0 -0.381)
			(stroke
				(width 0.1524)
				(type default)
			)
			(layer "B.SilkS")
		)
		(fp_line
			(start -0.7874 0.4064)
			(end 0.7874 0.4064)
			(stroke
				(width 0.1524)
				(type default)
			)
			(layer "B.SilkS")
		)
		(fp_line
			(start -0.7874 -0.4064)
			(end -0.7874 0.4064)
			(stroke
				(width 0.1524)
				(type default)
			)
			(layer "B.SilkS")
		)
		(fp_poly
			(pts
				(xy 0.5334 0.254) (xy 0.635 0.254) (xy 0.635 0.2286) (xy 0.635 -0.254) (xy 0.5334 -0.254) (xy 0.5334 -0.2794)
				(xy -0.5334 -0.2794) (xy -0.5334 -0.254) (xy -0.635 -0.254) (xy -0.635 0.254) (xy -0.5334 0.254)
				(xy -0.5334 0.2794) (xy 0.508 0.2794) (xy 0.5334 0.2794)
			)
			(stroke
				(width 0)
				(type default)
			)
			(fill no)
			(layer "B.CrtYd")
		)
		(pad "1" smd rect
			(at -0.40005 0)
			(size 0.4572 0.508)
			(layers "B.Cu" "B.Mask" "B.Paste")
			(net "P1V538_BMC_NODE1")
		)
		(pad "2" smd rect
			(at 0.40005 0)
			(size 0.4572 0.508)
			(layers "B.Cu" "B.Mask" "B.Paste")
			(net "GND")
		)
	)
	(footprint ""
		(layer "B.Cu")
		(at 56.24576 -188.126624 -90)
		(property "Reference" "C691"
			(at -4.276598 -0.065024 270)
			(unlocked yes)
			(layer "B.SilkS")
			(effects
				(font
					(size 0.7874 0.5842)
					(thickness 0.1524)
				)
				(justify left mirror)
			)
		)
		(property "Value" ""
			(at 0 0 90)
			(layer "B.Fab")
			(effects
				(font
					(size 1.27 1.27)
				)
				(justify mirror)
			)
		)
		(duplicate_pad_numbers_are_jumpers no)
		(fp_line
			(start -0.7874 0.4064)
			(end 0.7874 0.4064)
			(stroke
				(width 0.1524)
				(type default)
			)
			(layer "B.SilkS")
		)
		(fp_line
			(start 0.7874 0.4064)
			(end 0.7874 -0.4064)
			(stroke
				(width 0.1524)
				(type default)
			)
			(layer "B.SilkS")
		)
		(fp_line
			(start 0 0.381)
			(end 0 -0.381)
			(stroke
				(width 0.1524)
				(type default)
			)
			(layer "B.SilkS")
		)
		(fp_line
			(start -0.7874 -0.4064)
			(end -0.7874 0.4064)
			(stroke
				(width 0.1524)
				(type default)
			)
			(layer "B.SilkS")
		)
		(fp_line
			(start 0.7874 -0.4064)
			(end -0.7874 -0.4064)
			(stroke
				(width 0.1524)
				(type default)
			)
			(layer "B.SilkS")
		)
		(fp_poly
			(pts
				(xy 0.5334 0.254) (xy 0.635 0.254) (xy 0.635 0.2286) (xy 0.635 -0.254) (xy 0.5334 -0.254) (xy 0.5334 -0.2794)
				(xy -0.5334 -0.2794) (xy -0.5334 -0.254) (xy -0.635 -0.254) (xy -0.635 0.254) (xy -0.5334 0.254)
				(xy -0.5334 0.2794) (xy 0.508 0.2794) (xy 0.5334 0.2794)
			)
			(stroke
				(width 0)
				(type default)
			)
			(fill no)
			(layer "B.CrtYd")
		)
		(pad "1" smd rect
			(at -0.40005 0 90)
			(size 0.4572 0.508)
			(layers "B.Cu" "B.Mask" "B.Paste")
			(net "UART_T1_NODE4_TXD_R")
		)
		(pad "2" smd rect
			(at 0.40005 0 90)
			(size 0.4572 0.508)
			(layers "B.Cu" "B.Mask" "B.Paste")
			(net "GND")
		)
	)
	(footprint ""
		(layer "B.Cu")
		(at 94.451932 -174.156624)
		(property "Reference" "R708"
			(at 1.83642 14.281658 0)
			(unlocked yes)
			(layer "B.SilkS")
			(effects
				(font
					(size 0.7874 0.5842)
					(thickness 0.1524)
				)
				(justify left mirror)
			)
		)
		(property "Value" ""
			(at 0 0 0)
			(layer "B.Fab")
			(effects
				(font
					(size 1.27 1.27)
				)
				(justify mirror)
			)
		)
		(duplicate_pad_numbers_are_jumpers no)
		(fp_line
			(start -0.7874 -0.4064)
			(end -0.7874 0.4064)
			(stroke
				(width 0.1524)
				(type default)
			)
			(layer "B.SilkS")
		)
		(fp_line
			(start -0.7874 0.4064)
			(end 0.7874 0.4064)
			(stroke
				(width 0.1524)
				(type default)
			)
			(layer "B.SilkS")
		)
		(fp_line
			(start 0.7874 -0.4064)
			(end -0.7874 -0.4064)
			(stroke
				(width 0.1524)
				(type default)
			)
			(layer "B.SilkS")
		)
		(fp_line
			(start 0.7874 0.4064)
			(end 0.7874 -0.4064)
			(stroke
				(width 0.1524)
				(type default)
			)
			(layer "B.SilkS")
		)
		(fp_poly
			(pts
				(xy 0.508 0.2794) (xy 0.508 0.2286) (xy 0.635 0.2286) (xy 0.635 -0.254) (xy 0.5334 -0.254) (xy 0.5334 -0.2794)
				(xy -0.5334 -0.2794) (xy -0.5334 -0.254) (xy -0.635 -0.254) (xy -0.635 0.254) (xy -0.5334 0.254)
				(xy -0.5334 0.2794)
			)
			(stroke
				(width 0)
				(type default)
			)
			(fill no)
			(layer "B.CrtYd")
		)
		(pad "1" smd rect
			(at -0.40005 0 180)
			(size 0.4572 0.508)
			(layers "B.Cu" "B.Mask" "B.Paste")
			(net "P3V3_NODE1")
		)
		(pad "2" smd rect
			(at 0.40005 0 180)
			(size 0.4572 0.508)
			(layers "B.Cu" "B.Mask" "B.Paste")
			(net "N21701261")
		)
	)
	(footprint ""
		(layer "B.Cu")
		(at 59.67476 -185.205624 -90)
		(property "Reference" "C682"
			(at -4.15163 -0.200406 270)
			(unlocked yes)
			(layer "B.SilkS")
			(effects
				(font
					(size 0.7874 0.5842)
					(thickness 0.1524)
				)
				(justify left mirror)
			)
		)
		(property "Value" ""
			(at 0 0 90)
			(layer "B.Fab")
			(effects
				(font
					(size 1.27 1.27)
				)
				(justify mirror)
			)
		)
		(duplicate_pad_numbers_are_jumpers no)
		(fp_line
			(start -0.7874 0.4064)
			(end 0.7874 0.4064)
			(stroke
				(width 0.1524)
				(type default)
			)
			(layer "B.SilkS")
		)
		(fp_line
			(start 0.7874 0.4064)
			(end 0.7874 -0.4064)
			(stroke
				(width 0.1524)
				(type default)
			)
			(layer "B.SilkS")
		)
		(fp_line
			(start 0 0.381)
			(end 0 -0.381)
			(stroke
				(width 0.1524)
				(type default)
			)
			(layer "B.SilkS")
		)
		(fp_line
			(start -0.7874 -0.4064)
			(end -0.7874 0.4064)
			(stroke
				(width 0.1524)
				(type default)
			)
			(layer "B.SilkS")
		)
		(fp_line
			(start 0.7874 -0.4064)
			(end -0.7874 -0.4064)
			(stroke
				(width 0.1524)
				(type default)
			)
			(layer "B.SilkS")
		)
		(fp_poly
			(pts
				(xy 0.5334 0.254) (xy 0.635 0.254) (xy 0.635 0.2286) (xy 0.635 -0.254) (xy 0.5334 -0.254) (xy 0.5334 -0.2794)
				(xy -0.5334 -0.2794) (xy -0.5334 -0.254) (xy -0.635 -0.254) (xy -0.635 0.254) (xy -0.5334 0.254)
				(xy -0.5334 0.2794) (xy 0.508 0.2794) (xy 0.5334 0.2794)
			)
			(stroke
				(width 0)
				(type default)
			)
			(fill no)
			(layer "B.CrtYd")
		)
		(pad "1" smd rect
			(at -0.40005 0 90)
			(size 0.4572 0.508)
			(layers "B.Cu" "B.Mask" "B.Paste")
			(net "UART_T1_NODE3_RXD")
		)
		(pad "2" smd rect
			(at 0.40005 0 90)
			(size 0.4572 0.508)
			(layers "B.Cu" "B.Mask" "B.Paste")
			(net "GND")
		)
	)
	(footprint ""
		(layer "B.Cu")
		(at 144.909032 -40.742616 180)
		(property "Reference" "R814"
			(at -1.24714 -17.357344 0)
			(unlocked yes)
			(layer "B.SilkS")
			(effects
				(font
					(size 0.7874 0.5842)
					(thickness 0.1524)
				)
				(justify left mirror)
			)
		)
		(property "Value" ""
			(at 0 0 0)
			(layer "B.Fab")
			(effects
				(font
					(size 1.27 1.27)
				)
				(justify mirror)
			)
		)
		(duplicate_pad_numbers_are_jumpers no)
		(fp_line
			(start 0.7874 0.4064)
			(end 0.7874 -0.4064)
			(stroke
				(width 0.1524)
				(type default)
			)
			(layer "B.SilkS")
		)
		(fp_line
			(start 0.7874 -0.4064)
			(end -0.7874 -0.4064)
			(stroke
				(width 0.1524)
				(type default)
			)
			(layer "B.SilkS")
		)
		(fp_line
			(start -0.7874 0.4064)
			(end 0.7874 0.4064)
			(stroke
				(width 0.1524)
				(type default)
			)
			(layer "B.SilkS")
		)
		(fp_line
			(start -0.7874 -0.4064)
			(end -0.7874 0.4064)
			(stroke
				(width 0.1524)
				(type default)
			)
			(layer "B.SilkS")
		)
		(fp_poly
			(pts
				(xy 0.508 0.2794) (xy 0.508 0.2286) (xy 0.635 0.2286) (xy 0.635 -0.254) (xy 0.5334 -0.254) (xy 0.5334 -0.2794)
				(xy -0.5334 -0.2794) (xy -0.5334 -0.254) (xy -0.635 -0.254) (xy -0.635 0.254) (xy -0.5334 0.254)
				(xy -0.5334 0.2794)
			)
			(stroke
				(width 0)
				(type default)
			)
			(fill no)
			(layer "B.CrtYd")
		)
		(pad "1" smd rect
			(at -0.40005 0)
			(size 0.4572 0.508)
			(layers "B.Cu" "B.Mask" "B.Paste")
			(net "P3V3_NODE1")
		)
		(pad "2" smd rect
			(at 0.40005 0)
			(size 0.4572 0.508)
			(layers "B.Cu" "B.Mask" "B.Paste")
			(net "UART_RI_P1_N")
		)
	)
	(footprint ""
		(layer "B.Cu")
		(at 62.189614 -136.090406)
		(property "Reference" "C274"
			(at -40.642032 52.92217 0)
			(unlocked yes)
			(layer "B.SilkS")
			(effects
				(font
					(size 0.7874 0.5842)
					(thickness 0.1524)
				)
				(justify left mirror)
			)
		)
		(property "Value" ""
			(at 0 0 0)
			(layer "B.Fab")
			(effects
				(font
					(size 1.27 1.27)
				)
				(justify mirror)
			)
		)
		(duplicate_pad_numbers_are_jumpers no)
		(fp_line
			(start -0.7874 -0.4064)
			(end -0.7874 0.4064)
			(stroke
				(width 0.1524)
				(type default)
			)
			(layer "B.SilkS")
		)
		(fp_line
			(start -0.7874 0.4064)
			(end 0.7874 0.4064)
			(stroke
				(width 0.1524)
				(type default)
			)
			(layer "B.SilkS")
		)
		(fp_line
			(start 0 0.381)
			(end 0 -0.381)
			(stroke
				(width 0.1524)
				(type default)
			)
			(layer "B.SilkS")
		)
		(fp_line
			(start 0.7874 -0.4064)
			(end -0.7874 -0.4064)
			(stroke
				(width 0.1524)
				(type default)
			)
			(layer "B.SilkS")
		)
		(fp_line
			(start 0.7874 0.4064)
			(end 0.7874 -0.4064)
			(stroke
				(width 0.1524)
				(type default)
			)
			(layer "B.SilkS")
		)
		(fp_poly
			(pts
				(xy 0.5334 0.254) (xy 0.635 0.254) (xy 0.635 0.2286) (xy 0.635 -0.254) (xy 0.5334 -0.254) (xy 0.5334 -0.2794)
				(xy -0.5334 -0.2794) (xy -0.5334 -0.254) (xy -0.635 -0.254) (xy -0.635 0.254) (xy -0.5334 0.254)
				(xy -0.5334 0.2794) (xy 0.508 0.2794) (xy 0.5334 0.2794)
			)
			(stroke
				(width 0)
				(type default)
			)
			(fill no)
			(layer "B.CrtYd")
		)
		(pad "1" smd rect
			(at -0.40005 0 180)
			(size 0.4572 0.508)
			(layers "B.Cu" "B.Mask" "B.Paste")
			(net "P1V538_BMC_NODE1")
		)
		(pad "2" smd rect
			(at 0.40005 0 180)
			(size 0.4572 0.508)
			(layers "B.Cu" "B.Mask" "B.Paste")
			(net "GND")
		)
	)
	(footprint ""
		(layer "B.Cu")
		(at 54.469538 -88.040718 90)
		(property "Reference" "C91"
			(at 2.538222 0.924052 270)
			(unlocked yes)
			(layer "B.SilkS")
			(effects
				(font
					(size 0.7874 0.5842)
					(thickness 0.1524)
				)
				(justify mirror)
			)
		)
		(property "Value" ""
			(at 0 0 90)
			(layer "B.Fab")
			(effects
				(font
					(size 1.27 1.27)
				)
				(justify mirror)
			)
		)
		(duplicate_pad_numbers_are_jumpers no)
		(fp_line
			(start 1.2954 -0.5842)
			(end -1.2954 -0.5842)
			(stroke
				(width 0.1524)
				(type default)
			)
			(layer "B.SilkS")
		)
		(fp_line
			(start 0 -0.5842)
			(end 0 0.5842)
			(stroke
				(width 0.1524)
				(type default)
			)
			(layer "B.SilkS")
		)
		(fp_line
			(start -1.2954 -0.5842)
			(end -1.2954 0.5842)
			(stroke
				(width 0.1524)
				(type default)
			)
			(layer "B.SilkS")
		)
		(fp_line
			(start 1.2954 0.5842)
			(end 1.2954 -0.5842)
			(stroke
				(width 0.1524)
				(type default)
			)
			(layer "B.SilkS")
		)
		(fp_line
			(start -1.2954 0.5842)
			(end 1.2954 0.5842)
			(stroke
				(width 0.1524)
				(type default)
			)
			(layer "B.SilkS")
		)
		(fp_poly
			(pts
				(xy -0.8636 -0.4572) (xy -0.8636 -0.3556) (xy -1.143 -0.3556) (xy -1.143 0.3556) (xy -0.8636 0.3556)
				(xy -0.8636 0.4572) (xy 0.8636 0.4572) (xy 0.8636 0.3556) (xy 1.143 0.3556) (xy 1.143 -0.3556) (xy 0.8636 -0.3556)
				(xy 0.8636 -0.4572)
			)
			(stroke
				(width 0)
				(type default)
			)
			(fill no)
			(layer "B.CrtYd")
		)
		(fp_line
			(start 0.884936 -0.504952)
			(end -0.884936 -0.504952)
			(stroke
				(width 0.1)
				(type default)
			)
			(layer "B.Fab")
		)
		(fp_line
			(start -0.884936 -0.504952)
			(end -0.884936 0.504952)
			(stroke
				(width 0.1)
				(type default)
			)
			(layer "B.Fab")
		)
		(fp_line
			(start 0.884936 0.504952)
			(end 0.884936 -0.504952)
			(stroke
				(width 0.1)
				(type default)
			)
			(layer "B.Fab")
		)
		(fp_line
			(start -0.884936 0.504952)
			(end 0.884936 0.504952)
			(stroke
				(width 0.1)
				(type default)
			)
			(layer "B.Fab")
		)
		(pad "1" smd rect
			(at -0.7366 0 180)
			(size 0.7112 0.8128)
			(layers "B.Cu" "B.Mask" "B.Paste")
			(net "P1V8_NODE1")
		)
		(pad "2" smd rect
			(at 0.7366 0 180)
			(size 0.7112 0.8128)
			(layers "B.Cu" "B.Mask" "B.Paste")
			(net "GND")
		)
	)
	(footprint ""
		(layer "B.Cu")
		(at 41.670732 -94.40037 90)
		(property "Reference" "R121"
			(at -4.703318 -4.56311 270)
			(unlocked yes)
			(layer "B.SilkS")
			(effects
				(font
					(size 0.7874 0.5842)
					(thickness 0.1524)
				)
				(justify left mirror)
			)
		)
		(property "Value" ""
			(at 0 0 90)
			(layer "B.Fab")
			(effects
				(font
					(size 1.27 1.27)
				)
				(justify mirror)
			)
		)
		(duplicate_pad_numbers_are_jumpers no)
		(fp_line
			(start 0.7874 -0.4064)
			(end -0.7874 -0.4064)
			(stroke
				(width 0.1524)
				(type default)
			)
			(layer "B.SilkS")
		)
		(fp_line
			(start -0.7874 -0.4064)
			(end -0.7874 0.4064)
			(stroke
				(width 0.1524)
				(type default)
			)
			(layer "B.SilkS")
		)
		(fp_line
			(start 0.7874 0.4064)
			(end 0.7874 -0.4064)
			(stroke
				(width 0.1524)
				(type default)
			)
			(layer "B.SilkS")
		)
		(fp_line
			(start -0.7874 0.4064)
			(end 0.7874 0.4064)
			(stroke
				(width 0.1524)
				(type default)
			)
			(layer "B.SilkS")
		)
		(fp_poly
			(pts
				(xy 0.508 0.2794) (xy 0.508 0.2286) (xy 0.635 0.2286) (xy 0.635 -0.254) (xy 0.5334 -0.254) (xy 0.5334 -0.2794)
				(xy -0.5334 -0.2794) (xy -0.5334 -0.254) (xy -0.635 -0.254) (xy -0.635 0.254) (xy -0.5334 0.254)
				(xy -0.5334 0.2794)
			)
			(stroke
				(width 0)
				(type default)
			)
			(fill no)
			(layer "B.CrtYd")
		)
		(pad "1" smd rect
			(at -0.40005 0 270)
			(size 0.4572 0.508)
			(layers "B.Cu" "B.Mask" "B.Paste")
			(net "SMB_CPU_NODE1_XDP_CLK_R")
		)
		(pad "2" smd rect
			(at 0.40005 0 270)
			(size 0.4572 0.508)
			(layers "B.Cu" "B.Mask" "B.Paste")
			(net "SMB_CPU_NODE1_XDP_CLK")
		)
	)
	(footprint ""
		(layer "B.Cu")
		(at 125.892052 -144.22755 180)
		(property "Reference" "C896"
			(at 3.260598 3.312414 0)
			(unlocked yes)
			(layer "B.SilkS")
			(effects
				(font
					(size 0.7874 0.5842)
					(thickness 0.1524)
				)
				(justify left mirror)
			)
		)
		(property "Value" ""
			(at 0 0 0)
			(layer "B.Fab")
			(effects
				(font
					(size 1.27 1.27)
				)
				(justify mirror)
			)
		)
		(duplicate_pad_numbers_are_jumpers no)
		(fp_line
			(start 0.7874 0.4064)
			(end 0.7874 -0.4064)
			(stroke
				(width 0.1524)
				(type default)
			)
			(layer "B.SilkS")
		)
		(fp_line
			(start 0.7874 -0.4064)
			(end -0.7874 -0.4064)
			(stroke
				(width 0.1524)
				(type default)
			)
			(layer "B.SilkS")
		)
		(fp_line
			(start 0 0.381)
			(end 0 -0.381)
			(stroke
				(width 0.1524)
				(type default)
			)
			(layer "B.SilkS")
		)
		(fp_line
			(start -0.7874 0.4064)
			(end 0.7874 0.4064)
			(stroke
				(width 0.1524)
				(type default)
			)
			(layer "B.SilkS")
		)
		(fp_line
			(start -0.7874 -0.4064)
			(end -0.7874 0.4064)
			(stroke
				(width 0.1524)
				(type default)
			)
			(layer "B.SilkS")
		)
		(fp_poly
			(pts
				(xy 0.5334 0.254) (xy 0.635 0.254) (xy 0.635 0.2286) (xy 0.635 -0.254) (xy 0.5334 -0.254) (xy 0.5334 -0.2794)
				(xy -0.5334 -0.2794) (xy -0.5334 -0.254) (xy -0.635 -0.254) (xy -0.635 0.254) (xy -0.5334 0.254)
				(xy -0.5334 0.2794) (xy 0.508 0.2794) (xy 0.5334 0.2794)
			)
			(stroke
				(width 0)
				(type default)
			)
			(fill no)
			(layer "B.CrtYd")
		)
		(pad "1" smd rect
			(at -0.40005 0)
			(size 0.4572 0.508)
			(layers "B.Cu" "B.Mask" "B.Paste")
			(net "P1V0_PCI_SW_A")
		)
		(pad "2" smd rect
			(at 0.40005 0)
			(size 0.4572 0.508)
			(layers "B.Cu" "B.Mask" "B.Paste")
			(net "GND")
		)
	)
	(footprint ""
		(layer "B.Cu")
		(at 121.72061 -35.398456 180)
		(property "Reference" "R1201"
			(at 3.310636 -0.941578 0)
			(unlocked yes)
			(layer "B.SilkS")
			(effects
				(font
					(size 0.7874 0.5842)
					(thickness 0.1524)
				)
				(justify left mirror)
			)
		)
		(property "Value" ""
			(at 0 0 0)
			(layer "B.Fab")
			(effects
				(font
					(size 1.27 1.27)
				)
				(justify mirror)
			)
		)
		(duplicate_pad_numbers_are_jumpers no)
		(fp_line
			(start 0.7874 0.4064)
			(end 0.7874 -0.4064)
			(stroke
				(width 0.1524)
				(type default)
			)
			(layer "B.SilkS")
		)
		(fp_line
			(start 0.7874 -0.4064)
			(end -0.7874 -0.4064)
			(stroke
				(width 0.1524)
				(type default)
			)
			(layer "B.SilkS")
		)
		(fp_line
			(start -0.7874 0.4064)
			(end 0.7874 0.4064)
			(stroke
				(width 0.1524)
				(type default)
			)
			(layer "B.SilkS")
		)
		(fp_line
			(start -0.7874 -0.4064)
			(end -0.7874 0.4064)
			(stroke
				(width 0.1524)
				(type default)
			)
			(layer "B.SilkS")
		)
		(fp_poly
			(pts
				(xy 0.508 0.2794) (xy 0.508 0.2286) (xy 0.635 0.2286) (xy 0.635 -0.254) (xy 0.5334 -0.254) (xy 0.5334 -0.2794)
				(xy -0.5334 -0.2794) (xy -0.5334 -0.254) (xy -0.635 -0.254) (xy -0.635 0.254) (xy -0.5334 0.254)
				(xy -0.5334 0.2794)
			)
			(stroke
				(width 0)
				(type default)
			)
			(fill no)
			(layer "B.CrtYd")
		)
		(pad "1" smd rect
			(at -0.40005 0)
			(size 0.4572 0.508)
			(layers "B.Cu" "B.Mask" "B.Paste")
			(net "SIO_JTAG_CPLD3_TMS_R")
		)
		(pad "2" smd rect
			(at 0.40005 0)
			(size 0.4572 0.508)
			(layers "B.Cu" "B.Mask" "B.Paste")
			(net "P3V3_NODE1")
		)
	)
	(footprint ""
		(layer "B.Cu")
		(at 146.322796 -59.96813 90)
		(property "Reference" "C339"
			(at 1.050036 -0.288798 270)
			(unlocked yes)
			(layer "B.SilkS")
			(effects
				(font
					(size 0.7874 0.5842)
					(thickness 0.1524)
				)
				(justify left mirror)
			)
		)
		(property "Value" ""
			(at 0 0 90)
			(layer "B.Fab")
			(effects
				(font
					(size 1.27 1.27)
				)
				(justify mirror)
			)
		)
		(duplicate_pad_numbers_are_jumpers no)
		(fp_line
			(start 0.7874 -0.4064)
			(end -0.7874 -0.4064)
			(stroke
				(width 0.1524)
				(type default)
			)
			(layer "B.SilkS")
		)
		(fp_line
			(start -0.7874 -0.4064)
			(end -0.7874 0.4064)
			(stroke
				(width 0.1524)
				(type default)
			)
			(layer "B.SilkS")
		)
		(fp_line
			(start 0 0.381)
			(end 0 -0.381)
			(stroke
				(width 0.1524)
				(type default)
			)
			(layer "B.SilkS")
		)
		(fp_line
			(start 0.7874 0.4064)
			(end 0.7874 -0.4064)
			(stroke
				(width 0.1524)
				(type default)
			)
			(layer "B.SilkS")
		)
		(fp_line
			(start -0.7874 0.4064)
			(end 0.7874 0.4064)
			(stroke
				(width 0.1524)
				(type default)
			)
			(layer "B.SilkS")
		)
		(fp_poly
			(pts
				(xy 0.5334 0.254) (xy 0.635 0.254) (xy 0.635 0.2286) (xy 0.635 -0.254) (xy 0.5334 -0.254) (xy 0.5334 -0.2794)
				(xy -0.5334 -0.2794) (xy -0.5334 -0.254) (xy -0.635 -0.254) (xy -0.635 0.254) (xy -0.5334 0.254)
				(xy -0.5334 0.2794) (xy 0.508 0.2794) (xy 0.5334 0.2794)
			)
			(stroke
				(width 0)
				(type default)
			)
			(fill no)
			(layer "B.CrtYd")
		)
		(pad "1" smd rect
			(at -0.40005 0 270)
			(size 0.4572 0.508)
			(layers "B.Cu" "B.Mask" "B.Paste")
			(net "P1V0_SATA")
		)
		(pad "2" smd rect
			(at 0.40005 0 270)
			(size 0.4572 0.508)
			(layers "B.Cu" "B.Mask" "B.Paste")
			(net "GND")
		)
	)
	(footprint ""
		(layer "B.Cu")
		(at 133.597396 -163.884356 180)
		(property "Reference" "R1309"
			(at -1.443228 -0.335534 270)
			(unlocked yes)
			(layer "B.SilkS")
			(effects
				(font
					(size 0.7874 0.5842)
					(thickness 0.1524)
				)
				(justify left mirror)
			)
		)
		(property "Value" ""
			(at 0 0 0)
			(layer "B.Fab")
			(effects
				(font
					(size 1.27 1.27)
				)
				(justify mirror)
			)
		)
		(duplicate_pad_numbers_are_jumpers no)
		(fp_line
			(start 0.7874 0.4064)
			(end 0.7874 -0.4064)
			(stroke
				(width 0.1524)
				(type default)
			)
			(layer "B.SilkS")
		)
		(fp_line
			(start 0.7874 -0.4064)
			(end -0.7874 -0.4064)
			(stroke
				(width 0.1524)
				(type default)
			)
			(layer "B.SilkS")
		)
		(fp_line
			(start -0.7874 0.4064)
			(end 0.7874 0.4064)
			(stroke
				(width 0.1524)
				(type default)
			)
			(layer "B.SilkS")
		)
		(fp_line
			(start -0.7874 -0.4064)
			(end -0.7874 0.4064)
			(stroke
				(width 0.1524)
				(type default)
			)
			(layer "B.SilkS")
		)
		(fp_poly
			(pts
				(xy 0.508 0.2794) (xy 0.508 0.2286) (xy 0.635 0.2286) (xy 0.635 -0.254) (xy 0.5334 -0.254) (xy 0.5334 -0.2794)
				(xy -0.5334 -0.2794) (xy -0.5334 -0.254) (xy -0.635 -0.254) (xy -0.635 0.254) (xy -0.5334 0.254)
				(xy -0.5334 0.2794)
			)
			(stroke
				(width 0)
				(type default)
			)
			(fill no)
			(layer "B.CrtYd")
		)
		(pad "1" smd rect
			(at -0.40005 0)
			(size 0.4572 0.508)
			(layers "B.Cu" "B.Mask" "B.Paste")
			(net "P3V3_NODE1")
		)
		(pad "2" smd rect
			(at 0.40005 0)
			(size 0.4572 0.508)
			(layers "B.Cu" "B.Mask" "B.Paste")
			(net "TACKOVER_EN")
		)
	)
	(footprint ""
		(layer "B.Cu")
		(at 61.702442 -178.6001 180)
		(property "Reference" "R686"
			(at -1.487678 1.11633 0)
			(unlocked yes)
			(layer "B.SilkS")
			(effects
				(font
					(size 0.7874 0.5842)
					(thickness 0.1524)
				)
				(justify left mirror)
			)
		)
		(property "Value" ""
			(at 0 0 0)
			(layer "B.Fab")
			(effects
				(font
					(size 1.27 1.27)
				)
				(justify mirror)
			)
		)
		(duplicate_pad_numbers_are_jumpers no)
		(fp_line
			(start 0.7874 0.4064)
			(end 0.7874 -0.4064)
			(stroke
				(width 0.1524)
				(type default)
			)
			(layer "B.SilkS")
		)
		(fp_line
			(start 0.7874 -0.4064)
			(end -0.7874 -0.4064)
			(stroke
				(width 0.1524)
				(type default)
			)
			(layer "B.SilkS")
		)
		(fp_line
			(start -0.7874 0.4064)
			(end 0.7874 0.4064)
			(stroke
				(width 0.1524)
				(type default)
			)
			(layer "B.SilkS")
		)
		(fp_line
			(start -0.7874 -0.4064)
			(end -0.7874 0.4064)
			(stroke
				(width 0.1524)
				(type default)
			)
			(layer "B.SilkS")
		)
		(fp_poly
			(pts
				(xy 0.508 0.2794) (xy 0.508 0.2286) (xy 0.635 0.2286) (xy 0.635 -0.254) (xy 0.5334 -0.254) (xy 0.5334 -0.2794)
				(xy -0.5334 -0.2794) (xy -0.5334 -0.254) (xy -0.635 -0.254) (xy -0.635 0.254) (xy -0.5334 0.254)
				(xy -0.5334 0.2794)
			)
			(stroke
				(width 0)
				(type default)
			)
			(fill no)
			(layer "B.CrtYd")
		)
		(pad "1" smd rect
			(at -0.40005 0)
			(size 0.4572 0.508)
			(layers "B.Cu" "B.Mask" "B.Paste")
			(net "P3V3_NODE1")
		)
		(pad "2" smd rect
			(at 0.40005 0)
			(size 0.4572 0.508)
			(layers "B.Cu" "B.Mask" "B.Paste")
			(net "N21700864")
		)
	)
	(footprint ""
		(layer "B.Cu")
		(at 141.233652 -138.23315)
		(property "Reference" "C890"
			(at 3.977894 -3.295142 0)
			(unlocked yes)
			(layer "B.SilkS")
			(effects
				(font
					(size 0.7874 0.5842)
					(thickness 0.1524)
				)
				(justify left mirror)
			)
		)
		(property "Value" ""
			(at 0 0 0)
			(layer "B.Fab")
			(effects
				(font
					(size 1.27 1.27)
				)
				(justify mirror)
			)
		)
		(duplicate_pad_numbers_are_jumpers no)
		(fp_line
			(start -0.7874 -0.4064)
			(end -0.7874 0.4064)
			(stroke
				(width 0.1524)
				(type default)
			)
			(layer "B.SilkS")
		)
		(fp_line
			(start -0.7874 0.4064)
			(end 0.7874 0.4064)
			(stroke
				(width 0.1524)
				(type default)
			)
			(layer "B.SilkS")
		)
		(fp_line
			(start 0 0.381)
			(end 0 -0.381)
			(stroke
				(width 0.1524)
				(type default)
			)
			(layer "B.SilkS")
		)
		(fp_line
			(start 0.7874 -0.4064)
			(end -0.7874 -0.4064)
			(stroke
				(width 0.1524)
				(type default)
			)
			(layer "B.SilkS")
		)
		(fp_line
			(start 0.7874 0.4064)
			(end 0.7874 -0.4064)
			(stroke
				(width 0.1524)
				(type default)
			)
			(layer "B.SilkS")
		)
		(fp_poly
			(pts
				(xy 0.5334 0.254) (xy 0.635 0.254) (xy 0.635 0.2286) (xy 0.635 -0.254) (xy 0.5334 -0.254) (xy 0.5334 -0.2794)
				(xy -0.5334 -0.2794) (xy -0.5334 -0.254) (xy -0.635 -0.254) (xy -0.635 0.254) (xy -0.5334 0.254)
				(xy -0.5334 0.2794) (xy 0.508 0.2794) (xy 0.5334 0.2794)
			)
			(stroke
				(width 0)
				(type default)
			)
			(fill no)
			(layer "B.CrtYd")
		)
		(pad "1" smd rect
			(at -0.40005 0 180)
			(size 0.4572 0.508)
			(layers "B.Cu" "B.Mask" "B.Paste")
			(net "P1V0_NODE1")
		)
		(pad "2" smd rect
			(at 0.40005 0 180)
			(size 0.4572 0.508)
			(layers "B.Cu" "B.Mask" "B.Paste")
			(net "GND")
		)
	)
	(footprint ""
		(layer "B.Cu")
		(at 76.7461 -163.120832 180)
		(property "Reference" "R793"
			(at 2.647188 -0.339852 0)
			(unlocked yes)
			(layer "B.SilkS")
			(effects
				(font
					(size 0.7874 0.5842)
					(thickness 0.1524)
				)
				(justify left mirror)
			)
		)
		(property "Value" ""
			(at 0 0 0)
			(layer "B.Fab")
			(effects
				(font
					(size 1.27 1.27)
				)
				(justify mirror)
			)
		)
		(duplicate_pad_numbers_are_jumpers no)
		(fp_line
			(start 0.7874 0.4064)
			(end 0.7874 -0.4064)
			(stroke
				(width 0.1524)
				(type default)
			)
			(layer "B.SilkS")
		)
		(fp_line
			(start 0.7874 -0.4064)
			(end -0.7874 -0.4064)
			(stroke
				(width 0.1524)
				(type default)
			)
			(layer "B.SilkS")
		)
		(fp_line
			(start -0.7874 0.4064)
			(end 0.7874 0.4064)
			(stroke
				(width 0.1524)
				(type default)
			)
			(layer "B.SilkS")
		)
		(fp_line
			(start -0.7874 -0.4064)
			(end -0.7874 0.4064)
			(stroke
				(width 0.1524)
				(type default)
			)
			(layer "B.SilkS")
		)
		(fp_poly
			(pts
				(xy 0.508 0.2794) (xy 0.508 0.2286) (xy 0.635 0.2286) (xy 0.635 -0.254) (xy 0.5334 -0.254) (xy 0.5334 -0.2794)
				(xy -0.5334 -0.2794) (xy -0.5334 -0.254) (xy -0.635 -0.254) (xy -0.635 0.254) (xy -0.5334 0.254)
				(xy -0.5334 0.2794)
			)
			(stroke
				(width 0)
				(type default)
			)
			(fill no)
			(layer "B.CrtYd")
		)
		(pad "1" smd rect
			(at -0.40005 0)
			(size 0.4572 0.508)
			(layers "B.Cu" "B.Mask" "B.Paste")
			(net "CPLD_WDT2_R")
		)
		(pad "2" smd rect
			(at 0.40005 0)
			(size 0.4572 0.508)
			(layers "B.Cu" "B.Mask" "B.Paste")
			(net "P3V3_NODE1")
		)
	)
	(footprint ""
		(layer "B.Cu")
		(at 153.604214 -64.971422 -90)
		(property "Reference" "C344"
			(at 2.01422 -5.923026 270)
			(unlocked yes)
			(layer "B.SilkS")
			(effects
				(font
					(size 0.7874 0.5842)
					(thickness 0.1524)
				)
				(justify left mirror)
			)
		)
		(property "Value" ""
			(at 0 0 90)
			(layer "B.Fab")
			(effects
				(font
					(size 1.27 1.27)
				)
				(justify mirror)
			)
		)
		(duplicate_pad_numbers_are_jumpers no)
		(fp_line
			(start -0.7874 0.4064)
			(end 0.7874 0.4064)
			(stroke
				(width 0.1524)
				(type default)
			)
			(layer "B.SilkS")
		)
		(fp_line
			(start 0.7874 0.4064)
			(end 0.7874 -0.4064)
			(stroke
				(width 0.1524)
				(type default)
			)
			(layer "B.SilkS")
		)
		(fp_line
			(start 0 0.381)
			(end 0 -0.381)
			(stroke
				(width 0.1524)
				(type default)
			)
			(layer "B.SilkS")
		)
		(fp_line
			(start -0.7874 -0.4064)
			(end -0.7874 0.4064)
			(stroke
				(width 0.1524)
				(type default)
			)
			(layer "B.SilkS")
		)
		(fp_line
			(start 0.7874 -0.4064)
			(end -0.7874 -0.4064)
			(stroke
				(width 0.1524)
				(type default)
			)
			(layer "B.SilkS")
		)
		(fp_poly
			(pts
				(xy 0.5334 0.254) (xy 0.635 0.254) (xy 0.635 0.2286) (xy 0.635 -0.254) (xy 0.5334 -0.254) (xy 0.5334 -0.2794)
				(xy -0.5334 -0.2794) (xy -0.5334 -0.254) (xy -0.635 -0.254) (xy -0.635 0.254) (xy -0.5334 0.254)
				(xy -0.5334 0.2794) (xy 0.508 0.2794) (xy 0.5334 0.2794)
			)
			(stroke
				(width 0)
				(type default)
			)
			(fill no)
			(layer "B.CrtYd")
		)
		(pad "1" smd rect
			(at -0.40005 0 90)
			(size 0.4572 0.508)
			(layers "B.Cu" "B.Mask" "B.Paste")
			(net "P1V8_SATA_VAA2_0_NODE1")
		)
		(pad "2" smd rect
			(at 0.40005 0 90)
			(size 0.4572 0.508)
			(layers "B.Cu" "B.Mask" "B.Paste")
			(net "GND")
		)
	)
	(footprint ""
		(layer "B.Cu")
		(at 134.22376 -187.872624 -90)
		(property "Reference" "C722"
			(at -4.565396 1.361948 270)
			(unlocked yes)
			(layer "B.SilkS")
			(effects
				(font
					(size 0.7874 0.5842)
					(thickness 0.1524)
				)
				(justify left mirror)
			)
		)
		(property "Value" ""
			(at 0 0 90)
			(layer "B.Fab")
			(effects
				(font
					(size 1.27 1.27)
				)
				(justify mirror)
			)
		)
		(duplicate_pad_numbers_are_jumpers no)
		(fp_line
			(start -0.7874 0.4064)
			(end 0.7874 0.4064)
			(stroke
				(width 0.1524)
				(type default)
			)
			(layer "B.SilkS")
		)
		(fp_line
			(start 0.7874 0.4064)
			(end 0.7874 -0.4064)
			(stroke
				(width 0.1524)
				(type default)
			)
			(layer "B.SilkS")
		)
		(fp_line
			(start 0 0.381)
			(end 0 -0.381)
			(stroke
				(width 0.1524)
				(type default)
			)
			(layer "B.SilkS")
		)
		(fp_line
			(start -0.7874 -0.4064)
			(end -0.7874 0.4064)
			(stroke
				(width 0.1524)
				(type default)
			)
			(layer "B.SilkS")
		)
		(fp_line
			(start 0.7874 -0.4064)
			(end -0.7874 -0.4064)
			(stroke
				(width 0.1524)
				(type default)
			)
			(layer "B.SilkS")
		)
		(fp_poly
			(pts
				(xy 0.5334 0.254) (xy 0.635 0.254) (xy 0.635 0.2286) (xy 0.635 -0.254) (xy 0.5334 -0.254) (xy 0.5334 -0.2794)
				(xy -0.5334 -0.2794) (xy -0.5334 -0.254) (xy -0.635 -0.254) (xy -0.635 0.254) (xy -0.5334 0.254)
				(xy -0.5334 0.2794) (xy 0.508 0.2794) (xy 0.5334 0.2794)
			)
			(stroke
				(width 0)
				(type default)
			)
			(fill no)
			(layer "B.CrtYd")
		)
		(pad "1" smd rect
			(at -0.40005 0 90)
			(size 0.4572 0.508)
			(layers "B.Cu" "B.Mask" "B.Paste")
			(net "UART_T9_NODE1_TXD_R")
		)
		(pad "2" smd rect
			(at 0.40005 0 90)
			(size 0.4572 0.508)
			(layers "B.Cu" "B.Mask" "B.Paste")
			(net "GND")
		)
	)
	(footprint ""
		(layer "B.Cu")
		(at 141.589252 -46.487842)
		(property "Reference" "C481"
			(at 3.907028 -0.084836 0)
			(unlocked yes)
			(layer "B.SilkS")
			(effects
				(font
					(size 0.7874 0.5842)
					(thickness 0.1524)
				)
				(justify left mirror)
			)
		)
		(property "Value" ""
			(at 0 0 0)
			(layer "B.Fab")
			(effects
				(font
					(size 1.27 1.27)
				)
				(justify mirror)
			)
		)
		(duplicate_pad_numbers_are_jumpers no)
		(fp_line
			(start -0.7874 -0.4064)
			(end -0.7874 0.4064)
			(stroke
				(width 0.1524)
				(type default)
			)
			(layer "B.SilkS")
		)
		(fp_line
			(start -0.7874 0.4064)
			(end 0.7874 0.4064)
			(stroke
				(width 0.1524)
				(type default)
			)
			(layer "B.SilkS")
		)
		(fp_line
			(start 0 0.381)
			(end 0 -0.381)
			(stroke
				(width 0.1524)
				(type default)
			)
			(layer "B.SilkS")
		)
		(fp_line
			(start 0.7874 -0.4064)
			(end -0.7874 -0.4064)
			(stroke
				(width 0.1524)
				(type default)
			)
			(layer "B.SilkS")
		)
		(fp_line
			(start 0.7874 0.4064)
			(end 0.7874 -0.4064)
			(stroke
				(width 0.1524)
				(type default)
			)
			(layer "B.SilkS")
		)
		(fp_poly
			(pts
				(xy 0.5334 0.254) (xy 0.635 0.254) (xy 0.635 0.2286) (xy 0.635 -0.254) (xy 0.5334 -0.254) (xy 0.5334 -0.2794)
				(xy -0.5334 -0.2794) (xy -0.5334 -0.254) (xy -0.635 -0.254) (xy -0.635 0.254) (xy -0.5334 0.254)
				(xy -0.5334 0.2794) (xy 0.508 0.2794) (xy 0.5334 0.2794)
			)
			(stroke
				(width 0)
				(type default)
			)
			(fill no)
			(layer "B.CrtYd")
		)
		(pad "1" smd rect
			(at -0.40005 0 180)
			(size 0.4572 0.508)
			(layers "B.Cu" "B.Mask" "B.Paste")
			(net "P5V_NODE1")
		)
		(pad "2" smd rect
			(at 0.40005 0 180)
			(size 0.4572 0.508)
			(layers "B.Cu" "B.Mask" "B.Paste")
			(net "GND")
		)
	)
	(footprint ""
		(layer "B.Cu")
		(at 120.596914 -166.805102)
		(property "Reference" "R1211"
			(at 0.773938 -2.74447 0)
			(unlocked yes)
			(layer "B.SilkS")
			(effects
				(font
					(size 0.7874 0.5842)
					(thickness 0.1524)
				)
				(justify left mirror)
			)
		)
		(property "Value" ""
			(at 0 0 0)
			(layer "B.Fab")
			(effects
				(font
					(size 1.27 1.27)
				)
				(justify mirror)
			)
		)
		(duplicate_pad_numbers_are_jumpers no)
		(fp_line
			(start -0.7874 -0.4064)
			(end -0.7874 0.4064)
			(stroke
				(width 0.1524)
				(type default)
			)
			(layer "B.SilkS")
		)
		(fp_line
			(start -0.7874 0.4064)
			(end 0.7874 0.4064)
			(stroke
				(width 0.1524)
				(type default)
			)
			(layer "B.SilkS")
		)
		(fp_line
			(start 0.7874 -0.4064)
			(end -0.7874 -0.4064)
			(stroke
				(width 0.1524)
				(type default)
			)
			(layer "B.SilkS")
		)
		(fp_line
			(start 0.7874 0.4064)
			(end 0.7874 -0.4064)
			(stroke
				(width 0.1524)
				(type default)
			)
			(layer "B.SilkS")
		)
		(fp_poly
			(pts
				(xy 0.508 0.2794) (xy 0.508 0.2286) (xy 0.635 0.2286) (xy 0.635 -0.254) (xy 0.5334 -0.254) (xy 0.5334 -0.2794)
				(xy -0.5334 -0.2794) (xy -0.5334 -0.254) (xy -0.635 -0.254) (xy -0.635 0.254) (xy -0.5334 0.254)
				(xy -0.5334 0.2794)
			)
			(stroke
				(width 0)
				(type default)
			)
			(fill no)
			(layer "B.CrtYd")
		)
		(pad "1" smd rect
			(at -0.40005 0 180)
			(size 0.4572 0.508)
			(layers "B.Cu" "B.Mask" "B.Paste")
			(net "FAN_MAX_CTRL")
		)
		(pad "2" smd rect
			(at 0.40005 0 180)
			(size 0.4572 0.508)
			(layers "B.Cu" "B.Mask" "B.Paste")
			(net "P3V3_NODE1")
		)
	)
	(footprint ""
		(layer "B.Cu")
		(at 110.72876 -188.126624 -90)
		(property "Reference" "C733"
			(at -4.080256 -0.71755 270)
			(unlocked yes)
			(layer "B.SilkS")
			(effects
				(font
					(size 0.7874 0.5842)
					(thickness 0.1524)
				)
				(justify left mirror)
			)
		)
		(property "Value" ""
			(at 0 0 90)
			(layer "B.Fab")
			(effects
				(font
					(size 1.27 1.27)
				)
				(justify mirror)
			)
		)
		(duplicate_pad_numbers_are_jumpers no)
		(fp_line
			(start -0.7874 0.4064)
			(end 0.7874 0.4064)
			(stroke
				(width 0.1524)
				(type default)
			)
			(layer "B.SilkS")
		)
		(fp_line
			(start 0.7874 0.4064)
			(end 0.7874 -0.4064)
			(stroke
				(width 0.1524)
				(type default)
			)
			(layer "B.SilkS")
		)
		(fp_line
			(start 0 0.381)
			(end 0 -0.381)
			(stroke
				(width 0.1524)
				(type default)
			)
			(layer "B.SilkS")
		)
		(fp_line
			(start -0.7874 -0.4064)
			(end -0.7874 0.4064)
			(stroke
				(width 0.1524)
				(type default)
			)
			(layer "B.SilkS")
		)
		(fp_line
			(start 0.7874 -0.4064)
			(end -0.7874 -0.4064)
			(stroke
				(width 0.1524)
				(type default)
			)
			(layer "B.SilkS")
		)
		(fp_poly
			(pts
				(xy 0.5334 0.254) (xy 0.635 0.254) (xy 0.635 0.2286) (xy 0.635 -0.254) (xy 0.5334 -0.254) (xy 0.5334 -0.2794)
				(xy -0.5334 -0.2794) (xy -0.5334 -0.254) (xy -0.635 -0.254) (xy -0.635 0.254) (xy -0.5334 0.254)
				(xy -0.5334 0.2794) (xy 0.508 0.2794) (xy 0.5334 0.2794)
			)
			(stroke
				(width 0)
				(type default)
			)
			(fill no)
			(layer "B.CrtYd")
		)
		(pad "1" smd rect
			(at -0.40005 0 90)
			(size 0.4572 0.508)
			(layers "B.Cu" "B.Mask" "B.Paste")
			(net "UART_T7_NODE3_TXD_R")
		)
		(pad "2" smd rect
			(at 0.40005 0 90)
			(size 0.4572 0.508)
			(layers "B.Cu" "B.Mask" "B.Paste")
			(net "GND")
		)
	)
	(footprint ""
		(layer "B.Cu")
		(at 69.326252 -135.489188 180)
		(property "Reference" "C281"
			(at 35.998912 -52.76469 0)
			(unlocked yes)
			(layer "B.SilkS")
			(effects
				(font
					(size 0.7874 0.5842)
					(thickness 0.1524)
				)
				(justify left mirror)
			)
		)
		(property "Value" ""
			(at 0 0 0)
			(layer "B.Fab")
			(effects
				(font
					(size 1.27 1.27)
				)
				(justify mirror)
			)
		)
		(duplicate_pad_numbers_are_jumpers no)
		(fp_line
			(start 0.7874 0.4064)
			(end 0.7874 -0.4064)
			(stroke
				(width 0.1524)
				(type default)
			)
			(layer "B.SilkS")
		)
		(fp_line
			(start 0.7874 -0.4064)
			(end -0.7874 -0.4064)
			(stroke
				(width 0.1524)
				(type default)
			)
			(layer "B.SilkS")
		)
		(fp_line
			(start 0 0.381)
			(end 0 -0.381)
			(stroke
				(width 0.1524)
				(type default)
			)
			(layer "B.SilkS")
		)
		(fp_line
			(start -0.7874 0.4064)
			(end 0.7874 0.4064)
			(stroke
				(width 0.1524)
				(type default)
			)
			(layer "B.SilkS")
		)
		(fp_line
			(start -0.7874 -0.4064)
			(end -0.7874 0.4064)
			(stroke
				(width 0.1524)
				(type default)
			)
			(layer "B.SilkS")
		)
		(fp_poly
			(pts
				(xy 0.5334 0.254) (xy 0.635 0.254) (xy 0.635 0.2286) (xy 0.635 -0.254) (xy 0.5334 -0.254) (xy 0.5334 -0.2794)
				(xy -0.5334 -0.2794) (xy -0.5334 -0.254) (xy -0.635 -0.254) (xy -0.635 0.254) (xy -0.5334 0.254)
				(xy -0.5334 0.2794) (xy 0.508 0.2794) (xy 0.5334 0.2794)
			)
			(stroke
				(width 0)
				(type default)
			)
			(fill no)
			(layer "B.CrtYd")
		)
		(pad "1" smd rect
			(at -0.40005 0)
			(size 0.4572 0.508)
			(layers "B.Cu" "B.Mask" "B.Paste")
			(net "P3V3_NODE1")
		)
		(pad "2" smd rect
			(at 0.40005 0)
			(size 0.4572 0.508)
			(layers "B.Cu" "B.Mask" "B.Paste")
			(net "GND")
		)
	)
	(footprint ""
		(layer "B.Cu")
		(at 78.83144 -176.569624 180)
		(property "Reference" "R695"
			(at -30.562296 -20.108164 0)
			(unlocked yes)
			(layer "B.SilkS")
			(effects
				(font
					(size 0.7874 0.5842)
					(thickness 0.1524)
				)
				(justify left mirror)
			)
		)
		(property "Value" ""
			(at 0 0 0)
			(layer "B.Fab")
			(effects
				(font
					(size 1.27 1.27)
				)
				(justify mirror)
			)
		)
		(duplicate_pad_numbers_are_jumpers no)
		(fp_line
			(start 0.7874 0.4064)
			(end 0.7874 -0.4064)
			(stroke
				(width 0.1524)
				(type default)
			)
			(layer "B.SilkS")
		)
		(fp_line
			(start 0.7874 -0.4064)
			(end -0.7874 -0.4064)
			(stroke
				(width 0.1524)
				(type default)
			)
			(layer "B.SilkS")
		)
		(fp_line
			(start -0.7874 0.4064)
			(end 0.7874 0.4064)
			(stroke
				(width 0.1524)
				(type default)
			)
			(layer "B.SilkS")
		)
		(fp_line
			(start -0.7874 -0.4064)
			(end -0.7874 0.4064)
			(stroke
				(width 0.1524)
				(type default)
			)
			(layer "B.SilkS")
		)
		(fp_poly
			(pts
				(xy 0.508 0.2794) (xy 0.508 0.2286) (xy 0.635 0.2286) (xy 0.635 -0.254) (xy 0.5334 -0.254) (xy 0.5334 -0.2794)
				(xy -0.5334 -0.2794) (xy -0.5334 -0.254) (xy -0.635 -0.254) (xy -0.635 0.254) (xy -0.5334 0.254)
				(xy -0.5334 0.2794)
			)
			(stroke
				(width 0)
				(type default)
			)
			(fill no)
			(layer "B.CrtYd")
		)
		(pad "1" smd rect
			(at -0.40005 0)
			(size 0.4572 0.508)
			(layers "B.Cu" "B.Mask" "B.Paste")
			(net "T2_NODE3_EN")
		)
		(pad "2" smd rect
			(at 0.40005 0)
			(size 0.4572 0.508)
			(layers "B.Cu" "B.Mask" "B.Paste")
			(net "P5V_NODE1")
		)
	)
	(footprint ""
		(layer "B.Cu")
		(at 130.79476 -187.872624 90)
		(property "Reference" "R968"
			(at 4.565396 -1.054354 270)
			(unlocked yes)
			(layer "B.SilkS")
			(effects
				(font
					(size 0.7874 0.5842)
					(thickness 0.1524)
				)
				(justify left mirror)
			)
		)
		(property "Value" ""
			(at 0 0 90)
			(layer "B.Fab")
			(effects
				(font
					(size 1.27 1.27)
				)
				(justify mirror)
			)
		)
		(duplicate_pad_numbers_are_jumpers no)
		(fp_line
			(start 0.7874 -0.4064)
			(end -0.7874 -0.4064)
			(stroke
				(width 0.1524)
				(type default)
			)
			(layer "B.SilkS")
		)
		(fp_line
			(start -0.7874 -0.4064)
			(end -0.7874 0.4064)
			(stroke
				(width 0.1524)
				(type default)
			)
			(layer "B.SilkS")
		)
		(fp_line
			(start 0.7874 0.4064)
			(end 0.7874 -0.4064)
			(stroke
				(width 0.1524)
				(type default)
			)
			(layer "B.SilkS")
		)
		(fp_line
			(start -0.7874 0.4064)
			(end 0.7874 0.4064)
			(stroke
				(width 0.1524)
				(type default)
			)
			(layer "B.SilkS")
		)
		(fp_poly
			(pts
				(xy 0.508 0.2794) (xy 0.508 0.2286) (xy 0.635 0.2286) (xy 0.635 -0.254) (xy 0.5334 -0.254) (xy 0.5334 -0.2794)
				(xy -0.5334 -0.2794) (xy -0.5334 -0.254) (xy -0.635 -0.254) (xy -0.635 0.254) (xy -0.5334 0.254)
				(xy -0.5334 0.2794)
			)
			(stroke
				(width 0)
				(type default)
			)
			(fill no)
			(layer "B.CrtYd")
		)
		(pad "1" smd rect
			(at -0.40005 0 270)
			(size 0.4572 0.508)
			(layers "B.Cu" "B.Mask" "B.Paste")
			(net "UART_T9_NODE3_RXD")
		)
		(pad "2" smd rect
			(at 0.40005 0 270)
			(size 0.4572 0.508)
			(layers "B.Cu" "B.Mask" "B.Paste")
			(net "UART_T9_NODE3_RXD_R")
		)
	)
	(footprint ""
		(layer "B.Cu")
		(at 66.214498 -96.696784 90)
		(property "Reference" "R152"
			(at 6.314948 -4.996688 270)
			(unlocked yes)
			(layer "B.SilkS")
			(effects
				(font
					(size 0.7874 0.5842)
					(thickness 0.1524)
				)
				(justify left mirror)
			)
		)
		(property "Value" ""
			(at 0 0 90)
			(layer "B.Fab")
			(effects
				(font
					(size 1.27 1.27)
				)
				(justify mirror)
			)
		)
		(duplicate_pad_numbers_are_jumpers no)
		(fp_line
			(start 0.7874 -0.4064)
			(end -0.7874 -0.4064)
			(stroke
				(width 0.1524)
				(type default)
			)
			(layer "B.SilkS")
		)
		(fp_line
			(start -0.7874 -0.4064)
			(end -0.7874 0.4064)
			(stroke
				(width 0.1524)
				(type default)
			)
			(layer "B.SilkS")
		)
		(fp_line
			(start 0.7874 0.4064)
			(end 0.7874 -0.4064)
			(stroke
				(width 0.1524)
				(type default)
			)
			(layer "B.SilkS")
		)
		(fp_line
			(start -0.7874 0.4064)
			(end 0.7874 0.4064)
			(stroke
				(width 0.1524)
				(type default)
			)
			(layer "B.SilkS")
		)
		(fp_poly
			(pts
				(xy 0.508 0.2794) (xy 0.508 0.2286) (xy 0.635 0.2286) (xy 0.635 -0.254) (xy 0.5334 -0.254) (xy 0.5334 -0.2794)
				(xy -0.5334 -0.2794) (xy -0.5334 -0.254) (xy -0.635 -0.254) (xy -0.635 0.254) (xy -0.5334 0.254)
				(xy -0.5334 0.2794)
			)
			(stroke
				(width 0)
				(type default)
			)
			(fill no)
			(layer "B.CrtYd")
		)
		(pad "1" smd rect
			(at -0.40005 0 270)
			(size 0.4572 0.508)
			(layers "B.Cu" "B.Mask" "B.Paste")
			(net "PD_CPU_NODE1_BRD_ID1")
		)
		(pad "2" smd rect
			(at 0.40005 0 270)
			(size 0.4572 0.508)
			(layers "B.Cu" "B.Mask" "B.Paste")
			(net "P3V3_NODE1")
		)
	)
	(footprint ""
		(layer "B.Cu")
		(at 110.44936 -172.505624)
		(property "Reference" "R702"
			(at -21.356828 32.314642 0)
			(unlocked yes)
			(layer "B.SilkS")
			(effects
				(font
					(size 0.7874 0.5842)
					(thickness 0.1524)
				)
				(justify left mirror)
			)
		)
		(property "Value" ""
			(at 0 0 0)
			(layer "B.Fab")
			(effects
				(font
					(size 1.27 1.27)
				)
				(justify mirror)
			)
		)
		(duplicate_pad_numbers_are_jumpers no)
		(fp_line
			(start -0.7874 -0.4064)
			(end -0.7874 0.4064)
			(stroke
				(width 0.1524)
				(type default)
			)
			(layer "B.SilkS")
		)
		(fp_line
			(start -0.7874 0.4064)
			(end 0.7874 0.4064)
			(stroke
				(width 0.1524)
				(type default)
			)
			(layer "B.SilkS")
		)
		(fp_line
			(start 0.7874 -0.4064)
			(end -0.7874 -0.4064)
			(stroke
				(width 0.1524)
				(type default)
			)
			(layer "B.SilkS")
		)
		(fp_line
			(start 0.7874 0.4064)
			(end 0.7874 -0.4064)
			(stroke
				(width 0.1524)
				(type default)
			)
			(layer "B.SilkS")
		)
		(fp_poly
			(pts
				(xy 0.508 0.2794) (xy 0.508 0.2286) (xy 0.635 0.2286) (xy 0.635 -0.254) (xy 0.5334 -0.254) (xy 0.5334 -0.2794)
				(xy -0.5334 -0.2794) (xy -0.5334 -0.254) (xy -0.635 -0.254) (xy -0.635 0.254) (xy -0.5334 0.254)
				(xy -0.5334 0.2794)
			)
			(stroke
				(width 0)
				(type default)
			)
			(fill no)
			(layer "B.CrtYd")
		)
		(pad "1" smd rect
			(at -0.40005 0 180)
			(size 0.4572 0.508)
			(layers "B.Cu" "B.Mask" "B.Paste")
			(net "P3V3_NODE1")
		)
		(pad "2" smd rect
			(at 0.40005 0 180)
			(size 0.4572 0.508)
			(layers "B.Cu" "B.Mask" "B.Paste")
			(net "N21699571")
		)
	)
	(footprint ""
		(layer "B.Cu")
		(at 165.011608 -183.051196)
		(property "Reference" "R1173"
			(at 6.724904 -9.022588 0)
			(unlocked yes)
			(layer "B.SilkS")
			(effects
				(font
					(size 0.7874 0.5842)
					(thickness 0.1524)
				)
				(justify left mirror)
			)
		)
		(property "Value" ""
			(at 0 0 0)
			(layer "B.Fab")
			(effects
				(font
					(size 1.27 1.27)
				)
				(justify mirror)
			)
		)
		(duplicate_pad_numbers_are_jumpers no)
		(fp_line
			(start -0.7874 -0.406146)
			(end -0.7874 0.406146)
			(stroke
				(width 0.1524)
				(type default)
			)
			(layer "B.SilkS")
		)
		(fp_line
			(start -0.7874 0.406146)
			(end 0.7874 0.406146)
			(stroke
				(width 0.1524)
				(type default)
			)
			(layer "B.SilkS")
		)
		(fp_line
			(start 0.7874 -0.406146)
			(end -0.7874 -0.406146)
			(stroke
				(width 0.1524)
				(type default)
			)
			(layer "B.SilkS")
		)
		(fp_line
			(start 0.7874 0.406146)
			(end 0.7874 -0.406146)
			(stroke
				(width 0.1524)
				(type default)
			)
			(layer "B.SilkS")
		)
		(fp_poly
			(pts
				(xy 0.508 0.2794) (xy 0.508 0.2286) (xy 0.635 0.2286) (xy 0.635 -0.254) (xy 0.5334 -0.254) (xy 0.5334 -0.2794)
				(xy -0.5334 -0.2794) (xy -0.5334 -0.254) (xy -0.635 -0.254) (xy -0.635 0.254) (xy -0.5334 0.254)
				(xy -0.5334 0.2794)
			)
			(stroke
				(width 0)
				(type default)
			)
			(fill no)
			(layer "B.CrtYd")
		)
		(pad "1" smd rect
			(at -0.40005 0 180)
			(size 0.4572 0.508)
			(layers "B.Cu" "B.Mask" "B.Paste")
			(net "CPLD_UART_RX_P4_R")
		)
		(pad "2" smd rect
			(at 0.40005 0 180)
			(size 0.4572 0.508)
			(layers "B.Cu" "B.Mask" "B.Paste")
			(net "CPLD_UART_RX_P4")
		)
	)
	(footprint ""
		(layer "B.Cu")
		(at 57.345072 -126.518162 180)
		(property "Reference" "R294"
			(at 39.74211 -52.083208 0)
			(unlocked yes)
			(layer "B.SilkS")
			(effects
				(font
					(size 0.7874 0.5842)
					(thickness 0.1524)
				)
				(justify left mirror)
			)
		)
		(property "Value" ""
			(at 0 0 0)
			(layer "B.Fab")
			(effects
				(font
					(size 1.27 1.27)
				)
				(justify mirror)
			)
		)
		(duplicate_pad_numbers_are_jumpers no)
		(fp_line
			(start 0.7874 0.4064)
			(end 0.7874 -0.4064)
			(stroke
				(width 0.1524)
				(type default)
			)
			(layer "B.SilkS")
		)
		(fp_line
			(start 0.7874 -0.4064)
			(end -0.7874 -0.4064)
			(stroke
				(width 0.1524)
				(type default)
			)
			(layer "B.SilkS")
		)
		(fp_line
			(start -0.7874 0.4064)
			(end 0.7874 0.4064)
			(stroke
				(width 0.1524)
				(type default)
			)
			(layer "B.SilkS")
		)
		(fp_line
			(start -0.7874 -0.4064)
			(end -0.7874 0.4064)
			(stroke
				(width 0.1524)
				(type default)
			)
			(layer "B.SilkS")
		)
		(fp_poly
			(pts
				(xy 0.508 0.2794) (xy 0.508 0.2286) (xy 0.635 0.2286) (xy 0.635 -0.254) (xy 0.5334 -0.254) (xy 0.5334 -0.2794)
				(xy -0.5334 -0.2794) (xy -0.5334 -0.254) (xy -0.635 -0.254) (xy -0.635 0.254) (xy -0.5334 0.254)
				(xy -0.5334 0.2794)
			)
			(stroke
				(width 0)
				(type default)
			)
			(fill no)
			(layer "B.CrtYd")
		)
		(pad "1" smd rect
			(at -0.40005 0)
			(size 0.4572 0.508)
			(layers "B.Cu" "B.Mask" "B.Paste")
			(net "BMC_NODE1_USBVREF")
		)
		(pad "2" smd rect
			(at 0.40005 0)
			(size 0.4572 0.508)
			(layers "B.Cu" "B.Mask" "B.Paste")
			(net "GND")
		)
	)
	(footprint ""
		(layer "B.Cu")
		(at 90.81262 -169.958512)
		(property "Reference" "R687"
			(at 24.81707 20.071588 0)
			(unlocked yes)
			(layer "B.SilkS")
			(effects
				(font
					(size 0.7874 0.5842)
					(thickness 0.1524)
				)
				(justify left mirror)
			)
		)
		(property "Value" ""
			(at 0 0 0)
			(layer "B.Fab")
			(effects
				(font
					(size 1.27 1.27)
				)
				(justify mirror)
			)
		)
		(duplicate_pad_numbers_are_jumpers no)
		(fp_line
			(start -0.7874 -0.4064)
			(end -0.7874 0.4064)
			(stroke
				(width 0.1524)
				(type default)
			)
			(layer "B.SilkS")
		)
		(fp_line
			(start -0.7874 0.4064)
			(end 0.7874 0.4064)
			(stroke
				(width 0.1524)
				(type default)
			)
			(layer "B.SilkS")
		)
		(fp_line
			(start 0.7874 -0.4064)
			(end -0.7874 -0.4064)
			(stroke
				(width 0.1524)
				(type default)
			)
			(layer "B.SilkS")
		)
		(fp_line
			(start 0.7874 0.4064)
			(end 0.7874 -0.4064)
			(stroke
				(width 0.1524)
				(type default)
			)
			(layer "B.SilkS")
		)
		(fp_poly
			(pts
				(xy 0.508 0.2794) (xy 0.508 0.2286) (xy 0.635 0.2286) (xy 0.635 -0.254) (xy 0.5334 -0.254) (xy 0.5334 -0.2794)
				(xy -0.5334 -0.2794) (xy -0.5334 -0.254) (xy -0.635 -0.254) (xy -0.635 0.254) (xy -0.5334 0.254)
				(xy -0.5334 0.2794)
			)
			(stroke
				(width 0)
				(type default)
			)
			(fill no)
			(layer "B.CrtYd")
		)
		(pad "1" smd rect
			(at -0.40005 0 180)
			(size 0.4572 0.508)
			(layers "B.Cu" "B.Mask" "B.Paste")
			(net "N21700927")
		)
		(pad "2" smd rect
			(at 0.40005 0 180)
			(size 0.4572 0.508)
			(layers "B.Cu" "B.Mask" "B.Paste")
			(net "GND")
		)
	)
	(footprint ""
		(layer "B.Cu")
		(at 110.44936 -175.553624 180)
		(property "Reference" "R711"
			(at 21.356828 -32.269176 0)
			(unlocked yes)
			(layer "B.SilkS")
			(effects
				(font
					(size 0.7874 0.5842)
					(thickness 0.1524)
				)
				(justify left mirror)
			)
		)
		(property "Value" ""
			(at 0 0 0)
			(layer "B.Fab")
			(effects
				(font
					(size 1.27 1.27)
				)
				(justify mirror)
			)
		)
		(duplicate_pad_numbers_are_jumpers no)
		(fp_line
			(start 0.7874 0.4064)
			(end 0.7874 -0.4064)
			(stroke
				(width 0.1524)
				(type default)
			)
			(layer "B.SilkS")
		)
		(fp_line
			(start 0.7874 -0.4064)
			(end -0.7874 -0.4064)
			(stroke
				(width 0.1524)
				(type default)
			)
			(layer "B.SilkS")
		)
		(fp_line
			(start -0.7874 0.4064)
			(end 0.7874 0.4064)
			(stroke
				(width 0.1524)
				(type default)
			)
			(layer "B.SilkS")
		)
		(fp_line
			(start -0.7874 -0.4064)
			(end -0.7874 0.4064)
			(stroke
				(width 0.1524)
				(type default)
			)
			(layer "B.SilkS")
		)
		(fp_poly
			(pts
				(xy 0.508 0.2794) (xy 0.508 0.2286) (xy 0.635 0.2286) (xy 0.635 -0.254) (xy 0.5334 -0.254) (xy 0.5334 -0.2794)
				(xy -0.5334 -0.2794) (xy -0.5334 -0.254) (xy -0.635 -0.254) (xy -0.635 0.254) (xy -0.5334 0.254)
				(xy -0.5334 0.2794)
			)
			(stroke
				(width 0)
				(type default)
			)
			(fill no)
			(layer "B.CrtYd")
		)
		(pad "1" smd rect
			(at -0.40005 0)
			(size 0.4572 0.508)
			(layers "B.Cu" "B.Mask" "B.Paste")
			(net "T5_NODE2_EN")
		)
		(pad "2" smd rect
			(at 0.40005 0)
			(size 0.4572 0.508)
			(layers "B.Cu" "B.Mask" "B.Paste")
			(net "P5V_NODE1")
		)
	)
	(footprint ""
		(layer "B.Cu")
		(at 78.62062 -185.259218 90)
		(property "Reference" "R886"
			(at 3.798062 0.041148 270)
			(unlocked yes)
			(layer "B.SilkS")
			(effects
				(font
					(size 0.7874 0.5842)
					(thickness 0.1524)
				)
				(justify left mirror)
			)
		)
		(property "Value" ""
			(at 0 0 90)
			(layer "B.Fab")
			(effects
				(font
					(size 1.27 1.27)
				)
				(justify mirror)
			)
		)
		(duplicate_pad_numbers_are_jumpers no)
		(fp_line
			(start 0.7874 -0.4064)
			(end -0.7874 -0.4064)
			(stroke
				(width 0.1524)
				(type default)
			)
			(layer "B.SilkS")
		)
		(fp_line
			(start -0.7874 -0.4064)
			(end -0.7874 0.4064)
			(stroke
				(width 0.1524)
				(type default)
			)
			(layer "B.SilkS")
		)
		(fp_line
			(start 0.7874 0.4064)
			(end 0.7874 -0.4064)
			(stroke
				(width 0.1524)
				(type default)
			)
			(layer "B.SilkS")
		)
		(fp_line
			(start -0.7874 0.4064)
			(end 0.7874 0.4064)
			(stroke
				(width 0.1524)
				(type default)
			)
			(layer "B.SilkS")
		)
		(fp_poly
			(pts
				(xy 0.508 0.2794) (xy 0.508 0.2286) (xy 0.635 0.2286) (xy 0.635 -0.254) (xy 0.5334 -0.254) (xy 0.5334 -0.2794)
				(xy -0.5334 -0.2794) (xy -0.5334 -0.254) (xy -0.635 -0.254) (xy -0.635 0.254) (xy -0.5334 0.254)
				(xy -0.5334 0.2794)
			)
			(stroke
				(width 0)
				(type default)
			)
			(fill no)
			(layer "B.CrtYd")
		)
		(pad "1" smd rect
			(at -0.40005 0 270)
			(size 0.4572 0.508)
			(layers "B.Cu" "B.Mask" "B.Paste")
			(net "T3_NODE2_EN")
		)
		(pad "2" smd rect
			(at 0.40005 0 270)
			(size 0.4572 0.508)
			(layers "B.Cu" "B.Mask" "B.Paste")
			(net "T3_NODE2_EN_R")
		)
	)
	(footprint ""
		(layer "B.Cu")
		(at 115.011454 -163.24199 180)
		(property "Reference" "R795"
			(at -1.709166 -2.076196 0)
			(unlocked yes)
			(layer "B.SilkS")
			(effects
				(font
					(size 0.7874 0.5842)
					(thickness 0.1524)
				)
				(justify left mirror)
			)
		)
		(property "Value" ""
			(at 0 0 0)
			(layer "B.Fab")
			(effects
				(font
					(size 1.27 1.27)
				)
				(justify mirror)
			)
		)
		(duplicate_pad_numbers_are_jumpers no)
		(fp_line
			(start 0.7874 0.4064)
			(end 0.7874 -0.4064)
			(stroke
				(width 0.1524)
				(type default)
			)
			(layer "B.SilkS")
		)
		(fp_line
			(start 0.7874 -0.4064)
			(end -0.7874 -0.4064)
			(stroke
				(width 0.1524)
				(type default)
			)
			(layer "B.SilkS")
		)
		(fp_line
			(start -0.7874 0.4064)
			(end 0.7874 0.4064)
			(stroke
				(width 0.1524)
				(type default)
			)
			(layer "B.SilkS")
		)
		(fp_line
			(start -0.7874 -0.4064)
			(end -0.7874 0.4064)
			(stroke
				(width 0.1524)
				(type default)
			)
			(layer "B.SilkS")
		)
		(fp_poly
			(pts
				(xy 0.508 0.2794) (xy 0.508 0.2286) (xy 0.635 0.2286) (xy 0.635 -0.254) (xy 0.5334 -0.254) (xy 0.5334 -0.2794)
				(xy -0.5334 -0.2794) (xy -0.5334 -0.254) (xy -0.635 -0.254) (xy -0.635 0.254) (xy -0.5334 0.254)
				(xy -0.5334 0.2794)
			)
			(stroke
				(width 0)
				(type default)
			)
			(fill no)
			(layer "B.CrtYd")
		)
		(pad "1" smd rect
			(at -0.40005 0)
			(size 0.4572 0.508)
			(layers "B.Cu" "B.Mask" "B.Paste")
			(net "I2C_COM3_SDA_RC")
		)
		(pad "2" smd rect
			(at 0.40005 0)
			(size 0.4572 0.508)
			(layers "B.Cu" "B.Mask" "B.Paste")
			(net "I2C_COM3_SDA")
		)
	)
	(footprint ""
		(layer "B.Cu")
		(at 130.56616 -30.610048 180)
		(property "Reference" "R776"
			(at -3.80746 -0.509016 0)
			(unlocked yes)
			(layer "B.SilkS")
			(effects
				(font
					(size 0.7874 0.5842)
					(thickness 0.1524)
				)
				(justify left mirror)
			)
		)
		(property "Value" ""
			(at 0 0 0)
			(layer "B.Fab")
			(effects
				(font
					(size 1.27 1.27)
				)
				(justify mirror)
			)
		)
		(duplicate_pad_numbers_are_jumpers no)
		(fp_line
			(start 0.7874 0.4064)
			(end 0.7874 -0.4064)
			(stroke
				(width 0.1524)
				(type default)
			)
			(layer "B.SilkS")
		)
		(fp_line
			(start 0.7874 -0.4064)
			(end -0.7874 -0.4064)
			(stroke
				(width 0.1524)
				(type default)
			)
			(layer "B.SilkS")
		)
		(fp_line
			(start -0.7874 0.4064)
			(end 0.7874 0.4064)
			(stroke
				(width 0.1524)
				(type default)
			)
			(layer "B.SilkS")
		)
		(fp_line
			(start -0.7874 -0.4064)
			(end -0.7874 0.4064)
			(stroke
				(width 0.1524)
				(type default)
			)
			(layer "B.SilkS")
		)
		(fp_poly
			(pts
				(xy 0.508 0.2794) (xy 0.508 0.2286) (xy 0.635 0.2286) (xy 0.635 -0.254) (xy 0.5334 -0.254) (xy 0.5334 -0.2794)
				(xy -0.5334 -0.2794) (xy -0.5334 -0.254) (xy -0.635 -0.254) (xy -0.635 0.254) (xy -0.5334 0.254)
				(xy -0.5334 0.2794)
			)
			(stroke
				(width 0)
				(type default)
			)
			(fill no)
			(layer "B.CrtYd")
		)
		(pad "1" smd rect
			(at -0.40005 0)
			(size 0.4572 0.508)
			(layers "B.Cu" "B.Mask" "B.Paste")
			(net "P3V3_NODE1")
		)
		(pad "2" smd rect
			(at 0.40005 0)
			(size 0.4572 0.508)
			(layers "B.Cu" "B.Mask" "B.Paste")
			(net "UART_RI_P6_N")
		)
	)
	(footprint ""
		(layer "B.Cu")
		(at 37.645086 -138.392662)
		(property "Reference" "R262"
			(at -2.11328 -0.033782 0)
			(unlocked yes)
			(layer "B.SilkS")
			(effects
				(font
					(size 0.7874 0.5842)
					(thickness 0.1524)
				)
				(justify left mirror)
			)
		)
		(property "Value" ""
			(at 0 0 0)
			(layer "B.Fab")
			(effects
				(font
					(size 1.27 1.27)
				)
				(justify mirror)
			)
		)
		(duplicate_pad_numbers_are_jumpers no)
		(fp_line
			(start -0.7874 -0.4064)
			(end -0.7874 0.4064)
			(stroke
				(width 0.1524)
				(type default)
			)
			(layer "B.SilkS")
		)
		(fp_line
			(start -0.7874 0.4064)
			(end 0.7874 0.4064)
			(stroke
				(width 0.1524)
				(type default)
			)
			(layer "B.SilkS")
		)
		(fp_line
			(start 0.7874 -0.4064)
			(end -0.7874 -0.4064)
			(stroke
				(width 0.1524)
				(type default)
			)
			(layer "B.SilkS")
		)
		(fp_line
			(start 0.7874 0.4064)
			(end 0.7874 -0.4064)
			(stroke
				(width 0.1524)
				(type default)
			)
			(layer "B.SilkS")
		)
		(fp_poly
			(pts
				(xy 0.508 0.2794) (xy 0.508 0.2286) (xy 0.635 0.2286) (xy 0.635 -0.254) (xy 0.5334 -0.254) (xy 0.5334 -0.2794)
				(xy -0.5334 -0.2794) (xy -0.5334 -0.254) (xy -0.635 -0.254) (xy -0.635 0.254) (xy -0.5334 0.254)
				(xy -0.5334 0.2794)
			)
			(stroke
				(width 0)
				(type default)
			)
			(fill no)
			(layer "B.CrtYd")
		)
		(pad "1" smd rect
			(at -0.40005 0 180)
			(size 0.4572 0.508)
			(layers "B.Cu" "B.Mask" "B.Paste")
			(net "P0V75_BMC_VTTREF_NODE1")
		)
		(pad "2" smd rect
			(at 0.40005 0 180)
			(size 0.4572 0.508)
			(layers "B.Cu" "B.Mask" "B.Paste")
			(net "GND")
		)
	)
	(footprint ""
		(layer "B.Cu")
		(at 40.185086 -143.472662 180)
		(property "Reference" "C229"
			(at 3.121914 0.085598 0)
			(unlocked yes)
			(layer "B.SilkS")
			(effects
				(font
					(size 0.7874 0.5842)
					(thickness 0.1524)
				)
				(justify mirror)
			)
		)
		(property "Value" ""
			(at 0 0 0)
			(layer "B.Fab")
			(effects
				(font
					(size 1.27 1.27)
				)
				(justify mirror)
			)
		)
		(duplicate_pad_numbers_are_jumpers no)
		(fp_line
			(start 1.2954 0.5842)
			(end 1.2954 -0.5842)
			(stroke
				(width 0.1524)
				(type default)
			)
			(layer "B.SilkS")
		)
		(fp_line
			(start 1.2954 -0.5842)
			(end -1.2954 -0.5842)
			(stroke
				(width 0.1524)
				(type default)
			)
			(layer "B.SilkS")
		)
		(fp_line
			(start 0 -0.5842)
			(end 0 0.5842)
			(stroke
				(width 0.1524)
				(type default)
			)
			(layer "B.SilkS")
		)
		(fp_line
			(start -1.2954 0.5842)
			(end 1.2954 0.5842)
			(stroke
				(width 0.1524)
				(type default)
			)
			(layer "B.SilkS")
		)
		(fp_line
			(start -1.2954 -0.5842)
			(end -1.2954 0.5842)
			(stroke
				(width 0.1524)
				(type default)
			)
			(layer "B.SilkS")
		)
		(fp_poly
			(pts
				(xy -0.8636 -0.4572) (xy -0.8636 -0.3556) (xy -1.143 -0.3556) (xy -1.143 0.3556) (xy -0.8636 0.3556)
				(xy -0.8636 0.4572) (xy 0.8636 0.4572) (xy 0.8636 0.3556) (xy 1.143 0.3556) (xy 1.143 -0.3556) (xy 0.8636 -0.3556)
				(xy 0.8636 -0.4572)
			)
			(stroke
				(width 0)
				(type default)
			)
			(fill no)
			(layer "B.CrtYd")
		)
		(fp_line
			(start 0.884936 0.504952)
			(end 0.884936 -0.504952)
			(stroke
				(width 0.1)
				(type default)
			)
			(layer "B.Fab")
		)
		(fp_line
			(start 0.884936 -0.504952)
			(end -0.884936 -0.504952)
			(stroke
				(width 0.1)
				(type default)
			)
			(layer "B.Fab")
		)
		(fp_line
			(start -0.884936 0.504952)
			(end 0.884936 0.504952)
			(stroke
				(width 0.1)
				(type default)
			)
			(layer "B.Fab")
		)
		(fp_line
			(start -0.884936 -0.504952)
			(end -0.884936 0.504952)
			(stroke
				(width 0.1)
				(type default)
			)
			(layer "B.Fab")
		)
		(pad "1" smd rect
			(at -0.7366 0 270)
			(size 0.7112 0.8128)
			(layers "B.Cu" "B.Mask" "B.Paste")
			(net "P1V538_BMC_NODE1")
		)
		(pad "2" smd rect
			(at 0.7366 0 270)
			(size 0.7112 0.8128)
			(layers "B.Cu" "B.Mask" "B.Paste")
			(net "GND")
		)
	)
	(footprint ""
		(layer "B.Cu")
		(at 75.415902 -129.389124 90)
		(property "Reference" "R256"
			(at 1.673098 -0.09398 270)
			(unlocked yes)
			(layer "B.SilkS")
			(effects
				(font
					(size 0.7874 0.5842)
					(thickness 0.1524)
				)
				(justify left mirror)
			)
		)
		(property "Value" ""
			(at 0 0 90)
			(layer "B.Fab")
			(effects
				(font
					(size 1.27 1.27)
				)
				(justify mirror)
			)
		)
		(duplicate_pad_numbers_are_jumpers no)
		(fp_line
			(start 0.7874 -0.4064)
			(end -0.7874 -0.4064)
			(stroke
				(width 0.1524)
				(type default)
			)
			(layer "B.SilkS")
		)
		(fp_line
			(start -0.7874 -0.4064)
			(end -0.7874 0.4064)
			(stroke
				(width 0.1524)
				(type default)
			)
			(layer "B.SilkS")
		)
		(fp_line
			(start 0.7874 0.4064)
			(end 0.7874 -0.4064)
			(stroke
				(width 0.1524)
				(type default)
			)
			(layer "B.SilkS")
		)
		(fp_line
			(start -0.7874 0.4064)
			(end 0.7874 0.4064)
			(stroke
				(width 0.1524)
				(type default)
			)
			(layer "B.SilkS")
		)
		(fp_poly
			(pts
				(xy 0.508 0.2794) (xy 0.508 0.2286) (xy 0.635 0.2286) (xy 0.635 -0.254) (xy 0.5334 -0.254) (xy 0.5334 -0.2794)
				(xy -0.5334 -0.2794) (xy -0.5334 -0.254) (xy -0.635 -0.254) (xy -0.635 0.254) (xy -0.5334 0.254)
				(xy -0.5334 0.2794)
			)
			(stroke
				(width 0)
				(type default)
			)
			(fill no)
			(layer "B.CrtYd")
		)
		(pad "1" smd rect
			(at -0.40005 0 270)
			(size 0.4572 0.508)
			(layers "B.Cu" "B.Mask" "B.Paste")
			(net "PD_BMC_NODE1_PEREXT")
		)
		(pad "2" smd rect
			(at 0.40005 0 270)
			(size 0.4572 0.508)
			(layers "B.Cu" "B.Mask" "B.Paste")
			(net "GND")
		)
	)
	(footprint ""
		(layer "B.Cu")
		(at 135.162036 -42.501566 180)
		(property "Reference" "R1119"
			(at 5.38099 -18.982944 0)
			(unlocked yes)
			(layer "B.SilkS")
			(effects
				(font
					(size 0.7874 0.5842)
					(thickness 0.1524)
				)
				(justify left mirror)
			)
		)
		(property "Value" ""
			(at 0 0 0)
			(layer "B.Fab")
			(effects
				(font
					(size 1.27 1.27)
				)
				(justify mirror)
			)
		)
		(duplicate_pad_numbers_are_jumpers no)
		(fp_line
			(start 0.7874 0.4064)
			(end 0.7874 -0.4064)
			(stroke
				(width 0.1524)
				(type default)
			)
			(layer "B.SilkS")
		)
		(fp_line
			(start 0.7874 -0.4064)
			(end -0.7874 -0.4064)
			(stroke
				(width 0.1524)
				(type default)
			)
			(layer "B.SilkS")
		)
		(fp_line
			(start -0.7874 0.4064)
			(end 0.7874 0.4064)
			(stroke
				(width 0.1524)
				(type default)
			)
			(layer "B.SilkS")
		)
		(fp_line
			(start -0.7874 -0.4064)
			(end -0.7874 0.4064)
			(stroke
				(width 0.1524)
				(type default)
			)
			(layer "B.SilkS")
		)
		(fp_poly
			(pts
				(xy 0.508 0.2794) (xy 0.508 0.2286) (xy 0.635 0.2286) (xy 0.635 -0.254) (xy 0.5334 -0.254) (xy 0.5334 -0.2794)
				(xy -0.5334 -0.2794) (xy -0.5334 -0.254) (xy -0.635 -0.254) (xy -0.635 0.254) (xy -0.5334 0.254)
				(xy -0.5334 0.2794)
			)
			(stroke
				(width 0)
				(type default)
			)
			(fill no)
			(layer "B.CrtYd")
		)
		(pad "1" smd rect
			(at -0.40005 0)
			(size 0.4572 0.508)
			(layers "B.Cu" "B.Mask" "B.Paste")
			(net "SIO_JTAG_CPLD2_TCK")
		)
		(pad "2" smd rect
			(at 0.40005 0)
			(size 0.4572 0.508)
			(layers "B.Cu" "B.Mask" "B.Paste")
			(net "JTAG_CPLD2_TCK")
		)
	)
	(footprint ""
		(layer "B.Cu")
		(at 166.151814 -145.208498 -90)
		(property "Reference" "TP4"
			(at 0 0 90)
			(layer "B.SilkS")
			(hide yes)
			(effects
				(font
					(size 1.27 1.27)
				)
				(justify mirror)
			)
		)
		(property "Value" ""
			(at 0 0 90)
			(layer "B.Fab")
			(effects
				(font
					(size 1.27 1.27)
				)
				(justify mirror)
			)
		)
		(duplicate_pad_numbers_are_jumpers no)
		(fp_poly
			(pts
				(arc
					(start 0 -0.381)
					(mid 0 0.381)
					(end 0 -0.381)
				)
			)
			(stroke
				(width 0)
				(type default)
			)
			(fill no)
			(layer "B.CrtYd")
		)
		(pad "1" smd circle
			(at 0 0 90)
			(size 0.762 0.762)
			(layers "B.Cu" "B.Mask" "B.Paste")
			(net "N21357373")
		)
	)
	(footprint ""
		(layer "B.Cu")
		(at 154.06116 -171.489624)
		(property "Reference" "R750"
			(at -1.545844 12.970002 0)
			(unlocked yes)
			(layer "B.SilkS")
			(effects
				(font
					(size 0.7874 0.5842)
					(thickness 0.1524)
				)
				(justify left mirror)
			)
		)
		(property "Value" ""
			(at 0 0 0)
			(layer "B.Fab")
			(effects
				(font
					(size 1.27 1.27)
				)
				(justify mirror)
			)
		)
		(duplicate_pad_numbers_are_jumpers no)
		(fp_line
			(start -0.7874 -0.4064)
			(end -0.7874 0.4064)
			(stroke
				(width 0.1524)
				(type default)
			)
			(layer "B.SilkS")
		)
		(fp_line
			(start -0.7874 0.4064)
			(end 0.7874 0.4064)
			(stroke
				(width 0.1524)
				(type default)
			)
			(layer "B.SilkS")
		)
		(fp_line
			(start 0.7874 -0.4064)
			(end -0.7874 -0.4064)
			(stroke
				(width 0.1524)
				(type default)
			)
			(layer "B.SilkS")
		)
		(fp_line
			(start 0.7874 0.4064)
			(end 0.7874 -0.4064)
			(stroke
				(width 0.1524)
				(type default)
			)
			(layer "B.SilkS")
		)
		(fp_poly
			(pts
				(xy 0.508 0.2794) (xy 0.508 0.2286) (xy 0.635 0.2286) (xy 0.635 -0.254) (xy 0.5334 -0.254) (xy 0.5334 -0.2794)
				(xy -0.5334 -0.2794) (xy -0.5334 -0.254) (xy -0.635 -0.254) (xy -0.635 0.254) (xy -0.5334 0.254)
				(xy -0.5334 0.2794)
			)
			(stroke
				(width 0)
				(type default)
			)
			(fill no)
			(layer "B.CrtYd")
		)
		(pad "1" smd rect
			(at -0.40005 0 180)
			(size 0.4572 0.508)
			(layers "B.Cu" "B.Mask" "B.Paste")
			(net "N21698959")
		)
		(pad "2" smd rect
			(at 0.40005 0 180)
			(size 0.4572 0.508)
			(layers "B.Cu" "B.Mask" "B.Paste")
			(net "GND")
		)
	)
	(footprint ""
		(layer "B.Cu")
		(at 72.191372 -80.514698 90)
		(property "Reference" "C73"
			(at -32.158686 -14.55039 270)
			(unlocked yes)
			(layer "B.SilkS")
			(effects
				(font
					(size 0.7874 0.5842)
					(thickness 0.1524)
				)
				(justify left mirror)
			)
		)
		(property "Value" ""
			(at 0 0 90)
			(layer "B.Fab")
			(effects
				(font
					(size 1.27 1.27)
				)
				(justify mirror)
			)
		)
		(duplicate_pad_numbers_are_jumpers no)
		(fp_line
			(start 0.7874 -0.4064)
			(end -0.7874 -0.4064)
			(stroke
				(width 0.1524)
				(type default)
			)
			(layer "B.SilkS")
		)
		(fp_line
			(start -0.7874 -0.4064)
			(end -0.7874 0.4064)
			(stroke
				(width 0.1524)
				(type default)
			)
			(layer "B.SilkS")
		)
		(fp_line
			(start 0 0.381)
			(end 0 -0.381)
			(stroke
				(width 0.1524)
				(type default)
			)
			(layer "B.SilkS")
		)
		(fp_line
			(start 0.7874 0.4064)
			(end 0.7874 -0.4064)
			(stroke
				(width 0.1524)
				(type default)
			)
			(layer "B.SilkS")
		)
		(fp_line
			(start -0.7874 0.4064)
			(end 0.7874 0.4064)
			(stroke
				(width 0.1524)
				(type default)
			)
			(layer "B.SilkS")
		)
		(fp_poly
			(pts
				(xy 0.5334 0.254) (xy 0.635 0.254) (xy 0.635 0.2286) (xy 0.635 -0.254) (xy 0.5334 -0.254) (xy 0.5334 -0.2794)
				(xy -0.5334 -0.2794) (xy -0.5334 -0.254) (xy -0.635 -0.254) (xy -0.635 0.254) (xy -0.5334 0.254)
				(xy -0.5334 0.2794) (xy 0.508 0.2794) (xy 0.5334 0.2794)
			)
			(stroke
				(width 0)
				(type default)
			)
			(fill no)
			(layer "B.CrtYd")
		)
		(pad "1" smd rect
			(at -0.40005 0 270)
			(size 0.4572 0.508)
			(layers "B.Cu" "B.Mask" "B.Paste")
			(net "PV_VCCP_NODE1")
		)
		(pad "2" smd rect
			(at 0.40005 0 270)
			(size 0.4572 0.508)
			(layers "B.Cu" "B.Mask" "B.Paste")
			(net "GND")
		)
	)
	(footprint ""
		(layer "B.Cu")
		(at 59.717178 -75.948286 90)
		(property "Reference" "C52"
			(at -31.091886 -14.285468 270)
			(unlocked yes)
			(layer "B.SilkS")
			(effects
				(font
					(size 0.7874 0.5842)
					(thickness 0.1524)
				)
				(justify left mirror)
			)
		)
		(property "Value" ""
			(at 0 0 90)
			(layer "B.Fab")
			(effects
				(font
					(size 1.27 1.27)
				)
				(justify mirror)
			)
		)
		(duplicate_pad_numbers_are_jumpers no)
		(fp_line
			(start 0.7874 -0.4064)
			(end -0.7874 -0.4064)
			(stroke
				(width 0.1524)
				(type default)
			)
			(layer "B.SilkS")
		)
		(fp_line
			(start -0.7874 -0.4064)
			(end -0.7874 0.4064)
			(stroke
				(width 0.1524)
				(type default)
			)
			(layer "B.SilkS")
		)
		(fp_line
			(start 0 0.381)
			(end 0 -0.381)
			(stroke
				(width 0.1524)
				(type default)
			)
			(layer "B.SilkS")
		)
		(fp_line
			(start 0.7874 0.4064)
			(end 0.7874 -0.4064)
			(stroke
				(width 0.1524)
				(type default)
			)
			(layer "B.SilkS")
		)
		(fp_line
			(start -0.7874 0.4064)
			(end 0.7874 0.4064)
			(stroke
				(width 0.1524)
				(type default)
			)
			(layer "B.SilkS")
		)
		(fp_poly
			(pts
				(xy 0.5334 0.254) (xy 0.635 0.254) (xy 0.635 0.2286) (xy 0.635 -0.254) (xy 0.5334 -0.254) (xy 0.5334 -0.2794)
				(xy -0.5334 -0.2794) (xy -0.5334 -0.254) (xy -0.635 -0.254) (xy -0.635 0.254) (xy -0.5334 0.254)
				(xy -0.5334 0.2794) (xy 0.508 0.2794) (xy 0.5334 0.2794)
			)
			(stroke
				(width 0)
				(type default)
			)
			(fill no)
			(layer "B.CrtYd")
		)
		(pad "1" smd rect
			(at -0.40005 0 270)
			(size 0.4572 0.508)
			(layers "B.Cu" "B.Mask" "B.Paste")
			(net "P1V05_NODE1")
		)
		(pad "2" smd rect
			(at 0.40005 0 270)
			(size 0.4572 0.508)
			(layers "B.Cu" "B.Mask" "B.Paste")
			(net "GND")
		)
	)
	(footprint ""
		(layer "B.Cu")
		(at 127.492252 -136.04367 90)
		(property "Reference" "C865"
			(at -5.140706 -0.20574 270)
			(unlocked yes)
			(layer "B.SilkS")
			(effects
				(font
					(size 0.7874 0.5842)
					(thickness 0.1524)
				)
				(justify left mirror)
			)
		)
		(property "Value" ""
			(at 0 0 90)
			(layer "B.Fab")
			(effects
				(font
					(size 1.27 1.27)
				)
				(justify mirror)
			)
		)
		(duplicate_pad_numbers_are_jumpers no)
		(fp_line
			(start 0.7874 -0.4064)
			(end -0.7874 -0.4064)
			(stroke
				(width 0.1524)
				(type default)
			)
			(layer "B.SilkS")
		)
		(fp_line
			(start -0.7874 -0.4064)
			(end -0.7874 0.4064)
			(stroke
				(width 0.1524)
				(type default)
			)
			(layer "B.SilkS")
		)
		(fp_line
			(start 0 0.381)
			(end 0 -0.381)
			(stroke
				(width 0.1524)
				(type default)
			)
			(layer "B.SilkS")
		)
		(fp_line
			(start 0.7874 0.4064)
			(end 0.7874 -0.4064)
			(stroke
				(width 0.1524)
				(type default)
			)
			(layer "B.SilkS")
		)
		(fp_line
			(start -0.7874 0.4064)
			(end 0.7874 0.4064)
			(stroke
				(width 0.1524)
				(type default)
			)
			(layer "B.SilkS")
		)
		(fp_poly
			(pts
				(xy 0.5334 0.254) (xy 0.635 0.254) (xy 0.635 0.2286) (xy 0.635 -0.254) (xy 0.5334 -0.254) (xy 0.5334 -0.2794)
				(xy -0.5334 -0.2794) (xy -0.5334 -0.254) (xy -0.635 -0.254) (xy -0.635 0.254) (xy -0.5334 0.254)
				(xy -0.5334 0.2794) (xy 0.508 0.2794) (xy 0.5334 0.2794)
			)
			(stroke
				(width 0)
				(type default)
			)
			(fill no)
			(layer "B.CrtYd")
		)
		(pad "1" smd rect
			(at -0.40005 0 270)
			(size 0.4572 0.508)
			(layers "B.Cu" "B.Mask" "B.Paste")
			(net "P3V3_NODE1")
		)
		(pad "2" smd rect
			(at 0.40005 0 270)
			(size 0.4572 0.508)
			(layers "B.Cu" "B.Mask" "B.Paste")
			(net "GND")
		)
	)
	(footprint ""
		(layer "B.Cu")
		(at 40.376602 -151.620982)
		(property "Reference" "C428"
			(at -6.359652 -10.149332 0)
			(unlocked yes)
			(layer "B.SilkS")
			(effects
				(font
					(size 0.7874 0.5842)
					(thickness 0.1524)
				)
				(justify left mirror)
			)
		)
		(property "Value" ""
			(at 0 0 0)
			(layer "B.Fab")
			(effects
				(font
					(size 1.27 1.27)
				)
				(justify mirror)
			)
		)
		(duplicate_pad_numbers_are_jumpers no)
		(fp_line
			(start -0.7874 -0.4064)
			(end -0.7874 0.4064)
			(stroke
				(width 0.1524)
				(type default)
			)
			(layer "B.SilkS")
		)
		(fp_line
			(start -0.7874 0.4064)
			(end 0.7874 0.4064)
			(stroke
				(width 0.1524)
				(type default)
			)
			(layer "B.SilkS")
		)
		(fp_line
			(start 0 0.381)
			(end 0 -0.381)
			(stroke
				(width 0.1524)
				(type default)
			)
			(layer "B.SilkS")
		)
		(fp_line
			(start 0.7874 -0.4064)
			(end -0.7874 -0.4064)
			(stroke
				(width 0.1524)
				(type default)
			)
			(layer "B.SilkS")
		)
		(fp_line
			(start 0.7874 0.4064)
			(end 0.7874 -0.4064)
			(stroke
				(width 0.1524)
				(type default)
			)
			(layer "B.SilkS")
		)
		(fp_poly
			(pts
				(xy 0.5334 0.254) (xy 0.635 0.254) (xy 0.635 0.2286) (xy 0.635 -0.254) (xy 0.5334 -0.254) (xy 0.5334 -0.2794)
				(xy -0.5334 -0.2794) (xy -0.5334 -0.254) (xy -0.635 -0.254) (xy -0.635 0.254) (xy -0.5334 0.254)
				(xy -0.5334 0.2794) (xy 0.508 0.2794) (xy 0.5334 0.2794)
			)
			(stroke
				(width 0)
				(type default)
			)
			(fill no)
			(layer "B.CrtYd")
		)
		(pad "1" smd rect
			(at -0.40005 0 180)
			(size 0.4572 0.508)
			(layers "B.Cu" "B.Mask" "B.Paste")
			(net "P1V9_LAN1")
		)
		(pad "2" smd rect
			(at 0.40005 0 180)
			(size 0.4572 0.508)
			(layers "B.Cu" "B.Mask" "B.Paste")
			(net "GND")
		)
	)
	(footprint ""
		(layer "B.Cu")
		(at 115.12169 -164.88537 -90)
		(property "Reference" "R773"
			(at 3.1242 2.45237 270)
			(unlocked yes)
			(layer "B.SilkS")
			(effects
				(font
					(size 0.7874 0.5842)
					(thickness 0.1524)
				)
				(justify left mirror)
			)
		)
		(property "Value" ""
			(at 0 0 90)
			(layer "B.Fab")
			(effects
				(font
					(size 1.27 1.27)
				)
				(justify mirror)
			)
		)
		(duplicate_pad_numbers_are_jumpers no)
		(fp_line
			(start -0.7874 0.4064)
			(end 0.7874 0.4064)
			(stroke
				(width 0.1524)
				(type default)
			)
			(layer "B.SilkS")
		)
		(fp_line
			(start 0.7874 0.4064)
			(end 0.7874 -0.4064)
			(stroke
				(width 0.1524)
				(type default)
			)
			(layer "B.SilkS")
		)
		(fp_line
			(start -0.7874 -0.4064)
			(end -0.7874 0.4064)
			(stroke
				(width 0.1524)
				(type default)
			)
			(layer "B.SilkS")
		)
		(fp_line
			(start 0.7874 -0.4064)
			(end -0.7874 -0.4064)
			(stroke
				(width 0.1524)
				(type default)
			)
			(layer "B.SilkS")
		)
		(fp_poly
			(pts
				(xy 0.508 0.2794) (xy 0.508 0.2286) (xy 0.635 0.2286) (xy 0.635 -0.254) (xy 0.5334 -0.254) (xy 0.5334 -0.2794)
				(xy -0.5334 -0.2794) (xy -0.5334 -0.254) (xy -0.635 -0.254) (xy -0.635 0.254) (xy -0.5334 0.254)
				(xy -0.5334 0.2794)
			)
			(stroke
				(width 0)
				(type default)
			)
			(fill no)
			(layer "B.CrtYd")
		)
		(pad "1" smd rect
			(at -0.40005 0 90)
			(size 0.4572 0.508)
			(layers "B.Cu" "B.Mask" "B.Paste")
			(net "I2C_SCL_FANCTRL2_R")
		)
		(pad "2" smd rect
			(at 0.40005 0 90)
			(size 0.4572 0.508)
			(layers "B.Cu" "B.Mask" "B.Paste")
			(net "I2C_COM3_SCL")
		)
	)
	(footprint ""
		(layer "B.Cu")
		(at 91.102434 -186.826398 180)
		(property "Reference" "R921"
			(at 2.352294 3.135376 0)
			(unlocked yes)
			(layer "B.SilkS")
			(effects
				(font
					(size 0.7874 0.5842)
					(thickness 0.1524)
				)
				(justify left mirror)
			)
		)
		(property "Value" ""
			(at 0 0 0)
			(layer "B.Fab")
			(effects
				(font
					(size 1.27 1.27)
				)
				(justify mirror)
			)
		)
		(duplicate_pad_numbers_are_jumpers no)
		(fp_line
			(start 0.7874 0.4064)
			(end 0.7874 -0.4064)
			(stroke
				(width 0.1524)
				(type default)
			)
			(layer "B.SilkS")
		)
		(fp_line
			(start 0.7874 -0.4064)
			(end -0.7874 -0.4064)
			(stroke
				(width 0.1524)
				(type default)
			)
			(layer "B.SilkS")
		)
		(fp_line
			(start -0.7874 0.4064)
			(end 0.7874 0.4064)
			(stroke
				(width 0.1524)
				(type default)
			)
			(layer "B.SilkS")
		)
		(fp_line
			(start -0.7874 -0.4064)
			(end -0.7874 0.4064)
			(stroke
				(width 0.1524)
				(type default)
			)
			(layer "B.SilkS")
		)
		(fp_poly
			(pts
				(xy 0.508 0.2794) (xy 0.508 0.2286) (xy 0.635 0.2286) (xy 0.635 -0.254) (xy 0.5334 -0.254) (xy 0.5334 -0.2794)
				(xy -0.5334 -0.2794) (xy -0.5334 -0.254) (xy -0.635 -0.254) (xy -0.635 0.254) (xy -0.5334 0.254)
				(xy -0.5334 0.2794)
			)
			(stroke
				(width 0)
				(type default)
			)
			(fill no)
			(layer "B.CrtYd")
		)
		(pad "1" smd rect
			(at -0.40005 0)
			(size 0.4572 0.508)
			(layers "B.Cu" "B.Mask" "B.Paste")
			(net "UART_T5_NODE3_RXD")
		)
		(pad "2" smd rect
			(at 0.40005 0)
			(size 0.4572 0.508)
			(layers "B.Cu" "B.Mask" "B.Paste")
			(net "UART_T5_NODE3_RXD_R")
		)
	)
	(footprint ""
		(layer "B.Cu")
		(at 80.262222 -76.910692)
		(property "Reference" "R91"
			(at 3.545078 0.282194 0)
			(unlocked yes)
			(layer "B.SilkS")
			(effects
				(font
					(size 0.7874 0.5842)
					(thickness 0.1524)
				)
				(justify left mirror)
			)
		)
		(property "Value" ""
			(at 0 0 0)
			(layer "B.Fab")
			(effects
				(font
					(size 1.27 1.27)
				)
				(justify mirror)
			)
		)
		(duplicate_pad_numbers_are_jumpers no)
		(fp_line
			(start -0.7874 -0.4064)
			(end -0.7874 0.4064)
			(stroke
				(width 0.1524)
				(type default)
			)
			(layer "B.SilkS")
		)
		(fp_line
			(start -0.7874 0.4064)
			(end 0.7874 0.4064)
			(stroke
				(width 0.1524)
				(type default)
			)
			(layer "B.SilkS")
		)
		(fp_line
			(start 0.7874 -0.4064)
			(end -0.7874 -0.4064)
			(stroke
				(width 0.1524)
				(type default)
			)
			(layer "B.SilkS")
		)
		(fp_line
			(start 0.7874 0.4064)
			(end 0.7874 -0.4064)
			(stroke
				(width 0.1524)
				(type default)
			)
			(layer "B.SilkS")
		)
		(fp_poly
			(pts
				(xy 0.508 0.2794) (xy 0.508 0.2286) (xy 0.635 0.2286) (xy 0.635 -0.254) (xy 0.5334 -0.254) (xy 0.5334 -0.2794)
				(xy -0.5334 -0.2794) (xy -0.5334 -0.254) (xy -0.635 -0.254) (xy -0.635 0.254) (xy -0.5334 0.254)
				(xy -0.5334 0.2794)
			)
			(stroke
				(width 0)
				(type default)
			)
			(fill no)
			(layer "B.CrtYd")
		)
		(pad "1" smd rect
			(at -0.40005 0 180)
			(size 0.4572 0.508)
			(layers "B.Cu" "B.Mask" "B.Paste")
			(net "H_CPU_NODE1_PROCHOT_R")
		)
		(pad "2" smd rect
			(at 0.40005 0 180)
			(size 0.4572 0.508)
			(layers "B.Cu" "B.Mask" "B.Paste")
			(net "H_CPU_NODE1_PROCHOT_L")
		)
	)
	(footprint ""
		(layer "B.Cu")
		(at 155.05176 -184.951624 90)
		(property "Reference" "R885"
			(at 4.281424 -2.520442 270)
			(unlocked yes)
			(layer "B.SilkS")
			(effects
				(font
					(size 0.7874 0.5842)
					(thickness 0.1524)
				)
				(justify left mirror)
			)
		)
		(property "Value" ""
			(at 0 0 90)
			(layer "B.Fab")
			(effects
				(font
					(size 1.27 1.27)
				)
				(justify mirror)
			)
		)
		(duplicate_pad_numbers_are_jumpers no)
		(fp_line
			(start 0.7874 -0.4064)
			(end -0.7874 -0.4064)
			(stroke
				(width 0.1524)
				(type default)
			)
			(layer "B.SilkS")
		)
		(fp_line
			(start -0.7874 -0.4064)
			(end -0.7874 0.4064)
			(stroke
				(width 0.1524)
				(type default)
			)
			(layer "B.SilkS")
		)
		(fp_line
			(start 0.7874 0.4064)
			(end 0.7874 -0.4064)
			(stroke
				(width 0.1524)
				(type default)
			)
			(layer "B.SilkS")
		)
		(fp_line
			(start -0.7874 0.4064)
			(end 0.7874 0.4064)
			(stroke
				(width 0.1524)
				(type default)
			)
			(layer "B.SilkS")
		)
		(fp_poly
			(pts
				(xy 0.508 0.2794) (xy 0.508 0.2286) (xy 0.635 0.2286) (xy 0.635 -0.254) (xy 0.5334 -0.254) (xy 0.5334 -0.2794)
				(xy -0.5334 -0.2794) (xy -0.5334 -0.254) (xy -0.635 -0.254) (xy -0.635 0.254) (xy -0.5334 0.254)
				(xy -0.5334 0.2794)
			)
			(stroke
				(width 0)
				(type default)
			)
			(fill no)
			(layer "B.CrtYd")
		)
		(pad "1" smd rect
			(at -0.40005 0 270)
			(size 0.4572 0.508)
			(layers "B.Cu" "B.Mask" "B.Paste")
			(net "T11_NODE1_EN")
		)
		(pad "2" smd rect
			(at 0.40005 0 270)
			(size 0.4572 0.508)
			(layers "B.Cu" "B.Mask" "B.Paste")
			(net "T11_NODE1_EN_R")
		)
	)
	(footprint ""
		(layer "B.Cu")
		(at 128.305052 -151.31415 90)
		(property "Reference" "C872"
			(at 2.084578 1.440688 0)
			(unlocked yes)
			(layer "B.SilkS")
			(effects
				(font
					(size 0.7874 0.5842)
					(thickness 0.1524)
				)
				(justify left mirror)
			)
		)
		(property "Value" ""
			(at 0 0 90)
			(layer "B.Fab")
			(effects
				(font
					(size 1.27 1.27)
				)
				(justify mirror)
			)
		)
		(duplicate_pad_numbers_are_jumpers no)
		(fp_line
			(start 0.7874 -0.4064)
			(end -0.7874 -0.4064)
			(stroke
				(width 0.1524)
				(type default)
			)
			(layer "B.SilkS")
		)
		(fp_line
			(start -0.7874 -0.4064)
			(end -0.7874 0.4064)
			(stroke
				(width 0.1524)
				(type default)
			)
			(layer "B.SilkS")
		)
		(fp_line
			(start 0 0.381)
			(end 0 -0.381)
			(stroke
				(width 0.1524)
				(type default)
			)
			(layer "B.SilkS")
		)
		(fp_line
			(start 0.7874 0.4064)
			(end 0.7874 -0.4064)
			(stroke
				(width 0.1524)
				(type default)
			)
			(layer "B.SilkS")
		)
		(fp_line
			(start -0.7874 0.4064)
			(end 0.7874 0.4064)
			(stroke
				(width 0.1524)
				(type default)
			)
			(layer "B.SilkS")
		)
		(fp_poly
			(pts
				(xy 0.5334 0.254) (xy 0.635 0.254) (xy 0.635 0.2286) (xy 0.635 -0.254) (xy 0.5334 -0.254) (xy 0.5334 -0.2794)
				(xy -0.5334 -0.2794) (xy -0.5334 -0.254) (xy -0.635 -0.254) (xy -0.635 0.254) (xy -0.5334 0.254)
				(xy -0.5334 0.2794) (xy 0.508 0.2794) (xy 0.5334 0.2794)
			)
			(stroke
				(width 0)
				(type default)
			)
			(fill no)
			(layer "B.CrtYd")
		)
		(pad "1" smd rect
			(at -0.40005 0 270)
			(size 0.4572 0.508)
			(layers "B.Cu" "B.Mask" "B.Paste")
			(net "P1V0_NODE1")
		)
		(pad "2" smd rect
			(at 0.40005 0 270)
			(size 0.4572 0.508)
			(layers "B.Cu" "B.Mask" "B.Paste")
			(net "GND")
		)
	)
	(footprint ""
		(layer "B.Cu")
		(at 88.77935 -72.161654)
		(property "Reference" "R168"
			(at -1.91516 9.454896 0)
			(unlocked yes)
			(layer "B.SilkS")
			(effects
				(font
					(size 0.7874 0.5842)
					(thickness 0.1524)
				)
				(justify left mirror)
			)
		)
		(property "Value" ""
			(at 0 0 0)
			(layer "B.Fab")
			(effects
				(font
					(size 1.27 1.27)
				)
				(justify mirror)
			)
		)
		(duplicate_pad_numbers_are_jumpers no)
		(fp_line
			(start -0.7874 -0.4064)
			(end -0.7874 0.4064)
			(stroke
				(width 0.1524)
				(type default)
			)
			(layer "B.SilkS")
		)
		(fp_line
			(start -0.7874 0.4064)
			(end 0.7874 0.4064)
			(stroke
				(width 0.1524)
				(type default)
			)
			(layer "B.SilkS")
		)
		(fp_line
			(start 0.7874 -0.4064)
			(end -0.7874 -0.4064)
			(stroke
				(width 0.1524)
				(type default)
			)
			(layer "B.SilkS")
		)
		(fp_line
			(start 0.7874 0.4064)
			(end 0.7874 -0.4064)
			(stroke
				(width 0.1524)
				(type default)
			)
			(layer "B.SilkS")
		)
		(fp_poly
			(pts
				(xy 0.508 0.2794) (xy 0.508 0.2286) (xy 0.635 0.2286) (xy 0.635 -0.254) (xy 0.5334 -0.254) (xy 0.5334 -0.2794)
				(xy -0.5334 -0.2794) (xy -0.5334 -0.254) (xy -0.635 -0.254) (xy -0.635 0.254) (xy -0.5334 0.254)
				(xy -0.5334 0.2794)
			)
			(stroke
				(width 0)
				(type default)
			)
			(fill no)
			(layer "B.CrtYd")
		)
		(pad "1" smd rect
			(at -0.40005 0 180)
			(size 0.4572 0.508)
			(layers "B.Cu" "B.Mask" "B.Paste")
			(net "GND")
		)
		(pad "2" smd rect
			(at 0.40005 0 180)
			(size 0.4572 0.508)
			(layers "B.Cu" "B.Mask" "B.Paste")
			(net "PD_CPU_NODE1_PUNIT_ST_ADDR0")
		)
	)
	(footprint ""
		(layer "B.Cu")
		(at 142.07236 -173.013624 180)
		(property "Reference" "R730"
			(at 1.287272 0.298196 0)
			(unlocked yes)
			(layer "B.SilkS")
			(effects
				(font
					(size 0.7874 0.5842)
					(thickness 0.1524)
				)
				(justify left mirror)
			)
		)
		(property "Value" ""
			(at 0 0 0)
			(layer "B.Fab")
			(effects
				(font
					(size 1.27 1.27)
				)
				(justify mirror)
			)
		)
		(duplicate_pad_numbers_are_jumpers no)
		(fp_line
			(start 0.7874 0.4064)
			(end 0.7874 -0.4064)
			(stroke
				(width 0.1524)
				(type default)
			)
			(layer "B.SilkS")
		)
		(fp_line
			(start 0.7874 -0.4064)
			(end -0.7874 -0.4064)
			(stroke
				(width 0.1524)
				(type default)
			)
			(layer "B.SilkS")
		)
		(fp_line
			(start -0.7874 0.4064)
			(end 0.7874 0.4064)
			(stroke
				(width 0.1524)
				(type default)
			)
			(layer "B.SilkS")
		)
		(fp_line
			(start -0.7874 -0.4064)
			(end -0.7874 0.4064)
			(stroke
				(width 0.1524)
				(type default)
			)
			(layer "B.SilkS")
		)
		(fp_poly
			(pts
				(xy 0.508 0.2794) (xy 0.508 0.2286) (xy 0.635 0.2286) (xy 0.635 -0.254) (xy 0.5334 -0.254) (xy 0.5334 -0.2794)
				(xy -0.5334 -0.2794) (xy -0.5334 -0.254) (xy -0.635 -0.254) (xy -0.635 0.254) (xy -0.5334 0.254)
				(xy -0.5334 0.2794)
			)
			(stroke
				(width 0)
				(type default)
			)
			(fill no)
			(layer "B.CrtYd")
		)
		(pad "1" smd rect
			(at -0.40005 0)
			(size 0.4572 0.508)
			(layers "B.Cu" "B.Mask" "B.Paste")
			(net "T9_NODE3_EN")
		)
		(pad "2" smd rect
			(at 0.40005 0)
			(size 0.4572 0.508)
			(layers "B.Cu" "B.Mask" "B.Paste")
			(net "P5V_NODE1")
		)
	)
	(footprint ""
		(layer "B.Cu")
		(at 50.009298 -82.561938 90)
		(property "Reference" "R102"
			(at -32.484822 -14.724888 270)
			(unlocked yes)
			(layer "B.SilkS")
			(effects
				(font
					(size 0.7874 0.5842)
					(thickness 0.1524)
				)
				(justify left mirror)
			)
		)
		(property "Value" ""
			(at 0 0 90)
			(layer "B.Fab")
			(effects
				(font
					(size 1.27 1.27)
				)
				(justify mirror)
			)
		)
		(duplicate_pad_numbers_are_jumpers no)
		(fp_line
			(start 0.7874 -0.4064)
			(end -0.7874 -0.4064)
			(stroke
				(width 0.1524)
				(type default)
			)
			(layer "B.SilkS")
		)
		(fp_line
			(start -0.7874 -0.4064)
			(end -0.7874 0.4064)
			(stroke
				(width 0.1524)
				(type default)
			)
			(layer "B.SilkS")
		)
		(fp_line
			(start 0.7874 0.4064)
			(end 0.7874 -0.4064)
			(stroke
				(width 0.1524)
				(type default)
			)
			(layer "B.SilkS")
		)
		(fp_line
			(start -0.7874 0.4064)
			(end 0.7874 0.4064)
			(stroke
				(width 0.1524)
				(type default)
			)
			(layer "B.SilkS")
		)
		(fp_poly
			(pts
				(xy 0.508 0.2794) (xy 0.508 0.2286) (xy 0.635 0.2286) (xy 0.635 -0.254) (xy 0.5334 -0.254) (xy 0.5334 -0.2794)
				(xy -0.5334 -0.2794) (xy -0.5334 -0.254) (xy -0.635 -0.254) (xy -0.635 0.254) (xy -0.5334 0.254)
				(xy -0.5334 0.2794)
			)
			(stroke
				(width 0)
				(type default)
			)
			(fill no)
			(layer "B.CrtYd")
		)
		(pad "1" smd rect
			(at -0.40005 0 270)
			(size 0.4572 0.508)
			(layers "B.Cu" "B.Mask" "B.Paste")
			(net "PD_NODE1_NTB_RCOMP")
		)
		(pad "2" smd rect
			(at 0.40005 0 270)
			(size 0.4572 0.508)
			(layers "B.Cu" "B.Mask" "B.Paste")
			(net "GND")
		)
	)
	(footprint ""
		(layer "B.Cu")
		(at 69.96176 -188.126624 -90)
		(property "Reference" "C686"
			(at -4.318254 0.30099 270)
			(unlocked yes)
			(layer "B.SilkS")
			(effects
				(font
					(size 0.7874 0.5842)
					(thickness 0.1524)
				)
				(justify left mirror)
			)
		)
		(property "Value" ""
			(at 0 0 90)
			(layer "B.Fab")
			(effects
				(font
					(size 1.27 1.27)
				)
				(justify mirror)
			)
		)
		(duplicate_pad_numbers_are_jumpers no)
		(fp_line
			(start -0.7874 0.4064)
			(end 0.7874 0.4064)
			(stroke
				(width 0.1524)
				(type default)
			)
			(layer "B.SilkS")
		)
		(fp_line
			(start 0.7874 0.4064)
			(end 0.7874 -0.4064)
			(stroke
				(width 0.1524)
				(type default)
			)
			(layer "B.SilkS")
		)
		(fp_line
			(start 0 0.381)
			(end 0 -0.381)
			(stroke
				(width 0.1524)
				(type default)
			)
			(layer "B.SilkS")
		)
		(fp_line
			(start -0.7874 -0.4064)
			(end -0.7874 0.4064)
			(stroke
				(width 0.1524)
				(type default)
			)
			(layer "B.SilkS")
		)
		(fp_line
			(start 0.7874 -0.4064)
			(end -0.7874 -0.4064)
			(stroke
				(width 0.1524)
				(type default)
			)
			(layer "B.SilkS")
		)
		(fp_poly
			(pts
				(xy 0.5334 0.254) (xy 0.635 0.254) (xy 0.635 0.2286) (xy 0.635 -0.254) (xy 0.5334 -0.254) (xy 0.5334 -0.2794)
				(xy -0.5334 -0.2794) (xy -0.5334 -0.254) (xy -0.635 -0.254) (xy -0.635 0.254) (xy -0.5334 0.254)
				(xy -0.5334 0.2794) (xy 0.508 0.2794) (xy 0.5334 0.2794)
			)
			(stroke
				(width 0)
				(type default)
			)
			(fill no)
			(layer "B.CrtYd")
		)
		(pad "1" smd rect
			(at -0.40005 0 90)
			(size 0.4572 0.508)
			(layers "B.Cu" "B.Mask" "B.Paste")
			(net "UART_T3_NODE3_TXD_R")
		)
		(pad "2" smd rect
			(at 0.40005 0 90)
			(size 0.4572 0.508)
			(layers "B.Cu" "B.Mask" "B.Paste")
			(net "GND")
		)
	)
	(footprint ""
		(layer "B.Cu")
		(at 146.79676 -187.999624 90)
		(property "Reference" "R963"
			(at 4.438396 -1.74625 270)
			(unlocked yes)
			(layer "B.SilkS")
			(effects
				(font
					(size 0.7874 0.5842)
					(thickness 0.1524)
				)
				(justify left mirror)
			)
		)
		(property "Value" ""
			(at 0 0 90)
			(layer "B.Fab")
			(effects
				(font
					(size 1.27 1.27)
				)
				(justify mirror)
			)
		)
		(duplicate_pad_numbers_are_jumpers no)
		(fp_line
			(start 0.7874 -0.4064)
			(end -0.7874 -0.4064)
			(stroke
				(width 0.1524)
				(type default)
			)
			(layer "B.SilkS")
		)
		(fp_line
			(start -0.7874 -0.4064)
			(end -0.7874 0.4064)
			(stroke
				(width 0.1524)
				(type default)
			)
			(layer "B.SilkS")
		)
		(fp_line
			(start 0.7874 0.4064)
			(end 0.7874 -0.4064)
			(stroke
				(width 0.1524)
				(type default)
			)
			(layer "B.SilkS")
		)
		(fp_line
			(start -0.7874 0.4064)
			(end 0.7874 0.4064)
			(stroke
				(width 0.1524)
				(type default)
			)
			(layer "B.SilkS")
		)
		(fp_poly
			(pts
				(xy 0.508 0.2794) (xy 0.508 0.2286) (xy 0.635 0.2286) (xy 0.635 -0.254) (xy 0.5334 -0.254) (xy 0.5334 -0.2794)
				(xy -0.5334 -0.2794) (xy -0.5334 -0.254) (xy -0.635 -0.254) (xy -0.635 0.254) (xy -0.5334 0.254)
				(xy -0.5334 0.2794)
			)
			(stroke
				(width 0)
				(type default)
			)
			(fill no)
			(layer "B.CrtYd")
		)
		(pad "1" smd rect
			(at -0.40005 0 270)
			(size 0.4572 0.508)
			(layers "B.Cu" "B.Mask" "B.Paste")
			(net "UART_T11_NODE2_RXD")
		)
		(pad "2" smd rect
			(at 0.40005 0 270)
			(size 0.4572 0.508)
			(layers "B.Cu" "B.Mask" "B.Paste")
			(net "UART_T11_NODE2_RXD_R")
		)
	)
	(footprint ""
		(layer "B.Cu")
		(at 107.42676 -188.126624 -90)
		(property "Reference" "R838"
			(at -4.080256 -0.664972 270)
			(unlocked yes)
			(layer "B.SilkS")
			(effects
				(font
					(size 0.7874 0.5842)
					(thickness 0.1524)
				)
				(justify left mirror)
			)
		)
		(property "Value" ""
			(at 0 0 90)
			(layer "B.Fab")
			(effects
				(font
					(size 1.27 1.27)
				)
				(justify mirror)
			)
		)
		(duplicate_pad_numbers_are_jumpers no)
		(fp_line
			(start -0.7874 0.4064)
			(end 0.7874 0.4064)
			(stroke
				(width 0.1524)
				(type default)
			)
			(layer "B.SilkS")
		)
		(fp_line
			(start 0.7874 0.4064)
			(end 0.7874 -0.4064)
			(stroke
				(width 0.1524)
				(type default)
			)
			(layer "B.SilkS")
		)
		(fp_line
			(start -0.7874 -0.4064)
			(end -0.7874 0.4064)
			(stroke
				(width 0.1524)
				(type default)
			)
			(layer "B.SilkS")
		)
		(fp_line
			(start 0.7874 -0.4064)
			(end -0.7874 -0.4064)
			(stroke
				(width 0.1524)
				(type default)
			)
			(layer "B.SilkS")
		)
		(fp_poly
			(pts
				(xy 0.508 0.2794) (xy 0.508 0.2286) (xy 0.635 0.2286) (xy 0.635 -0.254) (xy 0.5334 -0.254) (xy 0.5334 -0.2794)
				(xy -0.5334 -0.2794) (xy -0.5334 -0.254) (xy -0.635 -0.254) (xy -0.635 0.254) (xy -0.5334 0.254)
				(xy -0.5334 0.2794)
			)
			(stroke
				(width 0)
				(type default)
			)
			(fill no)
			(layer "B.CrtYd")
		)
		(pad "1" smd rect
			(at -0.40005 0 90)
			(size 0.4572 0.508)
			(layers "B.Cu" "B.Mask" "B.Paste")
			(net "PSU_ALERT_R_N")
		)
		(pad "2" smd rect
			(at 0.40005 0 90)
			(size 0.4572 0.508)
			(layers "B.Cu" "B.Mask" "B.Paste")
			(net "PSU_ALERT_N")
		)
	)
	(footprint ""
		(layer "B.Cu")
		(at 37.621718 -137.4013 180)
		(property "Reference" "C227"
			(at 2.089912 -0.004064 0)
			(unlocked yes)
			(layer "B.SilkS")
			(effects
				(font
					(size 0.7874 0.5842)
					(thickness 0.1524)
				)
				(justify left mirror)
			)
		)
		(property "Value" ""
			(at 0 0 0)
			(layer "B.Fab")
			(effects
				(font
					(size 1.27 1.27)
				)
				(justify mirror)
			)
		)
		(duplicate_pad_numbers_are_jumpers no)
		(fp_line
			(start 0.7874 0.4064)
			(end 0.7874 -0.4064)
			(stroke
				(width 0.1524)
				(type default)
			)
			(layer "B.SilkS")
		)
		(fp_line
			(start 0.7874 -0.4064)
			(end -0.7874 -0.4064)
			(stroke
				(width 0.1524)
				(type default)
			)
			(layer "B.SilkS")
		)
		(fp_line
			(start 0 0.381)
			(end 0 -0.381)
			(stroke
				(width 0.1524)
				(type default)
			)
			(layer "B.SilkS")
		)
		(fp_line
			(start -0.7874 0.4064)
			(end 0.7874 0.4064)
			(stroke
				(width 0.1524)
				(type default)
			)
			(layer "B.SilkS")
		)
		(fp_line
			(start -0.7874 -0.4064)
			(end -0.7874 0.4064)
			(stroke
				(width 0.1524)
				(type default)
			)
			(layer "B.SilkS")
		)
		(fp_poly
			(pts
				(xy 0.5334 0.254) (xy 0.635 0.254) (xy 0.635 0.2286) (xy 0.635 -0.254) (xy 0.5334 -0.254) (xy 0.5334 -0.2794)
				(xy -0.5334 -0.2794) (xy -0.5334 -0.254) (xy -0.635 -0.254) (xy -0.635 0.254) (xy -0.5334 0.254)
				(xy -0.5334 0.2794) (xy 0.508 0.2794) (xy 0.5334 0.2794)
			)
			(stroke
				(width 0)
				(type default)
			)
			(fill no)
			(layer "B.CrtYd")
		)
		(pad "1" smd rect
			(at -0.40005 0)
			(size 0.4572 0.508)
			(layers "B.Cu" "B.Mask" "B.Paste")
			(net "GND")
		)
		(pad "2" smd rect
			(at 0.40005 0)
			(size 0.4572 0.508)
			(layers "B.Cu" "B.Mask" "B.Paste")
			(net "P0V75_BMC_VTTREF_NODE1")
		)
	)
	(footprint ""
		(layer "B.Cu")
		(at 130.794252 -135.87095 -90)
		(property "Reference" "C876"
			(at 5.07365 -0.27813 270)
			(unlocked yes)
			(layer "B.SilkS")
			(effects
				(font
					(size 0.7874 0.5842)
					(thickness 0.1524)
				)
				(justify left mirror)
			)
		)
		(property "Value" ""
			(at 0 0 90)
			(layer "B.Fab")
			(effects
				(font
					(size 1.27 1.27)
				)
				(justify mirror)
			)
		)
		(duplicate_pad_numbers_are_jumpers no)
		(fp_line
			(start -0.7874 0.4064)
			(end 0.7874 0.4064)
			(stroke
				(width 0.1524)
				(type default)
			)
			(layer "B.SilkS")
		)
		(fp_line
			(start 0.7874 0.4064)
			(end 0.7874 -0.4064)
			(stroke
				(width 0.1524)
				(type default)
			)
			(layer "B.SilkS")
		)
		(fp_line
			(start 0 0.381)
			(end 0 -0.381)
			(stroke
				(width 0.1524)
				(type default)
			)
			(layer "B.SilkS")
		)
		(fp_line
			(start -0.7874 -0.4064)
			(end -0.7874 0.4064)
			(stroke
				(width 0.1524)
				(type default)
			)
			(layer "B.SilkS")
		)
		(fp_line
			(start 0.7874 -0.4064)
			(end -0.7874 -0.4064)
			(stroke
				(width 0.1524)
				(type default)
			)
			(layer "B.SilkS")
		)
		(fp_poly
			(pts
				(xy 0.5334 0.254) (xy 0.635 0.254) (xy 0.635 0.2286) (xy 0.635 -0.254) (xy 0.5334 -0.254) (xy 0.5334 -0.2794)
				(xy -0.5334 -0.2794) (xy -0.5334 -0.254) (xy -0.635 -0.254) (xy -0.635 0.254) (xy -0.5334 0.254)
				(xy -0.5334 0.2794) (xy 0.508 0.2794) (xy 0.5334 0.2794)
			)
			(stroke
				(width 0)
				(type default)
			)
			(fill no)
			(layer "B.CrtYd")
		)
		(pad "1" smd rect
			(at -0.40005 0 90)
			(size 0.4572 0.508)
			(layers "B.Cu" "B.Mask" "B.Paste")
			(net "P1V0_NODE1")
		)
		(pad "2" smd rect
			(at 0.40005 0 90)
			(size 0.4572 0.508)
			(layers "B.Cu" "B.Mask" "B.Paste")
			(net "GND")
		)
	)
	(footprint ""
		(layer "B.Cu")
		(at 51.990498 -96.696784 90)
		(property "Reference" "R50"
			(at 6.405118 -4.494276 270)
			(unlocked yes)
			(layer "B.SilkS")
			(effects
				(font
					(size 0.7874 0.5842)
					(thickness 0.1524)
				)
				(justify left mirror)
			)
		)
		(property "Value" ""
			(at 0 0 90)
			(layer "B.Fab")
			(effects
				(font
					(size 1.27 1.27)
				)
				(justify mirror)
			)
		)
		(duplicate_pad_numbers_are_jumpers no)
		(fp_line
			(start 0.7874 -0.4064)
			(end -0.7874 -0.4064)
			(stroke
				(width 0.1524)
				(type default)
			)
			(layer "B.SilkS")
		)
		(fp_line
			(start -0.7874 -0.4064)
			(end -0.7874 0.4064)
			(stroke
				(width 0.1524)
				(type default)
			)
			(layer "B.SilkS")
		)
		(fp_line
			(start 0.7874 0.4064)
			(end 0.7874 -0.4064)
			(stroke
				(width 0.1524)
				(type default)
			)
			(layer "B.SilkS")
		)
		(fp_line
			(start -0.7874 0.4064)
			(end 0.7874 0.4064)
			(stroke
				(width 0.1524)
				(type default)
			)
			(layer "B.SilkS")
		)
		(fp_poly
			(pts
				(xy 0.508 0.2794) (xy 0.508 0.2286) (xy 0.635 0.2286) (xy 0.635 -0.254) (xy 0.5334 -0.254) (xy 0.5334 -0.2794)
				(xy -0.5334 -0.2794) (xy -0.5334 -0.254) (xy -0.635 -0.254) (xy -0.635 0.254) (xy -0.5334 0.254)
				(xy -0.5334 0.2794)
			)
			(stroke
				(width 0)
				(type default)
			)
			(fill no)
			(layer "B.CrtYd")
		)
		(pad "1" smd rect
			(at -0.40005 0 270)
			(size 0.4572 0.508)
			(layers "B.Cu" "B.Mask" "B.Paste")
			(net "PD_CPU_NODE1_DFX_GPIO_GRP1_7")
		)
		(pad "2" smd rect
			(at 0.40005 0 270)
			(size 0.4572 0.508)
			(layers "B.Cu" "B.Mask" "B.Paste")
			(net "GND")
		)
	)
	(footprint ""
		(layer "B.Cu")
		(at 78.83144 -164.377624)
		(property "Reference" "R783"
			(at 30.555946 20.921726 0)
			(unlocked yes)
			(layer "B.SilkS")
			(effects
				(font
					(size 0.7874 0.5842)
					(thickness 0.1524)
				)
				(justify left mirror)
			)
		)
		(property "Value" ""
			(at 0 0 0)
			(layer "B.Fab")
			(effects
				(font
					(size 1.27 1.27)
				)
				(justify mirror)
			)
		)
		(duplicate_pad_numbers_are_jumpers no)
		(fp_line
			(start -0.7874 -0.4064)
			(end -0.7874 0.4064)
			(stroke
				(width 0.1524)
				(type default)
			)
			(layer "B.SilkS")
		)
		(fp_line
			(start -0.7874 0.4064)
			(end 0.7874 0.4064)
			(stroke
				(width 0.1524)
				(type default)
			)
			(layer "B.SilkS")
		)
		(fp_line
			(start 0.7874 -0.4064)
			(end -0.7874 -0.4064)
			(stroke
				(width 0.1524)
				(type default)
			)
			(layer "B.SilkS")
		)
		(fp_line
			(start 0.7874 0.4064)
			(end 0.7874 -0.4064)
			(stroke
				(width 0.1524)
				(type default)
			)
			(layer "B.SilkS")
		)
		(fp_poly
			(pts
				(xy 0.508 0.2794) (xy 0.508 0.2286) (xy 0.635 0.2286) (xy 0.635 -0.254) (xy 0.5334 -0.254) (xy 0.5334 -0.2794)
				(xy -0.5334 -0.2794) (xy -0.5334 -0.254) (xy -0.635 -0.254) (xy -0.635 0.254) (xy -0.5334 0.254)
				(xy -0.5334 0.2794)
			)
			(stroke
				(width 0)
				(type default)
			)
			(fill no)
			(layer "B.CrtYd")
		)
		(pad "1" smd rect
			(at -0.40005 0 180)
			(size 0.4572 0.508)
			(layers "B.Cu" "B.Mask" "B.Paste")
			(net "GND")
		)
		(pad "2" smd rect
			(at 0.40005 0 180)
			(size 0.4572 0.508)
			(layers "B.Cu" "B.Mask" "B.Paste")
			(net "SDC_WAKEUP")
		)
	)
	(footprint ""
		(layer "B.Cu")
		(at 55.10276 -185.205624 90)
		(property "Reference" "C670"
			(at 4.15163 0.207264 270)
			(unlocked yes)
			(layer "B.SilkS")
			(effects
				(font
					(size 0.7874 0.5842)
					(thickness 0.1524)
				)
				(justify left mirror)
			)
		)
		(property "Value" ""
			(at 0 0 90)
			(layer "B.Fab")
			(effects
				(font
					(size 1.27 1.27)
				)
				(justify mirror)
			)
		)
		(duplicate_pad_numbers_are_jumpers no)
		(fp_line
			(start 0.7874 -0.4064)
			(end -0.7874 -0.4064)
			(stroke
				(width 0.1524)
				(type default)
			)
			(layer "B.SilkS")
		)
		(fp_line
			(start -0.7874 -0.4064)
			(end -0.7874 0.4064)
			(stroke
				(width 0.1524)
				(type default)
			)
			(layer "B.SilkS")
		)
		(fp_line
			(start 0 0.381)
			(end 0 -0.381)
			(stroke
				(width 0.1524)
				(type default)
			)
			(layer "B.SilkS")
		)
		(fp_line
			(start 0.7874 0.4064)
			(end 0.7874 -0.4064)
			(stroke
				(width 0.1524)
				(type default)
			)
			(layer "B.SilkS")
		)
		(fp_line
			(start -0.7874 0.4064)
			(end 0.7874 0.4064)
			(stroke
				(width 0.1524)
				(type default)
			)
			(layer "B.SilkS")
		)
		(fp_poly
			(pts
				(xy 0.5334 0.254) (xy 0.635 0.254) (xy 0.635 0.2286) (xy 0.635 -0.254) (xy 0.5334 -0.254) (xy 0.5334 -0.2794)
				(xy -0.5334 -0.2794) (xy -0.5334 -0.254) (xy -0.635 -0.254) (xy -0.635 0.254) (xy -0.5334 0.254)
				(xy -0.5334 0.2794) (xy 0.508 0.2794) (xy 0.5334 0.2794)
			)
			(stroke
				(width 0)
				(type default)
			)
			(fill no)
			(layer "B.CrtYd")
		)
		(pad "1" smd rect
			(at -0.40005 0 270)
			(size 0.4572 0.508)
			(layers "B.Cu" "B.Mask" "B.Paste")
			(net "UART_T1_NODE1_RXD")
		)
		(pad "2" smd rect
			(at 0.40005 0 270)
			(size 0.4572 0.508)
			(layers "B.Cu" "B.Mask" "B.Paste")
			(net "GND")
		)
	)
	(footprint ""
		(layer "B.Cu")
		(at 131.93776 -184.951624 90)
		(property "Reference" "R965"
			(at 4.329176 -2.62763 270)
			(unlocked yes)
			(layer "B.SilkS")
			(effects
				(font
					(size 0.7874 0.5842)
					(thickness 0.1524)
				)
				(justify left mirror)
			)
		)
		(property "Value" ""
			(at 0 0 90)
			(layer "B.Fab")
			(effects
				(font
					(size 1.27 1.27)
				)
				(justify mirror)
			)
		)
		(duplicate_pad_numbers_are_jumpers no)
		(fp_line
			(start 0.7874 -0.4064)
			(end -0.7874 -0.4064)
			(stroke
				(width 0.1524)
				(type default)
			)
			(layer "B.SilkS")
		)
		(fp_line
			(start -0.7874 -0.4064)
			(end -0.7874 0.4064)
			(stroke
				(width 0.1524)
				(type default)
			)
			(layer "B.SilkS")
		)
		(fp_line
			(start 0.7874 0.4064)
			(end 0.7874 -0.4064)
			(stroke
				(width 0.1524)
				(type default)
			)
			(layer "B.SilkS")
		)
		(fp_line
			(start -0.7874 0.4064)
			(end 0.7874 0.4064)
			(stroke
				(width 0.1524)
				(type default)
			)
			(layer "B.SilkS")
		)
		(fp_poly
			(pts
				(xy 0.508 0.2794) (xy 0.508 0.2286) (xy 0.635 0.2286) (xy 0.635 -0.254) (xy 0.5334 -0.254) (xy 0.5334 -0.2794)
				(xy -0.5334 -0.2794) (xy -0.5334 -0.254) (xy -0.635 -0.254) (xy -0.635 0.254) (xy -0.5334 0.254)
				(xy -0.5334 0.2794)
			)
			(stroke
				(width 0)
				(type default)
			)
			(fill no)
			(layer "B.CrtYd")
		)
		(pad "1" smd rect
			(at -0.40005 0 270)
			(size 0.4572 0.508)
			(layers "B.Cu" "B.Mask" "B.Paste")
			(net "UART_T9_NODE2_TXD")
		)
		(pad "2" smd rect
			(at 0.40005 0 270)
			(size 0.4572 0.508)
			(layers "B.Cu" "B.Mask" "B.Paste")
			(net "UART_T9_NODE2_TXD_R")
		)
	)
	(footprint ""
		(layer "B.Cu")
		(at 78.83144 -173.521624 180)
		(property "Reference" "R692"
			(at -30.562296 -20.108164 0)
			(unlocked yes)
			(layer "B.SilkS")
			(effects
				(font
					(size 0.7874 0.5842)
					(thickness 0.1524)
				)
				(justify left mirror)
			)
		)
		(property "Value" ""
			(at 0 0 0)
			(layer "B.Fab")
			(effects
				(font
					(size 1.27 1.27)
				)
				(justify mirror)
			)
		)
		(duplicate_pad_numbers_are_jumpers no)
		(fp_line
			(start 0.7874 0.4064)
			(end 0.7874 -0.4064)
			(stroke
				(width 0.1524)
				(type default)
			)
			(layer "B.SilkS")
		)
		(fp_line
			(start 0.7874 -0.4064)
			(end -0.7874 -0.4064)
			(stroke
				(width 0.1524)
				(type default)
			)
			(layer "B.SilkS")
		)
		(fp_line
			(start -0.7874 0.4064)
			(end 0.7874 0.4064)
			(stroke
				(width 0.1524)
				(type default)
			)
			(layer "B.SilkS")
		)
		(fp_line
			(start -0.7874 -0.4064)
			(end -0.7874 0.4064)
			(stroke
				(width 0.1524)
				(type default)
			)
			(layer "B.SilkS")
		)
		(fp_poly
			(pts
				(xy 0.508 0.2794) (xy 0.508 0.2286) (xy 0.635 0.2286) (xy 0.635 -0.254) (xy 0.5334 -0.254) (xy 0.5334 -0.2794)
				(xy -0.5334 -0.2794) (xy -0.5334 -0.254) (xy -0.635 -0.254) (xy -0.635 0.254) (xy -0.5334 0.254)
				(xy -0.5334 0.2794)
			)
			(stroke
				(width 0)
				(type default)
			)
			(fill no)
			(layer "B.CrtYd")
		)
		(pad "1" smd rect
			(at -0.40005 0)
			(size 0.4572 0.508)
			(layers "B.Cu" "B.Mask" "B.Paste")
			(net "T1_NODE4_EN")
		)
		(pad "2" smd rect
			(at 0.40005 0)
			(size 0.4572 0.508)
			(layers "B.Cu" "B.Mask" "B.Paste")
			(net "P5V_NODE1")
		)
	)
	(footprint ""
		(layer "B.Cu")
		(at 123.70816 -173.394624 180)
		(property "Reference" "R706"
			(at 28.598876 -31.524448 0)
			(unlocked yes)
			(layer "B.SilkS")
			(effects
				(font
					(size 0.7874 0.5842)
					(thickness 0.1524)
				)
				(justify left mirror)
			)
		)
		(property "Value" ""
			(at 0 0 0)
			(layer "B.Fab")
			(effects
				(font
					(size 1.27 1.27)
				)
				(justify mirror)
			)
		)
		(duplicate_pad_numbers_are_jumpers no)
		(fp_line
			(start 0.7874 0.4064)
			(end 0.7874 -0.4064)
			(stroke
				(width 0.1524)
				(type default)
			)
			(layer "B.SilkS")
		)
		(fp_line
			(start 0.7874 -0.4064)
			(end -0.7874 -0.4064)
			(stroke
				(width 0.1524)
				(type default)
			)
			(layer "B.SilkS")
		)
		(fp_line
			(start -0.7874 0.4064)
			(end 0.7874 0.4064)
			(stroke
				(width 0.1524)
				(type default)
			)
			(layer "B.SilkS")
		)
		(fp_line
			(start -0.7874 -0.4064)
			(end -0.7874 0.4064)
			(stroke
				(width 0.1524)
				(type default)
			)
			(layer "B.SilkS")
		)
		(fp_poly
			(pts
				(xy 0.508 0.2794) (xy 0.508 0.2286) (xy 0.635 0.2286) (xy 0.635 -0.254) (xy 0.5334 -0.254) (xy 0.5334 -0.2794)
				(xy -0.5334 -0.2794) (xy -0.5334 -0.254) (xy -0.635 -0.254) (xy -0.635 0.254) (xy -0.5334 0.254)
				(xy -0.5334 0.2794)
			)
			(stroke
				(width 0)
				(type default)
			)
			(fill no)
			(layer "B.CrtYd")
		)
		(pad "1" smd rect
			(at -0.40005 0)
			(size 0.4572 0.508)
			(layers "B.Cu" "B.Mask" "B.Paste")
			(net "P3V3_NODE1")
		)
		(pad "2" smd rect
			(at 0.40005 0)
			(size 0.4572 0.508)
			(layers "B.Cu" "B.Mask" "B.Paste")
			(net "N21699372")
		)
	)
	(footprint ""
		(layer "B.Cu")
		(at 149.60473 -168.612312)
		(property "Reference" "C572"
			(at 1.020572 1.1303 0)
			(unlocked yes)
			(layer "B.SilkS")
			(effects
				(font
					(size 0.7874 0.5842)
					(thickness 0.1524)
				)
				(justify left mirror)
			)
		)
		(property "Value" ""
			(at 0 0 0)
			(layer "B.Fab")
			(effects
				(font
					(size 1.27 1.27)
				)
				(justify mirror)
			)
		)
		(duplicate_pad_numbers_are_jumpers no)
		(fp_line
			(start -0.7874 -0.4064)
			(end -0.7874 0.4064)
			(stroke
				(width 0.1524)
				(type default)
			)
			(layer "B.SilkS")
		)
		(fp_line
			(start -0.7874 0.4064)
			(end 0.7874 0.4064)
			(stroke
				(width 0.1524)
				(type default)
			)
			(layer "B.SilkS")
		)
		(fp_line
			(start 0 0.381)
			(end 0 -0.381)
			(stroke
				(width 0.1524)
				(type default)
			)
			(layer "B.SilkS")
		)
		(fp_line
			(start 0.7874 -0.4064)
			(end -0.7874 -0.4064)
			(stroke
				(width 0.1524)
				(type default)
			)
			(layer "B.SilkS")
		)
		(fp_line
			(start 0.7874 0.4064)
			(end 0.7874 -0.4064)
			(stroke
				(width 0.1524)
				(type default)
			)
			(layer "B.SilkS")
		)
		(fp_poly
			(pts
				(xy 0.5334 0.254) (xy 0.635 0.254) (xy 0.635 0.2286) (xy 0.635 -0.254) (xy 0.5334 -0.254) (xy 0.5334 -0.2794)
				(xy -0.5334 -0.2794) (xy -0.5334 -0.254) (xy -0.635 -0.254) (xy -0.635 0.254) (xy -0.5334 0.254)
				(xy -0.5334 0.2794) (xy 0.508 0.2794) (xy 0.5334 0.2794)
			)
			(stroke
				(width 0)
				(type default)
			)
			(fill no)
			(layer "B.CrtYd")
		)
		(pad "1" smd rect
			(at -0.40005 0 180)
			(size 0.4572 0.508)
			(layers "B.Cu" "B.Mask" "B.Paste")
			(net "GND")
		)
		(pad "2" smd rect
			(at 0.40005 0 180)
			(size 0.4572 0.508)
			(layers "B.Cu" "B.Mask" "B.Paste")
			(net "P3V3_NODE1")
		)
	)
	(footprint ""
		(layer "B.Cu")
		(at 48.24476 -185.205624 -90)
		(property "Reference" "R843"
			(at -4.15163 -0.163068 270)
			(unlocked yes)
			(layer "B.SilkS")
			(effects
				(font
					(size 0.7874 0.5842)
					(thickness 0.1524)
				)
				(justify left mirror)
			)
		)
		(property "Value" ""
			(at 0 0 90)
			(layer "B.Fab")
			(effects
				(font
					(size 1.27 1.27)
				)
				(justify mirror)
			)
		)
		(duplicate_pad_numbers_are_jumpers no)
		(fp_line
			(start -0.7874 0.4064)
			(end 0.7874 0.4064)
			(stroke
				(width 0.1524)
				(type default)
			)
			(layer "B.SilkS")
		)
		(fp_line
			(start 0.7874 0.4064)
			(end 0.7874 -0.4064)
			(stroke
				(width 0.1524)
				(type default)
			)
			(layer "B.SilkS")
		)
		(fp_line
			(start -0.7874 -0.4064)
			(end -0.7874 0.4064)
			(stroke
				(width 0.1524)
				(type default)
			)
			(layer "B.SilkS")
		)
		(fp_line
			(start 0.7874 -0.4064)
			(end -0.7874 -0.4064)
			(stroke
				(width 0.1524)
				(type default)
			)
			(layer "B.SilkS")
		)
		(fp_poly
			(pts
				(xy 0.508 0.2794) (xy 0.508 0.2286) (xy 0.635 0.2286) (xy 0.635 -0.254) (xy 0.5334 -0.254) (xy 0.5334 -0.2794)
				(xy -0.5334 -0.2794) (xy -0.5334 -0.254) (xy -0.635 -0.254) (xy -0.635 0.254) (xy -0.5334 0.254)
				(xy -0.5334 0.2794)
			)
			(stroke
				(width 0)
				(type default)
			)
			(fill no)
			(layer "B.CrtYd")
		)
		(pad "1" smd rect
			(at -0.40005 0 90)
			(size 0.4572 0.508)
			(layers "B.Cu" "B.Mask" "B.Paste")
			(net "PSU5_DC_OK_R")
		)
		(pad "2" smd rect
			(at 0.40005 0 90)
			(size 0.4572 0.508)
			(layers "B.Cu" "B.Mask" "B.Paste")
			(net "PSU5_DC_OK_R_BUF")
		)
	)
	(footprint ""
		(layer "B.Cu")
		(at 66.1289 -92.814648 90)
		(property "Reference" "R155"
			(at -2.211324 0.99949 270)
			(unlocked yes)
			(layer "B.SilkS")
			(effects
				(font
					(size 0.7874 0.5842)
					(thickness 0.1524)
				)
				(justify left mirror)
			)
		)
		(property "Value" ""
			(at 0 0 90)
			(layer "B.Fab")
			(effects
				(font
					(size 1.27 1.27)
				)
				(justify mirror)
			)
		)
		(duplicate_pad_numbers_are_jumpers no)
		(fp_line
			(start 0.7874 -0.4064)
			(end -0.7874 -0.4064)
			(stroke
				(width 0.1524)
				(type default)
			)
			(layer "B.SilkS")
		)
		(fp_line
			(start -0.7874 -0.4064)
			(end -0.7874 0.4064)
			(stroke
				(width 0.1524)
				(type default)
			)
			(layer "B.SilkS")
		)
		(fp_line
			(start 0.7874 0.4064)
			(end 0.7874 -0.4064)
			(stroke
				(width 0.1524)
				(type default)
			)
			(layer "B.SilkS")
		)
		(fp_line
			(start -0.7874 0.4064)
			(end 0.7874 0.4064)
			(stroke
				(width 0.1524)
				(type default)
			)
			(layer "B.SilkS")
		)
		(fp_poly
			(pts
				(xy 0.508 0.2794) (xy 0.508 0.2286) (xy 0.635 0.2286) (xy 0.635 -0.254) (xy 0.5334 -0.254) (xy 0.5334 -0.2794)
				(xy -0.5334 -0.2794) (xy -0.5334 -0.254) (xy -0.635 -0.254) (xy -0.635 0.254) (xy -0.5334 0.254)
				(xy -0.5334 0.2794)
			)
			(stroke
				(width 0)
				(type default)
			)
			(fill no)
			(layer "B.CrtYd")
		)
		(pad "1" smd rect
			(at -0.40005 0 270)
			(size 0.4572 0.508)
			(layers "B.Cu" "B.Mask" "B.Paste")
			(net "GND")
		)
		(pad "2" smd rect
			(at 0.40005 0 270)
			(size 0.4572 0.508)
			(layers "B.Cu" "B.Mask" "B.Paste")
			(net "PD_CPU_NODE1_BRD_ID1")
		)
	)
	(footprint ""
		(layer "B.Cu")
		(at 64.182498 -96.696784 -90)
		(property "Reference" "R88"
			(at -6.314948 5.033264 270)
			(unlocked yes)
			(layer "B.SilkS")
			(effects
				(font
					(size 0.7874 0.5842)
					(thickness 0.1524)
				)
				(justify left mirror)
			)
		)
		(property "Value" ""
			(at 0 0 90)
			(layer "B.Fab")
			(effects
				(font
					(size 1.27 1.27)
				)
				(justify mirror)
			)
		)
		(duplicate_pad_numbers_are_jumpers no)
		(fp_line
			(start -0.7874 0.4064)
			(end 0.7874 0.4064)
			(stroke
				(width 0.1524)
				(type default)
			)
			(layer "B.SilkS")
		)
		(fp_line
			(start 0.7874 0.4064)
			(end 0.7874 -0.4064)
			(stroke
				(width 0.1524)
				(type default)
			)
			(layer "B.SilkS")
		)
		(fp_line
			(start -0.7874 -0.4064)
			(end -0.7874 0.4064)
			(stroke
				(width 0.1524)
				(type default)
			)
			(layer "B.SilkS")
		)
		(fp_line
			(start 0.7874 -0.4064)
			(end -0.7874 -0.4064)
			(stroke
				(width 0.1524)
				(type default)
			)
			(layer "B.SilkS")
		)
		(fp_poly
			(pts
				(xy 0.508 0.2794) (xy 0.508 0.2286) (xy 0.635 0.2286) (xy 0.635 -0.254) (xy 0.5334 -0.254) (xy 0.5334 -0.2794)
				(xy -0.5334 -0.2794) (xy -0.5334 -0.254) (xy -0.635 -0.254) (xy -0.635 0.254) (xy -0.5334 0.254)
				(xy -0.5334 0.2794)
			)
			(stroke
				(width 0)
				(type default)
			)
			(fill no)
			(layer "B.CrtYd")
		)
		(pad "1" smd rect
			(at -0.40005 0 90)
			(size 0.4572 0.508)
			(layers "B.Cu" "B.Mask" "B.Paste")
			(net "GND")
		)
		(pad "2" smd rect
			(at 0.40005 0 90)
			(size 0.4572 0.508)
			(layers "B.Cu" "B.Mask" "B.Paste")
			(net "NODE1_BIOS_MB_REV_ID0")
		)
	)
	(footprint ""
		(layer "B.Cu")
		(at 114.543078 -123.92152 -90)
		(property "Reference" "PC90"
			(at -2.466086 -0.681228 270)
			(unlocked yes)
			(layer "B.SilkS")
			(effects
				(font
					(size 0.7874 0.5842)
					(thickness 0.1524)
				)
				(justify left mirror)
			)
		)
		(property "Value" ""
			(at 0 0 90)
			(layer "B.Fab")
			(effects
				(font
					(size 1.27 1.27)
				)
				(justify mirror)
			)
		)
		(duplicate_pad_numbers_are_jumpers no)
		(fp_line
			(start -0.7874 0.4064)
			(end 0.7874 0.4064)
			(stroke
				(width 0.1524)
				(type default)
			)
			(layer "B.SilkS")
		)
		(fp_line
			(start 0.7874 0.4064)
			(end 0.7874 -0.4064)
			(stroke
				(width 0.1524)
				(type default)
			)
			(layer "B.SilkS")
		)
		(fp_line
			(start 0 0.381)
			(end 0 -0.381)
			(stroke
				(width 0.1524)
				(type default)
			)
			(layer "B.SilkS")
		)
		(fp_line
			(start -0.7874 -0.4064)
			(end -0.7874 0.4064)
			(stroke
				(width 0.1524)
				(type default)
			)
			(layer "B.SilkS")
		)
		(fp_line
			(start 0.7874 -0.4064)
			(end -0.7874 -0.4064)
			(stroke
				(width 0.1524)
				(type default)
			)
			(layer "B.SilkS")
		)
		(fp_poly
			(pts
				(xy 0.5334 0.254) (xy 0.635 0.254) (xy 0.635 0.2286) (xy 0.635 -0.254) (xy 0.5334 -0.254) (xy 0.5334 -0.2794)
				(xy -0.5334 -0.2794) (xy -0.5334 -0.254) (xy -0.635 -0.254) (xy -0.635 0.254) (xy -0.5334 0.254)
				(xy -0.5334 0.2794) (xy 0.508 0.2794) (xy 0.5334 0.2794)
			)
			(stroke
				(width 0)
				(type default)
			)
			(fill no)
			(layer "B.CrtYd")
		)
		(pad "1" smd rect
			(at -0.40005 0 90)
			(size 0.4572 0.508)
			(layers "B.Cu" "B.Mask" "B.Paste")
			(net "SW_VR_PVCCP_NODE1_VIN_FLT")
		)
		(pad "2" smd rect
			(at 0.40005 0 90)
			(size 0.4572 0.508)
			(layers "B.Cu" "B.Mask" "B.Paste")
			(net "GND")
		)
	)
	(footprint ""
		(layer "B.Cu")
		(at 37.647118 -136.400032)
		(property "Reference" "C228"
			(at -2.115312 0.07874 0)
			(unlocked yes)
			(layer "B.SilkS")
			(effects
				(font
					(size 0.7874 0.5842)
					(thickness 0.1524)
				)
				(justify left mirror)
			)
		)
		(property "Value" ""
			(at 0 0 0)
			(layer "B.Fab")
			(effects
				(font
					(size 1.27 1.27)
				)
				(justify mirror)
			)
		)
		(duplicate_pad_numbers_are_jumpers no)
		(fp_line
			(start -0.7874 -0.4064)
			(end -0.7874 0.4064)
			(stroke
				(width 0.1524)
				(type default)
			)
			(layer "B.SilkS")
		)
		(fp_line
			(start -0.7874 0.4064)
			(end 0.7874 0.4064)
			(stroke
				(width 0.1524)
				(type default)
			)
			(layer "B.SilkS")
		)
		(fp_line
			(start 0 0.381)
			(end 0 -0.381)
			(stroke
				(width 0.1524)
				(type default)
			)
			(layer "B.SilkS")
		)
		(fp_line
			(start 0.7874 -0.4064)
			(end -0.7874 -0.4064)
			(stroke
				(width 0.1524)
				(type default)
			)
			(layer "B.SilkS")
		)
		(fp_line
			(start 0.7874 0.4064)
			(end 0.7874 -0.4064)
			(stroke
				(width 0.1524)
				(type default)
			)
			(layer "B.SilkS")
		)
		(fp_poly
			(pts
				(xy 0.5334 0.254) (xy 0.635 0.254) (xy 0.635 0.2286) (xy 0.635 -0.254) (xy 0.5334 -0.254) (xy 0.5334 -0.2794)
				(xy -0.5334 -0.2794) (xy -0.5334 -0.254) (xy -0.635 -0.254) (xy -0.635 0.254) (xy -0.5334 0.254)
				(xy -0.5334 0.2794) (xy 0.508 0.2794) (xy 0.5334 0.2794)
			)
			(stroke
				(width 0)
				(type default)
			)
			(fill no)
			(layer "B.CrtYd")
		)
		(pad "1" smd rect
			(at -0.40005 0 180)
			(size 0.4572 0.508)
			(layers "B.Cu" "B.Mask" "B.Paste")
			(net "P0V75_BMC_VTTREF_NODE1")
		)
		(pad "2" smd rect
			(at 0.40005 0 180)
			(size 0.4572 0.508)
			(layers "B.Cu" "B.Mask" "B.Paste")
			(net "GND")
		)
	)
	(footprint ""
		(layer "B.Cu")
		(at 50.457862 -71.938134 90)
		(property "Reference" "R149"
			(at -32.133794 -15.404592 270)
			(unlocked yes)
			(layer "B.SilkS")
			(effects
				(font
					(size 0.7874 0.5842)
					(thickness 0.1524)
				)
				(justify left mirror)
			)
		)
		(property "Value" ""
			(at 0 0 90)
			(layer "B.Fab")
			(effects
				(font
					(size 1.27 1.27)
				)
				(justify mirror)
			)
		)
		(duplicate_pad_numbers_are_jumpers no)
		(fp_line
			(start 0.7874 -0.4064)
			(end -0.7874 -0.4064)
			(stroke
				(width 0.1524)
				(type default)
			)
			(layer "B.SilkS")
		)
		(fp_line
			(start -0.7874 -0.4064)
			(end -0.7874 0.4064)
			(stroke
				(width 0.1524)
				(type default)
			)
			(layer "B.SilkS")
		)
		(fp_line
			(start 0.7874 0.4064)
			(end 0.7874 -0.4064)
			(stroke
				(width 0.1524)
				(type default)
			)
			(layer "B.SilkS")
		)
		(fp_line
			(start -0.7874 0.4064)
			(end 0.7874 0.4064)
			(stroke
				(width 0.1524)
				(type default)
			)
			(layer "B.SilkS")
		)
		(fp_poly
			(pts
				(xy 0.508 0.2794) (xy 0.508 0.2286) (xy 0.635 0.2286) (xy 0.635 -0.254) (xy 0.5334 -0.254) (xy 0.5334 -0.2794)
				(xy -0.5334 -0.2794) (xy -0.5334 -0.254) (xy -0.635 -0.254) (xy -0.635 0.254) (xy -0.5334 0.254)
				(xy -0.5334 0.2794)
			)
			(stroke
				(width 0)
				(type default)
			)
			(fill no)
			(layer "B.CrtYd")
		)
		(pad "1" smd rect
			(at -0.40005 0 270)
			(size 0.4572 0.508)
			(layers "B.Cu" "B.Mask" "B.Paste")
			(net "P1V5_NODE1")
		)
		(pad "2" smd rect
			(at 0.40005 0 270)
			(size 0.4572 0.508)
			(layers "B.Cu" "B.Mask" "B.Paste")
			(net "P1V5_NODE1_AM21")
		)
	)
	(footprint ""
		(layer "B.Cu")
		(at 62.067186 -79.813404 90)
		(property "Reference" "C83"
			(at -32.260032 -14.407896 270)
			(unlocked yes)
			(layer "B.SilkS")
			(effects
				(font
					(size 0.7874 0.5842)
					(thickness 0.1524)
				)
				(justify left mirror)
			)
		)
		(property "Value" ""
			(at 0 0 90)
			(layer "B.Fab")
			(effects
				(font
					(size 1.27 1.27)
				)
				(justify mirror)
			)
		)
		(duplicate_pad_numbers_are_jumpers no)
		(fp_line
			(start 0.7874 -0.4064)
			(end -0.7874 -0.4064)
			(stroke
				(width 0.1524)
				(type default)
			)
			(layer "B.SilkS")
		)
		(fp_line
			(start -0.7874 -0.4064)
			(end -0.7874 0.4064)
			(stroke
				(width 0.1524)
				(type default)
			)
			(layer "B.SilkS")
		)
		(fp_line
			(start 0 0.381)
			(end 0 -0.381)
			(stroke
				(width 0.1524)
				(type default)
			)
			(layer "B.SilkS")
		)
		(fp_line
			(start 0.7874 0.4064)
			(end 0.7874 -0.4064)
			(stroke
				(width 0.1524)
				(type default)
			)
			(layer "B.SilkS")
		)
		(fp_line
			(start -0.7874 0.4064)
			(end 0.7874 0.4064)
			(stroke
				(width 0.1524)
				(type default)
			)
			(layer "B.SilkS")
		)
		(fp_poly
			(pts
				(xy 0.5334 0.254) (xy 0.635 0.254) (xy 0.635 0.2286) (xy 0.635 -0.254) (xy 0.5334 -0.254) (xy 0.5334 -0.2794)
				(xy -0.5334 -0.2794) (xy -0.5334 -0.254) (xy -0.635 -0.254) (xy -0.635 0.254) (xy -0.5334 0.254)
				(xy -0.5334 0.2794) (xy 0.508 0.2794) (xy 0.5334 0.2794)
			)
			(stroke
				(width 0)
				(type default)
			)
			(fill no)
			(layer "B.CrtYd")
		)
		(pad "1" smd rect
			(at -0.40005 0 270)
			(size 0.4572 0.508)
			(layers "B.Cu" "B.Mask" "B.Paste")
			(net "PV_VCCP_NODE1")
		)
		(pad "2" smd rect
			(at 0.40005 0 270)
			(size 0.4572 0.508)
			(layers "B.Cu" "B.Mask" "B.Paste")
			(net "GND")
		)
	)
	(footprint ""
		(layer "B.Cu")
		(at 75.299062 -165.296596 -90)
		(property "Reference" "R917"
			(at -0.476758 2.78638 270)
			(unlocked yes)
			(layer "B.SilkS")
			(effects
				(font
					(size 0.7874 0.5842)
					(thickness 0.1524)
				)
				(justify left mirror)
			)
		)
		(property "Value" ""
			(at 0 0 90)
			(layer "B.Fab")
			(effects
				(font
					(size 1.27 1.27)
				)
				(justify mirror)
			)
		)
		(duplicate_pad_numbers_are_jumpers no)
		(fp_line
			(start -0.7874 0.4064)
			(end 0.7874 0.4064)
			(stroke
				(width 0.1524)
				(type default)
			)
			(layer "B.SilkS")
		)
		(fp_line
			(start 0.7874 0.4064)
			(end 0.7874 -0.4064)
			(stroke
				(width 0.1524)
				(type default)
			)
			(layer "B.SilkS")
		)
		(fp_line
			(start -0.7874 -0.4064)
			(end -0.7874 0.4064)
			(stroke
				(width 0.1524)
				(type default)
			)
			(layer "B.SilkS")
		)
		(fp_line
			(start 0.7874 -0.4064)
			(end -0.7874 -0.4064)
			(stroke
				(width 0.1524)
				(type default)
			)
			(layer "B.SilkS")
		)
		(fp_poly
			(pts
				(xy 0.508 0.2794) (xy 0.508 0.2286) (xy 0.635 0.2286) (xy 0.635 -0.254) (xy 0.5334 -0.254) (xy 0.5334 -0.2794)
				(xy -0.5334 -0.2794) (xy -0.5334 -0.254) (xy -0.635 -0.254) (xy -0.635 0.254) (xy -0.5334 0.254)
				(xy -0.5334 0.2794)
			)
			(stroke
				(width 0)
				(type default)
			)
			(fill no)
			(layer "B.CrtYd")
		)
		(pad "1" smd rect
			(at -0.40005 0 90)
			(size 0.4572 0.508)
			(layers "B.Cu" "B.Mask" "B.Paste")
			(net "UART_T3_NODE2_TXD")
		)
		(pad "2" smd rect
			(at 0.40005 0 90)
			(size 0.4572 0.508)
			(layers "B.Cu" "B.Mask" "B.Paste")
			(net "UART_T3_NODE2_TXD_R")
		)
	)
	(footprint ""
		(layer "B.Cu")
		(at 57.898538 -79.023718 -90)
		(property "Reference" "C44"
			(at 32.112204 14.534388 270)
			(unlocked yes)
			(layer "B.SilkS")
			(effects
				(font
					(size 0.7874 0.5842)
					(thickness 0.1524)
				)
				(justify left mirror)
			)
		)
		(property "Value" ""
			(at 0 0 90)
			(layer "B.Fab")
			(effects
				(font
					(size 1.27 1.27)
				)
				(justify mirror)
			)
		)
		(duplicate_pad_numbers_are_jumpers no)
		(fp_line
			(start -0.7874 0.4064)
			(end 0.7874 0.4064)
			(stroke
				(width 0.1524)
				(type default)
			)
			(layer "B.SilkS")
		)
		(fp_line
			(start 0.7874 0.4064)
			(end 0.7874 -0.4064)
			(stroke
				(width 0.1524)
				(type default)
			)
			(layer "B.SilkS")
		)
		(fp_line
			(start 0 0.381)
			(end 0 -0.381)
			(stroke
				(width 0.1524)
				(type default)
			)
			(layer "B.SilkS")
		)
		(fp_line
			(start -0.7874 -0.4064)
			(end -0.7874 0.4064)
			(stroke
				(width 0.1524)
				(type default)
			)
			(layer "B.SilkS")
		)
		(fp_line
			(start 0.7874 -0.4064)
			(end -0.7874 -0.4064)
			(stroke
				(width 0.1524)
				(type default)
			)
			(layer "B.SilkS")
		)
		(fp_poly
			(pts
				(xy 0.5334 0.254) (xy 0.635 0.254) (xy 0.635 0.2286) (xy 0.635 -0.254) (xy 0.5334 -0.254) (xy 0.5334 -0.2794)
				(xy -0.5334 -0.2794) (xy -0.5334 -0.254) (xy -0.635 -0.254) (xy -0.635 0.254) (xy -0.5334 0.254)
				(xy -0.5334 0.2794) (xy 0.508 0.2794) (xy 0.5334 0.2794)
			)
			(stroke
				(width 0)
				(type default)
			)
			(fill no)
			(layer "B.CrtYd")
		)
		(pad "1" smd rect
			(at -0.40005 0 90)
			(size 0.4572 0.508)
			(layers "B.Cu" "B.Mask" "B.Paste")
			(net "P1V05_NODE1")
		)
		(pad "2" smd rect
			(at 0.40005 0 90)
			(size 0.4572 0.508)
			(layers "B.Cu" "B.Mask" "B.Paste")
			(net "GND")
		)
	)
	(footprint ""
		(layer "B.Cu")
		(at 154.06116 -176.569624)
		(property "Reference" "R745"
			(at -1.323086 12.476226 0)
			(unlocked yes)
			(layer "B.SilkS")
			(effects
				(font
					(size 0.7874 0.5842)
					(thickness 0.1524)
				)
				(justify left mirror)
			)
		)
		(property "Value" ""
			(at 0 0 0)
			(layer "B.Fab")
			(effects
				(font
					(size 1.27 1.27)
				)
				(justify mirror)
			)
		)
		(duplicate_pad_numbers_are_jumpers no)
		(fp_line
			(start -0.7874 -0.4064)
			(end -0.7874 0.4064)
			(stroke
				(width 0.1524)
				(type default)
			)
			(layer "B.SilkS")
		)
		(fp_line
			(start -0.7874 0.4064)
			(end 0.7874 0.4064)
			(stroke
				(width 0.1524)
				(type default)
			)
			(layer "B.SilkS")
		)
		(fp_line
			(start 0.7874 -0.4064)
			(end -0.7874 -0.4064)
			(stroke
				(width 0.1524)
				(type default)
			)
			(layer "B.SilkS")
		)
		(fp_line
			(start 0.7874 0.4064)
			(end 0.7874 -0.4064)
			(stroke
				(width 0.1524)
				(type default)
			)
			(layer "B.SilkS")
		)
		(fp_poly
			(pts
				(xy 0.508 0.2794) (xy 0.508 0.2286) (xy 0.635 0.2286) (xy 0.635 -0.254) (xy 0.5334 -0.254) (xy 0.5334 -0.2794)
				(xy -0.5334 -0.2794) (xy -0.5334 -0.254) (xy -0.635 -0.254) (xy -0.635 0.254) (xy -0.5334 0.254)
				(xy -0.5334 0.2794)
			)
			(stroke
				(width 0)
				(type default)
			)
			(fill no)
			(layer "B.CrtYd")
		)
		(pad "1" smd rect
			(at -0.40005 0 180)
			(size 0.4572 0.508)
			(layers "B.Cu" "B.Mask" "B.Paste")
			(net "T11_NODE4_EN")
		)
		(pad "2" smd rect
			(at 0.40005 0 180)
			(size 0.4572 0.508)
			(layers "B.Cu" "B.Mask" "B.Paste")
			(net "P5V_NODE1")
		)
	)
	(footprint ""
		(layer "B.Cu")
		(at 175.038004 -116.29771 -90)
		(property "Reference" "C786"
			(at 3.083052 -0.327152 270)
			(unlocked yes)
			(layer "B.SilkS")
			(effects
				(font
					(size 0.7874 0.5842)
					(thickness 0.1524)
				)
				(justify mirror)
			)
		)
		(property "Value" ""
			(at 0 0 90)
			(layer "B.Fab")
			(effects
				(font
					(size 1.27 1.27)
				)
				(justify mirror)
			)
		)
		(duplicate_pad_numbers_are_jumpers no)
		(fp_line
			(start -1.2954 0.5842)
			(end 1.2954 0.5842)
			(stroke
				(width 0.1524)
				(type default)
			)
			(layer "B.SilkS")
		)
		(fp_line
			(start 1.2954 0.5842)
			(end 1.2954 -0.5842)
			(stroke
				(width 0.1524)
				(type default)
			)
			(layer "B.SilkS")
		)
		(fp_line
			(start -1.2954 -0.5842)
			(end -1.2954 0.5842)
			(stroke
				(width 0.1524)
				(type default)
			)
			(layer "B.SilkS")
		)
		(fp_line
			(start 0 -0.5842)
			(end 0 0.5842)
			(stroke
				(width 0.1524)
				(type default)
			)
			(layer "B.SilkS")
		)
		(fp_line
			(start 1.2954 -0.5842)
			(end -1.2954 -0.5842)
			(stroke
				(width 0.1524)
				(type default)
			)
			(layer "B.SilkS")
		)
		(fp_poly
			(pts
				(xy -0.8636 -0.4572) (xy -0.8636 -0.3556) (xy -1.143 -0.3556) (xy -1.143 0.3556) (xy -0.8636 0.3556)
				(xy -0.8636 0.4572) (xy 0.8636 0.4572) (xy 0.8636 0.3556) (xy 1.143 0.3556) (xy 1.143 -0.3556) (xy 0.8636 -0.3556)
				(xy 0.8636 -0.4572)
			)
			(stroke
				(width 0)
				(type default)
			)
			(fill no)
			(layer "B.CrtYd")
		)
		(fp_line
			(start -0.884936 0.504952)
			(end 0.884936 0.504952)
			(stroke
				(width 0.1)
				(type default)
			)
			(layer "B.Fab")
		)
		(fp_line
			(start 0.884936 0.504952)
			(end 0.884936 -0.504952)
			(stroke
				(width 0.1)
				(type default)
			)
			(layer "B.Fab")
		)
		(fp_line
			(start -0.884936 -0.504952)
			(end -0.884936 0.504952)
			(stroke
				(width 0.1)
				(type default)
			)
			(layer "B.Fab")
		)
		(fp_line
			(start 0.884936 -0.504952)
			(end -0.884936 -0.504952)
			(stroke
				(width 0.1)
				(type default)
			)
			(layer "B.Fab")
		)
		(pad "1" smd rect
			(at -0.7366 0)
			(size 0.7112 0.8128)
			(layers "B.Cu" "B.Mask" "B.Paste")
			(net "P3V3_STB_NODE1")
		)
		(pad "2" smd rect
			(at 0.7366 0)
			(size 0.7112 0.8128)
			(layers "B.Cu" "B.Mask" "B.Paste")
			(net "GND")
		)
	)
	(footprint ""
		(layer "B.Cu")
		(at 123.70816 -175.426624)
		(property "Reference" "R726"
			(at -28.598876 31.521146 0)
			(unlocked yes)
			(layer "B.SilkS")
			(effects
				(font
					(size 0.7874 0.5842)
					(thickness 0.1524)
				)
				(justify left mirror)
			)
		)
		(property "Value" ""
			(at 0 0 0)
			(layer "B.Fab")
			(effects
				(font
					(size 1.27 1.27)
				)
				(justify mirror)
			)
		)
		(duplicate_pad_numbers_are_jumpers no)
		(fp_line
			(start -0.7874 -0.4064)
			(end -0.7874 0.4064)
			(stroke
				(width 0.1524)
				(type default)
			)
			(layer "B.SilkS")
		)
		(fp_line
			(start -0.7874 0.4064)
			(end 0.7874 0.4064)
			(stroke
				(width 0.1524)
				(type default)
			)
			(layer "B.SilkS")
		)
		(fp_line
			(start 0.7874 -0.4064)
			(end -0.7874 -0.4064)
			(stroke
				(width 0.1524)
				(type default)
			)
			(layer "B.SilkS")
		)
		(fp_line
			(start 0.7874 0.4064)
			(end 0.7874 -0.4064)
			(stroke
				(width 0.1524)
				(type default)
			)
			(layer "B.SilkS")
		)
		(fp_poly
			(pts
				(xy 0.508 0.2794) (xy 0.508 0.2286) (xy 0.635 0.2286) (xy 0.635 -0.254) (xy 0.5334 -0.254) (xy 0.5334 -0.2794)
				(xy -0.5334 -0.2794) (xy -0.5334 -0.254) (xy -0.635 -0.254) (xy -0.635 0.254) (xy -0.5334 0.254)
				(xy -0.5334 0.2794)
			)
			(stroke
				(width 0)
				(type default)
			)
			(fill no)
			(layer "B.CrtYd")
		)
		(pad "1" smd rect
			(at -0.40005 0 180)
			(size 0.4572 0.508)
			(layers "B.Cu" "B.Mask" "B.Paste")
			(net "T8_NODE3_EN")
		)
		(pad "2" smd rect
			(at 0.40005 0 180)
			(size 0.4572 0.508)
			(layers "B.Cu" "B.Mask" "B.Paste")
			(net "P5V_NODE1")
		)
	)
	(footprint ""
		(layer "B.Cu")
		(at 39.70782 -149.41169 180)
		(property "Reference" "C397"
			(at 10.382504 9.51992 0)
			(unlocked yes)
			(layer "B.SilkS")
			(effects
				(font
					(size 0.7874 0.5842)
					(thickness 0.1524)
				)
				(justify left mirror)
			)
		)
		(property "Value" ""
			(at 0 0 0)
			(layer "B.Fab")
			(effects
				(font
					(size 1.27 1.27)
				)
				(justify mirror)
			)
		)
		(duplicate_pad_numbers_are_jumpers no)
		(fp_line
			(start 0.7874 0.4064)
			(end 0.7874 -0.4064)
			(stroke
				(width 0.1524)
				(type default)
			)
			(layer "B.SilkS")
		)
		(fp_line
			(start 0.7874 -0.4064)
			(end -0.7874 -0.4064)
			(stroke
				(width 0.1524)
				(type default)
			)
			(layer "B.SilkS")
		)
		(fp_line
			(start 0 0.381)
			(end 0 -0.381)
			(stroke
				(width 0.1524)
				(type default)
			)
			(layer "B.SilkS")
		)
		(fp_line
			(start -0.7874 0.4064)
			(end 0.7874 0.4064)
			(stroke
				(width 0.1524)
				(type default)
			)
			(layer "B.SilkS")
		)
		(fp_line
			(start -0.7874 -0.4064)
			(end -0.7874 0.4064)
			(stroke
				(width 0.1524)
				(type default)
			)
			(layer "B.SilkS")
		)
		(fp_poly
			(pts
				(xy 0.5334 0.254) (xy 0.635 0.254) (xy 0.635 0.2286) (xy 0.635 -0.254) (xy 0.5334 -0.254) (xy 0.5334 -0.2794)
				(xy -0.5334 -0.2794) (xy -0.5334 -0.254) (xy -0.635 -0.254) (xy -0.635 0.254) (xy -0.5334 0.254)
				(xy -0.5334 0.2794) (xy 0.508 0.2794) (xy 0.5334 0.2794)
			)
			(stroke
				(width 0)
				(type default)
			)
			(fill no)
			(layer "B.CrtYd")
		)
		(pad "1" smd rect
			(at -0.40005 0)
			(size 0.4572 0.508)
			(layers "B.Cu" "B.Mask" "B.Paste")
			(net "P3V3_NODE1")
		)
		(pad "2" smd rect
			(at 0.40005 0)
			(size 0.4572 0.508)
			(layers "B.Cu" "B.Mask" "B.Paste")
			(net "GND")
		)
	)
	(footprint ""
		(layer "B.Cu")
		(at 75.37069 -124.644404 -90)
		(property "Reference" "C283"
			(at 2.140204 -7.91464 270)
			(unlocked yes)
			(layer "B.SilkS")
			(effects
				(font
					(size 0.7874 0.5842)
					(thickness 0.1524)
				)
				(justify mirror)
			)
		)
		(property "Value" ""
			(at 0 0 90)
			(layer "B.Fab")
			(effects
				(font
					(size 1.27 1.27)
				)
				(justify mirror)
			)
		)
		(duplicate_pad_numbers_are_jumpers no)
		(fp_line
			(start -1.2954 0.5842)
			(end 1.2954 0.5842)
			(stroke
				(width 0.1524)
				(type default)
			)
			(layer "B.SilkS")
		)
		(fp_line
			(start 1.2954 0.5842)
			(end 1.2954 -0.5842)
			(stroke
				(width 0.1524)
				(type default)
			)
			(layer "B.SilkS")
		)
		(fp_line
			(start -1.2954 -0.5842)
			(end -1.2954 0.5842)
			(stroke
				(width 0.1524)
				(type default)
			)
			(layer "B.SilkS")
		)
		(fp_line
			(start 0 -0.5842)
			(end 0 0.5842)
			(stroke
				(width 0.1524)
				(type default)
			)
			(layer "B.SilkS")
		)
		(fp_line
			(start 1.2954 -0.5842)
			(end -1.2954 -0.5842)
			(stroke
				(width 0.1524)
				(type default)
			)
			(layer "B.SilkS")
		)
		(fp_poly
			(pts
				(xy -0.8636 -0.4572) (xy -0.8636 -0.3556) (xy -1.143 -0.3556) (xy -1.143 0.3556) (xy -0.8636 0.3556)
				(xy -0.8636 0.4572) (xy 0.8636 0.4572) (xy 0.8636 0.3556) (xy 1.143 0.3556) (xy 1.143 -0.3556) (xy 0.8636 -0.3556)
				(xy 0.8636 -0.4572)
			)
			(stroke
				(width 0)
				(type default)
			)
			(fill no)
			(layer "B.CrtYd")
		)
		(fp_line
			(start -0.884936 0.504952)
			(end 0.884936 0.504952)
			(stroke
				(width 0.1)
				(type default)
			)
			(layer "B.Fab")
		)
		(fp_line
			(start 0.884936 0.504952)
			(end 0.884936 -0.504952)
			(stroke
				(width 0.1)
				(type default)
			)
			(layer "B.Fab")
		)
		(fp_line
			(start -0.884936 -0.504952)
			(end -0.884936 0.504952)
			(stroke
				(width 0.1)
				(type default)
			)
			(layer "B.Fab")
		)
		(fp_line
			(start 0.884936 -0.504952)
			(end -0.884936 -0.504952)
			(stroke
				(width 0.1)
				(type default)
			)
			(layer "B.Fab")
		)
		(pad "1" smd rect
			(at -0.7366 0)
			(size 0.7112 0.8128)
			(layers "B.Cu" "B.Mask" "B.Paste")
			(net "BMC_NODE1_VCC_1V8_PCIEA")
		)
		(pad "2" smd rect
			(at 0.7366 0)
			(size 0.7112 0.8128)
			(layers "B.Cu" "B.Mask" "B.Paste")
			(net "GND")
		)
	)
	(footprint ""
		(layer "B.Cu")
		(at 65.198498 -96.696784 -90)
		(property "Reference" "R86"
			(at -6.314948 5.033264 270)
			(unlocked yes)
			(layer "B.SilkS")
			(effects
				(font
					(size 0.7874 0.5842)
					(thickness 0.1524)
				)
				(justify left mirror)
			)
		)
		(property "Value" ""
			(at 0 0 90)
			(layer "B.Fab")
			(effects
				(font
					(size 1.27 1.27)
				)
				(justify mirror)
			)
		)
		(duplicate_pad_numbers_are_jumpers no)
		(fp_line
			(start -0.7874 0.4064)
			(end 0.7874 0.4064)
			(stroke
				(width 0.1524)
				(type default)
			)
			(layer "B.SilkS")
		)
		(fp_line
			(start 0.7874 0.4064)
			(end 0.7874 -0.4064)
			(stroke
				(width 0.1524)
				(type default)
			)
			(layer "B.SilkS")
		)
		(fp_line
			(start -0.7874 -0.4064)
			(end -0.7874 0.4064)
			(stroke
				(width 0.1524)
				(type default)
			)
			(layer "B.SilkS")
		)
		(fp_line
			(start 0.7874 -0.4064)
			(end -0.7874 -0.4064)
			(stroke
				(width 0.1524)
				(type default)
			)
			(layer "B.SilkS")
		)
		(fp_poly
			(pts
				(xy 0.508 0.2794) (xy 0.508 0.2286) (xy 0.635 0.2286) (xy 0.635 -0.254) (xy 0.5334 -0.254) (xy 0.5334 -0.2794)
				(xy -0.5334 -0.2794) (xy -0.5334 -0.254) (xy -0.635 -0.254) (xy -0.635 0.254) (xy -0.5334 0.254)
				(xy -0.5334 0.2794)
			)
			(stroke
				(width 0)
				(type default)
			)
			(fill no)
			(layer "B.CrtYd")
		)
		(pad "1" smd rect
			(at -0.40005 0 90)
			(size 0.4572 0.508)
			(layers "B.Cu" "B.Mask" "B.Paste")
			(net "P3V3_NODE1")
		)
		(pad "2" smd rect
			(at 0.40005 0 90)
			(size 0.4572 0.508)
			(layers "B.Cu" "B.Mask" "B.Paste")
			(net "NODE1_BIOS_MB_REV_ID0")
		)
	)
	(footprint ""
		(layer "B.Cu")
		(at 132.750052 -113.975642 90)
		(property "Reference" "C4"
			(at 1.252728 0.302514 270)
			(unlocked yes)
			(layer "B.SilkS")
			(effects
				(font
					(size 0.7874 0.5842)
					(thickness 0.1524)
				)
				(justify left mirror)
			)
		)
		(property "Value" ""
			(at 0 0 90)
			(layer "B.Fab")
			(effects
				(font
					(size 1.27 1.27)
				)
				(justify mirror)
			)
		)
		(duplicate_pad_numbers_are_jumpers no)
		(fp_line
			(start 0.7874 -0.4064)
			(end -0.7874 -0.4064)
			(stroke
				(width 0.1524)
				(type default)
			)
			(layer "B.SilkS")
		)
		(fp_line
			(start -0.7874 -0.4064)
			(end -0.7874 0.4064)
			(stroke
				(width 0.1524)
				(type default)
			)
			(layer "B.SilkS")
		)
		(fp_line
			(start 0 0.381)
			(end 0 -0.381)
			(stroke
				(width 0.1524)
				(type default)
			)
			(layer "B.SilkS")
		)
		(fp_line
			(start 0.7874 0.4064)
			(end 0.7874 -0.4064)
			(stroke
				(width 0.1524)
				(type default)
			)
			(layer "B.SilkS")
		)
		(fp_line
			(start -0.7874 0.4064)
			(end 0.7874 0.4064)
			(stroke
				(width 0.1524)
				(type default)
			)
			(layer "B.SilkS")
		)
		(fp_poly
			(pts
				(xy 0.5334 0.254) (xy 0.635 0.254) (xy 0.635 0.2286) (xy 0.635 -0.254) (xy 0.5334 -0.254) (xy 0.5334 -0.2794)
				(xy -0.5334 -0.2794) (xy -0.5334 -0.254) (xy -0.635 -0.254) (xy -0.635 0.254) (xy -0.5334 0.254)
				(xy -0.5334 0.2794) (xy 0.508 0.2794) (xy 0.5334 0.2794)
			)
			(stroke
				(width 0)
				(type default)
			)
			(fill no)
			(layer "B.CrtYd")
		)
		(pad "1" smd rect
			(at -0.40005 0 270)
			(size 0.4572 0.508)
			(layers "B.Cu" "B.Mask" "B.Paste")
			(net "P3V3_CLK_NODE1")
		)
		(pad "2" smd rect
			(at 0.40005 0 270)
			(size 0.4572 0.508)
			(layers "B.Cu" "B.Mask" "B.Paste")
			(net "GND")
		)
	)
	(footprint ""
		(layer "B.Cu")
		(at 79.23276 -188.126624 -90)
		(property "Reference" "C646"
			(at -4.172712 0.173482 270)
			(unlocked yes)
			(layer "B.SilkS")
			(effects
				(font
					(size 0.7874 0.5842)
					(thickness 0.1524)
				)
				(justify left mirror)
			)
		)
		(property "Value" ""
			(at 0 0 90)
			(layer "B.Fab")
			(effects
				(font
					(size 1.27 1.27)
				)
				(justify mirror)
			)
		)
		(duplicate_pad_numbers_are_jumpers no)
		(fp_line
			(start -0.7874 0.4064)
			(end 0.7874 0.4064)
			(stroke
				(width 0.1524)
				(type default)
			)
			(layer "B.SilkS")
		)
		(fp_line
			(start 0.7874 0.4064)
			(end 0.7874 -0.4064)
			(stroke
				(width 0.1524)
				(type default)
			)
			(layer "B.SilkS")
		)
		(fp_line
			(start 0 0.381)
			(end 0 -0.381)
			(stroke
				(width 0.1524)
				(type default)
			)
			(layer "B.SilkS")
		)
		(fp_line
			(start -0.7874 -0.4064)
			(end -0.7874 0.4064)
			(stroke
				(width 0.1524)
				(type default)
			)
			(layer "B.SilkS")
		)
		(fp_line
			(start 0.7874 -0.4064)
			(end -0.7874 -0.4064)
			(stroke
				(width 0.1524)
				(type default)
			)
			(layer "B.SilkS")
		)
		(fp_poly
			(pts
				(xy 0.5334 0.254) (xy 0.635 0.254) (xy 0.635 0.2286) (xy 0.635 -0.254) (xy 0.5334 -0.254) (xy 0.5334 -0.2794)
				(xy -0.5334 -0.2794) (xy -0.5334 -0.254) (xy -0.635 -0.254) (xy -0.635 0.254) (xy -0.5334 0.254)
				(xy -0.5334 0.2794) (xy 0.508 0.2794) (xy 0.5334 0.2794)
			)
			(stroke
				(width 0)
				(type default)
			)
			(fill no)
			(layer "B.CrtYd")
		)
		(pad "1" smd rect
			(at -0.40005 0 90)
			(size 0.4572 0.508)
			(layers "B.Cu" "B.Mask" "B.Paste")
			(net "T3_NODE1_EN_R")
		)
		(pad "2" smd rect
			(at 0.40005 0 90)
			(size 0.4572 0.508)
			(layers "B.Cu" "B.Mask" "B.Paste")
			(net "GND")
		)
	)
	(footprint ""
		(layer "B.Cu")
		(at 110.44936 -174.537624 180)
		(property "Reference" "R710"
			(at 21.356828 -32.269176 0)
			(unlocked yes)
			(layer "B.SilkS")
			(effects
				(font
					(size 0.7874 0.5842)
					(thickness 0.1524)
				)
				(justify left mirror)
			)
		)
		(property "Value" ""
			(at 0 0 0)
			(layer "B.Fab")
			(effects
				(font
					(size 1.27 1.27)
				)
				(justify mirror)
			)
		)
		(duplicate_pad_numbers_are_jumpers no)
		(fp_line
			(start 0.7874 0.4064)
			(end 0.7874 -0.4064)
			(stroke
				(width 0.1524)
				(type default)
			)
			(layer "B.SilkS")
		)
		(fp_line
			(start 0.7874 -0.4064)
			(end -0.7874 -0.4064)
			(stroke
				(width 0.1524)
				(type default)
			)
			(layer "B.SilkS")
		)
		(fp_line
			(start -0.7874 0.4064)
			(end 0.7874 0.4064)
			(stroke
				(width 0.1524)
				(type default)
			)
			(layer "B.SilkS")
		)
		(fp_line
			(start -0.7874 -0.4064)
			(end -0.7874 0.4064)
			(stroke
				(width 0.1524)
				(type default)
			)
			(layer "B.SilkS")
		)
		(fp_poly
			(pts
				(xy 0.508 0.2794) (xy 0.508 0.2286) (xy 0.635 0.2286) (xy 0.635 -0.254) (xy 0.5334 -0.254) (xy 0.5334 -0.2794)
				(xy -0.5334 -0.2794) (xy -0.5334 -0.254) (xy -0.635 -0.254) (xy -0.635 0.254) (xy -0.5334 0.254)
				(xy -0.5334 0.2794)
			)
			(stroke
				(width 0)
				(type default)
			)
			(fill no)
			(layer "B.CrtYd")
		)
		(pad "1" smd rect
			(at -0.40005 0)
			(size 0.4572 0.508)
			(layers "B.Cu" "B.Mask" "B.Paste")
			(net "T5_NODE1_EN")
		)
		(pad "2" smd rect
			(at 0.40005 0)
			(size 0.4572 0.508)
			(layers "B.Cu" "B.Mask" "B.Paste")
			(net "P5V_NODE1")
		)
	)
	(footprint ""
		(layer "B.Cu")
		(at 171.180252 -102.05339)
		(property "Reference" "C373"
			(at 7.670038 0.26543 0)
			(unlocked yes)
			(layer "B.SilkS")
			(effects
				(font
					(size 0.7874 0.5842)
					(thickness 0.1524)
				)
				(justify left mirror)
			)
		)
		(property "Value" ""
			(at 0 0 0)
			(layer "B.Fab")
			(effects
				(font
					(size 1.27 1.27)
				)
				(justify mirror)
			)
		)
		(duplicate_pad_numbers_are_jumpers no)
		(fp_line
			(start -0.7874 -0.4064)
			(end -0.7874 0.4064)
			(stroke
				(width 0.1524)
				(type default)
			)
			(layer "B.SilkS")
		)
		(fp_line
			(start -0.7874 0.4064)
			(end 0.7874 0.4064)
			(stroke
				(width 0.1524)
				(type default)
			)
			(layer "B.SilkS")
		)
		(fp_line
			(start 0 0.381)
			(end 0 -0.381)
			(stroke
				(width 0.1524)
				(type default)
			)
			(layer "B.SilkS")
		)
		(fp_line
			(start 0.7874 -0.4064)
			(end -0.7874 -0.4064)
			(stroke
				(width 0.1524)
				(type default)
			)
			(layer "B.SilkS")
		)
		(fp_line
			(start 0.7874 0.4064)
			(end 0.7874 -0.4064)
			(stroke
				(width 0.1524)
				(type default)
			)
			(layer "B.SilkS")
		)
		(fp_poly
			(pts
				(xy 0.5334 0.254) (xy 0.635 0.254) (xy 0.635 0.2286) (xy 0.635 -0.254) (xy 0.5334 -0.254) (xy 0.5334 -0.2794)
				(xy -0.5334 -0.2794) (xy -0.5334 -0.254) (xy -0.635 -0.254) (xy -0.635 0.254) (xy -0.5334 0.254)
				(xy -0.5334 0.2794) (xy 0.508 0.2794) (xy 0.5334 0.2794)
			)
			(stroke
				(width 0)
				(type default)
			)
			(fill no)
			(layer "B.CrtYd")
		)
		(pad "1" smd rect
			(at -0.40005 0 180)
			(size 0.4572 0.508)
			(layers "B.Cu" "B.Mask" "B.Paste")
			(net "GND")
		)
		(pad "2" smd rect
			(at 0.40005 0 180)
			(size 0.4572 0.508)
			(layers "B.Cu" "B.Mask" "B.Paste")
			(net "P1V05_NODE1")
		)
	)
	(footprint ""
		(layer "B.Cu")
		(at 62.09792 -69.164454 90)
		(property "Reference" "C131"
			(at -34.018982 -14.26845 270)
			(unlocked yes)
			(layer "B.SilkS")
			(effects
				(font
					(size 0.7874 0.5842)
					(thickness 0.1524)
				)
				(justify left mirror)
			)
		)
		(property "Value" ""
			(at 0 0 90)
			(layer "B.Fab")
			(effects
				(font
					(size 1.27 1.27)
				)
				(justify mirror)
			)
		)
		(duplicate_pad_numbers_are_jumpers no)
		(fp_line
			(start 0.7874 -0.4064)
			(end -0.7874 -0.4064)
			(stroke
				(width 0.1524)
				(type default)
			)
			(layer "B.SilkS")
		)
		(fp_line
			(start -0.7874 -0.4064)
			(end -0.7874 0.4064)
			(stroke
				(width 0.1524)
				(type default)
			)
			(layer "B.SilkS")
		)
		(fp_line
			(start 0 0.381)
			(end 0 -0.381)
			(stroke
				(width 0.1524)
				(type default)
			)
			(layer "B.SilkS")
		)
		(fp_line
			(start 0.7874 0.4064)
			(end 0.7874 -0.4064)
			(stroke
				(width 0.1524)
				(type default)
			)
			(layer "B.SilkS")
		)
		(fp_line
			(start -0.7874 0.4064)
			(end 0.7874 0.4064)
			(stroke
				(width 0.1524)
				(type default)
			)
			(layer "B.SilkS")
		)
		(fp_poly
			(pts
				(xy 0.5334 0.254) (xy 0.635 0.254) (xy 0.635 0.2286) (xy 0.635 -0.254) (xy 0.5334 -0.254) (xy 0.5334 -0.2794)
				(xy -0.5334 -0.2794) (xy -0.5334 -0.254) (xy -0.635 -0.254) (xy -0.635 0.254) (xy -0.5334 0.254)
				(xy -0.5334 0.2794) (xy 0.508 0.2794) (xy 0.5334 0.2794)
			)
			(stroke
				(width 0)
				(type default)
			)
			(fill no)
			(layer "B.CrtYd")
		)
		(pad "1" smd rect
			(at -0.40005 0 270)
			(size 0.4572 0.508)
			(layers "B.Cu" "B.Mask" "B.Paste")
			(net "PV_VDDR_VCCCLK_DDR3_NODE1")
		)
		(pad "2" smd rect
			(at 0.40005 0 270)
			(size 0.4572 0.508)
			(layers "B.Cu" "B.Mask" "B.Paste")
			(net "GND")
		)
	)
	(footprint ""
		(layer "B.Cu")
		(at 142.07236 -178.093624 180)
		(property "Reference" "R740"
			(at 0.467868 1.204722 0)
			(unlocked yes)
			(layer "B.SilkS")
			(effects
				(font
					(size 0.7874 0.5842)
					(thickness 0.1524)
				)
				(justify left mirror)
			)
		)
		(property "Value" ""
			(at 0 0 0)
			(layer "B.Fab")
			(effects
				(font
					(size 1.27 1.27)
				)
				(justify mirror)
			)
		)
		(duplicate_pad_numbers_are_jumpers no)
		(fp_line
			(start 0.7874 0.4064)
			(end 0.7874 -0.4064)
			(stroke
				(width 0.1524)
				(type default)
			)
			(layer "B.SilkS")
		)
		(fp_line
			(start 0.7874 -0.4064)
			(end -0.7874 -0.4064)
			(stroke
				(width 0.1524)
				(type default)
			)
			(layer "B.SilkS")
		)
		(fp_line
			(start -0.7874 0.4064)
			(end 0.7874 0.4064)
			(stroke
				(width 0.1524)
				(type default)
			)
			(layer "B.SilkS")
		)
		(fp_line
			(start -0.7874 -0.4064)
			(end -0.7874 0.4064)
			(stroke
				(width 0.1524)
				(type default)
			)
			(layer "B.SilkS")
		)
		(fp_poly
			(pts
				(xy 0.508 0.2794) (xy 0.508 0.2286) (xy 0.635 0.2286) (xy 0.635 -0.254) (xy 0.5334 -0.254) (xy 0.5334 -0.2794)
				(xy -0.5334 -0.2794) (xy -0.5334 -0.254) (xy -0.635 -0.254) (xy -0.635 0.254) (xy -0.5334 0.254)
				(xy -0.5334 0.2794)
			)
			(stroke
				(width 0)
				(type default)
			)
			(fill no)
			(layer "B.CrtYd")
		)
		(pad "1" smd rect
			(at -0.40005 0)
			(size 0.4572 0.508)
			(layers "B.Cu" "B.Mask" "B.Paste")
			(net "T10_NODE4_EN")
		)
		(pad "2" smd rect
			(at 0.40005 0)
			(size 0.4572 0.508)
			(layers "B.Cu" "B.Mask" "B.Paste")
			(net "P5V_NODE1")
		)
	)
	(footprint ""
		(layer "B.Cu")
		(at 47.424086 -129.883662 180)
		(property "Reference" "C235"
			(at -3.865372 -0.06858 0)
			(unlocked yes)
			(layer "B.SilkS")
			(effects
				(font
					(size 0.7874 0.5842)
					(thickness 0.1524)
				)
				(justify left mirror)
			)
		)
		(property "Value" ""
			(at 0 0 0)
			(layer "B.Fab")
			(effects
				(font
					(size 1.27 1.27)
				)
				(justify mirror)
			)
		)
		(duplicate_pad_numbers_are_jumpers no)
		(fp_line
			(start 0.7874 0.4064)
			(end 0.7874 -0.4064)
			(stroke
				(width 0.1524)
				(type default)
			)
			(layer "B.SilkS")
		)
		(fp_line
			(start 0.7874 -0.4064)
			(end -0.7874 -0.4064)
			(stroke
				(width 0.1524)
				(type default)
			)
			(layer "B.SilkS")
		)
		(fp_line
			(start 0 0.381)
			(end 0 -0.381)
			(stroke
				(width 0.1524)
				(type default)
			)
			(layer "B.SilkS")
		)
		(fp_line
			(start -0.7874 0.4064)
			(end 0.7874 0.4064)
			(stroke
				(width 0.1524)
				(type default)
			)
			(layer "B.SilkS")
		)
		(fp_line
			(start -0.7874 -0.4064)
			(end -0.7874 0.4064)
			(stroke
				(width 0.1524)
				(type default)
			)
			(layer "B.SilkS")
		)
		(fp_poly
			(pts
				(xy 0.5334 0.254) (xy 0.635 0.254) (xy 0.635 0.2286) (xy 0.635 -0.254) (xy 0.5334 -0.254) (xy 0.5334 -0.2794)
				(xy -0.5334 -0.2794) (xy -0.5334 -0.254) (xy -0.635 -0.254) (xy -0.635 0.254) (xy -0.5334 0.254)
				(xy -0.5334 0.2794) (xy 0.508 0.2794) (xy 0.5334 0.2794)
			)
			(stroke
				(width 0)
				(type default)
			)
			(fill no)
			(layer "B.CrtYd")
		)
		(pad "1" smd rect
			(at -0.40005 0)
			(size 0.4572 0.508)
			(layers "B.Cu" "B.Mask" "B.Paste")
			(net "P1V538_BMC_NODE1")
		)
		(pad "2" smd rect
			(at 0.40005 0)
			(size 0.4572 0.508)
			(layers "B.Cu" "B.Mask" "B.Paste")
			(net "GND")
		)
	)
	(footprint ""
		(layer "B.Cu")
		(at 44.718732 -94.40037 -90)
		(property "Reference" "C31"
			(at 4.703318 4.488434 270)
			(unlocked yes)
			(layer "B.SilkS")
			(effects
				(font
					(size 0.7874 0.5842)
					(thickness 0.1524)
				)
				(justify left mirror)
			)
		)
		(property "Value" ""
			(at 0 0 90)
			(layer "B.Fab")
			(effects
				(font
					(size 1.27 1.27)
				)
				(justify mirror)
			)
		)
		(duplicate_pad_numbers_are_jumpers no)
		(fp_line
			(start -0.7874 0.4064)
			(end 0.7874 0.4064)
			(stroke
				(width 0.1524)
				(type default)
			)
			(layer "B.SilkS")
		)
		(fp_line
			(start 0.7874 0.4064)
			(end 0.7874 -0.4064)
			(stroke
				(width 0.1524)
				(type default)
			)
			(layer "B.SilkS")
		)
		(fp_line
			(start 0 0.381)
			(end 0 -0.381)
			(stroke
				(width 0.1524)
				(type default)
			)
			(layer "B.SilkS")
		)
		(fp_line
			(start -0.7874 -0.4064)
			(end -0.7874 0.4064)
			(stroke
				(width 0.1524)
				(type default)
			)
			(layer "B.SilkS")
		)
		(fp_line
			(start 0.7874 -0.4064)
			(end -0.7874 -0.4064)
			(stroke
				(width 0.1524)
				(type default)
			)
			(layer "B.SilkS")
		)
		(fp_poly
			(pts
				(xy 0.5334 0.254) (xy 0.635 0.254) (xy 0.635 0.2286) (xy 0.635 -0.254) (xy 0.5334 -0.254) (xy 0.5334 -0.2794)
				(xy -0.5334 -0.2794) (xy -0.5334 -0.254) (xy -0.635 -0.254) (xy -0.635 0.254) (xy -0.5334 0.254)
				(xy -0.5334 0.2794) (xy 0.508 0.2794) (xy 0.5334 0.2794)
			)
			(stroke
				(width 0)
				(type default)
			)
			(fill no)
			(layer "B.CrtYd")
		)
		(pad "1" smd rect
			(at -0.40005 0 90)
			(size 0.4572 0.508)
			(layers "B.Cu" "B.Mask" "B.Paste")
			(net "GND")
		)
		(pad "2" smd rect
			(at 0.40005 0 90)
			(size 0.4572 0.508)
			(layers "B.Cu" "B.Mask" "B.Paste")
			(net "SMB_CPU_NODE1_BMC_DAT_RR")
		)
	)
	(footprint ""
		(layer "B.Cu")
		(at 37.645086 -139.789662)
		(property "Reference" "C224"
			(at -2.11328 0.263906 0)
			(unlocked yes)
			(layer "B.SilkS")
			(effects
				(font
					(size 0.7874 0.5842)
					(thickness 0.1524)
				)
				(justify left mirror)
			)
		)
		(property "Value" ""
			(at 0 0 0)
			(layer "B.Fab")
			(effects
				(font
					(size 1.27 1.27)
				)
				(justify mirror)
			)
		)
		(duplicate_pad_numbers_are_jumpers no)
		(fp_line
			(start -0.7874 -0.4064)
			(end -0.7874 0.4064)
			(stroke
				(width 0.1524)
				(type default)
			)
			(layer "B.SilkS")
		)
		(fp_line
			(start -0.7874 0.4064)
			(end 0.7874 0.4064)
			(stroke
				(width 0.1524)
				(type default)
			)
			(layer "B.SilkS")
		)
		(fp_line
			(start 0 0.381)
			(end 0 -0.381)
			(stroke
				(width 0.1524)
				(type default)
			)
			(layer "B.SilkS")
		)
		(fp_line
			(start 0.7874 -0.4064)
			(end -0.7874 -0.4064)
			(stroke
				(width 0.1524)
				(type default)
			)
			(layer "B.SilkS")
		)
		(fp_line
			(start 0.7874 0.4064)
			(end 0.7874 -0.4064)
			(stroke
				(width 0.1524)
				(type default)
			)
			(layer "B.SilkS")
		)
		(fp_poly
			(pts
				(xy 0.5334 0.254) (xy 0.635 0.254) (xy 0.635 0.2286) (xy 0.635 -0.254) (xy 0.5334 -0.254) (xy 0.5334 -0.2794)
				(xy -0.5334 -0.2794) (xy -0.5334 -0.254) (xy -0.635 -0.254) (xy -0.635 0.254) (xy -0.5334 0.254)
				(xy -0.5334 0.2794) (xy 0.508 0.2794) (xy 0.5334 0.2794)
			)
			(stroke
				(width 0)
				(type default)
			)
			(fill no)
			(layer "B.CrtYd")
		)
		(pad "1" smd rect
			(at -0.40005 0 180)
			(size 0.4572 0.508)
			(layers "B.Cu" "B.Mask" "B.Paste")
			(net "P0V75_BMC_VTTREF_NODE1")
		)
		(pad "2" smd rect
			(at 0.40005 0 180)
			(size 0.4572 0.508)
			(layers "B.Cu" "B.Mask" "B.Paste")
			(net "GND")
		)
	)
	(footprint ""
		(layer "B.Cu")
		(at 129.143252 -123.7488 90)
		(property "Reference" "C9"
			(at -0.178054 1.089152 270)
			(unlocked yes)
			(layer "B.SilkS")
			(effects
				(font
					(size 0.7874 0.5842)
					(thickness 0.1524)
				)
				(justify mirror)
			)
		)
		(property "Value" ""
			(at 0 0 90)
			(layer "B.Fab")
			(effects
				(font
					(size 1.27 1.27)
				)
				(justify mirror)
			)
		)
		(duplicate_pad_numbers_are_jumpers no)
		(fp_line
			(start 1.2954 -0.5842)
			(end -1.2954 -0.5842)
			(stroke
				(width 0.1524)
				(type default)
			)
			(layer "B.SilkS")
		)
		(fp_line
			(start 0 -0.5842)
			(end 0 0.5842)
			(stroke
				(width 0.1524)
				(type default)
			)
			(layer "B.SilkS")
		)
		(fp_line
			(start -1.2954 -0.5842)
			(end -1.2954 0.5842)
			(stroke
				(width 0.1524)
				(type default)
			)
			(layer "B.SilkS")
		)
		(fp_line
			(start 1.2954 0.5842)
			(end 1.2954 -0.5842)
			(stroke
				(width 0.1524)
				(type default)
			)
			(layer "B.SilkS")
		)
		(fp_line
			(start -1.2954 0.5842)
			(end 1.2954 0.5842)
			(stroke
				(width 0.1524)
				(type default)
			)
			(layer "B.SilkS")
		)
		(fp_poly
			(pts
				(xy -0.8636 -0.4572) (xy -0.8636 -0.3556) (xy -1.143 -0.3556) (xy -1.143 0.3556) (xy -0.8636 0.3556)
				(xy -0.8636 0.4572) (xy 0.8636 0.4572) (xy 0.8636 0.3556) (xy 1.143 0.3556) (xy 1.143 -0.3556) (xy 0.8636 -0.3556)
				(xy 0.8636 -0.4572)
			)
			(stroke
				(width 0)
				(type default)
			)
			(fill no)
			(layer "B.CrtYd")
		)
		(fp_line
			(start 0.884936 -0.504952)
			(end -0.884936 -0.504952)
			(stroke
				(width 0.1)
				(type default)
			)
			(layer "B.Fab")
		)
		(fp_line
			(start -0.884936 -0.504952)
			(end -0.884936 0.504952)
			(stroke
				(width 0.1)
				(type default)
			)
			(layer "B.Fab")
		)
		(fp_line
			(start 0.884936 0.504952)
			(end 0.884936 -0.504952)
			(stroke
				(width 0.1)
				(type default)
			)
			(layer "B.Fab")
		)
		(fp_line
			(start -0.884936 0.504952)
			(end 0.884936 0.504952)
			(stroke
				(width 0.1)
				(type default)
			)
			(layer "B.Fab")
		)
		(pad "1" smd rect
			(at -0.7366 0 180)
			(size 0.7112 0.8128)
			(layers "B.Cu" "B.Mask" "B.Paste")
			(net "P1V05_CLK_NODE1")
		)
		(pad "2" smd rect
			(at 0.7366 0 180)
			(size 0.7112 0.8128)
			(layers "B.Cu" "B.Mask" "B.Paste")
			(net "GND")
		)
	)
	(footprint ""
		(layer "B.Cu")
		(at 153.90876 -187.872624 -90)
		(property "Reference" "C651"
			(at -4.565396 3.533902 270)
			(unlocked yes)
			(layer "B.SilkS")
			(effects
				(font
					(size 0.7874 0.5842)
					(thickness 0.1524)
				)
				(justify left mirror)
			)
		)
		(property "Value" ""
			(at 0 0 90)
			(layer "B.Fab")
			(effects
				(font
					(size 1.27 1.27)
				)
				(justify mirror)
			)
		)
		(duplicate_pad_numbers_are_jumpers no)
		(fp_line
			(start -0.7874 0.4064)
			(end 0.7874 0.4064)
			(stroke
				(width 0.1524)
				(type default)
			)
			(layer "B.SilkS")
		)
		(fp_line
			(start 0.7874 0.4064)
			(end 0.7874 -0.4064)
			(stroke
				(width 0.1524)
				(type default)
			)
			(layer "B.SilkS")
		)
		(fp_line
			(start 0 0.381)
			(end 0 -0.381)
			(stroke
				(width 0.1524)
				(type default)
			)
			(layer "B.SilkS")
		)
		(fp_line
			(start -0.7874 -0.4064)
			(end -0.7874 0.4064)
			(stroke
				(width 0.1524)
				(type default)
			)
			(layer "B.SilkS")
		)
		(fp_line
			(start 0.7874 -0.4064)
			(end -0.7874 -0.4064)
			(stroke
				(width 0.1524)
				(type default)
			)
			(layer "B.SilkS")
		)
		(fp_poly
			(pts
				(xy 0.5334 0.254) (xy 0.635 0.254) (xy 0.635 0.2286) (xy 0.635 -0.254) (xy 0.5334 -0.254) (xy 0.5334 -0.2794)
				(xy -0.5334 -0.2794) (xy -0.5334 -0.254) (xy -0.635 -0.254) (xy -0.635 0.254) (xy -0.5334 0.254)
				(xy -0.5334 0.2794) (xy 0.508 0.2794) (xy 0.5334 0.2794)
			)
			(stroke
				(width 0)
				(type default)
			)
			(fill no)
			(layer "B.CrtYd")
		)
		(pad "1" smd rect
			(at -0.40005 0 90)
			(size 0.4572 0.508)
			(layers "B.Cu" "B.Mask" "B.Paste")
			(net "T11_NODE2_EN_R")
		)
		(pad "2" smd rect
			(at 0.40005 0 90)
			(size 0.4572 0.508)
			(layers "B.Cu" "B.Mask" "B.Paste")
			(net "GND")
		)
	)
	(footprint ""
		(layer "B.Cu")
		(at 57.070498 -96.696784 90)
		(property "Reference" "R140"
			(at 6.405118 -4.364228 270)
			(unlocked yes)
			(layer "B.SilkS")
			(effects
				(font
					(size 0.7874 0.5842)
					(thickness 0.1524)
				)
				(justify left mirror)
			)
		)
		(property "Value" ""
			(at 0 0 90)
			(layer "B.Fab")
			(effects
				(font
					(size 1.27 1.27)
				)
				(justify mirror)
			)
		)
		(duplicate_pad_numbers_are_jumpers no)
		(fp_line
			(start 0.7874 -0.4064)
			(end -0.7874 -0.4064)
			(stroke
				(width 0.1524)
				(type default)
			)
			(layer "B.SilkS")
		)
		(fp_line
			(start -0.7874 -0.4064)
			(end -0.7874 0.4064)
			(stroke
				(width 0.1524)
				(type default)
			)
			(layer "B.SilkS")
		)
		(fp_line
			(start 0.7874 0.4064)
			(end 0.7874 -0.4064)
			(stroke
				(width 0.1524)
				(type default)
			)
			(layer "B.SilkS")
		)
		(fp_line
			(start -0.7874 0.4064)
			(end 0.7874 0.4064)
			(stroke
				(width 0.1524)
				(type default)
			)
			(layer "B.SilkS")
		)
		(fp_poly
			(pts
				(xy 0.508 0.2794) (xy 0.508 0.2286) (xy 0.635 0.2286) (xy 0.635 -0.254) (xy 0.5334 -0.254) (xy 0.5334 -0.2794)
				(xy -0.5334 -0.2794) (xy -0.5334 -0.254) (xy -0.635 -0.254) (xy -0.635 0.254) (xy -0.5334 0.254)
				(xy -0.5334 0.2794)
			)
			(stroke
				(width 0)
				(type default)
			)
			(fill no)
			(layer "B.CrtYd")
		)
		(pad "1" smd rect
			(at -0.40005 0 270)
			(size 0.4572 0.508)
			(layers "B.Cu" "B.Mask" "B.Paste")
			(net "H_CPU_NODE1_THRM_LS_L")
		)
		(pad "2" smd rect
			(at 0.40005 0 270)
			(size 0.4572 0.508)
			(layers "B.Cu" "B.Mask" "B.Paste")
			(net "P3V3_NODE1")
		)
	)
	(footprint ""
		(layer "B.Cu")
		(at 161.458148 -196.09943)
		(property "Reference" "TP12"
			(at 0 0 0)
			(layer "B.SilkS")
			(hide yes)
			(effects
				(font
					(size 1.27 1.27)
				)
				(justify mirror)
			)
		)
		(property "Value" ""
			(at 0 0 0)
			(layer "B.Fab")
			(effects
				(font
					(size 1.27 1.27)
				)
				(justify mirror)
			)
		)
		(duplicate_pad_numbers_are_jumpers no)
		(fp_poly
			(pts
				(arc
					(start 0 -0.381)
					(mid 0 0.381)
					(end 0 -0.381)
				)
			)
			(stroke
				(width 0)
				(type default)
			)
			(fill no)
			(layer "B.CrtYd")
		)
		(pad "1" smd circle
			(at 0 0 180)
			(size 0.762 0.762)
			(layers "B.Cu" "B.Mask" "B.Paste")
			(net "UART_CTS_RP6_L")
		)
	)
	(footprint ""
		(layer "B.Cu")
		(at 61.96076 -185.205624 -90)
		(property "Reference" "C676"
			(at -4.15163 0.002286 270)
			(unlocked yes)
			(layer "B.SilkS")
			(effects
				(font
					(size 0.7874 0.5842)
					(thickness 0.1524)
				)
				(justify left mirror)
			)
		)
		(property "Value" ""
			(at 0 0 90)
			(layer "B.Fab")
			(effects
				(font
					(size 1.27 1.27)
				)
				(justify mirror)
			)
		)
		(duplicate_pad_numbers_are_jumpers no)
		(fp_line
			(start -0.7874 0.4064)
			(end 0.7874 0.4064)
			(stroke
				(width 0.1524)
				(type default)
			)
			(layer "B.SilkS")
		)
		(fp_line
			(start 0.7874 0.4064)
			(end 0.7874 -0.4064)
			(stroke
				(width 0.1524)
				(type default)
			)
			(layer "B.SilkS")
		)
		(fp_line
			(start 0 0.381)
			(end 0 -0.381)
			(stroke
				(width 0.1524)
				(type default)
			)
			(layer "B.SilkS")
		)
		(fp_line
			(start -0.7874 -0.4064)
			(end -0.7874 0.4064)
			(stroke
				(width 0.1524)
				(type default)
			)
			(layer "B.SilkS")
		)
		(fp_line
			(start 0.7874 -0.4064)
			(end -0.7874 -0.4064)
			(stroke
				(width 0.1524)
				(type default)
			)
			(layer "B.SilkS")
		)
		(fp_poly
			(pts
				(xy 0.5334 0.254) (xy 0.635 0.254) (xy 0.635 0.2286) (xy 0.635 -0.254) (xy 0.5334 -0.254) (xy 0.5334 -0.2794)
				(xy -0.5334 -0.2794) (xy -0.5334 -0.254) (xy -0.635 -0.254) (xy -0.635 0.254) (xy -0.5334 0.254)
				(xy -0.5334 0.2794) (xy 0.508 0.2794) (xy 0.5334 0.2794)
			)
			(stroke
				(width 0)
				(type default)
			)
			(fill no)
			(layer "B.CrtYd")
		)
		(pad "1" smd rect
			(at -0.40005 0 90)
			(size 0.4572 0.508)
			(layers "B.Cu" "B.Mask" "B.Paste")
			(net "UART_T1_NODE2_RXD")
		)
		(pad "2" smd rect
			(at 0.40005 0 90)
			(size 0.4572 0.508)
			(layers "B.Cu" "B.Mask" "B.Paste")
			(net "GND")
		)
	)
	(footprint ""
		(layer "B.Cu")
		(at 94.451932 -173.140624 180)
		(property "Reference" "R719"
			(at -1.83642 -14.364716 0)
			(unlocked yes)
			(layer "B.SilkS")
			(effects
				(font
					(size 0.7874 0.5842)
					(thickness 0.1524)
				)
				(justify left mirror)
			)
		)
		(property "Value" ""
			(at 0 0 0)
			(layer "B.Fab")
			(effects
				(font
					(size 1.27 1.27)
				)
				(justify mirror)
			)
		)
		(duplicate_pad_numbers_are_jumpers no)
		(fp_line
			(start 0.7874 0.4064)
			(end 0.7874 -0.4064)
			(stroke
				(width 0.1524)
				(type default)
			)
			(layer "B.SilkS")
		)
		(fp_line
			(start 0.7874 -0.4064)
			(end -0.7874 -0.4064)
			(stroke
				(width 0.1524)
				(type default)
			)
			(layer "B.SilkS")
		)
		(fp_line
			(start -0.7874 0.4064)
			(end 0.7874 0.4064)
			(stroke
				(width 0.1524)
				(type default)
			)
			(layer "B.SilkS")
		)
		(fp_line
			(start -0.7874 -0.4064)
			(end -0.7874 0.4064)
			(stroke
				(width 0.1524)
				(type default)
			)
			(layer "B.SilkS")
		)
		(fp_poly
			(pts
				(xy 0.508 0.2794) (xy 0.508 0.2286) (xy 0.635 0.2286) (xy 0.635 -0.254) (xy 0.5334 -0.254) (xy 0.5334 -0.2794)
				(xy -0.5334 -0.2794) (xy -0.5334 -0.254) (xy -0.635 -0.254) (xy -0.635 0.254) (xy -0.5334 0.254)
				(xy -0.5334 0.2794)
			)
			(stroke
				(width 0)
				(type default)
			)
			(fill no)
			(layer "B.CrtYd")
		)
		(pad "1" smd rect
			(at -0.40005 0)
			(size 0.4572 0.508)
			(layers "B.Cu" "B.Mask" "B.Paste")
			(net "N21699606")
		)
		(pad "2" smd rect
			(at 0.40005 0)
			(size 0.4572 0.508)
			(layers "B.Cu" "B.Mask" "B.Paste")
			(net "GND")
		)
	)
	(footprint ""
		(layer "B.Cu")
		(at 130.514852 -151.03475 180)
		(property "Reference" "C871"
			(at -1.054862 -2.075434 0)
			(unlocked yes)
			(layer "B.SilkS")
			(effects
				(font
					(size 0.7874 0.5842)
					(thickness 0.1524)
				)
				(justify left mirror)
			)
		)
		(property "Value" ""
			(at 0 0 0)
			(layer "B.Fab")
			(effects
				(font
					(size 1.27 1.27)
				)
				(justify mirror)
			)
		)
		(duplicate_pad_numbers_are_jumpers no)
		(fp_line
			(start 0.7874 0.4064)
			(end 0.7874 -0.4064)
			(stroke
				(width 0.1524)
				(type default)
			)
			(layer "B.SilkS")
		)
		(fp_line
			(start 0.7874 -0.4064)
			(end -0.7874 -0.4064)
			(stroke
				(width 0.1524)
				(type default)
			)
			(layer "B.SilkS")
		)
		(fp_line
			(start 0 0.381)
			(end 0 -0.381)
			(stroke
				(width 0.1524)
				(type default)
			)
			(layer "B.SilkS")
		)
		(fp_line
			(start -0.7874 0.4064)
			(end 0.7874 0.4064)
			(stroke
				(width 0.1524)
				(type default)
			)
			(layer "B.SilkS")
		)
		(fp_line
			(start -0.7874 -0.4064)
			(end -0.7874 0.4064)
			(stroke
				(width 0.1524)
				(type default)
			)
			(layer "B.SilkS")
		)
		(fp_poly
			(pts
				(xy 0.5334 0.254) (xy 0.635 0.254) (xy 0.635 0.2286) (xy 0.635 -0.254) (xy 0.5334 -0.254) (xy 0.5334 -0.2794)
				(xy -0.5334 -0.2794) (xy -0.5334 -0.254) (xy -0.635 -0.254) (xy -0.635 0.254) (xy -0.5334 0.254)
				(xy -0.5334 0.2794) (xy 0.508 0.2794) (xy 0.5334 0.2794)
			)
			(stroke
				(width 0)
				(type default)
			)
			(fill no)
			(layer "B.CrtYd")
		)
		(pad "1" smd rect
			(at -0.40005 0)
			(size 0.4572 0.508)
			(layers "B.Cu" "B.Mask" "B.Paste")
			(net "P3V3_NODE1")
		)
		(pad "2" smd rect
			(at 0.40005 0)
			(size 0.4572 0.508)
			(layers "B.Cu" "B.Mask" "B.Paste")
			(net "GND")
		)
	)
	(footprint ""
		(layer "B.Cu")
		(at 75.471274 -94.131384 -90)
		(property "Reference" "R96"
			(at 3.075432 -0.409448 270)
			(unlocked yes)
			(layer "B.SilkS")
			(effects
				(font
					(size 0.7874 0.5842)
					(thickness 0.1524)
				)
				(justify left mirror)
			)
		)
		(property "Value" ""
			(at 0 0 90)
			(layer "B.Fab")
			(effects
				(font
					(size 1.27 1.27)
				)
				(justify mirror)
			)
		)
		(duplicate_pad_numbers_are_jumpers no)
		(fp_line
			(start -0.7874 0.4064)
			(end 0.7874 0.4064)
			(stroke
				(width 0.1524)
				(type default)
			)
			(layer "B.SilkS")
		)
		(fp_line
			(start 0.7874 0.4064)
			(end 0.7874 -0.4064)
			(stroke
				(width 0.1524)
				(type default)
			)
			(layer "B.SilkS")
		)
		(fp_line
			(start -0.7874 -0.4064)
			(end -0.7874 0.4064)
			(stroke
				(width 0.1524)
				(type default)
			)
			(layer "B.SilkS")
		)
		(fp_line
			(start 0.7874 -0.4064)
			(end -0.7874 -0.4064)
			(stroke
				(width 0.1524)
				(type default)
			)
			(layer "B.SilkS")
		)
		(fp_poly
			(pts
				(xy 0.508 0.2794) (xy 0.508 0.2286) (xy 0.635 0.2286) (xy 0.635 -0.254) (xy 0.5334 -0.254) (xy 0.5334 -0.2794)
				(xy -0.5334 -0.2794) (xy -0.5334 -0.254) (xy -0.635 -0.254) (xy -0.635 0.254) (xy -0.5334 0.254)
				(xy -0.5334 0.2794)
			)
			(stroke
				(width 0)
				(type default)
			)
			(fill no)
			(layer "B.CrtYd")
		)
		(pad "1" smd rect
			(at -0.40005 0 90)
			(size 0.4572 0.508)
			(layers "B.Cu" "B.Mask" "B.Paste")
			(net "GND")
		)
		(pad "2" smd rect
			(at 0.40005 0 90)
			(size 0.4572 0.508)
			(layers "B.Cu" "B.Mask" "B.Paste")
			(net "NODE1_BIOS_MB_REV_ID2")
		)
	)
	(footprint ""
		(layer "B.Cu")
		(at 64.24676 -188.126624 -90)
		(property "Reference" "C628"
			(at -4.318254 0.390906 270)
			(unlocked yes)
			(layer "B.SilkS")
			(effects
				(font
					(size 0.7874 0.5842)
					(thickness 0.1524)
				)
				(justify left mirror)
			)
		)
		(property "Value" ""
			(at 0 0 90)
			(layer "B.Fab")
			(effects
				(font
					(size 1.27 1.27)
				)
				(justify mirror)
			)
		)
		(duplicate_pad_numbers_are_jumpers no)
		(fp_line
			(start -0.7874 0.4064)
			(end 0.7874 0.4064)
			(stroke
				(width 0.1524)
				(type default)
			)
			(layer "B.SilkS")
		)
		(fp_line
			(start 0.7874 0.4064)
			(end 0.7874 -0.4064)
			(stroke
				(width 0.1524)
				(type default)
			)
			(layer "B.SilkS")
		)
		(fp_line
			(start 0 0.381)
			(end 0 -0.381)
			(stroke
				(width 0.1524)
				(type default)
			)
			(layer "B.SilkS")
		)
		(fp_line
			(start -0.7874 -0.4064)
			(end -0.7874 0.4064)
			(stroke
				(width 0.1524)
				(type default)
			)
			(layer "B.SilkS")
		)
		(fp_line
			(start 0.7874 -0.4064)
			(end -0.7874 -0.4064)
			(stroke
				(width 0.1524)
				(type default)
			)
			(layer "B.SilkS")
		)
		(fp_poly
			(pts
				(xy 0.5334 0.254) (xy 0.635 0.254) (xy 0.635 0.2286) (xy 0.635 -0.254) (xy 0.5334 -0.254) (xy 0.5334 -0.2794)
				(xy -0.5334 -0.2794) (xy -0.5334 -0.254) (xy -0.635 -0.254) (xy -0.635 0.254) (xy -0.5334 0.254)
				(xy -0.5334 0.2794) (xy 0.508 0.2794) (xy 0.5334 0.2794)
			)
			(stroke
				(width 0)
				(type default)
			)
			(fill no)
			(layer "B.CrtYd")
		)
		(pad "1" smd rect
			(at -0.40005 0 90)
			(size 0.4572 0.508)
			(layers "B.Cu" "B.Mask" "B.Paste")
			(net "T1_NODE3_EN_R")
		)
		(pad "2" smd rect
			(at 0.40005 0 90)
			(size 0.4572 0.508)
			(layers "B.Cu" "B.Mask" "B.Paste")
			(net "GND")
		)
	)
	(footprint ""
		(layer "B.Cu")
		(at 48.75022 -156.14269 180)
		(property "Reference" "C423"
			(at 11.81354 4.520184 0)
			(unlocked yes)
			(layer "B.SilkS")
			(effects
				(font
					(size 0.7874 0.5842)
					(thickness 0.1524)
				)
				(justify left mirror)
			)
		)
		(property "Value" ""
			(at 0 0 0)
			(layer "B.Fab")
			(effects
				(font
					(size 1.27 1.27)
				)
				(justify mirror)
			)
		)
		(duplicate_pad_numbers_are_jumpers no)
		(fp_line
			(start 0.7874 0.4064)
			(end 0.7874 -0.4064)
			(stroke
				(width 0.1524)
				(type default)
			)
			(layer "B.SilkS")
		)
		(fp_line
			(start 0.7874 -0.4064)
			(end -0.7874 -0.4064)
			(stroke
				(width 0.1524)
				(type default)
			)
			(layer "B.SilkS")
		)
		(fp_line
			(start 0 0.381)
			(end 0 -0.381)
			(stroke
				(width 0.1524)
				(type default)
			)
			(layer "B.SilkS")
		)
		(fp_line
			(start -0.7874 0.4064)
			(end 0.7874 0.4064)
			(stroke
				(width 0.1524)
				(type default)
			)
			(layer "B.SilkS")
		)
		(fp_line
			(start -0.7874 -0.4064)
			(end -0.7874 0.4064)
			(stroke
				(width 0.1524)
				(type default)
			)
			(layer "B.SilkS")
		)
		(fp_poly
			(pts
				(xy 0.5334 0.254) (xy 0.635 0.254) (xy 0.635 0.2286) (xy 0.635 -0.254) (xy 0.5334 -0.254) (xy 0.5334 -0.2794)
				(xy -0.5334 -0.2794) (xy -0.5334 -0.254) (xy -0.635 -0.254) (xy -0.635 0.254) (xy -0.5334 0.254)
				(xy -0.5334 0.2794) (xy 0.508 0.2794) (xy 0.5334 0.2794)
			)
			(stroke
				(width 0)
				(type default)
			)
			(fill no)
			(layer "B.CrtYd")
		)
		(pad "1" smd rect
			(at -0.40005 0)
			(size 0.4572 0.508)
			(layers "B.Cu" "B.Mask" "B.Paste")
			(net "P1V05_LAN1")
		)
		(pad "2" smd rect
			(at 0.40005 0)
			(size 0.4572 0.508)
			(layers "B.Cu" "B.Mask" "B.Paste")
			(net "GND")
		)
	)
	(footprint ""
		(layer "B.Cu")
		(at 51.67376 -185.205624 -90)
		(property "Reference" "R834"
			(at -4.15163 -0.209804 270)
			(unlocked yes)
			(layer "B.SilkS")
			(effects
				(font
					(size 0.7874 0.5842)
					(thickness 0.1524)
				)
				(justify left mirror)
			)
		)
		(property "Value" ""
			(at 0 0 90)
			(layer "B.Fab")
			(effects
				(font
					(size 1.27 1.27)
				)
				(justify mirror)
			)
		)
		(duplicate_pad_numbers_are_jumpers no)
		(fp_line
			(start -0.7874 0.4064)
			(end 0.7874 0.4064)
			(stroke
				(width 0.1524)
				(type default)
			)
			(layer "B.SilkS")
		)
		(fp_line
			(start 0.7874 0.4064)
			(end 0.7874 -0.4064)
			(stroke
				(width 0.1524)
				(type default)
			)
			(layer "B.SilkS")
		)
		(fp_line
			(start -0.7874 -0.4064)
			(end -0.7874 0.4064)
			(stroke
				(width 0.1524)
				(type default)
			)
			(layer "B.SilkS")
		)
		(fp_line
			(start 0.7874 -0.4064)
			(end -0.7874 -0.4064)
			(stroke
				(width 0.1524)
				(type default)
			)
			(layer "B.SilkS")
		)
		(fp_poly
			(pts
				(xy 0.508 0.2794) (xy 0.508 0.2286) (xy 0.635 0.2286) (xy 0.635 -0.254) (xy 0.5334 -0.254) (xy 0.5334 -0.2794)
				(xy -0.5334 -0.2794) (xy -0.5334 -0.254) (xy -0.635 -0.254) (xy -0.635 0.254) (xy -0.5334 0.254)
				(xy -0.5334 0.2794)
			)
			(stroke
				(width 0)
				(type default)
			)
			(fill no)
			(layer "B.CrtYd")
		)
		(pad "1" smd rect
			(at -0.40005 0 90)
			(size 0.4572 0.508)
			(layers "B.Cu" "B.Mask" "B.Paste")
			(net "PSU2_DC_OK_R")
		)
		(pad "2" smd rect
			(at 0.40005 0 90)
			(size 0.4572 0.508)
			(layers "B.Cu" "B.Mask" "B.Paste")
			(net "PSU2_DC_OK_R_BUF")
		)
	)
	(footprint ""
		(layer "B.Cu")
		(at 55.552086 -127.724662 180)
		(property "Reference" "C265"
			(at 41.609518 -53.453538 0)
			(unlocked yes)
			(layer "B.SilkS")
			(effects
				(font
					(size 0.7874 0.5842)
					(thickness 0.1524)
				)
				(justify left mirror)
			)
		)
		(property "Value" ""
			(at 0 0 0)
			(layer "B.Fab")
			(effects
				(font
					(size 1.27 1.27)
				)
				(justify mirror)
			)
		)
		(duplicate_pad_numbers_are_jumpers no)
		(fp_line
			(start 0.7874 0.4064)
			(end 0.7874 -0.4064)
			(stroke
				(width 0.1524)
				(type default)
			)
			(layer "B.SilkS")
		)
		(fp_line
			(start 0.7874 -0.4064)
			(end -0.7874 -0.4064)
			(stroke
				(width 0.1524)
				(type default)
			)
			(layer "B.SilkS")
		)
		(fp_line
			(start 0 0.381)
			(end 0 -0.381)
			(stroke
				(width 0.1524)
				(type default)
			)
			(layer "B.SilkS")
		)
		(fp_line
			(start -0.7874 0.4064)
			(end 0.7874 0.4064)
			(stroke
				(width 0.1524)
				(type default)
			)
			(layer "B.SilkS")
		)
		(fp_line
			(start -0.7874 -0.4064)
			(end -0.7874 0.4064)
			(stroke
				(width 0.1524)
				(type default)
			)
			(layer "B.SilkS")
		)
		(fp_poly
			(pts
				(xy 0.5334 0.254) (xy 0.635 0.254) (xy 0.635 0.2286) (xy 0.635 -0.254) (xy 0.5334 -0.254) (xy 0.5334 -0.2794)
				(xy -0.5334 -0.2794) (xy -0.5334 -0.254) (xy -0.635 -0.254) (xy -0.635 0.254) (xy -0.5334 0.254)
				(xy -0.5334 0.2794) (xy 0.508 0.2794) (xy 0.5334 0.2794)
			)
			(stroke
				(width 0)
				(type default)
			)
			(fill no)
			(layer "B.CrtYd")
		)
		(pad "1" smd rect
			(at -0.40005 0)
			(size 0.4572 0.508)
			(layers "B.Cu" "B.Mask" "B.Paste")
			(net "BMC_NODE1_MPLLAV33")
		)
		(pad "2" smd rect
			(at 0.40005 0)
			(size 0.4572 0.508)
			(layers "B.Cu" "B.Mask" "B.Paste")
			(net "GND")
		)
	)
	(footprint ""
		(layer "B.Cu")
		(at 39.687754 -76.22794 -90)
		(property "Reference" "C36"
			(at 0.150114 1.236218 270)
			(unlocked yes)
			(layer "B.SilkS")
			(effects
				(font
					(size 0.7874 0.5842)
					(thickness 0.1524)
				)
				(justify mirror)
			)
		)
		(property "Value" ""
			(at 0 0 90)
			(layer "B.Fab")
			(effects
				(font
					(size 1.27 1.27)
				)
				(justify mirror)
			)
		)
		(duplicate_pad_numbers_are_jumpers no)
		(fp_line
			(start -1.2954 0.5842)
			(end 1.2954 0.5842)
			(stroke
				(width 0.1524)
				(type default)
			)
			(layer "B.SilkS")
		)
		(fp_line
			(start 1.2954 0.5842)
			(end 1.2954 -0.5842)
			(stroke
				(width 0.1524)
				(type default)
			)
			(layer "B.SilkS")
		)
		(fp_line
			(start -1.2954 -0.5842)
			(end -1.2954 0.5842)
			(stroke
				(width 0.1524)
				(type default)
			)
			(layer "B.SilkS")
		)
		(fp_line
			(start 0 -0.5842)
			(end 0 0.5842)
			(stroke
				(width 0.1524)
				(type default)
			)
			(layer "B.SilkS")
		)
		(fp_line
			(start 1.2954 -0.5842)
			(end -1.2954 -0.5842)
			(stroke
				(width 0.1524)
				(type default)
			)
			(layer "B.SilkS")
		)
		(fp_poly
			(pts
				(xy -0.8636 -0.4572) (xy -0.8636 -0.3556) (xy -1.143 -0.3556) (xy -1.143 0.3556) (xy -0.8636 0.3556)
				(xy -0.8636 0.4572) (xy 0.8636 0.4572) (xy 0.8636 0.3556) (xy 1.143 0.3556) (xy 1.143 -0.3556) (xy 0.8636 -0.3556)
				(xy 0.8636 -0.4572)
			)
			(stroke
				(width 0)
				(type default)
			)
			(fill no)
			(layer "B.CrtYd")
		)
		(fp_line
			(start -0.884936 0.504952)
			(end 0.884936 0.504952)
			(stroke
				(width 0.1)
				(type default)
			)
			(layer "B.Fab")
		)
		(fp_line
			(start 0.884936 0.504952)
			(end 0.884936 -0.504952)
			(stroke
				(width 0.1)
				(type default)
			)
			(layer "B.Fab")
		)
		(fp_line
			(start -0.884936 -0.504952)
			(end -0.884936 0.504952)
			(stroke
				(width 0.1)
				(type default)
			)
			(layer "B.Fab")
		)
		(fp_line
			(start 0.884936 -0.504952)
			(end -0.884936 -0.504952)
			(stroke
				(width 0.1)
				(type default)
			)
			(layer "B.Fab")
		)
		(pad "1" smd rect
			(at -0.7366 0)
			(size 0.7112 0.8128)
			(layers "B.Cu" "B.Mask" "B.Paste")
			(net "P1V05_NODE1")
		)
		(pad "2" smd rect
			(at 0.7366 0)
			(size 0.7112 0.8128)
			(layers "B.Cu" "B.Mask" "B.Paste")
			(net "GND")
		)
	)
	(footprint ""
		(layer "B.Cu")
		(at 132.978652 -151.31415 90)
		(property "Reference" "C331"
			(at 1.439926 0.660146 270)
			(unlocked yes)
			(layer "B.SilkS")
			(effects
				(font
					(size 0.7874 0.5842)
					(thickness 0.1524)
				)
				(justify left mirror)
			)
		)
		(property "Value" ""
			(at 0 0 90)
			(layer "B.Fab")
			(effects
				(font
					(size 1.27 1.27)
				)
				(justify mirror)
			)
		)
		(duplicate_pad_numbers_are_jumpers no)
		(fp_line
			(start 0.7874 -0.4064)
			(end -0.7874 -0.4064)
			(stroke
				(width 0.1524)
				(type default)
			)
			(layer "B.SilkS")
		)
		(fp_line
			(start -0.7874 -0.4064)
			(end -0.7874 0.4064)
			(stroke
				(width 0.1524)
				(type default)
			)
			(layer "B.SilkS")
		)
		(fp_line
			(start 0 0.381)
			(end 0 -0.381)
			(stroke
				(width 0.1524)
				(type default)
			)
			(layer "B.SilkS")
		)
		(fp_line
			(start 0.7874 0.4064)
			(end 0.7874 -0.4064)
			(stroke
				(width 0.1524)
				(type default)
			)
			(layer "B.SilkS")
		)
		(fp_line
			(start -0.7874 0.4064)
			(end 0.7874 0.4064)
			(stroke
				(width 0.1524)
				(type default)
			)
			(layer "B.SilkS")
		)
		(fp_poly
			(pts
				(xy 0.5334 0.254) (xy 0.635 0.254) (xy 0.635 0.2286) (xy 0.635 -0.254) (xy 0.5334 -0.254) (xy 0.5334 -0.2794)
				(xy -0.5334 -0.2794) (xy -0.5334 -0.254) (xy -0.635 -0.254) (xy -0.635 0.254) (xy -0.5334 0.254)
				(xy -0.5334 0.2794) (xy 0.508 0.2794) (xy 0.5334 0.2794)
			)
			(stroke
				(width 0)
				(type default)
			)
			(fill no)
			(layer "B.CrtYd")
		)
		(pad "1" smd rect
			(at -0.40005 0 270)
			(size 0.4572 0.508)
			(layers "B.Cu" "B.Mask" "B.Paste")
			(net "P1V0_NODE1")
		)
		(pad "2" smd rect
			(at 0.40005 0 270)
			(size 0.4572 0.508)
			(layers "B.Cu" "B.Mask" "B.Paste")
			(net "GND")
		)
	)
	(footprint ""
		(layer "B.Cu")
		(at 167.68318 -156.093922)
		(property "Reference" "C458"
			(at 5.988558 -0.052832 0)
			(unlocked yes)
			(layer "B.SilkS")
			(effects
				(font
					(size 0.7874 0.5842)
					(thickness 0.1524)
				)
				(justify left mirror)
			)
		)
		(property "Value" ""
			(at 0 0 0)
			(layer "B.Fab")
			(effects
				(font
					(size 1.27 1.27)
				)
				(justify mirror)
			)
		)
		(duplicate_pad_numbers_are_jumpers no)
		(fp_line
			(start -0.7874 -0.4064)
			(end -0.7874 0.4064)
			(stroke
				(width 0.1524)
				(type default)
			)
			(layer "B.SilkS")
		)
		(fp_line
			(start -0.7874 0.4064)
			(end 0.7874 0.4064)
			(stroke
				(width 0.1524)
				(type default)
			)
			(layer "B.SilkS")
		)
		(fp_line
			(start 0 0.381)
			(end 0 -0.381)
			(stroke
				(width 0.1524)
				(type default)
			)
			(layer "B.SilkS")
		)
		(fp_line
			(start 0.7874 -0.4064)
			(end -0.7874 -0.4064)
			(stroke
				(width 0.1524)
				(type default)
			)
			(layer "B.SilkS")
		)
		(fp_line
			(start 0.7874 0.4064)
			(end 0.7874 -0.4064)
			(stroke
				(width 0.1524)
				(type default)
			)
			(layer "B.SilkS")
		)
		(fp_poly
			(pts
				(xy 0.5334 0.254) (xy 0.635 0.254) (xy 0.635 0.2286) (xy 0.635 -0.254) (xy 0.5334 -0.254) (xy 0.5334 -0.2794)
				(xy -0.5334 -0.2794) (xy -0.5334 -0.254) (xy -0.635 -0.254) (xy -0.635 0.254) (xy -0.5334 0.254)
				(xy -0.5334 0.2794) (xy 0.508 0.2794) (xy 0.5334 0.2794)
			)
			(stroke
				(width 0)
				(type default)
			)
			(fill no)
			(layer "B.CrtYd")
		)
		(pad "1" smd rect
			(at -0.40005 0 180)
			(size 0.4572 0.508)
			(layers "B.Cu" "B.Mask" "B.Paste")
			(net "P1V9_LAN2")
		)
		(pad "2" smd rect
			(at 0.40005 0 180)
			(size 0.4572 0.508)
			(layers "B.Cu" "B.Mask" "B.Paste")
			(net "GND")
		)
	)
	(footprint ""
		(layer "B.Cu")
		(at 122.60453 -33.627314 180)
		(property "Reference" "C488"
			(at 2.543556 -1.50241 0)
			(unlocked yes)
			(layer "B.SilkS")
			(effects
				(font
					(size 0.7874 0.5842)
					(thickness 0.1524)
				)
				(justify left mirror)
			)
		)
		(property "Value" ""
			(at 0 0 0)
			(layer "B.Fab")
			(effects
				(font
					(size 1.27 1.27)
				)
				(justify mirror)
			)
		)
		(duplicate_pad_numbers_are_jumpers no)
		(fp_line
			(start 1.905 0.8636)
			(end 1.905 -0.8636)
			(stroke
				(width 0.1524)
				(type default)
			)
			(layer "B.SilkS")
		)
		(fp_line
			(start 1.905 -0.8636)
			(end -1.905 -0.8636)
			(stroke
				(width 0.1524)
				(type default)
			)
			(layer "B.SilkS")
		)
		(fp_line
			(start 0 0.8382)
			(end 0 -0.8382)
			(stroke
				(width 0.1524)
				(type default)
			)
			(layer "B.SilkS")
		)
		(fp_line
			(start -1.905 0.8636)
			(end 1.905 0.8636)
			(stroke
				(width 0.1524)
				(type default)
			)
			(layer "B.SilkS")
		)
		(fp_line
			(start -1.905 -0.8636)
			(end -1.905 0.8636)
			(stroke
				(width 0.1524)
				(type default)
			)
			(layer "B.SilkS")
		)
		(fp_rect
			(start 1.524 0.7366)
			(end -1.524 -0.7366)
			(stroke
				(width 0)
				(type default)
			)
			(fill no)
			(layer "B.CrtYd")
		)
		(pad "1" smd rect
			(at -0.94996 0)
			(size 1.1176 1.3716)
			(layers "B.Cu" "B.Mask" "B.Paste")
			(net "SIO_VCCH")
		)
		(pad "2" smd rect
			(at 0.94996 0)
			(size 1.1176 1.3716)
			(layers "B.Cu" "B.Mask" "B.Paste")
			(net "GND")
		)
	)
	(footprint ""
		(layer "B.Cu")
		(at 119.126 -35.941 -90)
		(property "Reference" "R1291"
			(at 1.651 5.23367 270)
			(unlocked yes)
			(layer "B.SilkS")
			(effects
				(font
					(size 0.7874 0.5842)
					(thickness 0.1524)
				)
				(justify left mirror)
			)
		)
		(property "Value" ""
			(at 0 0 90)
			(layer "B.Fab")
			(effects
				(font
					(size 1.27 1.27)
				)
				(justify mirror)
			)
		)
		(duplicate_pad_numbers_are_jumpers no)
		(fp_line
			(start -0.7874 0.4064)
			(end 0.7874 0.4064)
			(stroke
				(width 0.1524)
				(type default)
			)
			(layer "B.SilkS")
		)
		(fp_line
			(start 0.7874 0.4064)
			(end 0.7874 -0.4064)
			(stroke
				(width 0.1524)
				(type default)
			)
			(layer "B.SilkS")
		)
		(fp_line
			(start -0.7874 -0.4064)
			(end -0.7874 0.4064)
			(stroke
				(width 0.1524)
				(type default)
			)
			(layer "B.SilkS")
		)
		(fp_line
			(start 0.7874 -0.4064)
			(end -0.7874 -0.4064)
			(stroke
				(width 0.1524)
				(type default)
			)
			(layer "B.SilkS")
		)
		(fp_poly
			(pts
				(xy 0.508 0.2794) (xy 0.508 0.2286) (xy 0.635 0.2286) (xy 0.635 -0.254) (xy 0.5334 -0.254) (xy 0.5334 -0.2794)
				(xy -0.5334 -0.2794) (xy -0.5334 -0.254) (xy -0.635 -0.254) (xy -0.635 0.254) (xy -0.5334 0.254)
				(xy -0.5334 0.2794)
			)
			(stroke
				(width 0)
				(type default)
			)
			(fill no)
			(layer "B.CrtYd")
		)
		(pad "1" smd rect
			(at -0.40005 0 90)
			(size 0.4572 0.508)
			(layers "B.Cu" "B.Mask" "B.Paste")
			(net "SIO_JTAG_CPLD1_TCK_R")
		)
		(pad "2" smd rect
			(at 0.40005 0 90)
			(size 0.4572 0.508)
			(layers "B.Cu" "B.Mask" "B.Paste")
			(net "P3V3_NODE1")
		)
	)
	(footprint ""
		(layer "B.Cu")
		(at 42.113962 -163.52647 90)
		(property "Reference" "TP1"
			(at 0 0 90)
			(layer "B.SilkS")
			(hide yes)
			(effects
				(font
					(size 1.27 1.27)
				)
				(justify mirror)
			)
		)
		(property "Value" ""
			(at 0 0 90)
			(layer "B.Fab")
			(effects
				(font
					(size 1.27 1.27)
				)
				(justify mirror)
			)
		)
		(duplicate_pad_numbers_are_jumpers no)
		(fp_poly
			(pts
				(arc
					(start 0 -0.381)
					(mid 0 0.381)
					(end 0 -0.381)
				)
			)
			(stroke
				(width 0)
				(type default)
			)
			(fill no)
			(layer "B.CrtYd")
		)
		(pad "1" smd circle
			(at 0 0 270)
			(size 0.762 0.762)
			(layers "B.Cu" "B.Mask" "B.Paste")
			(net "N21311590")
		)
	)
	(footprint ""
		(layer "B.Cu")
		(at 52.81676 -188.126624 -90)
		(property "Reference" "R853"
			(at -4.339082 -0.278384 270)
			(unlocked yes)
			(layer "B.SilkS")
			(effects
				(font
					(size 0.7874 0.5842)
					(thickness 0.1524)
				)
				(justify left mirror)
			)
		)
		(property "Value" ""
			(at 0 0 90)
			(layer "B.Fab")
			(effects
				(font
					(size 1.27 1.27)
				)
				(justify mirror)
			)
		)
		(duplicate_pad_numbers_are_jumpers no)
		(fp_line
			(start -0.7874 0.4064)
			(end 0.7874 0.4064)
			(stroke
				(width 0.1524)
				(type default)
			)
			(layer "B.SilkS")
		)
		(fp_line
			(start 0.7874 0.4064)
			(end 0.7874 -0.4064)
			(stroke
				(width 0.1524)
				(type default)
			)
			(layer "B.SilkS")
		)
		(fp_line
			(start -0.7874 -0.4064)
			(end -0.7874 0.4064)
			(stroke
				(width 0.1524)
				(type default)
			)
			(layer "B.SilkS")
		)
		(fp_line
			(start 0.7874 -0.4064)
			(end -0.7874 -0.4064)
			(stroke
				(width 0.1524)
				(type default)
			)
			(layer "B.SilkS")
		)
		(fp_poly
			(pts
				(xy 0.508 0.2794) (xy 0.508 0.2286) (xy 0.635 0.2286) (xy 0.635 -0.254) (xy 0.5334 -0.254) (xy 0.5334 -0.2794)
				(xy -0.5334 -0.2794) (xy -0.5334 -0.254) (xy -0.635 -0.254) (xy -0.635 0.254) (xy -0.5334 0.254)
				(xy -0.5334 0.2794)
			)
			(stroke
				(width 0)
				(type default)
			)
			(fill no)
			(layer "B.CrtYd")
		)
		(pad "1" smd rect
			(at -0.40005 0 90)
			(size 0.4572 0.508)
			(layers "B.Cu" "B.Mask" "B.Paste")
			(net "PSU1_DC_OK_R")
		)
		(pad "2" smd rect
			(at 0.40005 0 90)
			(size 0.4572 0.508)
			(layers "B.Cu" "B.Mask" "B.Paste")
			(net "GND")
		)
	)
	(footprint ""
		(layer "B.Cu")
		(at 109.58576 -188.126624 90)
		(property "Reference" "R973"
			(at 4.080256 0.645922 270)
			(unlocked yes)
			(layer "B.SilkS")
			(effects
				(font
					(size 0.7874 0.5842)
					(thickness 0.1524)
				)
				(justify left mirror)
			)
		)
		(property "Value" ""
			(at 0 0 90)
			(layer "B.Fab")
			(effects
				(font
					(size 1.27 1.27)
				)
				(justify mirror)
			)
		)
		(duplicate_pad_numbers_are_jumpers no)
		(fp_line
			(start 0.7874 -0.4064)
			(end -0.7874 -0.4064)
			(stroke
				(width 0.1524)
				(type default)
			)
			(layer "B.SilkS")
		)
		(fp_line
			(start -0.7874 -0.4064)
			(end -0.7874 0.4064)
			(stroke
				(width 0.1524)
				(type default)
			)
			(layer "B.SilkS")
		)
		(fp_line
			(start 0.7874 0.4064)
			(end 0.7874 -0.4064)
			(stroke
				(width 0.1524)
				(type default)
			)
			(layer "B.SilkS")
		)
		(fp_line
			(start -0.7874 0.4064)
			(end 0.7874 0.4064)
			(stroke
				(width 0.1524)
				(type default)
			)
			(layer "B.SilkS")
		)
		(fp_poly
			(pts
				(xy 0.508 0.2794) (xy 0.508 0.2286) (xy 0.635 0.2286) (xy 0.635 -0.254) (xy 0.5334 -0.254) (xy 0.5334 -0.2794)
				(xy -0.5334 -0.2794) (xy -0.5334 -0.254) (xy -0.635 -0.254) (xy -0.635 0.254) (xy -0.5334 0.254)
				(xy -0.5334 0.2794)
			)
			(stroke
				(width 0)
				(type default)
			)
			(fill no)
			(layer "B.CrtYd")
		)
		(pad "1" smd rect
			(at -0.40005 0 270)
			(size 0.4572 0.508)
			(layers "B.Cu" "B.Mask" "B.Paste")
			(net "UART_T7_NODE4_RXD")
		)
		(pad "2" smd rect
			(at 0.40005 0 270)
			(size 0.4572 0.508)
			(layers "B.Cu" "B.Mask" "B.Paste")
			(net "UART_T7_NODE4_RXD_R")
		)
	)
	(footprint ""
		(layer "B.Cu")
		(at 172.84573 -118.87962 180)
		(property "Reference" "C792"
			(at 2.503678 -1.906778 0)
			(unlocked yes)
			(layer "B.SilkS")
			(effects
				(font
					(size 0.7874 0.5842)
					(thickness 0.1524)
				)
				(justify mirror)
			)
		)
		(property "Value" ""
			(at 0 0 0)
			(layer "B.Fab")
			(effects
				(font
					(size 1.27 1.27)
				)
				(justify mirror)
			)
		)
		(duplicate_pad_numbers_are_jumpers no)
		(fp_line
			(start 1.2954 0.5842)
			(end 1.2954 -0.5842)
			(stroke
				(width 0.1524)
				(type default)
			)
			(layer "B.SilkS")
		)
		(fp_line
			(start 1.2954 -0.5842)
			(end -1.2954 -0.5842)
			(stroke
				(width 0.1524)
				(type default)
			)
			(layer "B.SilkS")
		)
		(fp_line
			(start 0 -0.5842)
			(end 0 0.5842)
			(stroke
				(width 0.1524)
				(type default)
			)
			(layer "B.SilkS")
		)
		(fp_line
			(start -1.2954 0.5842)
			(end 1.2954 0.5842)
			(stroke
				(width 0.1524)
				(type default)
			)
			(layer "B.SilkS")
		)
		(fp_line
			(start -1.2954 -0.5842)
			(end -1.2954 0.5842)
			(stroke
				(width 0.1524)
				(type default)
			)
			(layer "B.SilkS")
		)
		(fp_poly
			(pts
				(xy -0.8636 -0.4572) (xy -0.8636 -0.3556) (xy -1.143 -0.3556) (xy -1.143 0.3556) (xy -0.8636 0.3556)
				(xy -0.8636 0.4572) (xy 0.8636 0.4572) (xy 0.8636 0.3556) (xy 1.143 0.3556) (xy 1.143 -0.3556) (xy 0.8636 -0.3556)
				(xy 0.8636 -0.4572)
			)
			(stroke
				(width 0)
				(type default)
			)
			(fill no)
			(layer "B.CrtYd")
		)
		(fp_line
			(start 0.884936 0.504952)
			(end 0.884936 -0.504952)
			(stroke
				(width 0.1)
				(type default)
			)
			(layer "B.Fab")
		)
		(fp_line
			(start 0.884936 -0.504952)
			(end -0.884936 -0.504952)
			(stroke
				(width 0.1)
				(type default)
			)
			(layer "B.Fab")
		)
		(fp_line
			(start -0.884936 0.504952)
			(end 0.884936 0.504952)
			(stroke
				(width 0.1)
				(type default)
			)
			(layer "B.Fab")
		)
		(fp_line
			(start -0.884936 -0.504952)
			(end -0.884936 0.504952)
			(stroke
				(width 0.1)
				(type default)
			)
			(layer "B.Fab")
		)
		(pad "1" smd rect
			(at -0.7366 0 270)
			(size 0.7112 0.8128)
			(layers "B.Cu" "B.Mask" "B.Paste")
			(net "P3V3_STB_NODE1")
		)
		(pad "2" smd rect
			(at 0.7366 0 270)
			(size 0.7112 0.8128)
			(layers "B.Cu" "B.Mask" "B.Paste")
			(net "GND")
		)
	)
	(footprint ""
		(layer "B.Cu")
		(at 110.44936 -179.617624 180)
		(property "Reference" "R715"
			(at 21.356828 -32.269176 0)
			(unlocked yes)
			(layer "B.SilkS")
			(effects
				(font
					(size 0.7874 0.5842)
					(thickness 0.1524)
				)
				(justify left mirror)
			)
		)
		(property "Value" ""
			(at 0 0 0)
			(layer "B.Fab")
			(effects
				(font
					(size 1.27 1.27)
				)
				(justify mirror)
			)
		)
		(duplicate_pad_numbers_are_jumpers no)
		(fp_line
			(start 0.7874 0.4064)
			(end 0.7874 -0.4064)
			(stroke
				(width 0.1524)
				(type default)
			)
			(layer "B.SilkS")
		)
		(fp_line
			(start 0.7874 -0.4064)
			(end -0.7874 -0.4064)
			(stroke
				(width 0.1524)
				(type default)
			)
			(layer "B.SilkS")
		)
		(fp_line
			(start -0.7874 0.4064)
			(end 0.7874 0.4064)
			(stroke
				(width 0.1524)
				(type default)
			)
			(layer "B.SilkS")
		)
		(fp_line
			(start -0.7874 -0.4064)
			(end -0.7874 0.4064)
			(stroke
				(width 0.1524)
				(type default)
			)
			(layer "B.SilkS")
		)
		(fp_poly
			(pts
				(xy 0.508 0.2794) (xy 0.508 0.2286) (xy 0.635 0.2286) (xy 0.635 -0.254) (xy 0.5334 -0.254) (xy 0.5334 -0.2794)
				(xy -0.5334 -0.2794) (xy -0.5334 -0.254) (xy -0.635 -0.254) (xy -0.635 0.254) (xy -0.5334 0.254)
				(xy -0.5334 0.2794)
			)
			(stroke
				(width 0)
				(type default)
			)
			(fill no)
			(layer "B.CrtYd")
		)
		(pad "1" smd rect
			(at -0.40005 0)
			(size 0.4572 0.508)
			(layers "B.Cu" "B.Mask" "B.Paste")
			(net "T6_NODE2_EN")
		)
		(pad "2" smd rect
			(at 0.40005 0)
			(size 0.4572 0.508)
			(layers "B.Cu" "B.Mask" "B.Paste")
			(net "P5V_NODE1")
		)
	)
	(footprint ""
		(layer "B.Cu")
		(at 94.211394 -185.790586 180)
		(property "Reference" "R927"
			(at -1.315466 6.002782 0)
			(unlocked yes)
			(layer "B.SilkS")
			(effects
				(font
					(size 0.7874 0.5842)
					(thickness 0.1524)
				)
				(justify left mirror)
			)
		)
		(property "Value" ""
			(at 0 0 0)
			(layer "B.Fab")
			(effects
				(font
					(size 1.27 1.27)
				)
				(justify mirror)
			)
		)
		(duplicate_pad_numbers_are_jumpers no)
		(fp_line
			(start 0.7874 0.406146)
			(end 0.7874 -0.406146)
			(stroke
				(width 0.1524)
				(type default)
			)
			(layer "B.SilkS")
		)
		(fp_line
			(start 0.7874 -0.406146)
			(end -0.7874 -0.406146)
			(stroke
				(width 0.1524)
				(type default)
			)
			(layer "B.SilkS")
		)
		(fp_line
			(start -0.7874 0.406146)
			(end 0.7874 0.406146)
			(stroke
				(width 0.1524)
				(type default)
			)
			(layer "B.SilkS")
		)
		(fp_line
			(start -0.7874 -0.406146)
			(end -0.7874 0.406146)
			(stroke
				(width 0.1524)
				(type default)
			)
			(layer "B.SilkS")
		)
		(fp_poly
			(pts
				(xy 0.508 0.2794) (xy 0.508 0.2286) (xy 0.635 0.2286) (xy 0.635 -0.254) (xy 0.5334 -0.254) (xy 0.5334 -0.2794)
				(xy -0.5334 -0.2794) (xy -0.5334 -0.254) (xy -0.635 -0.254) (xy -0.635 0.254) (xy -0.5334 0.254)
				(xy -0.5334 0.2794)
			)
			(stroke
				(width 0)
				(type default)
			)
			(fill no)
			(layer "B.CrtYd")
		)
		(pad "1" smd rect
			(at -0.40005 0)
			(size 0.4572 0.508)
			(layers "B.Cu" "B.Mask" "B.Paste")
			(net "UART_T5_NODE4_RXD")
		)
		(pad "2" smd rect
			(at 0.40005 0)
			(size 0.4572 0.508)
			(layers "B.Cu" "B.Mask" "B.Paste")
			(net "UART_T5_NODE4_RXD_R")
		)
	)
	(footprint ""
		(layer "B.Cu")
		(at 95.740982 -29.925518)
		(property "Reference" "R206"
			(at 1.810766 1.08839 0)
			(unlocked yes)
			(layer "B.SilkS")
			(effects
				(font
					(size 0.7874 0.5842)
					(thickness 0.1524)
				)
				(justify left mirror)
			)
		)
		(property "Value" ""
			(at 0 0 0)
			(layer "B.Fab")
			(effects
				(font
					(size 1.27 1.27)
				)
				(justify mirror)
			)
		)
		(duplicate_pad_numbers_are_jumpers no)
		(fp_line
			(start -0.7874 -0.4064)
			(end -0.7874 0.4064)
			(stroke
				(width 0.1524)
				(type default)
			)
			(layer "B.SilkS")
		)
		(fp_line
			(start -0.7874 0.4064)
			(end 0.7874 0.4064)
			(stroke
				(width 0.1524)
				(type default)
			)
			(layer "B.SilkS")
		)
		(fp_line
			(start 0.7874 -0.4064)
			(end -0.7874 -0.4064)
			(stroke
				(width 0.1524)
				(type default)
			)
			(layer "B.SilkS")
		)
		(fp_line
			(start 0.7874 0.4064)
			(end 0.7874 -0.4064)
			(stroke
				(width 0.1524)
				(type default)
			)
			(layer "B.SilkS")
		)
		(fp_poly
			(pts
				(xy 0.508 0.2794) (xy 0.508 0.2286) (xy 0.635 0.2286) (xy 0.635 -0.254) (xy 0.5334 -0.254) (xy 0.5334 -0.2794)
				(xy -0.5334 -0.2794) (xy -0.5334 -0.254) (xy -0.635 -0.254) (xy -0.635 0.254) (xy -0.5334 0.254)
				(xy -0.5334 0.2794)
			)
			(stroke
				(width 0)
				(type default)
			)
			(fill no)
			(layer "B.CrtYd")
		)
		(pad "1" smd rect
			(at -0.40005 0 180)
			(size 0.4572 0.508)
			(layers "B.Cu" "B.Mask" "B.Paste")
			(net "GND")
		)
		(pad "2" smd rect
			(at 0.40005 0 180)
			(size 0.4572 0.508)
			(layers "B.Cu" "B.Mask" "B.Paste")
			(net "PD_NODE1_DM6")
		)
	)
	(footprint ""
		(layer "B.Cu")
		(at 44.609258 -60.445396 -90)
		(property "Reference" "C22"
			(at 2.31775 2.249424 270)
			(unlocked yes)
			(layer "B.SilkS")
			(effects
				(font
					(size 0.7874 0.5842)
					(thickness 0.1524)
				)
				(justify left mirror)
			)
		)
		(property "Value" ""
			(at 0 0 90)
			(layer "B.Fab")
			(effects
				(font
					(size 1.27 1.27)
				)
				(justify mirror)
			)
		)
		(duplicate_pad_numbers_are_jumpers no)
		(fp_line
			(start -0.7874 0.4064)
			(end 0.7874 0.4064)
			(stroke
				(width 0.1524)
				(type default)
			)
			(layer "B.SilkS")
		)
		(fp_line
			(start 0.7874 0.4064)
			(end 0.7874 -0.4064)
			(stroke
				(width 0.1524)
				(type default)
			)
			(layer "B.SilkS")
		)
		(fp_line
			(start 0 0.381)
			(end 0 -0.381)
			(stroke
				(width 0.1524)
				(type default)
			)
			(layer "B.SilkS")
		)
		(fp_line
			(start -0.7874 -0.4064)
			(end -0.7874 0.4064)
			(stroke
				(width 0.1524)
				(type default)
			)
			(layer "B.SilkS")
		)
		(fp_line
			(start 0.7874 -0.4064)
			(end -0.7874 -0.4064)
			(stroke
				(width 0.1524)
				(type default)
			)
			(layer "B.SilkS")
		)
		(fp_poly
			(pts
				(xy 0.5334 0.254) (xy 0.635 0.254) (xy 0.635 0.2286) (xy 0.635 -0.254) (xy 0.5334 -0.254) (xy 0.5334 -0.2794)
				(xy -0.5334 -0.2794) (xy -0.5334 -0.254) (xy -0.635 -0.254) (xy -0.635 0.254) (xy -0.5334 0.254)
				(xy -0.5334 0.2794) (xy 0.508 0.2794) (xy 0.5334 0.2794)
			)
			(stroke
				(width 0)
				(type default)
			)
			(fill no)
			(layer "B.CrtYd")
		)
		(pad "1" smd rect
			(at -0.40005 0 90)
			(size 0.4572 0.508)
			(layers "B.Cu" "B.Mask" "B.Paste")
			(net "P2E_CPU_SATA_NODE1_TX_C_DN")
		)
		(pad "2" smd rect
			(at 0.40005 0 90)
			(size 0.4572 0.508)
			(layers "B.Cu" "B.Mask" "B.Paste")
			(net "P2E_CPU_SATA_NODE1_TX_DN")
		)
	)
	(footprint ""
		(layer "B.Cu")
		(at 48.758602 -153.373582 180)
		(property "Reference" "C412"
			(at 11.821922 5.316728 0)
			(unlocked yes)
			(layer "B.SilkS")
			(effects
				(font
					(size 0.7874 0.5842)
					(thickness 0.1524)
				)
				(justify left mirror)
			)
		)
		(property "Value" ""
			(at 0 0 0)
			(layer "B.Fab")
			(effects
				(font
					(size 1.27 1.27)
				)
				(justify mirror)
			)
		)
		(duplicate_pad_numbers_are_jumpers no)
		(fp_line
			(start 0.7874 0.4064)
			(end 0.7874 -0.4064)
			(stroke
				(width 0.1524)
				(type default)
			)
			(layer "B.SilkS")
		)
		(fp_line
			(start 0.7874 -0.4064)
			(end -0.7874 -0.4064)
			(stroke
				(width 0.1524)
				(type default)
			)
			(layer "B.SilkS")
		)
		(fp_line
			(start 0 0.381)
			(end 0 -0.381)
			(stroke
				(width 0.1524)
				(type default)
			)
			(layer "B.SilkS")
		)
		(fp_line
			(start -0.7874 0.4064)
			(end 0.7874 0.4064)
			(stroke
				(width 0.1524)
				(type default)
			)
			(layer "B.SilkS")
		)
		(fp_line
			(start -0.7874 -0.4064)
			(end -0.7874 0.4064)
			(stroke
				(width 0.1524)
				(type default)
			)
			(layer "B.SilkS")
		)
		(fp_poly
			(pts
				(xy 0.5334 0.254) (xy 0.635 0.254) (xy 0.635 0.2286) (xy 0.635 -0.254) (xy 0.5334 -0.254) (xy 0.5334 -0.2794)
				(xy -0.5334 -0.2794) (xy -0.5334 -0.254) (xy -0.635 -0.254) (xy -0.635 0.254) (xy -0.5334 0.254)
				(xy -0.5334 0.2794) (xy 0.508 0.2794) (xy 0.5334 0.2794)
			)
			(stroke
				(width 0)
				(type default)
			)
			(fill no)
			(layer "B.CrtYd")
		)
		(pad "1" smd rect
			(at -0.40005 0)
			(size 0.4572 0.508)
			(layers "B.Cu" "B.Mask" "B.Paste")
			(net "P1V9_LAN1")
		)
		(pad "2" smd rect
			(at 0.40005 0)
			(size 0.4572 0.508)
			(layers "B.Cu" "B.Mask" "B.Paste")
			(net "GND")
		)
	)
	(footprint ""
		(layer "B.Cu")
		(at 185.293 -188.468 -90)
		(property "Reference" "C596"
			(at -1.6764 0.05207 270)
			(unlocked yes)
			(layer "B.SilkS")
			(effects
				(font
					(size 0.7874 0.5842)
					(thickness 0.1524)
				)
				(justify left mirror)
			)
		)
		(property "Value" ""
			(at 0 0 90)
			(layer "B.Fab")
			(effects
				(font
					(size 1.27 1.27)
				)
				(justify mirror)
			)
		)
		(duplicate_pad_numbers_are_jumpers no)
		(fp_line
			(start -0.7874 0.4064)
			(end 0.7874 0.4064)
			(stroke
				(width 0.1524)
				(type default)
			)
			(layer "B.SilkS")
		)
		(fp_line
			(start 0.7874 0.4064)
			(end 0.7874 -0.4064)
			(stroke
				(width 0.1524)
				(type default)
			)
			(layer "B.SilkS")
		)
		(fp_line
			(start 0 0.381)
			(end 0 -0.381)
			(stroke
				(width 0.1524)
				(type default)
			)
			(layer "B.SilkS")
		)
		(fp_line
			(start -0.7874 -0.4064)
			(end -0.7874 0.4064)
			(stroke
				(width 0.1524)
				(type default)
			)
			(layer "B.SilkS")
		)
		(fp_line
			(start 0.7874 -0.4064)
			(end -0.7874 -0.4064)
			(stroke
				(width 0.1524)
				(type default)
			)
			(layer "B.SilkS")
		)
		(fp_poly
			(pts
				(xy 0.5334 0.254) (xy 0.635 0.254) (xy 0.635 0.2286) (xy 0.635 -0.254) (xy 0.5334 -0.254) (xy 0.5334 -0.2794)
				(xy -0.5334 -0.2794) (xy -0.5334 -0.254) (xy -0.635 -0.254) (xy -0.635 0.254) (xy -0.5334 0.254)
				(xy -0.5334 0.2794) (xy 0.508 0.2794) (xy 0.5334 0.2794)
			)
			(stroke
				(width 0)
				(type default)
			)
			(fill no)
			(layer "B.CrtYd")
		)
		(pad "1" smd rect
			(at -0.40005 0 90)
			(size 0.4572 0.508)
			(layers "B.Cu" "B.Mask" "B.Paste")
			(net "POWER_SW3_PWR_CTR_12V_R")
		)
		(pad "2" smd rect
			(at 0.40005 0 90)
			(size 0.4572 0.508)
			(layers "B.Cu" "B.Mask" "B.Paste")
			(net "GND")
		)
	)
	(footprint ""
		(layer "B.Cu")
		(at 68.81876 -185.205624 90)
		(property "Reference" "C689"
			(at 4.15163 0.125984 270)
			(unlocked yes)
			(layer "B.SilkS")
			(effects
				(font
					(size 0.7874 0.5842)
					(thickness 0.1524)
				)
				(justify left mirror)
			)
		)
		(property "Value" ""
			(at 0 0 90)
			(layer "B.Fab")
			(effects
				(font
					(size 1.27 1.27)
				)
				(justify mirror)
			)
		)
		(duplicate_pad_numbers_are_jumpers no)
		(fp_line
			(start 0.7874 -0.4064)
			(end -0.7874 -0.4064)
			(stroke
				(width 0.1524)
				(type default)
			)
			(layer "B.SilkS")
		)
		(fp_line
			(start -0.7874 -0.4064)
			(end -0.7874 0.4064)
			(stroke
				(width 0.1524)
				(type default)
			)
			(layer "B.SilkS")
		)
		(fp_line
			(start 0 0.381)
			(end 0 -0.381)
			(stroke
				(width 0.1524)
				(type default)
			)
			(layer "B.SilkS")
		)
		(fp_line
			(start 0.7874 0.4064)
			(end 0.7874 -0.4064)
			(stroke
				(width 0.1524)
				(type default)
			)
			(layer "B.SilkS")
		)
		(fp_line
			(start -0.7874 0.4064)
			(end 0.7874 0.4064)
			(stroke
				(width 0.1524)
				(type default)
			)
			(layer "B.SilkS")
		)
		(fp_poly
			(pts
				(xy 0.5334 0.254) (xy 0.635 0.254) (xy 0.635 0.2286) (xy 0.635 -0.254) (xy 0.5334 -0.254) (xy 0.5334 -0.2794)
				(xy -0.5334 -0.2794) (xy -0.5334 -0.254) (xy -0.635 -0.254) (xy -0.635 0.254) (xy -0.5334 0.254)
				(xy -0.5334 0.2794) (xy 0.508 0.2794) (xy 0.5334 0.2794)
			)
			(stroke
				(width 0)
				(type default)
			)
			(fill no)
			(layer "B.CrtYd")
		)
		(pad "1" smd rect
			(at -0.40005 0 270)
			(size 0.4572 0.508)
			(layers "B.Cu" "B.Mask" "B.Paste")
			(net "UART_T3_NODE4_RXD")
		)
		(pad "2" smd rect
			(at 0.40005 0 270)
			(size 0.4572 0.508)
			(layers "B.Cu" "B.Mask" "B.Paste")
			(net "GND")
		)
	)
	(footprint ""
		(layer "B.Cu")
		(at 47.297086 -128.359662 180)
		(property "Reference" "C232"
			(at -3.945636 0.017018 0)
			(unlocked yes)
			(layer "B.SilkS")
			(effects
				(font
					(size 0.7874 0.5842)
					(thickness 0.1524)
				)
				(justify left mirror)
			)
		)
		(property "Value" ""
			(at 0 0 0)
			(layer "B.Fab")
			(effects
				(font
					(size 1.27 1.27)
				)
				(justify mirror)
			)
		)
		(duplicate_pad_numbers_are_jumpers no)
		(fp_line
			(start 0.7874 0.4064)
			(end 0.7874 -0.4064)
			(stroke
				(width 0.1524)
				(type default)
			)
			(layer "B.SilkS")
		)
		(fp_line
			(start 0.7874 -0.4064)
			(end -0.7874 -0.4064)
			(stroke
				(width 0.1524)
				(type default)
			)
			(layer "B.SilkS")
		)
		(fp_line
			(start 0 0.381)
			(end 0 -0.381)
			(stroke
				(width 0.1524)
				(type default)
			)
			(layer "B.SilkS")
		)
		(fp_line
			(start -0.7874 0.4064)
			(end 0.7874 0.4064)
			(stroke
				(width 0.1524)
				(type default)
			)
			(layer "B.SilkS")
		)
		(fp_line
			(start -0.7874 -0.4064)
			(end -0.7874 0.4064)
			(stroke
				(width 0.1524)
				(type default)
			)
			(layer "B.SilkS")
		)
		(fp_poly
			(pts
				(xy 0.5334 0.254) (xy 0.635 0.254) (xy 0.635 0.2286) (xy 0.635 -0.254) (xy 0.5334 -0.254) (xy 0.5334 -0.2794)
				(xy -0.5334 -0.2794) (xy -0.5334 -0.254) (xy -0.635 -0.254) (xy -0.635 0.254) (xy -0.5334 0.254)
				(xy -0.5334 0.2794) (xy 0.508 0.2794) (xy 0.5334 0.2794)
			)
			(stroke
				(width 0)
				(type default)
			)
			(fill no)
			(layer "B.CrtYd")
		)
		(pad "1" smd rect
			(at -0.40005 0)
			(size 0.4572 0.508)
			(layers "B.Cu" "B.Mask" "B.Paste")
			(net "P1V538_BMC_NODE1")
		)
		(pad "2" smd rect
			(at 0.40005 0)
			(size 0.4572 0.508)
			(layers "B.Cu" "B.Mask" "B.Paste")
			(net "GND")
		)
	)
	(footprint ""
		(layer "B.Cu")
		(at 75.98029 -82.35315 -90)
		(property "Reference" "C32"
			(at 32.277304 14.4272 270)
			(unlocked yes)
			(layer "B.SilkS")
			(effects
				(font
					(size 0.7874 0.5842)
					(thickness 0.1524)
				)
				(justify left mirror)
			)
		)
		(property "Value" ""
			(at 0 0 90)
			(layer "B.Fab")
			(effects
				(font
					(size 1.27 1.27)
				)
				(justify mirror)
			)
		)
		(duplicate_pad_numbers_are_jumpers no)
		(fp_line
			(start -0.7874 0.4064)
			(end 0.7874 0.4064)
			(stroke
				(width 0.1524)
				(type default)
			)
			(layer "B.SilkS")
		)
		(fp_line
			(start 0.7874 0.4064)
			(end 0.7874 -0.4064)
			(stroke
				(width 0.1524)
				(type default)
			)
			(layer "B.SilkS")
		)
		(fp_line
			(start 0 0.381)
			(end 0 -0.381)
			(stroke
				(width 0.1524)
				(type default)
			)
			(layer "B.SilkS")
		)
		(fp_line
			(start -0.7874 -0.4064)
			(end -0.7874 0.4064)
			(stroke
				(width 0.1524)
				(type default)
			)
			(layer "B.SilkS")
		)
		(fp_line
			(start 0.7874 -0.4064)
			(end -0.7874 -0.4064)
			(stroke
				(width 0.1524)
				(type default)
			)
			(layer "B.SilkS")
		)
		(fp_poly
			(pts
				(xy 0.5334 0.254) (xy 0.635 0.254) (xy 0.635 0.2286) (xy 0.635 -0.254) (xy 0.5334 -0.254) (xy 0.5334 -0.2794)
				(xy -0.5334 -0.2794) (xy -0.5334 -0.254) (xy -0.635 -0.254) (xy -0.635 0.254) (xy -0.5334 0.254)
				(xy -0.5334 0.2794) (xy 0.508 0.2794) (xy 0.5334 0.2794)
			)
			(stroke
				(width 0)
				(type default)
			)
			(fill no)
			(layer "B.CrtYd")
		)
		(pad "1" smd rect
			(at -0.40005 0 90)
			(size 0.4572 0.508)
			(layers "B.Cu" "B.Mask" "B.Paste")
			(net "N32265582")
		)
		(pad "2" smd rect
			(at 0.40005 0 90)
			(size 0.4572 0.508)
			(layers "B.Cu" "B.Mask" "B.Paste")
			(net "GND")
		)
	)
	(footprint ""
		(layer "B.Cu")
		(at 136.633712 -46.953932 90)
		(property "Reference" "R1133"
			(at 3.160268 11.167618 270)
			(unlocked yes)
			(layer "B.SilkS")
			(effects
				(font
					(size 0.7874 0.5842)
					(thickness 0.1524)
				)
				(justify left mirror)
			)
		)
		(property "Value" ""
			(at 0 0 90)
			(layer "B.Fab")
			(effects
				(font
					(size 1.27 1.27)
				)
				(justify mirror)
			)
		)
		(duplicate_pad_numbers_are_jumpers no)
		(fp_line
			(start 0.7874 -0.4064)
			(end -0.7874 -0.4064)
			(stroke
				(width 0.1524)
				(type default)
			)
			(layer "B.SilkS")
		)
		(fp_line
			(start -0.7874 -0.4064)
			(end -0.7874 0.4064)
			(stroke
				(width 0.1524)
				(type default)
			)
			(layer "B.SilkS")
		)
		(fp_line
			(start 0.7874 0.4064)
			(end 0.7874 -0.4064)
			(stroke
				(width 0.1524)
				(type default)
			)
			(layer "B.SilkS")
		)
		(fp_line
			(start -0.7874 0.4064)
			(end 0.7874 0.4064)
			(stroke
				(width 0.1524)
				(type default)
			)
			(layer "B.SilkS")
		)
		(fp_poly
			(pts
				(xy 0.508 0.2794) (xy 0.508 0.2286) (xy 0.635 0.2286) (xy 0.635 -0.254) (xy 0.5334 -0.254) (xy 0.5334 -0.2794)
				(xy -0.5334 -0.2794) (xy -0.5334 -0.254) (xy -0.635 -0.254) (xy -0.635 0.254) (xy -0.5334 0.254)
				(xy -0.5334 0.2794)
			)
			(stroke
				(width 0)
				(type default)
			)
			(fill no)
			(layer "B.CrtYd")
		)
		(pad "1" smd rect
			(at -0.40005 0 270)
			(size 0.4572 0.508)
			(layers "B.Cu" "B.Mask" "B.Paste")
			(net "GND")
		)
		(pad "2" smd rect
			(at 0.40005 0 270)
			(size 0.4572 0.508)
			(layers "B.Cu" "B.Mask" "B.Paste")
			(net "UART_DTR_P3_R_N")
		)
	)
	(footprint ""
		(layer "B.Cu")
		(at 62.742572 -72.767698 -90)
		(property "Reference" "C122"
			(at 31.735522 14.765782 270)
			(unlocked yes)
			(layer "B.SilkS")
			(effects
				(font
					(size 0.7874 0.5842)
					(thickness 0.1524)
				)
				(justify left mirror)
			)
		)
		(property "Value" ""
			(at 0 0 90)
			(layer "B.Fab")
			(effects
				(font
					(size 1.27 1.27)
				)
				(justify mirror)
			)
		)
		(duplicate_pad_numbers_are_jumpers no)
		(fp_line
			(start -0.7874 0.4064)
			(end 0.7874 0.4064)
			(stroke
				(width 0.1524)
				(type default)
			)
			(layer "B.SilkS")
		)
		(fp_line
			(start 0.7874 0.4064)
			(end 0.7874 -0.4064)
			(stroke
				(width 0.1524)
				(type default)
			)
			(layer "B.SilkS")
		)
		(fp_line
			(start 0 0.381)
			(end 0 -0.381)
			(stroke
				(width 0.1524)
				(type default)
			)
			(layer "B.SilkS")
		)
		(fp_line
			(start -0.7874 -0.4064)
			(end -0.7874 0.4064)
			(stroke
				(width 0.1524)
				(type default)
			)
			(layer "B.SilkS")
		)
		(fp_line
			(start 0.7874 -0.4064)
			(end -0.7874 -0.4064)
			(stroke
				(width 0.1524)
				(type default)
			)
			(layer "B.SilkS")
		)
		(fp_poly
			(pts
				(xy 0.5334 0.254) (xy 0.635 0.254) (xy 0.635 0.2286) (xy 0.635 -0.254) (xy 0.5334 -0.254) (xy 0.5334 -0.2794)
				(xy -0.5334 -0.2794) (xy -0.5334 -0.254) (xy -0.635 -0.254) (xy -0.635 0.254) (xy -0.5334 0.254)
				(xy -0.5334 0.2794) (xy 0.508 0.2794) (xy 0.5334 0.2794)
			)
			(stroke
				(width 0)
				(type default)
			)
			(fill no)
			(layer "B.CrtYd")
		)
		(pad "1" smd rect
			(at -0.40005 0 90)
			(size 0.4572 0.508)
			(layers "B.Cu" "B.Mask" "B.Paste")
			(net "P1V05_NODE1")
		)
		(pad "2" smd rect
			(at 0.40005 0 90)
			(size 0.4572 0.508)
			(layers "B.Cu" "B.Mask" "B.Paste")
			(net "GND")
		)
	)
	(footprint ""
		(layer "B.Cu")
		(at 66.095372 -80.514698 90)
		(property "Reference" "C64"
			(at -32.158686 -14.55039 270)
			(unlocked yes)
			(layer "B.SilkS")
			(effects
				(font
					(size 0.7874 0.5842)
					(thickness 0.1524)
				)
				(justify left mirror)
			)
		)
		(property "Value" ""
			(at 0 0 90)
			(layer "B.Fab")
			(effects
				(font
					(size 1.27 1.27)
				)
				(justify mirror)
			)
		)
		(duplicate_pad_numbers_are_jumpers no)
		(fp_line
			(start 0.7874 -0.4064)
			(end -0.7874 -0.4064)
			(stroke
				(width 0.1524)
				(type default)
			)
			(layer "B.SilkS")
		)
		(fp_line
			(start -0.7874 -0.4064)
			(end -0.7874 0.4064)
			(stroke
				(width 0.1524)
				(type default)
			)
			(layer "B.SilkS")
		)
		(fp_line
			(start 0 0.381)
			(end 0 -0.381)
			(stroke
				(width 0.1524)
				(type default)
			)
			(layer "B.SilkS")
		)
		(fp_line
			(start 0.7874 0.4064)
			(end 0.7874 -0.4064)
			(stroke
				(width 0.1524)
				(type default)
			)
			(layer "B.SilkS")
		)
		(fp_line
			(start -0.7874 0.4064)
			(end 0.7874 0.4064)
			(stroke
				(width 0.1524)
				(type default)
			)
			(layer "B.SilkS")
		)
		(fp_poly
			(pts
				(xy 0.5334 0.254) (xy 0.635 0.254) (xy 0.635 0.2286) (xy 0.635 -0.254) (xy 0.5334 -0.254) (xy 0.5334 -0.2794)
				(xy -0.5334 -0.2794) (xy -0.5334 -0.254) (xy -0.635 -0.254) (xy -0.635 0.254) (xy -0.5334 0.254)
				(xy -0.5334 0.2794) (xy 0.508 0.2794) (xy 0.5334 0.2794)
			)
			(stroke
				(width 0)
				(type default)
			)
			(fill no)
			(layer "B.CrtYd")
		)
		(pad "1" smd rect
			(at -0.40005 0 270)
			(size 0.4572 0.508)
			(layers "B.Cu" "B.Mask" "B.Paste")
			(net "PV_VCCP_NODE1")
		)
		(pad "2" smd rect
			(at 0.40005 0 270)
			(size 0.4572 0.508)
			(layers "B.Cu" "B.Mask" "B.Paste")
			(net "GND")
		)
	)
	(footprint ""
		(layer "B.Cu")
		(at 161.76498 -148.854922 90)
		(property "Reference" "C454"
			(at -8.519922 -0.556006 270)
			(unlocked yes)
			(layer "B.SilkS")
			(effects
				(font
					(size 0.7874 0.5842)
					(thickness 0.1524)
				)
				(justify left mirror)
			)
		)
		(property "Value" ""
			(at 0 0 90)
			(layer "B.Fab")
			(effects
				(font
					(size 1.27 1.27)
				)
				(justify mirror)
			)
		)
		(duplicate_pad_numbers_are_jumpers no)
		(fp_line
			(start 0.7874 -0.4064)
			(end -0.7874 -0.4064)
			(stroke
				(width 0.1524)
				(type default)
			)
			(layer "B.SilkS")
		)
		(fp_line
			(start -0.7874 -0.4064)
			(end -0.7874 0.4064)
			(stroke
				(width 0.1524)
				(type default)
			)
			(layer "B.SilkS")
		)
		(fp_line
			(start 0 0.381)
			(end 0 -0.381)
			(stroke
				(width 0.1524)
				(type default)
			)
			(layer "B.SilkS")
		)
		(fp_line
			(start 0.7874 0.4064)
			(end 0.7874 -0.4064)
			(stroke
				(width 0.1524)
				(type default)
			)
			(layer "B.SilkS")
		)
		(fp_line
			(start -0.7874 0.4064)
			(end 0.7874 0.4064)
			(stroke
				(width 0.1524)
				(type default)
			)
			(layer "B.SilkS")
		)
		(fp_poly
			(pts
				(xy 0.5334 0.254) (xy 0.635 0.254) (xy 0.635 0.2286) (xy 0.635 -0.254) (xy 0.5334 -0.254) (xy 0.5334 -0.2794)
				(xy -0.5334 -0.2794) (xy -0.5334 -0.254) (xy -0.635 -0.254) (xy -0.635 0.254) (xy -0.5334 0.254)
				(xy -0.5334 0.2794) (xy 0.508 0.2794) (xy 0.5334 0.2794)
			)
			(stroke
				(width 0)
				(type default)
			)
			(fill no)
			(layer "B.CrtYd")
		)
		(pad "1" smd rect
			(at -0.40005 0 270)
			(size 0.4572 0.508)
			(layers "B.Cu" "B.Mask" "B.Paste")
			(net "P1V9_LAN2")
		)
		(pad "2" smd rect
			(at 0.40005 0 270)
			(size 0.4572 0.508)
			(layers "B.Cu" "B.Mask" "B.Paste")
			(net "GND")
		)
	)
	(footprint ""
		(layer "B.Cu")
		(at 156.19476 -187.872624 -90)
		(property "Reference" "C595"
			(at -4.565396 3.755898 270)
			(unlocked yes)
			(layer "B.SilkS")
			(effects
				(font
					(size 0.7874 0.5842)
					(thickness 0.1524)
				)
				(justify left mirror)
			)
		)
		(property "Value" ""
			(at 0 0 90)
			(layer "B.Fab")
			(effects
				(font
					(size 1.27 1.27)
				)
				(justify mirror)
			)
		)
		(duplicate_pad_numbers_are_jumpers no)
		(fp_line
			(start -0.7874 0.4064)
			(end 0.7874 0.4064)
			(stroke
				(width 0.1524)
				(type default)
			)
			(layer "B.SilkS")
		)
		(fp_line
			(start 0.7874 0.4064)
			(end 0.7874 -0.4064)
			(stroke
				(width 0.1524)
				(type default)
			)
			(layer "B.SilkS")
		)
		(fp_line
			(start 0 0.381)
			(end 0 -0.381)
			(stroke
				(width 0.1524)
				(type default)
			)
			(layer "B.SilkS")
		)
		(fp_line
			(start -0.7874 -0.4064)
			(end -0.7874 0.4064)
			(stroke
				(width 0.1524)
				(type default)
			)
			(layer "B.SilkS")
		)
		(fp_line
			(start 0.7874 -0.4064)
			(end -0.7874 -0.4064)
			(stroke
				(width 0.1524)
				(type default)
			)
			(layer "B.SilkS")
		)
		(fp_poly
			(pts
				(xy 0.5334 0.254) (xy 0.635 0.254) (xy 0.635 0.2286) (xy 0.635 -0.254) (xy 0.5334 -0.254) (xy 0.5334 -0.2794)
				(xy -0.5334 -0.2794) (xy -0.5334 -0.254) (xy -0.635 -0.254) (xy -0.635 0.254) (xy -0.5334 0.254)
				(xy -0.5334 0.2794) (xy 0.508 0.2794) (xy 0.5334 0.2794)
			)
			(stroke
				(width 0)
				(type default)
			)
			(fill no)
			(layer "B.CrtYd")
		)
		(pad "1" smd rect
			(at -0.40005 0 90)
			(size 0.4572 0.508)
			(layers "B.Cu" "B.Mask" "B.Paste")
			(net "I2C_PSU3_R_SDA")
		)
		(pad "2" smd rect
			(at 0.40005 0 90)
			(size 0.4572 0.508)
			(layers "B.Cu" "B.Mask" "B.Paste")
			(net "GND")
		)
	)
	(footprint ""
		(layer "B.Cu")
		(at 105.14076 -188.126624 -90)
		(property "Reference" "C662"
			(at -4.10337 0.070358 270)
			(unlocked yes)
			(layer "B.SilkS")
			(effects
				(font
					(size 0.7874 0.5842)
					(thickness 0.1524)
				)
				(justify left mirror)
			)
		)
		(property "Value" ""
			(at 0 0 90)
			(layer "B.Fab")
			(effects
				(font
					(size 1.27 1.27)
				)
				(justify mirror)
			)
		)
		(duplicate_pad_numbers_are_jumpers no)
		(fp_line
			(start -0.7874 0.4064)
			(end 0.7874 0.4064)
			(stroke
				(width 0.1524)
				(type default)
			)
			(layer "B.SilkS")
		)
		(fp_line
			(start 0.7874 0.4064)
			(end 0.7874 -0.4064)
			(stroke
				(width 0.1524)
				(type default)
			)
			(layer "B.SilkS")
		)
		(fp_line
			(start 0 0.381)
			(end 0 -0.381)
			(stroke
				(width 0.1524)
				(type default)
			)
			(layer "B.SilkS")
		)
		(fp_line
			(start -0.7874 -0.4064)
			(end -0.7874 0.4064)
			(stroke
				(width 0.1524)
				(type default)
			)
			(layer "B.SilkS")
		)
		(fp_line
			(start 0.7874 -0.4064)
			(end -0.7874 -0.4064)
			(stroke
				(width 0.1524)
				(type default)
			)
			(layer "B.SilkS")
		)
		(fp_poly
			(pts
				(xy 0.5334 0.254) (xy 0.635 0.254) (xy 0.635 0.2286) (xy 0.635 -0.254) (xy 0.5334 -0.254) (xy 0.5334 -0.2794)
				(xy -0.5334 -0.2794) (xy -0.5334 -0.254) (xy -0.635 -0.254) (xy -0.635 0.254) (xy -0.5334 0.254)
				(xy -0.5334 0.2794) (xy 0.508 0.2794) (xy 0.5334 0.2794)
			)
			(stroke
				(width 0)
				(type default)
			)
			(fill no)
			(layer "B.CrtYd")
		)
		(pad "1" smd rect
			(at -0.40005 0 90)
			(size 0.4572 0.508)
			(layers "B.Cu" "B.Mask" "B.Paste")
			(net "T5_NODE2_EN_R")
		)
		(pad "2" smd rect
			(at 0.40005 0 90)
			(size 0.4572 0.508)
			(layers "B.Cu" "B.Mask" "B.Paste")
			(net "GND")
		)
	)
	(footprint ""
		(layer "B.Cu")
		(at 54.469538 -78.515718)
		(property "Reference" "C104"
			(at -12.341098 31.108904 0)
			(unlocked yes)
			(layer "B.SilkS")
			(effects
				(font
					(size 0.7874 0.5842)
					(thickness 0.1524)
				)
				(justify left mirror)
			)
		)
		(property "Value" ""
			(at 0 0 0)
			(layer "B.Fab")
			(effects
				(font
					(size 1.27 1.27)
				)
				(justify mirror)
			)
		)
		(duplicate_pad_numbers_are_jumpers no)
		(fp_line
			(start -0.7874 -0.4064)
			(end -0.7874 0.4064)
			(stroke
				(width 0.1524)
				(type default)
			)
			(layer "B.SilkS")
		)
		(fp_line
			(start -0.7874 0.4064)
			(end 0.7874 0.4064)
			(stroke
				(width 0.1524)
				(type default)
			)
			(layer "B.SilkS")
		)
		(fp_line
			(start 0 0.381)
			(end 0 -0.381)
			(stroke
				(width 0.1524)
				(type default)
			)
			(layer "B.SilkS")
		)
		(fp_line
			(start 0.7874 -0.4064)
			(end -0.7874 -0.4064)
			(stroke
				(width 0.1524)
				(type default)
			)
			(layer "B.SilkS")
		)
		(fp_line
			(start 0.7874 0.4064)
			(end 0.7874 -0.4064)
			(stroke
				(width 0.1524)
				(type default)
			)
			(layer "B.SilkS")
		)
		(fp_poly
			(pts
				(xy 0.5334 0.254) (xy 0.635 0.254) (xy 0.635 0.2286) (xy 0.635 -0.254) (xy 0.5334 -0.254) (xy 0.5334 -0.2794)
				(xy -0.5334 -0.2794) (xy -0.5334 -0.254) (xy -0.635 -0.254) (xy -0.635 0.254) (xy -0.5334 0.254)
				(xy -0.5334 0.2794) (xy 0.508 0.2794) (xy 0.5334 0.2794)
			)
			(stroke
				(width 0)
				(type default)
			)
			(fill no)
			(layer "B.CrtYd")
		)
		(pad "1" smd rect
			(at -0.40005 0 180)
			(size 0.4572 0.508)
			(layers "B.Cu" "B.Mask" "B.Paste")
			(net "P1V05_NODE1")
		)
		(pad "2" smd rect
			(at 0.40005 0 180)
			(size 0.4572 0.508)
			(layers "B.Cu" "B.Mask" "B.Paste")
			(net "GND")
		)
	)
	(footprint ""
		(layer "B.Cu")
		(at 71.645526 -83.960208 180)
		(property "Reference" "R77"
			(at -2.476754 1.427988 0)
			(unlocked yes)
			(layer "B.SilkS")
			(effects
				(font
					(size 0.7874 0.5842)
					(thickness 0.1524)
				)
				(justify left mirror)
			)
		)
		(property "Value" ""
			(at 0 0 0)
			(layer "B.Fab")
			(effects
				(font
					(size 1.27 1.27)
				)
				(justify mirror)
			)
		)
		(duplicate_pad_numbers_are_jumpers no)
		(fp_line
			(start 0.7874 0.4064)
			(end 0.7874 -0.4064)
			(stroke
				(width 0.1524)
				(type default)
			)
			(layer "B.SilkS")
		)
		(fp_line
			(start 0.7874 -0.4064)
			(end -0.7874 -0.4064)
			(stroke
				(width 0.1524)
				(type default)
			)
			(layer "B.SilkS")
		)
		(fp_line
			(start -0.7874 0.4064)
			(end 0.7874 0.4064)
			(stroke
				(width 0.1524)
				(type default)
			)
			(layer "B.SilkS")
		)
		(fp_line
			(start -0.7874 -0.4064)
			(end -0.7874 0.4064)
			(stroke
				(width 0.1524)
				(type default)
			)
			(layer "B.SilkS")
		)
		(fp_poly
			(pts
				(xy 0.508 0.2794) (xy 0.508 0.2286) (xy 0.635 0.2286) (xy 0.635 -0.254) (xy 0.5334 -0.254) (xy 0.5334 -0.2794)
				(xy -0.5334 -0.2794) (xy -0.5334 -0.254) (xy -0.635 -0.254) (xy -0.635 0.254) (xy -0.5334 0.254)
				(xy -0.5334 0.2794)
			)
			(stroke
				(width 0)
				(type default)
			)
			(fill no)
			(layer "B.CrtYd")
		)
		(pad "1" smd rect
			(at -0.40005 0)
			(size 0.4572 0.508)
			(layers "B.Cu" "B.Mask" "B.Paste")
			(net "P3V3_SUS_NODE1")
		)
		(pad "2" smd rect
			(at 0.40005 0)
			(size 0.4572 0.508)
			(layers "B.Cu" "B.Mask" "B.Paste")
			(net "VR_NODE1_VDDR_1V5_CNTL")
		)
	)
	(footprint ""
		(layer "B.Cu")
		(at 160.67278 -148.854922 90)
		(property "Reference" "C463"
			(at -8.519922 -0.503174 270)
			(unlocked yes)
			(layer "B.SilkS")
			(effects
				(font
					(size 0.7874 0.5842)
					(thickness 0.1524)
				)
				(justify left mirror)
			)
		)
		(property "Value" ""
			(at 0 0 90)
			(layer "B.Fab")
			(effects
				(font
					(size 1.27 1.27)
				)
				(justify mirror)
			)
		)
		(duplicate_pad_numbers_are_jumpers no)
		(fp_line
			(start 0.7874 -0.4064)
			(end -0.7874 -0.4064)
			(stroke
				(width 0.1524)
				(type default)
			)
			(layer "B.SilkS")
		)
		(fp_line
			(start -0.7874 -0.4064)
			(end -0.7874 0.4064)
			(stroke
				(width 0.1524)
				(type default)
			)
			(layer "B.SilkS")
		)
		(fp_line
			(start 0 0.381)
			(end 0 -0.381)
			(stroke
				(width 0.1524)
				(type default)
			)
			(layer "B.SilkS")
		)
		(fp_line
			(start 0.7874 0.4064)
			(end 0.7874 -0.4064)
			(stroke
				(width 0.1524)
				(type default)
			)
			(layer "B.SilkS")
		)
		(fp_line
			(start -0.7874 0.4064)
			(end 0.7874 0.4064)
			(stroke
				(width 0.1524)
				(type default)
			)
			(layer "B.SilkS")
		)
		(fp_poly
			(pts
				(xy 0.5334 0.254) (xy 0.635 0.254) (xy 0.635 0.2286) (xy 0.635 -0.254) (xy 0.5334 -0.254) (xy 0.5334 -0.2794)
				(xy -0.5334 -0.2794) (xy -0.5334 -0.254) (xy -0.635 -0.254) (xy -0.635 0.254) (xy -0.5334 0.254)
				(xy -0.5334 0.2794) (xy 0.508 0.2794) (xy 0.5334 0.2794)
			)
			(stroke
				(width 0)
				(type default)
			)
			(fill no)
			(layer "B.CrtYd")
		)
		(pad "1" smd rect
			(at -0.40005 0 270)
			(size 0.4572 0.508)
			(layers "B.Cu" "B.Mask" "B.Paste")
			(net "P1V05_LAN2")
		)
		(pad "2" smd rect
			(at 0.40005 0 270)
			(size 0.4572 0.508)
			(layers "B.Cu" "B.Mask" "B.Paste")
			(net "GND")
		)
	)
	(footprint ""
		(layer "B.Cu")
		(at 72.186546 -27.351736 -90)
		(property "Reference" "C169"
			(at -1.096772 0.018796 270)
			(unlocked yes)
			(layer "B.SilkS")
			(effects
				(font
					(size 0.7874 0.5842)
					(thickness 0.1524)
				)
				(justify left mirror)
			)
		)
		(property "Value" ""
			(at 0 0 90)
			(layer "B.Fab")
			(effects
				(font
					(size 1.27 1.27)
				)
				(justify mirror)
			)
		)
		(duplicate_pad_numbers_are_jumpers no)
		(fp_line
			(start -0.7874 0.4064)
			(end 0.7874 0.4064)
			(stroke
				(width 0.1524)
				(type default)
			)
			(layer "B.SilkS")
		)
		(fp_line
			(start 0.7874 0.4064)
			(end 0.7874 -0.4064)
			(stroke
				(width 0.1524)
				(type default)
			)
			(layer "B.SilkS")
		)
		(fp_line
			(start 0 0.381)
			(end 0 -0.381)
			(stroke
				(width 0.1524)
				(type default)
			)
			(layer "B.SilkS")
		)
		(fp_line
			(start -0.7874 -0.4064)
			(end -0.7874 0.4064)
			(stroke
				(width 0.1524)
				(type default)
			)
			(layer "B.SilkS")
		)
		(fp_line
			(start 0.7874 -0.4064)
			(end -0.7874 -0.4064)
			(stroke
				(width 0.1524)
				(type default)
			)
			(layer "B.SilkS")
		)
		(fp_poly
			(pts
				(xy 0.5334 0.254) (xy 0.635 0.254) (xy 0.635 0.2286) (xy 0.635 -0.254) (xy 0.5334 -0.254) (xy 0.5334 -0.2794)
				(xy -0.5334 -0.2794) (xy -0.5334 -0.254) (xy -0.635 -0.254) (xy -0.635 0.254) (xy -0.5334 0.254)
				(xy -0.5334 0.2794) (xy 0.508 0.2794) (xy 0.5334 0.2794)
			)
			(stroke
				(width 0)
				(type default)
			)
			(fill no)
			(layer "B.CrtYd")
		)
		(pad "1" smd rect
			(at -0.40005 0 90)
			(size 0.4572 0.508)
			(layers "B.Cu" "B.Mask" "B.Paste")
			(net "PV_VDDR_NODE1")
		)
		(pad "2" smd rect
			(at 0.40005 0 90)
			(size 0.4572 0.508)
			(layers "B.Cu" "B.Mask" "B.Paste")
			(net "GND")
		)
	)
	(footprint ""
		(layer "B.Cu")
		(at 63.832486 -121.044462 90)
		(property "Reference" "R321"
			(at -7.37235 10.08634 270)
			(unlocked yes)
			(layer "B.SilkS")
			(effects
				(font
					(size 0.7874 0.5842)
					(thickness 0.1524)
				)
				(justify left mirror)
			)
		)
		(property "Value" ""
			(at 0 0 90)
			(layer "B.Fab")
			(effects
				(font
					(size 1.27 1.27)
				)
				(justify mirror)
			)
		)
		(duplicate_pad_numbers_are_jumpers no)
		(fp_line
			(start 0.7874 -0.4064)
			(end -0.7874 -0.4064)
			(stroke
				(width 0.1524)
				(type default)
			)
			(layer "B.SilkS")
		)
		(fp_line
			(start -0.7874 -0.4064)
			(end -0.7874 0.4064)
			(stroke
				(width 0.1524)
				(type default)
			)
			(layer "B.SilkS")
		)
		(fp_line
			(start 0.7874 0.4064)
			(end 0.7874 -0.4064)
			(stroke
				(width 0.1524)
				(type default)
			)
			(layer "B.SilkS")
		)
		(fp_line
			(start -0.7874 0.4064)
			(end 0.7874 0.4064)
			(stroke
				(width 0.1524)
				(type default)
			)
			(layer "B.SilkS")
		)
		(fp_poly
			(pts
				(xy 0.508 0.2794) (xy 0.508 0.2286) (xy 0.635 0.2286) (xy 0.635 -0.254) (xy 0.5334 -0.254) (xy 0.5334 -0.2794)
				(xy -0.5334 -0.2794) (xy -0.5334 -0.254) (xy -0.635 -0.254) (xy -0.635 0.254) (xy -0.5334 0.254)
				(xy -0.5334 0.2794)
			)
			(stroke
				(width 0)
				(type default)
			)
			(fill no)
			(layer "B.CrtYd")
		)
		(pad "1" smd rect
			(at -0.40005 0 270)
			(size 0.4572 0.508)
			(layers "B.Cu" "B.Mask" "B.Paste")
			(net "P3V3_NODE1")
		)
		(pad "2" smd rect
			(at 0.40005 0 270)
			(size 0.4572 0.508)
			(layers "B.Cu" "B.Mask" "B.Paste")
			(net "BMC_ROMA5")
		)
	)
	(footprint ""
		(layer "B.Cu")
		(at 54.16931 -68.50507 -90)
		(property "Reference" "C95"
			(at 32.190436 14.44752 270)
			(unlocked yes)
			(layer "B.SilkS")
			(effects
				(font
					(size 0.7874 0.5842)
					(thickness 0.1524)
				)
				(justify left mirror)
			)
		)
		(property "Value" ""
			(at 0 0 90)
			(layer "B.Fab")
			(effects
				(font
					(size 1.27 1.27)
				)
				(justify mirror)
			)
		)
		(duplicate_pad_numbers_are_jumpers no)
		(fp_line
			(start -0.7874 0.4064)
			(end 0.7874 0.4064)
			(stroke
				(width 0.1524)
				(type default)
			)
			(layer "B.SilkS")
		)
		(fp_line
			(start 0.7874 0.4064)
			(end 0.7874 -0.4064)
			(stroke
				(width 0.1524)
				(type default)
			)
			(layer "B.SilkS")
		)
		(fp_line
			(start 0 0.381)
			(end 0 -0.381)
			(stroke
				(width 0.1524)
				(type default)
			)
			(layer "B.SilkS")
		)
		(fp_line
			(start -0.7874 -0.4064)
			(end -0.7874 0.4064)
			(stroke
				(width 0.1524)
				(type default)
			)
			(layer "B.SilkS")
		)
		(fp_line
			(start 0.7874 -0.4064)
			(end -0.7874 -0.4064)
			(stroke
				(width 0.1524)
				(type default)
			)
			(layer "B.SilkS")
		)
		(fp_poly
			(pts
				(xy 0.5334 0.254) (xy 0.635 0.254) (xy 0.635 0.2286) (xy 0.635 -0.254) (xy 0.5334 -0.254) (xy 0.5334 -0.2794)
				(xy -0.5334 -0.2794) (xy -0.5334 -0.254) (xy -0.635 -0.254) (xy -0.635 0.254) (xy -0.5334 0.254)
				(xy -0.5334 0.2794) (xy 0.508 0.2794) (xy 0.5334 0.2794)
			)
			(stroke
				(width 0)
				(type default)
			)
			(fill no)
			(layer "B.CrtYd")
		)
		(pad "1" smd rect
			(at -0.40005 0 90)
			(size 0.4572 0.508)
			(layers "B.Cu" "B.Mask" "B.Paste")
			(net "P1V5_SUS_NODE1")
		)
		(pad "2" smd rect
			(at 0.40005 0 90)
			(size 0.4572 0.508)
			(layers "B.Cu" "B.Mask" "B.Paste")
			(net "GND")
		)
	)
	(footprint ""
		(layer "B.Cu")
		(at 83.05927 -21.09724 90)
		(property "Reference" "C147"
			(at -5.738114 -0.62992 270)
			(unlocked yes)
			(layer "B.SilkS")
			(effects
				(font
					(size 0.7874 0.5842)
					(thickness 0.1524)
				)
				(justify left mirror)
			)
		)
		(property "Value" ""
			(at 0 0 90)
			(layer "B.Fab")
			(effects
				(font
					(size 1.27 1.27)
				)
				(justify mirror)
			)
		)
		(duplicate_pad_numbers_are_jumpers no)
		(fp_line
			(start 0.7874 -0.4064)
			(end -0.7874 -0.4064)
			(stroke
				(width 0.1524)
				(type default)
			)
			(layer "B.SilkS")
		)
		(fp_line
			(start -0.7874 -0.4064)
			(end -0.7874 0.4064)
			(stroke
				(width 0.1524)
				(type default)
			)
			(layer "B.SilkS")
		)
		(fp_line
			(start 0 0.381)
			(end 0 -0.381)
			(stroke
				(width 0.1524)
				(type default)
			)
			(layer "B.SilkS")
		)
		(fp_line
			(start 0.7874 0.4064)
			(end 0.7874 -0.4064)
			(stroke
				(width 0.1524)
				(type default)
			)
			(layer "B.SilkS")
		)
		(fp_line
			(start -0.7874 0.4064)
			(end 0.7874 0.4064)
			(stroke
				(width 0.1524)
				(type default)
			)
			(layer "B.SilkS")
		)
		(fp_poly
			(pts
				(xy 0.5334 0.254) (xy 0.635 0.254) (xy 0.635 0.2286) (xy 0.635 -0.254) (xy 0.5334 -0.254) (xy 0.5334 -0.2794)
				(xy -0.5334 -0.2794) (xy -0.5334 -0.254) (xy -0.635 -0.254) (xy -0.635 0.254) (xy -0.5334 0.254)
				(xy -0.5334 0.2794) (xy 0.508 0.2794) (xy 0.5334 0.2794)
			)
			(stroke
				(width 0)
				(type default)
			)
			(fill no)
			(layer "B.CrtYd")
		)
		(pad "1" smd rect
			(at -0.40005 0 270)
			(size 0.4572 0.508)
			(layers "B.Cu" "B.Mask" "B.Paste")
			(net "PV_VDDR_NODE1")
		)
		(pad "2" smd rect
			(at 0.40005 0 270)
			(size 0.4572 0.508)
			(layers "B.Cu" "B.Mask" "B.Paste")
			(net "GND")
		)
	)
	(footprint ""
		(layer "B.Cu")
		(at 76.7461 -164.132768)
		(property "Reference" "R622"
			(at -1.420368 0.208026 0)
			(unlocked yes)
			(layer "B.SilkS")
			(effects
				(font
					(size 0.7874 0.5842)
					(thickness 0.1524)
				)
				(justify left mirror)
			)
		)
		(property "Value" ""
			(at 0 0 0)
			(layer "B.Fab")
			(effects
				(font
					(size 1.27 1.27)
				)
				(justify mirror)
			)
		)
		(duplicate_pad_numbers_are_jumpers no)
		(fp_line
			(start -0.7874 -0.4064)
			(end -0.7874 0.4064)
			(stroke
				(width 0.1524)
				(type default)
			)
			(layer "B.SilkS")
		)
		(fp_line
			(start -0.7874 0.4064)
			(end 0.7874 0.4064)
			(stroke
				(width 0.1524)
				(type default)
			)
			(layer "B.SilkS")
		)
		(fp_line
			(start 0.7874 -0.4064)
			(end -0.7874 -0.4064)
			(stroke
				(width 0.1524)
				(type default)
			)
			(layer "B.SilkS")
		)
		(fp_line
			(start 0.7874 0.4064)
			(end 0.7874 -0.4064)
			(stroke
				(width 0.1524)
				(type default)
			)
			(layer "B.SilkS")
		)
		(fp_poly
			(pts
				(xy 0.508 0.2794) (xy 0.508 0.2286) (xy 0.635 0.2286) (xy 0.635 -0.254) (xy 0.5334 -0.254) (xy 0.5334 -0.2794)
				(xy -0.5334 -0.2794) (xy -0.5334 -0.254) (xy -0.635 -0.254) (xy -0.635 0.254) (xy -0.5334 0.254)
				(xy -0.5334 0.2794)
			)
			(stroke
				(width 0)
				(type default)
			)
			(fill no)
			(layer "B.CrtYd")
		)
		(pad "1" smd rect
			(at -0.40005 0 180)
			(size 0.4572 0.508)
			(layers "B.Cu" "B.Mask" "B.Paste")
			(net "CPLD_WDT2")
		)
		(pad "2" smd rect
			(at 0.40005 0 180)
			(size 0.4572 0.508)
			(layers "B.Cu" "B.Mask" "B.Paste")
			(net "CPLD_WDT2_R")
		)
	)
	(footprint ""
		(layer "B.Cu")
		(at 39.120572 -67.941698 180)
		(property "Reference" "C15"
			(at -3.128264 -0.293116 0)
			(unlocked yes)
			(layer "B.SilkS")
			(effects
				(font
					(size 0.7874 0.5842)
					(thickness 0.1524)
				)
				(justify left mirror)
			)
		)
		(property "Value" ""
			(at 0 0 0)
			(layer "B.Fab")
			(effects
				(font
					(size 1.27 1.27)
				)
				(justify mirror)
			)
		)
		(duplicate_pad_numbers_are_jumpers no)
		(fp_line
			(start 0.7874 0.4064)
			(end 0.7874 -0.4064)
			(stroke
				(width 0.1524)
				(type default)
			)
			(layer "B.SilkS")
		)
		(fp_line
			(start 0.7874 -0.4064)
			(end -0.7874 -0.4064)
			(stroke
				(width 0.1524)
				(type default)
			)
			(layer "B.SilkS")
		)
		(fp_line
			(start 0 0.381)
			(end 0 -0.381)
			(stroke
				(width 0.1524)
				(type default)
			)
			(layer "B.SilkS")
		)
		(fp_line
			(start -0.7874 0.4064)
			(end 0.7874 0.4064)
			(stroke
				(width 0.1524)
				(type default)
			)
			(layer "B.SilkS")
		)
		(fp_line
			(start -0.7874 -0.4064)
			(end -0.7874 0.4064)
			(stroke
				(width 0.1524)
				(type default)
			)
			(layer "B.SilkS")
		)
		(fp_poly
			(pts
				(xy 0.5334 0.254) (xy 0.635 0.254) (xy 0.635 0.2286) (xy 0.635 -0.254) (xy 0.5334 -0.254) (xy 0.5334 -0.2794)
				(xy -0.5334 -0.2794) (xy -0.5334 -0.254) (xy -0.635 -0.254) (xy -0.635 0.254) (xy -0.5334 0.254)
				(xy -0.5334 0.2794) (xy 0.508 0.2794) (xy 0.5334 0.2794)
			)
			(stroke
				(width 0)
				(type default)
			)
			(fill no)
			(layer "B.CrtYd")
		)
		(pad "1" smd rect
			(at -0.40005 0)
			(size 0.4572 0.508)
			(layers "B.Cu" "B.Mask" "B.Paste")
			(net "P2E_CPU_PCIE_SW_NODE1_TX_C_DP")
		)
		(pad "2" smd rect
			(at 0.40005 0)
			(size 0.4572 0.508)
			(layers "B.Cu" "B.Mask" "B.Paste")
			(net "P2E_CPU_PCIE_SW_NODE1_TX_DP")
		)
	)
	(footprint ""
		(layer "B.Cu")
		(at 58.087006 -125.121924 90)
		(property "Reference" "C269"
			(at -54.315868 -40.971724 270)
			(unlocked yes)
			(layer "B.SilkS")
			(effects
				(font
					(size 0.7874 0.5842)
					(thickness 0.1524)
				)
				(justify left mirror)
			)
		)
		(property "Value" ""
			(at 0 0 90)
			(layer "B.Fab")
			(effects
				(font
					(size 1.27 1.27)
				)
				(justify mirror)
			)
		)
		(duplicate_pad_numbers_are_jumpers no)
		(fp_line
			(start 0.7874 -0.4064)
			(end -0.7874 -0.4064)
			(stroke
				(width 0.1524)
				(type default)
			)
			(layer "B.SilkS")
		)
		(fp_line
			(start -0.7874 -0.4064)
			(end -0.7874 0.4064)
			(stroke
				(width 0.1524)
				(type default)
			)
			(layer "B.SilkS")
		)
		(fp_line
			(start 0 0.381)
			(end 0 -0.381)
			(stroke
				(width 0.1524)
				(type default)
			)
			(layer "B.SilkS")
		)
		(fp_line
			(start 0.7874 0.4064)
			(end 0.7874 -0.4064)
			(stroke
				(width 0.1524)
				(type default)
			)
			(layer "B.SilkS")
		)
		(fp_line
			(start -0.7874 0.4064)
			(end 0.7874 0.4064)
			(stroke
				(width 0.1524)
				(type default)
			)
			(layer "B.SilkS")
		)
		(fp_poly
			(pts
				(xy 0.5334 0.254) (xy 0.635 0.254) (xy 0.635 0.2286) (xy 0.635 -0.254) (xy 0.5334 -0.254) (xy 0.5334 -0.2794)
				(xy -0.5334 -0.2794) (xy -0.5334 -0.254) (xy -0.635 -0.254) (xy -0.635 0.254) (xy -0.5334 0.254)
				(xy -0.5334 0.2794) (xy 0.508 0.2794) (xy 0.5334 0.2794)
			)
			(stroke
				(width 0)
				(type default)
			)
			(fill no)
			(layer "B.CrtYd")
		)
		(pad "1" smd rect
			(at -0.40005 0 270)
			(size 0.4572 0.508)
			(layers "B.Cu" "B.Mask" "B.Paste")
			(net "BMC_NODE1_HPLLAV33")
		)
		(pad "2" smd rect
			(at 0.40005 0 270)
			(size 0.4572 0.508)
			(layers "B.Cu" "B.Mask" "B.Paste")
			(net "GND")
		)
	)
	(footprint ""
		(layer "B.Cu")
		(at 165.252908 -185.083196 180)
		(property "Reference" "R1308"
			(at -6.483604 7.920482 0)
			(unlocked yes)
			(layer "B.SilkS")
			(effects
				(font
					(size 0.7874 0.5842)
					(thickness 0.1524)
				)
				(justify left mirror)
			)
		)
		(property "Value" ""
			(at 0 0 0)
			(layer "B.Fab")
			(effects
				(font
					(size 1.27 1.27)
				)
				(justify mirror)
			)
		)
		(duplicate_pad_numbers_are_jumpers no)
		(fp_line
			(start 0.7874 0.4064)
			(end 0.7874 -0.4064)
			(stroke
				(width 0.1524)
				(type default)
			)
			(layer "B.SilkS")
		)
		(fp_line
			(start 0.7874 -0.4064)
			(end -0.7874 -0.4064)
			(stroke
				(width 0.1524)
				(type default)
			)
			(layer "B.SilkS")
		)
		(fp_line
			(start -0.7874 0.4064)
			(end 0.7874 0.4064)
			(stroke
				(width 0.1524)
				(type default)
			)
			(layer "B.SilkS")
		)
		(fp_line
			(start -0.7874 -0.4064)
			(end -0.7874 0.4064)
			(stroke
				(width 0.1524)
				(type default)
			)
			(layer "B.SilkS")
		)
		(fp_poly
			(pts
				(xy 0.508 0.2794) (xy 0.508 0.2286) (xy 0.635 0.2286) (xy 0.635 -0.254) (xy 0.5334 -0.254) (xy 0.5334 -0.2794)
				(xy -0.5334 -0.2794) (xy -0.5334 -0.254) (xy -0.635 -0.254) (xy -0.635 0.254) (xy -0.5334 0.254)
				(xy -0.5334 0.2794)
			)
			(stroke
				(width 0)
				(type default)
			)
			(fill no)
			(layer "B.CrtYd")
		)
		(pad "1" smd rect
			(at -0.40005 0)
			(size 0.4572 0.508)
			(layers "B.Cu" "B.Mask" "B.Paste")
			(net "P3V3_NODE1")
		)
		(pad "2" smd rect
			(at 0.40005 0)
			(size 0.4572 0.508)
			(layers "B.Cu" "B.Mask" "B.Paste")
			(net "N54365772")
		)
	)
	(footprint ""
		(layer "B.Cu")
		(at 110.44936 -177.585624 180)
		(property "Reference" "R713"
			(at 21.356828 -32.269176 0)
			(unlocked yes)
			(layer "B.SilkS")
			(effects
				(font
					(size 0.7874 0.5842)
					(thickness 0.1524)
				)
				(justify left mirror)
			)
		)
		(property "Value" ""
			(at 0 0 0)
			(layer "B.Fab")
			(effects
				(font
					(size 1.27 1.27)
				)
				(justify mirror)
			)
		)
		(duplicate_pad_numbers_are_jumpers no)
		(fp_line
			(start 0.7874 0.4064)
			(end 0.7874 -0.4064)
			(stroke
				(width 0.1524)
				(type default)
			)
			(layer "B.SilkS")
		)
		(fp_line
			(start 0.7874 -0.4064)
			(end -0.7874 -0.4064)
			(stroke
				(width 0.1524)
				(type default)
			)
			(layer "B.SilkS")
		)
		(fp_line
			(start -0.7874 0.4064)
			(end 0.7874 0.4064)
			(stroke
				(width 0.1524)
				(type default)
			)
			(layer "B.SilkS")
		)
		(fp_line
			(start -0.7874 -0.4064)
			(end -0.7874 0.4064)
			(stroke
				(width 0.1524)
				(type default)
			)
			(layer "B.SilkS")
		)
		(fp_poly
			(pts
				(xy 0.508 0.2794) (xy 0.508 0.2286) (xy 0.635 0.2286) (xy 0.635 -0.254) (xy 0.5334 -0.254) (xy 0.5334 -0.2794)
				(xy -0.5334 -0.2794) (xy -0.5334 -0.254) (xy -0.635 -0.254) (xy -0.635 0.254) (xy -0.5334 0.254)
				(xy -0.5334 0.2794)
			)
			(stroke
				(width 0)
				(type default)
			)
			(fill no)
			(layer "B.CrtYd")
		)
		(pad "1" smd rect
			(at -0.40005 0)
			(size 0.4572 0.508)
			(layers "B.Cu" "B.Mask" "B.Paste")
			(net "T5_NODE4_EN")
		)
		(pad "2" smd rect
			(at 0.40005 0)
			(size 0.4572 0.508)
			(layers "B.Cu" "B.Mask" "B.Paste")
			(net "P5V_NODE1")
		)
	)
	(footprint ""
		(layer "B.Cu")
		(at 157.33776 -187.872624 -90)
		(property "Reference" "C597"
			(at -4.565396 3.861308 270)
			(unlocked yes)
			(layer "B.SilkS")
			(effects
				(font
					(size 0.7874 0.5842)
					(thickness 0.1524)
				)
				(justify left mirror)
			)
		)
		(property "Value" ""
			(at 0 0 90)
			(layer "B.Fab")
			(effects
				(font
					(size 1.27 1.27)
				)
				(justify mirror)
			)
		)
		(duplicate_pad_numbers_are_jumpers no)
		(fp_line
			(start -0.7874 0.4064)
			(end 0.7874 0.4064)
			(stroke
				(width 0.1524)
				(type default)
			)
			(layer "B.SilkS")
		)
		(fp_line
			(start 0.7874 0.4064)
			(end 0.7874 -0.4064)
			(stroke
				(width 0.1524)
				(type default)
			)
			(layer "B.SilkS")
		)
		(fp_line
			(start 0 0.381)
			(end 0 -0.381)
			(stroke
				(width 0.1524)
				(type default)
			)
			(layer "B.SilkS")
		)
		(fp_line
			(start -0.7874 -0.4064)
			(end -0.7874 0.4064)
			(stroke
				(width 0.1524)
				(type default)
			)
			(layer "B.SilkS")
		)
		(fp_line
			(start 0.7874 -0.4064)
			(end -0.7874 -0.4064)
			(stroke
				(width 0.1524)
				(type default)
			)
			(layer "B.SilkS")
		)
		(fp_poly
			(pts
				(xy 0.5334 0.254) (xy 0.635 0.254) (xy 0.635 0.2286) (xy 0.635 -0.254) (xy 0.5334 -0.254) (xy 0.5334 -0.2794)
				(xy -0.5334 -0.2794) (xy -0.5334 -0.254) (xy -0.635 -0.254) (xy -0.635 0.254) (xy -0.5334 0.254)
				(xy -0.5334 0.2794) (xy 0.508 0.2794) (xy 0.5334 0.2794)
			)
			(stroke
				(width 0)
				(type default)
			)
			(fill no)
			(layer "B.CrtYd")
		)
		(pad "1" smd rect
			(at -0.40005 0 90)
			(size 0.4572 0.508)
			(layers "B.Cu" "B.Mask" "B.Paste")
			(net "I2C_PSU3_R_SCL")
		)
		(pad "2" smd rect
			(at 0.40005 0 90)
			(size 0.4572 0.508)
			(layers "B.Cu" "B.Mask" "B.Paste")
			(net "GND")
		)
	)
	(footprint ""
		(layer "B.Cu")
		(at 156.19476 -184.951624 90)
		(property "Reference" "R826"
			(at 4.230624 -1.838198 270)
			(unlocked yes)
			(layer "B.SilkS")
			(effects
				(font
					(size 0.7874 0.5842)
					(thickness 0.1524)
				)
				(justify left mirror)
			)
		)
		(property "Value" ""
			(at 0 0 90)
			(layer "B.Fab")
			(effects
				(font
					(size 1.27 1.27)
				)
				(justify mirror)
			)
		)
		(duplicate_pad_numbers_are_jumpers no)
		(fp_line
			(start 0.7874 -0.4064)
			(end -0.7874 -0.4064)
			(stroke
				(width 0.1524)
				(type default)
			)
			(layer "B.SilkS")
		)
		(fp_line
			(start -0.7874 -0.4064)
			(end -0.7874 0.4064)
			(stroke
				(width 0.1524)
				(type default)
			)
			(layer "B.SilkS")
		)
		(fp_line
			(start 0.7874 0.4064)
			(end 0.7874 -0.4064)
			(stroke
				(width 0.1524)
				(type default)
			)
			(layer "B.SilkS")
		)
		(fp_line
			(start -0.7874 0.4064)
			(end 0.7874 0.4064)
			(stroke
				(width 0.1524)
				(type default)
			)
			(layer "B.SilkS")
		)
		(fp_poly
			(pts
				(xy 0.508 0.2794) (xy 0.508 0.2286) (xy 0.635 0.2286) (xy 0.635 -0.254) (xy 0.5334 -0.254) (xy 0.5334 -0.2794)
				(xy -0.5334 -0.2794) (xy -0.5334 -0.254) (xy -0.635 -0.254) (xy -0.635 0.254) (xy -0.5334 0.254)
				(xy -0.5334 0.2794)
			)
			(stroke
				(width 0)
				(type default)
			)
			(fill no)
			(layer "B.CrtYd")
		)
		(pad "1" smd rect
			(at -0.40005 0 270)
			(size 0.4572 0.508)
			(layers "B.Cu" "B.Mask" "B.Paste")
			(net "I2C_PSU3_SDA")
		)
		(pad "2" smd rect
			(at 0.40005 0 270)
			(size 0.4572 0.508)
			(layers "B.Cu" "B.Mask" "B.Paste")
			(net "I2C_PSU3_R_SDA")
		)
	)
	(footprint ""
		(layer "B.Cu")
		(at 58.602372 -71.370698)
		(property "Reference" "PJ8"
			(at -13.960602 34.763456 270)
			(unlocked yes)
			(layer "B.SilkS")
			(effects
				(font
					(size 0.7874 0.5842)
					(thickness 0.1524)
				)
				(justify left mirror)
			)
		)
		(property "Value" ""
			(at 0 0 0)
			(layer "B.Fab")
			(effects
				(font
					(size 1.27 1.27)
				)
				(justify mirror)
			)
		)
		(duplicate_pad_numbers_are_jumpers no)
		(fp_poly
			(pts
				(xy -0.2794 0.907796) (xy -0.254 0.907796) (xy -0.254 1.0414) (xy 0.254 1.0414) (xy 0.254 1.034796)
				(xy 0.254 0.933196) (xy 0.2794 0.933196) (xy 0.2794 -0.133604) (xy 0.254 -0.133604) (xy 0.254 -0.235204)
				(xy -0.254 -0.235204) (xy -0.254 -0.133604) (xy -0.2794 -0.133604)
			)
			(stroke
				(width 0)
				(type default)
			)
			(fill no)
			(layer "B.CrtYd")
		)
		(pad "1" smd custom
			(at 0 -0.000254 180)
			(size 0.127 0.127)
			(layers "B.Cu" "B.Mask" "B.Paste")
			(net "P1V05_NODE1")
			(options
				(clearance outline)
				(anchor circle)
			)
			(primitives
				(gr_poly
					(pts
						(xy -0.127 -0.508) (xy -0.127 0.0508) (xy -0.254 0.0508) (xy -0.254 0.508) (xy 0.254 0.508) (xy 0.254 0.0508)
						(xy 0.127 0.0508) (xy 0.127 -0.508)
					)
					(width 0)
					(fill yes)
				)
			)
		)
		(pad "2" smd rect
			(at 0 0.799846 90)
			(size 0.4572 0.508)
			(layers "B.Cu" "B.Mask" "B.Paste")
			(net "VSENSE_P1V05_NODE1_P")
		)
		(zone
			(layer "B.Cu")
			(hatch none 0.5)
			(connect_pads
				(clearance 0)
			)
			(min_thickness 0.25)
			(keepout
				(tracks allowed)
				(vias not_allowed)
				(pads allowed)
				(copperpour not_allowed)
				(footprints allowed)
			)
			(placement
				(enabled no)
				(sheetname "")
			)
			(fill
				(thermal_gap 0.5)
				(thermal_bridge_width 0.5)
				(island_removal_mode 0)
			)
			(polygon
				(pts
					(xy 58.907172 -70.285102) (xy 58.297572 -70.285102) (xy 58.297572 -71.656702) (xy 58.907172 -71.656702)
				)
			)
		)
	)
	(footprint ""
		(layer "B.Cu")
		(at 103.329994 -116.985796)
		(property "Reference" "PC124"
			(at -2.577846 0.009144 0)
			(unlocked yes)
			(layer "B.SilkS")
			(effects
				(font
					(size 0.7874 0.5842)
					(thickness 0.1524)
				)
				(justify left mirror)
			)
		)
		(property "Value" ""
			(at 0 0 0)
			(layer "B.Fab")
			(effects
				(font
					(size 1.27 1.27)
				)
				(justify mirror)
			)
		)
		(duplicate_pad_numbers_are_jumpers no)
		(fp_line
			(start -1.905 -0.8636)
			(end -1.905 0.8636)
			(stroke
				(width 0.1524)
				(type default)
			)
			(layer "B.SilkS")
		)
		(fp_line
			(start -1.905 0.8636)
			(end 1.905 0.8636)
			(stroke
				(width 0.1524)
				(type default)
			)
			(layer "B.SilkS")
		)
		(fp_line
			(start 0 0.8382)
			(end 0 -0.8382)
			(stroke
				(width 0.1524)
				(type default)
			)
			(layer "B.SilkS")
		)
		(fp_line
			(start 1.905 -0.8636)
			(end -1.905 -0.8636)
			(stroke
				(width 0.1524)
				(type default)
			)
			(layer "B.SilkS")
		)
		(fp_line
			(start 1.905 0.8636)
			(end 1.905 -0.8636)
			(stroke
				(width 0.1524)
				(type default)
			)
			(layer "B.SilkS")
		)
		(fp_rect
			(start 1.524 0.7366)
			(end -1.524 -0.7366)
			(stroke
				(width 0)
				(type default)
			)
			(fill no)
			(layer "B.CrtYd")
		)
		(pad "1" smd rect
			(at -0.94996 0 180)
			(size 1.1176 1.3716)
			(layers "B.Cu" "B.Mask" "B.Paste")
			(net "GND")
		)
		(pad "2" smd rect
			(at 0.94996 0 180)
			(size 1.1176 1.3716)
			(layers "B.Cu" "B.Mask" "B.Paste")
			(net "PV_VCCP_NODE1")
		)
	)
	(footprint ""
		(layer "B.Cu")
		(at 106.28376 -185.205624 90)
		(property "Reference" "R896"
			(at 3.957828 0.394208 270)
			(unlocked yes)
			(layer "B.SilkS")
			(effects
				(font
					(size 0.7874 0.5842)
					(thickness 0.1524)
				)
				(justify left mirror)
			)
		)
		(property "Value" ""
			(at 0 0 90)
			(layer "B.Fab")
			(effects
				(font
					(size 1.27 1.27)
				)
				(justify mirror)
			)
		)
		(duplicate_pad_numbers_are_jumpers no)
		(fp_line
			(start 0.7874 -0.4064)
			(end -0.7874 -0.4064)
			(stroke
				(width 0.1524)
				(type default)
			)
			(layer "B.SilkS")
		)
		(fp_line
			(start -0.7874 -0.4064)
			(end -0.7874 0.4064)
			(stroke
				(width 0.1524)
				(type default)
			)
			(layer "B.SilkS")
		)
		(fp_line
			(start 0.7874 0.4064)
			(end 0.7874 -0.4064)
			(stroke
				(width 0.1524)
				(type default)
			)
			(layer "B.SilkS")
		)
		(fp_line
			(start -0.7874 0.4064)
			(end 0.7874 0.4064)
			(stroke
				(width 0.1524)
				(type default)
			)
			(layer "B.SilkS")
		)
		(fp_poly
			(pts
				(xy 0.508 0.2794) (xy 0.508 0.2286) (xy 0.635 0.2286) (xy 0.635 -0.254) (xy 0.5334 -0.254) (xy 0.5334 -0.2794)
				(xy -0.5334 -0.2794) (xy -0.5334 -0.254) (xy -0.635 -0.254) (xy -0.635 0.254) (xy -0.5334 0.254)
				(xy -0.5334 0.2794)
			)
			(stroke
				(width 0)
				(type default)
			)
			(fill no)
			(layer "B.CrtYd")
		)
		(pad "1" smd rect
			(at -0.40005 0 270)
			(size 0.4572 0.508)
			(layers "B.Cu" "B.Mask" "B.Paste")
			(net "T5_NODE1_EN")
		)
		(pad "2" smd rect
			(at 0.40005 0 270)
			(size 0.4572 0.508)
			(layers "B.Cu" "B.Mask" "B.Paste")
			(net "T5_NODE1_EN_R")
		)
	)
	(footprint ""
		(layer "B.Cu")
		(at 68.353686 -121.044462 90)
		(property "Reference" "R330"
			(at -7.37235 9.927336 270)
			(unlocked yes)
			(layer "B.SilkS")
			(effects
				(font
					(size 0.7874 0.5842)
					(thickness 0.1524)
				)
				(justify left mirror)
			)
		)
		(property "Value" ""
			(at 0 0 90)
			(layer "B.Fab")
			(effects
				(font
					(size 1.27 1.27)
				)
				(justify mirror)
			)
		)
		(duplicate_pad_numbers_are_jumpers no)
		(fp_line
			(start 0.7874 -0.4064)
			(end -0.7874 -0.4064)
			(stroke
				(width 0.1524)
				(type default)
			)
			(layer "B.SilkS")
		)
		(fp_line
			(start -0.7874 -0.4064)
			(end -0.7874 0.4064)
			(stroke
				(width 0.1524)
				(type default)
			)
			(layer "B.SilkS")
		)
		(fp_line
			(start 0.7874 0.4064)
			(end 0.7874 -0.4064)
			(stroke
				(width 0.1524)
				(type default)
			)
			(layer "B.SilkS")
		)
		(fp_line
			(start -0.7874 0.4064)
			(end 0.7874 0.4064)
			(stroke
				(width 0.1524)
				(type default)
			)
			(layer "B.SilkS")
		)
		(fp_poly
			(pts
				(xy 0.508 0.2794) (xy 0.508 0.2286) (xy 0.635 0.2286) (xy 0.635 -0.254) (xy 0.5334 -0.254) (xy 0.5334 -0.2794)
				(xy -0.5334 -0.2794) (xy -0.5334 -0.254) (xy -0.635 -0.254) (xy -0.635 0.254) (xy -0.5334 0.254)
				(xy -0.5334 0.2794)
			)
			(stroke
				(width 0)
				(type default)
			)
			(fill no)
			(layer "B.CrtYd")
		)
		(pad "1" smd rect
			(at -0.40005 0 270)
			(size 0.4572 0.508)
			(layers "B.Cu" "B.Mask" "B.Paste")
			(net "P3V3_NODE1")
		)
		(pad "2" smd rect
			(at 0.40005 0 270)
			(size 0.4572 0.508)
			(layers "B.Cu" "B.Mask" "B.Paste")
			(net "BMC_ROMA14")
		)
	)
	(footprint ""
		(layer "B.Cu")
		(at 144.909032 -36.678616)
		(property "Reference" "R1078"
			(at 1.24714 17.425924 0)
			(unlocked yes)
			(layer "B.SilkS")
			(effects
				(font
					(size 0.7874 0.5842)
					(thickness 0.1524)
				)
				(justify left mirror)
			)
		)
		(property "Value" ""
			(at 0 0 0)
			(layer "B.Fab")
			(effects
				(font
					(size 1.27 1.27)
				)
				(justify mirror)
			)
		)
		(duplicate_pad_numbers_are_jumpers no)
		(fp_line
			(start -0.7874 -0.4064)
			(end -0.7874 0.4064)
			(stroke
				(width 0.1524)
				(type default)
			)
			(layer "B.SilkS")
		)
		(fp_line
			(start -0.7874 0.4064)
			(end 0.7874 0.4064)
			(stroke
				(width 0.1524)
				(type default)
			)
			(layer "B.SilkS")
		)
		(fp_line
			(start 0.7874 -0.4064)
			(end -0.7874 -0.4064)
			(stroke
				(width 0.1524)
				(type default)
			)
			(layer "B.SilkS")
		)
		(fp_line
			(start 0.7874 0.4064)
			(end 0.7874 -0.4064)
			(stroke
				(width 0.1524)
				(type default)
			)
			(layer "B.SilkS")
		)
		(fp_poly
			(pts
				(xy 0.508 0.2794) (xy 0.508 0.2286) (xy 0.635 0.2286) (xy 0.635 -0.254) (xy 0.5334 -0.254) (xy 0.5334 -0.2794)
				(xy -0.5334 -0.2794) (xy -0.5334 -0.254) (xy -0.635 -0.254) (xy -0.635 0.254) (xy -0.5334 0.254)
				(xy -0.5334 0.2794)
			)
			(stroke
				(width 0)
				(type default)
			)
			(fill no)
			(layer "B.CrtYd")
		)
		(pad "1" smd rect
			(at -0.40005 0 180)
			(size 0.4572 0.508)
			(layers "B.Cu" "B.Mask" "B.Paste")
			(net "SIO_CPLD_RSV1_R")
		)
		(pad "2" smd rect
			(at 0.40005 0 180)
			(size 0.4572 0.508)
			(layers "B.Cu" "B.Mask" "B.Paste")
			(net "P3V3_NODE1")
		)
	)
	(footprint ""
		(layer "B.Cu")
		(at 54.028086 -123.152662 90)
		(property "Reference" "C297"
			(at -55.125874 -42.362628 270)
			(unlocked yes)
			(layer "B.SilkS")
			(effects
				(font
					(size 0.7874 0.5842)
					(thickness 0.1524)
				)
				(justify left mirror)
			)
		)
		(property "Value" ""
			(at 0 0 90)
			(layer "B.Fab")
			(effects
				(font
					(size 1.27 1.27)
				)
				(justify mirror)
			)
		)
		(duplicate_pad_numbers_are_jumpers no)
		(fp_line
			(start 0.7874 -0.4064)
			(end -0.7874 -0.4064)
			(stroke
				(width 0.1524)
				(type default)
			)
			(layer "B.SilkS")
		)
		(fp_line
			(start -0.7874 -0.4064)
			(end -0.7874 0.4064)
			(stroke
				(width 0.1524)
				(type default)
			)
			(layer "B.SilkS")
		)
		(fp_line
			(start 0 0.381)
			(end 0 -0.381)
			(stroke
				(width 0.1524)
				(type default)
			)
			(layer "B.SilkS")
		)
		(fp_line
			(start 0.7874 0.4064)
			(end 0.7874 -0.4064)
			(stroke
				(width 0.1524)
				(type default)
			)
			(layer "B.SilkS")
		)
		(fp_line
			(start -0.7874 0.4064)
			(end 0.7874 0.4064)
			(stroke
				(width 0.1524)
				(type default)
			)
			(layer "B.SilkS")
		)
		(fp_poly
			(pts
				(xy 0.5334 0.254) (xy 0.635 0.254) (xy 0.635 0.2286) (xy 0.635 -0.254) (xy 0.5334 -0.254) (xy 0.5334 -0.2794)
				(xy -0.5334 -0.2794) (xy -0.5334 -0.254) (xy -0.635 -0.254) (xy -0.635 0.254) (xy -0.5334 0.254)
				(xy -0.5334 0.2794) (xy 0.508 0.2794) (xy 0.5334 0.2794)
			)
			(stroke
				(width 0)
				(type default)
			)
			(fill no)
			(layer "B.CrtYd")
		)
		(pad "1" smd rect
			(at -0.40005 0 270)
			(size 0.4572 0.508)
			(layers "B.Cu" "B.Mask" "B.Paste")
			(net "BMC_NODE1_V1PLLAV12")
		)
		(pad "2" smd rect
			(at 0.40005 0 270)
			(size 0.4572 0.508)
			(layers "B.Cu" "B.Mask" "B.Paste")
			(net "GND")
		)
	)
	(footprint ""
		(layer "B.Cu")
		(at 139.93876 -187.872624 -90)
		(property "Reference" "C624"
			(at -4.565396 1.448308 270)
			(unlocked yes)
			(layer "B.SilkS")
			(effects
				(font
					(size 0.7874 0.5842)
					(thickness 0.1524)
				)
				(justify left mirror)
			)
		)
		(property "Value" ""
			(at 0 0 90)
			(layer "B.Fab")
			(effects
				(font
					(size 1.27 1.27)
				)
				(justify mirror)
			)
		)
		(duplicate_pad_numbers_are_jumpers no)
		(fp_line
			(start -0.7874 0.4064)
			(end 0.7874 0.4064)
			(stroke
				(width 0.1524)
				(type default)
			)
			(layer "B.SilkS")
		)
		(fp_line
			(start 0.7874 0.4064)
			(end 0.7874 -0.4064)
			(stroke
				(width 0.1524)
				(type default)
			)
			(layer "B.SilkS")
		)
		(fp_line
			(start 0 0.381)
			(end 0 -0.381)
			(stroke
				(width 0.1524)
				(type default)
			)
			(layer "B.SilkS")
		)
		(fp_line
			(start -0.7874 -0.4064)
			(end -0.7874 0.4064)
			(stroke
				(width 0.1524)
				(type default)
			)
			(layer "B.SilkS")
		)
		(fp_line
			(start 0.7874 -0.4064)
			(end -0.7874 -0.4064)
			(stroke
				(width 0.1524)
				(type default)
			)
			(layer "B.SilkS")
		)
		(fp_poly
			(pts
				(xy 0.5334 0.254) (xy 0.635 0.254) (xy 0.635 0.2286) (xy 0.635 -0.254) (xy 0.5334 -0.254) (xy 0.5334 -0.2794)
				(xy -0.5334 -0.2794) (xy -0.5334 -0.254) (xy -0.635 -0.254) (xy -0.635 0.254) (xy -0.5334 0.254)
				(xy -0.5334 0.2794) (xy 0.508 0.2794) (xy 0.5334 0.2794)
			)
			(stroke
				(width 0)
				(type default)
			)
			(fill no)
			(layer "B.CrtYd")
		)
		(pad "1" smd rect
			(at -0.40005 0 90)
			(size 0.4572 0.508)
			(layers "B.Cu" "B.Mask" "B.Paste")
			(net "T9_NODE1_EN_R")
		)
		(pad "2" smd rect
			(at 0.40005 0 90)
			(size 0.4572 0.508)
			(layers "B.Cu" "B.Mask" "B.Paste")
			(net "GND")
		)
	)
	(footprint ""
		(layer "B.Cu")
		(at 125.49251 -124.26315 90)
		(property "Reference" "R3"
			(at 2.12979 0.033782 270)
			(unlocked yes)
			(layer "B.SilkS")
			(effects
				(font
					(size 0.7874 0.5842)
					(thickness 0.1524)
				)
				(justify mirror)
			)
		)
		(property "Value" ""
			(at 0 0 90)
			(layer "B.Fab")
			(effects
				(font
					(size 1.27 1.27)
				)
				(justify mirror)
			)
		)
		(duplicate_pad_numbers_are_jumpers no)
		(fp_line
			(start 1.2954 -0.5842)
			(end -1.2954 -0.5842)
			(stroke
				(width 0.1524)
				(type default)
			)
			(layer "B.SilkS")
		)
		(fp_line
			(start -1.2954 -0.5842)
			(end -1.2954 0.5842)
			(stroke
				(width 0.1524)
				(type default)
			)
			(layer "B.SilkS")
		)
		(fp_line
			(start 1.2954 0.5842)
			(end 1.2954 -0.5842)
			(stroke
				(width 0.1524)
				(type default)
			)
			(layer "B.SilkS")
		)
		(fp_line
			(start -1.2954 0.5842)
			(end 1.2954 0.5842)
			(stroke
				(width 0.1524)
				(type default)
			)
			(layer "B.SilkS")
		)
		(fp_poly
			(pts
				(xy -1.143 -0.3556) (xy -1.143 0.3556) (xy -0.8636 0.3556) (xy -0.8636 0.4572) (xy 0.8636 0.4572)
				(xy 0.8636 0.4318) (xy 0.8636 0.3556) (xy 1.143 0.3556) (xy 1.143 -0.3556) (xy 0.8636 -0.3556) (xy 0.8636 -0.4572)
				(xy -0.8636 -0.4572) (xy -0.8636 -0.3556)
			)
			(stroke
				(width 0)
				(type default)
			)
			(fill no)
			(layer "B.CrtYd")
		)
		(pad "1" smd rect
			(at -0.7366 0 180)
			(size 0.7112 0.8128)
			(layers "B.Cu" "B.Mask" "B.Paste")
			(net "P1V05_NODE1")
		)
		(pad "2" smd rect
			(at 0.7366 0 180)
			(size 0.7112 0.8128)
			(layers "B.Cu" "B.Mask" "B.Paste")
			(net "P1V05_CLK_NODE1_R")
		)
	)
	(footprint ""
		(layer "B.Cu")
		(at 70.278752 -98.467926)
		(property "Reference" "R92"
			(at 2.51841 1.571498 0)
			(unlocked yes)
			(layer "B.SilkS")
			(effects
				(font
					(size 0.7874 0.5842)
					(thickness 0.1524)
				)
				(justify left mirror)
			)
		)
		(property "Value" ""
			(at 0 0 0)
			(layer "B.Fab")
			(effects
				(font
					(size 1.27 1.27)
				)
				(justify mirror)
			)
		)
		(duplicate_pad_numbers_are_jumpers no)
		(fp_line
			(start -0.7874 -0.4064)
			(end -0.7874 0.4064)
			(stroke
				(width 0.1524)
				(type default)
			)
			(layer "B.SilkS")
		)
		(fp_line
			(start -0.7874 0.4064)
			(end 0.7874 0.4064)
			(stroke
				(width 0.1524)
				(type default)
			)
			(layer "B.SilkS")
		)
		(fp_line
			(start 0.7874 -0.4064)
			(end -0.7874 -0.4064)
			(stroke
				(width 0.1524)
				(type default)
			)
			(layer "B.SilkS")
		)
		(fp_line
			(start 0.7874 0.4064)
			(end 0.7874 -0.4064)
			(stroke
				(width 0.1524)
				(type default)
			)
			(layer "B.SilkS")
		)
		(fp_poly
			(pts
				(xy 0.508 0.2794) (xy 0.508 0.2286) (xy 0.635 0.2286) (xy 0.635 -0.254) (xy 0.5334 -0.254) (xy 0.5334 -0.2794)
				(xy -0.5334 -0.2794) (xy -0.5334 -0.254) (xy -0.635 -0.254) (xy -0.635 0.254) (xy -0.5334 0.254)
				(xy -0.5334 0.2794)
			)
			(stroke
				(width 0)
				(type default)
			)
			(fill no)
			(layer "B.CrtYd")
		)
		(pad "1" smd rect
			(at -0.40005 0 180)
			(size 0.4572 0.508)
			(layers "B.Cu" "B.Mask" "B.Paste")
			(net "GND")
		)
		(pad "2" smd rect
			(at 0.40005 0 180)
			(size 0.4572 0.508)
			(layers "B.Cu" "B.Mask" "B.Paste")
			(net "NODE1_BIOS_MB_REV_ID1")
		)
	)
	(footprint ""
		(layer "B.Cu")
		(at 67.879468 -138.45032 -90)
		(property "Reference" "C243"
			(at 55.985156 38.169342 270)
			(unlocked yes)
			(layer "B.SilkS")
			(effects
				(font
					(size 0.7874 0.5842)
					(thickness 0.1524)
				)
				(justify left mirror)
			)
		)
		(property "Value" ""
			(at 0 0 90)
			(layer "B.Fab")
			(effects
				(font
					(size 1.27 1.27)
				)
				(justify mirror)
			)
		)
		(duplicate_pad_numbers_are_jumpers no)
		(fp_line
			(start -0.7874 0.4064)
			(end 0.7874 0.4064)
			(stroke
				(width 0.1524)
				(type default)
			)
			(layer "B.SilkS")
		)
		(fp_line
			(start 0.7874 0.4064)
			(end 0.7874 -0.4064)
			(stroke
				(width 0.1524)
				(type default)
			)
			(layer "B.SilkS")
		)
		(fp_line
			(start 0 0.381)
			(end 0 -0.381)
			(stroke
				(width 0.1524)
				(type default)
			)
			(layer "B.SilkS")
		)
		(fp_line
			(start -0.7874 -0.4064)
			(end -0.7874 0.4064)
			(stroke
				(width 0.1524)
				(type default)
			)
			(layer "B.SilkS")
		)
		(fp_line
			(start 0.7874 -0.4064)
			(end -0.7874 -0.4064)
			(stroke
				(width 0.1524)
				(type default)
			)
			(layer "B.SilkS")
		)
		(fp_poly
			(pts
				(xy 0.5334 0.254) (xy 0.635 0.254) (xy 0.635 0.2286) (xy 0.635 -0.254) (xy 0.5334 -0.254) (xy 0.5334 -0.2794)
				(xy -0.5334 -0.2794) (xy -0.5334 -0.254) (xy -0.635 -0.254) (xy -0.635 0.254) (xy -0.5334 0.254)
				(xy -0.5334 0.2794) (xy 0.508 0.2794) (xy 0.5334 0.2794)
			)
			(stroke
				(width 0)
				(type default)
			)
			(fill no)
			(layer "B.CrtYd")
		)
		(pad "1" smd rect
			(at -0.40005 0 90)
			(size 0.4572 0.508)
			(layers "B.Cu" "B.Mask" "B.Paste")
			(net "P3V3_NODE1")
		)
		(pad "2" smd rect
			(at 0.40005 0 90)
			(size 0.4572 0.508)
			(layers "B.Cu" "B.Mask" "B.Paste")
			(net "GND")
		)
	)
	(footprint ""
		(layer "B.Cu")
		(at 156.828998 -154.64663)
		(property "Reference" "C470"
			(at -3.44805 -0.463042 0)
			(unlocked yes)
			(layer "B.SilkS")
			(effects
				(font
					(size 0.7874 0.5842)
					(thickness 0.1524)
				)
				(justify left mirror)
			)
		)
		(property "Value" ""
			(at 0 0 0)
			(layer "B.Fab")
			(effects
				(font
					(size 1.27 1.27)
				)
				(justify mirror)
			)
		)
		(duplicate_pad_numbers_are_jumpers no)
		(fp_line
			(start -0.7874 -0.4064)
			(end -0.7874 0.4064)
			(stroke
				(width 0.1524)
				(type default)
			)
			(layer "B.SilkS")
		)
		(fp_line
			(start -0.7874 0.4064)
			(end 0.7874 0.4064)
			(stroke
				(width 0.1524)
				(type default)
			)
			(layer "B.SilkS")
		)
		(fp_line
			(start 0 0.381)
			(end 0 -0.381)
			(stroke
				(width 0.1524)
				(type default)
			)
			(layer "B.SilkS")
		)
		(fp_line
			(start 0.7874 -0.4064)
			(end -0.7874 -0.4064)
			(stroke
				(width 0.1524)
				(type default)
			)
			(layer "B.SilkS")
		)
		(fp_line
			(start 0.7874 0.4064)
			(end 0.7874 -0.4064)
			(stroke
				(width 0.1524)
				(type default)
			)
			(layer "B.SilkS")
		)
		(fp_poly
			(pts
				(xy 0.5334 0.254) (xy 0.635 0.254) (xy 0.635 0.2286) (xy 0.635 -0.254) (xy 0.5334 -0.254) (xy 0.5334 -0.2794)
				(xy -0.5334 -0.2794) (xy -0.5334 -0.254) (xy -0.635 -0.254) (xy -0.635 0.254) (xy -0.5334 0.254)
				(xy -0.5334 0.2794) (xy 0.508 0.2794) (xy 0.5334 0.2794)
			)
			(stroke
				(width 0)
				(type default)
			)
			(fill no)
			(layer "B.CrtYd")
		)
		(pad "1" smd rect
			(at -0.40005 0 180)
			(size 0.4572 0.508)
			(layers "B.Cu" "B.Mask" "B.Paste")
			(net "P1V9_LAN2")
		)
		(pad "2" smd rect
			(at 0.40005 0 180)
			(size 0.4572 0.508)
			(layers "B.Cu" "B.Mask" "B.Paste")
			(net "GND")
		)
	)
	(footprint ""
		(layer "B.Cu")
		(at 151.572214 -64.971422 -90)
		(property "Reference" "C346"
			(at 2.01422 -5.959602 270)
			(unlocked yes)
			(layer "B.SilkS")
			(effects
				(font
					(size 0.7874 0.5842)
					(thickness 0.1524)
				)
				(justify left mirror)
			)
		)
		(property "Value" ""
			(at 0 0 90)
			(layer "B.Fab")
			(effects
				(font
					(size 1.27 1.27)
				)
				(justify mirror)
			)
		)
		(duplicate_pad_numbers_are_jumpers no)
		(fp_line
			(start -0.7874 0.4064)
			(end 0.7874 0.4064)
			(stroke
				(width 0.1524)
				(type default)
			)
			(layer "B.SilkS")
		)
		(fp_line
			(start 0.7874 0.4064)
			(end 0.7874 -0.4064)
			(stroke
				(width 0.1524)
				(type default)
			)
			(layer "B.SilkS")
		)
		(fp_line
			(start 0 0.381)
			(end 0 -0.381)
			(stroke
				(width 0.1524)
				(type default)
			)
			(layer "B.SilkS")
		)
		(fp_line
			(start -0.7874 -0.4064)
			(end -0.7874 0.4064)
			(stroke
				(width 0.1524)
				(type default)
			)
			(layer "B.SilkS")
		)
		(fp_line
			(start 0.7874 -0.4064)
			(end -0.7874 -0.4064)
			(stroke
				(width 0.1524)
				(type default)
			)
			(layer "B.SilkS")
		)
		(fp_poly
			(pts
				(xy 0.5334 0.254) (xy 0.635 0.254) (xy 0.635 0.2286) (xy 0.635 -0.254) (xy 0.5334 -0.254) (xy 0.5334 -0.2794)
				(xy -0.5334 -0.2794) (xy -0.5334 -0.254) (xy -0.635 -0.254) (xy -0.635 0.254) (xy -0.5334 0.254)
				(xy -0.5334 0.2794) (xy 0.508 0.2794) (xy 0.5334 0.2794)
			)
			(stroke
				(width 0)
				(type default)
			)
			(fill no)
			(layer "B.CrtYd")
		)
		(pad "1" smd rect
			(at -0.40005 0 90)
			(size 0.4572 0.508)
			(layers "B.Cu" "B.Mask" "B.Paste")
			(net "P1V8_SATA_VAA2_0_NODE1")
		)
		(pad "2" smd rect
			(at 0.40005 0 90)
			(size 0.4572 0.508)
			(layers "B.Cu" "B.Mask" "B.Paste")
			(net "GND")
		)
	)
	(footprint ""
		(layer "B.Cu")
		(at 95.26524 -181.616604 180)
		(property "Reference" "R145"
			(at 0.29972 -1.595628 0)
			(unlocked yes)
			(layer "B.SilkS")
			(effects
				(font
					(size 0.7874 0.5842)
					(thickness 0.1524)
				)
				(justify left mirror)
			)
		)
		(property "Value" ""
			(at 0 0 0)
			(layer "B.Fab")
			(effects
				(font
					(size 1.27 1.27)
				)
				(justify mirror)
			)
		)
		(duplicate_pad_numbers_are_jumpers no)
		(fp_line
			(start 0.7874 0.4064)
			(end 0.7874 -0.4064)
			(stroke
				(width 0.1524)
				(type default)
			)
			(layer "B.SilkS")
		)
		(fp_line
			(start 0.7874 -0.4064)
			(end -0.7874 -0.4064)
			(stroke
				(width 0.1524)
				(type default)
			)
			(layer "B.SilkS")
		)
		(fp_line
			(start -0.7874 0.4064)
			(end 0.7874 0.4064)
			(stroke
				(width 0.1524)
				(type default)
			)
			(layer "B.SilkS")
		)
		(fp_line
			(start -0.7874 -0.4064)
			(end -0.7874 0.4064)
			(stroke
				(width 0.1524)
				(type default)
			)
			(layer "B.SilkS")
		)
		(fp_poly
			(pts
				(xy 0.508 0.2794) (xy 0.508 0.2286) (xy 0.635 0.2286) (xy 0.635 -0.254) (xy 0.5334 -0.254) (xy 0.5334 -0.2794)
				(xy -0.5334 -0.2794) (xy -0.5334 -0.254) (xy -0.635 -0.254) (xy -0.635 0.254) (xy -0.5334 0.254)
				(xy -0.5334 0.2794)
			)
			(stroke
				(width 0)
				(type default)
			)
			(fill no)
			(layer "B.CrtYd")
		)
		(pad "1" smd rect
			(at -0.40005 0)
			(size 0.4572 0.508)
			(layers "B.Cu" "B.Mask" "B.Paste")
			(net "CM_STATUS_LED_N")
		)
		(pad "2" smd rect
			(at 0.40005 0)
			(size 0.4572 0.508)
			(layers "B.Cu" "B.Mask" "B.Paste")
			(net "P3V3_NODE1")
		)
	)
	(footprint ""
		(layer "B.Cu")
		(at 111.99876 -185.205624 90)
		(property "Reference" "R964"
			(at 3.957828 0.479806 270)
			(unlocked yes)
			(layer "B.SilkS")
			(effects
				(font
					(size 0.7874 0.5842)
					(thickness 0.1524)
				)
				(justify left mirror)
			)
		)
		(property "Value" ""
			(at 0 0 90)
			(layer "B.Fab")
			(effects
				(font
					(size 1.27 1.27)
				)
				(justify mirror)
			)
		)
		(duplicate_pad_numbers_are_jumpers no)
		(fp_line
			(start 0.7874 -0.4064)
			(end -0.7874 -0.4064)
			(stroke
				(width 0.1524)
				(type default)
			)
			(layer "B.SilkS")
		)
		(fp_line
			(start -0.7874 -0.4064)
			(end -0.7874 0.4064)
			(stroke
				(width 0.1524)
				(type default)
			)
			(layer "B.SilkS")
		)
		(fp_line
			(start 0.7874 0.4064)
			(end 0.7874 -0.4064)
			(stroke
				(width 0.1524)
				(type default)
			)
			(layer "B.SilkS")
		)
		(fp_line
			(start -0.7874 0.4064)
			(end 0.7874 0.4064)
			(stroke
				(width 0.1524)
				(type default)
			)
			(layer "B.SilkS")
		)
		(fp_poly
			(pts
				(xy 0.508 0.2794) (xy 0.508 0.2286) (xy 0.635 0.2286) (xy 0.635 -0.254) (xy 0.5334 -0.254) (xy 0.5334 -0.2794)
				(xy -0.5334 -0.2794) (xy -0.5334 -0.254) (xy -0.635 -0.254) (xy -0.635 0.254) (xy -0.5334 0.254)
				(xy -0.5334 0.2794)
			)
			(stroke
				(width 0)
				(type default)
			)
			(fill no)
			(layer "B.CrtYd")
		)
		(pad "1" smd rect
			(at -0.40005 0 270)
			(size 0.4572 0.508)
			(layers "B.Cu" "B.Mask" "B.Paste")
			(net "UART_T7_NODE2_TXD")
		)
		(pad "2" smd rect
			(at 0.40005 0 270)
			(size 0.4572 0.508)
			(layers "B.Cu" "B.Mask" "B.Paste")
			(net "UART_T7_NODE2_TXD_R")
		)
	)
	(footprint ""
		(layer "B.Cu")
		(at 158.293308 -166.71798)
		(property "Reference" "U142"
			(at 0.123698 2.82702 0)
			(unlocked yes)
			(layer "B.SilkS")
			(effects
				(font
					(size 0.7874 0.5842)
					(thickness 0.1524)
				)
				(justify mirror)
			)
		)
		(property "Value" ""
			(at 0 0 0)
			(layer "B.Fab")
			(effects
				(font
					(size 1.27 1.27)
				)
				(justify mirror)
			)
		)
		(duplicate_pad_numbers_are_jumpers no)
		(fp_line
			(start -1.651 -1.905)
			(end -1.651 1.905)
			(stroke
				(width 0.1524)
				(type default)
			)
			(layer "B.SilkS")
		)
		(fp_line
			(start -1.651 1.905)
			(end 1.651 1.905)
			(stroke
				(width 0.1524)
				(type default)
			)
			(layer "B.SilkS")
		)
		(fp_line
			(start 1.651 -1.905)
			(end -1.651 -1.905)
			(stroke
				(width 0.1524)
				(type default)
			)
			(layer "B.SilkS")
		)
		(fp_line
			(start 1.651 1.905)
			(end 1.651 -1.905)
			(stroke
				(width 0.1524)
				(type default)
			)
			(layer "B.SilkS")
		)
		(fp_poly
			(pts
				(xy 1.524 0.7112) (xy 1.524 1.7526) (xy 0.508 1.7526) (xy 0.508 0.6985) (xy -0.508 0.6985) (xy -0.508 1.7526)
				(xy -1.524 1.7526) (xy -1.524 0.6985) (xy -1.524 -0.6985) (xy -0.508 -0.6985) (xy -0.508 -1.7526)
				(xy 0.508 -1.7526) (xy 0.508 -0.6985) (xy 1.524 -0.6985) (xy 1.524 0.6985)
			)
			(stroke
				(width 0)
				(type default)
			)
			(fill no)
			(layer "B.CrtYd")
		)
		(fp_text user "S"
			(at -2.135632 0.43942 90)
			(unlocked yes)
			(layer "B.SilkS")
			(effects
				(font
					(size 0.635 0.4064)
					(thickness 0.1524)
				)
				(justify mirror)
			)
		)
		(fp_text user "D"
			(at -0.96139 -2.471674 0)
			(unlocked yes)
			(layer "B.SilkS")
			(effects
				(font
					(size 0.635 0.4064)
					(thickness 0.1524)
				)
				(justify mirror)
			)
		)
		(fp_text user "G"
			(at 1.968246 1.998218 0)
			(unlocked yes)
			(layer "B.SilkS")
			(effects
				(font
					(size 0.635 0.4064)
					(thickness 0.1524)
				)
				(justify mirror)
			)
		)
		(pad "D" smd rect
			(at 0 -1.1176 180)
			(size 1.016 1.27)
			(layers "B.Cu" "B.Mask" "B.Paste")
			(net "CPLD_UART_RI_P4_N")
		)
		(pad "G" smd rect
			(at 1.016 1.1176 180)
			(size 1.016 1.27)
			(layers "B.Cu" "B.Mask" "B.Paste")
			(net "TACKOVER_EN")
		)
		(pad "S" smd rect
			(at -1.016 1.1176 180)
			(size 1.016 1.27)
			(layers "B.Cu" "B.Mask" "B.Paste")
			(net "CPLD_UART_RI_P4_LS_N")
		)
	)
	(footprint ""
		(layer "B.Cu")
		(at 121.72061 -37.430456 180)
		(property "Reference" "R1203"
			(at 3.310636 -0.941578 0)
			(unlocked yes)
			(layer "B.SilkS")
			(effects
				(font
					(size 0.7874 0.5842)
					(thickness 0.1524)
				)
				(justify left mirror)
			)
		)
		(property "Value" ""
			(at 0 0 0)
			(layer "B.Fab")
			(effects
				(font
					(size 1.27 1.27)
				)
				(justify mirror)
			)
		)
		(duplicate_pad_numbers_are_jumpers no)
		(fp_line
			(start 0.7874 0.4064)
			(end 0.7874 -0.4064)
			(stroke
				(width 0.1524)
				(type default)
			)
			(layer "B.SilkS")
		)
		(fp_line
			(start 0.7874 -0.4064)
			(end -0.7874 -0.4064)
			(stroke
				(width 0.1524)
				(type default)
			)
			(layer "B.SilkS")
		)
		(fp_line
			(start -0.7874 0.4064)
			(end 0.7874 0.4064)
			(stroke
				(width 0.1524)
				(type default)
			)
			(layer "B.SilkS")
		)
		(fp_line
			(start -0.7874 -0.4064)
			(end -0.7874 0.4064)
			(stroke
				(width 0.1524)
				(type default)
			)
			(layer "B.SilkS")
		)
		(fp_poly
			(pts
				(xy 0.508 0.2794) (xy 0.508 0.2286) (xy 0.635 0.2286) (xy 0.635 -0.254) (xy 0.5334 -0.254) (xy 0.5334 -0.2794)
				(xy -0.5334 -0.2794) (xy -0.5334 -0.254) (xy -0.635 -0.254) (xy -0.635 0.254) (xy -0.5334 0.254)
				(xy -0.5334 0.2794)
			)
			(stroke
				(width 0)
				(type default)
			)
			(fill no)
			(layer "B.CrtYd")
		)
		(pad "1" smd rect
			(at -0.40005 0)
			(size 0.4572 0.508)
			(layers "B.Cu" "B.Mask" "B.Paste")
			(net "SIO_JTAG_CPLD3_TDO")
		)
		(pad "2" smd rect
			(at 0.40005 0)
			(size 0.4572 0.508)
			(layers "B.Cu" "B.Mask" "B.Paste")
			(net "P3V3_NODE1")
		)
	)
	(footprint ""
		(layer "B.Cu")
		(at 88.77935 -74.701654)
		(property "Reference" "R162"
			(at -1.91516 9.822434 0)
			(unlocked yes)
			(layer "B.SilkS")
			(effects
				(font
					(size 0.7874 0.5842)
					(thickness 0.1524)
				)
				(justify left mirror)
			)
		)
		(property "Value" ""
			(at 0 0 0)
			(layer "B.Fab")
			(effects
				(font
					(size 1.27 1.27)
				)
				(justify mirror)
			)
		)
		(duplicate_pad_numbers_are_jumpers no)
		(fp_line
			(start -0.7874 -0.4064)
			(end -0.7874 0.4064)
			(stroke
				(width 0.1524)
				(type default)
			)
			(layer "B.SilkS")
		)
		(fp_line
			(start -0.7874 0.4064)
			(end 0.7874 0.4064)
			(stroke
				(width 0.1524)
				(type default)
			)
			(layer "B.SilkS")
		)
		(fp_line
			(start 0.7874 -0.4064)
			(end -0.7874 -0.4064)
			(stroke
				(width 0.1524)
				(type default)
			)
			(layer "B.SilkS")
		)
		(fp_line
			(start 0.7874 0.4064)
			(end 0.7874 -0.4064)
			(stroke
				(width 0.1524)
				(type default)
			)
			(layer "B.SilkS")
		)
		(fp_poly
			(pts
				(xy 0.508 0.2794) (xy 0.508 0.2286) (xy 0.635 0.2286) (xy 0.635 -0.254) (xy 0.5334 -0.254) (xy 0.5334 -0.2794)
				(xy -0.5334 -0.2794) (xy -0.5334 -0.254) (xy -0.635 -0.254) (xy -0.635 0.254) (xy -0.5334 0.254)
				(xy -0.5334 0.2794)
			)
			(stroke
				(width 0)
				(type default)
			)
			(fill no)
			(layer "B.CrtYd")
		)
		(pad "1" smd rect
			(at -0.40005 0 180)
			(size 0.4572 0.508)
			(layers "B.Cu" "B.Mask" "B.Paste")
			(net "GND")
		)
		(pad "2" smd rect
			(at 0.40005 0 180)
			(size 0.4572 0.508)
			(layers "B.Cu" "B.Mask" "B.Paste")
			(net "PD_CPU_NODE1_HVMGEAR_SEL")
		)
	)
	(footprint ""
		(layer "B.Cu")
		(at 78.83144 -170.473624 180)
		(property "Reference" "R689"
			(at -30.663388 -21.657818 0)
			(unlocked yes)
			(layer "B.SilkS")
			(effects
				(font
					(size 0.7874 0.5842)
					(thickness 0.1524)
				)
				(justify left mirror)
			)
		)
		(property "Value" ""
			(at 0 0 0)
			(layer "B.Fab")
			(effects
				(font
					(size 1.27 1.27)
				)
				(justify mirror)
			)
		)
		(duplicate_pad_numbers_are_jumpers no)
		(fp_line
			(start 0.7874 0.4064)
			(end 0.7874 -0.4064)
			(stroke
				(width 0.1524)
				(type default)
			)
			(layer "B.SilkS")
		)
		(fp_line
			(start 0.7874 -0.4064)
			(end -0.7874 -0.4064)
			(stroke
				(width 0.1524)
				(type default)
			)
			(layer "B.SilkS")
		)
		(fp_line
			(start -0.7874 0.4064)
			(end 0.7874 0.4064)
			(stroke
				(width 0.1524)
				(type default)
			)
			(layer "B.SilkS")
		)
		(fp_line
			(start -0.7874 -0.4064)
			(end -0.7874 0.4064)
			(stroke
				(width 0.1524)
				(type default)
			)
			(layer "B.SilkS")
		)
		(fp_poly
			(pts
				(xy 0.508 0.2794) (xy 0.508 0.2286) (xy 0.635 0.2286) (xy 0.635 -0.254) (xy 0.5334 -0.254) (xy 0.5334 -0.2794)
				(xy -0.5334 -0.2794) (xy -0.5334 -0.254) (xy -0.635 -0.254) (xy -0.635 0.254) (xy -0.5334 0.254)
				(xy -0.5334 0.2794)
			)
			(stroke
				(width 0)
				(type default)
			)
			(fill no)
			(layer "B.CrtYd")
		)
		(pad "1" smd rect
			(at -0.40005 0)
			(size 0.4572 0.508)
			(layers "B.Cu" "B.Mask" "B.Paste")
			(net "T1_NODE1_EN")
		)
		(pad "2" smd rect
			(at 0.40005 0)
			(size 0.4572 0.508)
			(layers "B.Cu" "B.Mask" "B.Paste")
			(net "P5V_NODE1")
		)
	)
	(footprint ""
		(layer "B.Cu")
		(at 75.239372 -80.514698 90)
		(property "Reference" "C86"
			(at -32.158686 -14.55039 270)
			(unlocked yes)
			(layer "B.SilkS")
			(effects
				(font
					(size 0.7874 0.5842)
					(thickness 0.1524)
				)
				(justify left mirror)
			)
		)
		(property "Value" ""
			(at 0 0 90)
			(layer "B.Fab")
			(effects
				(font
					(size 1.27 1.27)
				)
				(justify mirror)
			)
		)
		(duplicate_pad_numbers_are_jumpers no)
		(fp_line
			(start 0.7874 -0.4064)
			(end -0.7874 -0.4064)
			(stroke
				(width 0.1524)
				(type default)
			)
			(layer "B.SilkS")
		)
		(fp_line
			(start -0.7874 -0.4064)
			(end -0.7874 0.4064)
			(stroke
				(width 0.1524)
				(type default)
			)
			(layer "B.SilkS")
		)
		(fp_line
			(start 0 0.381)
			(end 0 -0.381)
			(stroke
				(width 0.1524)
				(type default)
			)
			(layer "B.SilkS")
		)
		(fp_line
			(start 0.7874 0.4064)
			(end 0.7874 -0.4064)
			(stroke
				(width 0.1524)
				(type default)
			)
			(layer "B.SilkS")
		)
		(fp_line
			(start -0.7874 0.4064)
			(end 0.7874 0.4064)
			(stroke
				(width 0.1524)
				(type default)
			)
			(layer "B.SilkS")
		)
		(fp_poly
			(pts
				(xy 0.5334 0.254) (xy 0.635 0.254) (xy 0.635 0.2286) (xy 0.635 -0.254) (xy 0.5334 -0.254) (xy 0.5334 -0.2794)
				(xy -0.5334 -0.2794) (xy -0.5334 -0.254) (xy -0.635 -0.254) (xy -0.635 0.254) (xy -0.5334 0.254)
				(xy -0.5334 0.2794) (xy 0.508 0.2794) (xy 0.5334 0.2794)
			)
			(stroke
				(width 0)
				(type default)
			)
			(fill no)
			(layer "B.CrtYd")
		)
		(pad "1" smd rect
			(at -0.40005 0 270)
			(size 0.4572 0.508)
			(layers "B.Cu" "B.Mask" "B.Paste")
			(net "PV_VCCP_NODE1")
		)
		(pad "2" smd rect
			(at 0.40005 0 270)
			(size 0.4572 0.508)
			(layers "B.Cu" "B.Mask" "B.Paste")
			(net "GND")
		)
	)
	(footprint ""
		(layer "B.Cu")
		(at 125.892052 -147.19935 180)
		(property "Reference" "C862"
			(at 3.002534 4.472432 0)
			(unlocked yes)
			(layer "B.SilkS")
			(effects
				(font
					(size 0.7874 0.5842)
					(thickness 0.1524)
				)
				(justify left mirror)
			)
		)
		(property "Value" ""
			(at 0 0 0)
			(layer "B.Fab")
			(effects
				(font
					(size 1.27 1.27)
				)
				(justify mirror)
			)
		)
		(duplicate_pad_numbers_are_jumpers no)
		(fp_line
			(start 0.7874 0.4064)
			(end 0.7874 -0.4064)
			(stroke
				(width 0.1524)
				(type default)
			)
			(layer "B.SilkS")
		)
		(fp_line
			(start 0.7874 -0.4064)
			(end -0.7874 -0.4064)
			(stroke
				(width 0.1524)
				(type default)
			)
			(layer "B.SilkS")
		)
		(fp_line
			(start 0 0.381)
			(end 0 -0.381)
			(stroke
				(width 0.1524)
				(type default)
			)
			(layer "B.SilkS")
		)
		(fp_line
			(start -0.7874 0.4064)
			(end 0.7874 0.4064)
			(stroke
				(width 0.1524)
				(type default)
			)
			(layer "B.SilkS")
		)
		(fp_line
			(start -0.7874 -0.4064)
			(end -0.7874 0.4064)
			(stroke
				(width 0.1524)
				(type default)
			)
			(layer "B.SilkS")
		)
		(fp_poly
			(pts
				(xy 0.5334 0.254) (xy 0.635 0.254) (xy 0.635 0.2286) (xy 0.635 -0.254) (xy 0.5334 -0.254) (xy 0.5334 -0.2794)
				(xy -0.5334 -0.2794) (xy -0.5334 -0.254) (xy -0.635 -0.254) (xy -0.635 0.254) (xy -0.5334 0.254)
				(xy -0.5334 0.2794) (xy 0.508 0.2794) (xy 0.5334 0.2794)
			)
			(stroke
				(width 0)
				(type default)
			)
			(fill no)
			(layer "B.CrtYd")
		)
		(pad "1" smd rect
			(at -0.40005 0)
			(size 0.4572 0.508)
			(layers "B.Cu" "B.Mask" "B.Paste")
			(net "P1V0_NODE1")
		)
		(pad "2" smd rect
			(at 0.40005 0)
			(size 0.4572 0.508)
			(layers "B.Cu" "B.Mask" "B.Paste")
			(net "GND")
		)
	)
	(footprint ""
		(layer "B.Cu")
		(at 141.005052 -143.00835 -90)
		(property "Reference" "C889"
			(at 0.15875 1.207516 0)
			(unlocked yes)
			(layer "B.SilkS")
			(effects
				(font
					(size 0.7874 0.5842)
					(thickness 0.1524)
				)
				(justify left mirror)
			)
		)
		(property "Value" ""
			(at 0 0 90)
			(layer "B.Fab")
			(effects
				(font
					(size 1.27 1.27)
				)
				(justify mirror)
			)
		)
		(duplicate_pad_numbers_are_jumpers no)
		(fp_line
			(start -0.7874 0.4064)
			(end 0.7874 0.4064)
			(stroke
				(width 0.1524)
				(type default)
			)
			(layer "B.SilkS")
		)
		(fp_line
			(start 0.7874 0.4064)
			(end 0.7874 -0.4064)
			(stroke
				(width 0.1524)
				(type default)
			)
			(layer "B.SilkS")
		)
		(fp_line
			(start 0 0.381)
			(end 0 -0.381)
			(stroke
				(width 0.1524)
				(type default)
			)
			(layer "B.SilkS")
		)
		(fp_line
			(start -0.7874 -0.4064)
			(end -0.7874 0.4064)
			(stroke
				(width 0.1524)
				(type default)
			)
			(layer "B.SilkS")
		)
		(fp_line
			(start 0.7874 -0.4064)
			(end -0.7874 -0.4064)
			(stroke
				(width 0.1524)
				(type default)
			)
			(layer "B.SilkS")
		)
		(fp_poly
			(pts
				(xy 0.5334 0.254) (xy 0.635 0.254) (xy 0.635 0.2286) (xy 0.635 -0.254) (xy 0.5334 -0.254) (xy 0.5334 -0.2794)
				(xy -0.5334 -0.2794) (xy -0.5334 -0.254) (xy -0.635 -0.254) (xy -0.635 0.254) (xy -0.5334 0.254)
				(xy -0.5334 0.2794) (xy 0.508 0.2794) (xy 0.5334 0.2794)
			)
			(stroke
				(width 0)
				(type default)
			)
			(fill no)
			(layer "B.CrtYd")
		)
		(pad "1" smd rect
			(at -0.40005 0 90)
			(size 0.4572 0.508)
			(layers "B.Cu" "B.Mask" "B.Paste")
			(net "P1V0_NODE1")
		)
		(pad "2" smd rect
			(at 0.40005 0 90)
			(size 0.4572 0.508)
			(layers "B.Cu" "B.Mask" "B.Paste")
			(net "GND")
		)
	)
	(footprint ""
		(layer "B.Cu")
		(at 56.202326 -144.809464 180)
		(property "Reference" "R670"
			(at 0.974852 -2.773934 0)
			(unlocked yes)
			(layer "B.SilkS")
			(effects
				(font
					(size 0.7874 0.5842)
					(thickness 0.1524)
				)
				(justify left mirror)
			)
		)
		(property "Value" ""
			(at 0 0 0)
			(layer "B.Fab")
			(effects
				(font
					(size 1.27 1.27)
				)
				(justify mirror)
			)
		)
		(duplicate_pad_numbers_are_jumpers no)
		(fp_line
			(start 0.7874 0.4064)
			(end 0.7874 -0.4064)
			(stroke
				(width 0.1524)
				(type default)
			)
			(layer "B.SilkS")
		)
		(fp_line
			(start 0.7874 -0.4064)
			(end -0.7874 -0.4064)
			(stroke
				(width 0.1524)
				(type default)
			)
			(layer "B.SilkS")
		)
		(fp_line
			(start -0.7874 0.4064)
			(end 0.7874 0.4064)
			(stroke
				(width 0.1524)
				(type default)
			)
			(layer "B.SilkS")
		)
		(fp_line
			(start -0.7874 -0.4064)
			(end -0.7874 0.4064)
			(stroke
				(width 0.1524)
				(type default)
			)
			(layer "B.SilkS")
		)
		(fp_poly
			(pts
				(xy 0.508 0.2794) (xy 0.508 0.2286) (xy 0.635 0.2286) (xy 0.635 -0.254) (xy 0.5334 -0.254) (xy 0.5334 -0.2794)
				(xy -0.5334 -0.2794) (xy -0.5334 -0.254) (xy -0.635 -0.254) (xy -0.635 0.254) (xy -0.5334 0.254)
				(xy -0.5334 0.2794)
			)
			(stroke
				(width 0)
				(type default)
			)
			(fill no)
			(layer "B.CrtYd")
		)
		(pad "1" smd rect
			(at -0.40005 0)
			(size 0.4572 0.508)
			(layers "B.Cu" "B.Mask" "B.Paste")
			(net "BMC_NODE1_GFX_HSYNC_R")
		)
		(pad "2" smd rect
			(at 0.40005 0)
			(size 0.4572 0.508)
			(layers "B.Cu" "B.Mask" "B.Paste")
			(net "BMC_NODE1_GFX_HSYNC")
		)
	)
	(footprint ""
		(layer "B.Cu")
		(at 54.101492 -132.452618 180)
		(property "Reference" "C204"
			(at -0.447548 0.951992 0)
			(unlocked yes)
			(layer "B.SilkS")
			(effects
				(font
					(size 0.7874 0.5842)
					(thickness 0.1524)
				)
				(justify left mirror)
			)
		)
		(property "Value" ""
			(at 0 0 0)
			(layer "B.Fab")
			(effects
				(font
					(size 1.27 1.27)
				)
				(justify mirror)
			)
		)
		(duplicate_pad_numbers_are_jumpers no)
		(fp_line
			(start 0.7874 0.4064)
			(end 0.7874 -0.4064)
			(stroke
				(width 0.1524)
				(type default)
			)
			(layer "B.SilkS")
		)
		(fp_line
			(start 0.7874 -0.4064)
			(end -0.7874 -0.4064)
			(stroke
				(width 0.1524)
				(type default)
			)
			(layer "B.SilkS")
		)
		(fp_line
			(start 0 0.381)
			(end 0 -0.381)
			(stroke
				(width 0.1524)
				(type default)
			)
			(layer "B.SilkS")
		)
		(fp_line
			(start -0.7874 0.4064)
			(end 0.7874 0.4064)
			(stroke
				(width 0.1524)
				(type default)
			)
			(layer "B.SilkS")
		)
		(fp_line
			(start -0.7874 -0.4064)
			(end -0.7874 0.4064)
			(stroke
				(width 0.1524)
				(type default)
			)
			(layer "B.SilkS")
		)
		(fp_poly
			(pts
				(xy 0.5334 0.254) (xy 0.635 0.254) (xy 0.635 0.2286) (xy 0.635 -0.254) (xy 0.5334 -0.254) (xy 0.5334 -0.2794)
				(xy -0.5334 -0.2794) (xy -0.5334 -0.254) (xy -0.635 -0.254) (xy -0.635 0.254) (xy -0.5334 0.254)
				(xy -0.5334 0.2794) (xy 0.508 0.2794) (xy 0.5334 0.2794)
			)
			(stroke
				(width 0)
				(type default)
			)
			(fill no)
			(layer "B.CrtYd")
		)
		(pad "1" smd rect
			(at -0.40005 0)
			(size 0.4572 0.508)
			(layers "B.Cu" "B.Mask" "B.Paste")
			(net "P0V75_BMC_VTTREF_NODE1")
		)
		(pad "2" smd rect
			(at 0.40005 0)
			(size 0.4572 0.508)
			(layers "B.Cu" "B.Mask" "B.Paste")
			(net "GND")
		)
	)
	(footprint ""
		(layer "B.Cu")
		(at 131.311904 -39.064438 180)
		(property "Reference" "R1081"
			(at -0.412496 2.463292 0)
			(unlocked yes)
			(layer "B.SilkS")
			(effects
				(font
					(size 0.7874 0.5842)
					(thickness 0.1524)
				)
				(justify left mirror)
			)
		)
		(property "Value" ""
			(at 0 0 0)
			(layer "B.Fab")
			(effects
				(font
					(size 1.27 1.27)
				)
				(justify mirror)
			)
		)
		(duplicate_pad_numbers_are_jumpers no)
		(fp_line
			(start 0.7874 0.4064)
			(end 0.7874 -0.4064)
			(stroke
				(width 0.1524)
				(type default)
			)
			(layer "B.SilkS")
		)
		(fp_line
			(start 0.7874 -0.4064)
			(end -0.7874 -0.4064)
			(stroke
				(width 0.1524)
				(type default)
			)
			(layer "B.SilkS")
		)
		(fp_line
			(start -0.7874 0.4064)
			(end 0.7874 0.4064)
			(stroke
				(width 0.1524)
				(type default)
			)
			(layer "B.SilkS")
		)
		(fp_line
			(start -0.7874 -0.4064)
			(end -0.7874 0.4064)
			(stroke
				(width 0.1524)
				(type default)
			)
			(layer "B.SilkS")
		)
		(fp_poly
			(pts
				(xy 0.508 0.2794) (xy 0.508 0.2286) (xy 0.635 0.2286) (xy 0.635 -0.254) (xy 0.5334 -0.254) (xy 0.5334 -0.2794)
				(xy -0.5334 -0.2794) (xy -0.5334 -0.254) (xy -0.635 -0.254) (xy -0.635 0.254) (xy -0.5334 0.254)
				(xy -0.5334 0.2794)
			)
			(stroke
				(width 0)
				(type default)
			)
			(fill no)
			(layer "B.CrtYd")
		)
		(pad "1" smd rect
			(at -0.40005 0)
			(size 0.4572 0.508)
			(layers "B.Cu" "B.Mask" "B.Paste")
			(net "SIO_JTAG_CPLD2_TDI")
		)
		(pad "2" smd rect
			(at 0.40005 0)
			(size 0.4572 0.508)
			(layers "B.Cu" "B.Mask" "B.Paste")
			(net "JTAG_CPLD2_TDI")
		)
	)
	(footprint ""
		(layer "B.Cu")
		(at 65.38976 -185.205624 90)
		(property "Reference" "R862"
			(at 4.15163 0.217678 270)
			(unlocked yes)
			(layer "B.SilkS")
			(effects
				(font
					(size 0.7874 0.5842)
					(thickness 0.1524)
				)
				(justify left mirror)
			)
		)
		(property "Value" ""
			(at 0 0 90)
			(layer "B.Fab")
			(effects
				(font
					(size 1.27 1.27)
				)
				(justify mirror)
			)
		)
		(duplicate_pad_numbers_are_jumpers no)
		(fp_line
			(start 0.7874 -0.406146)
			(end -0.7874 -0.406146)
			(stroke
				(width 0.1524)
				(type default)
			)
			(layer "B.SilkS")
		)
		(fp_line
			(start -0.7874 -0.406146)
			(end -0.7874 0.406146)
			(stroke
				(width 0.1524)
				(type default)
			)
			(layer "B.SilkS")
		)
		(fp_line
			(start 0.7874 0.406146)
			(end 0.7874 -0.406146)
			(stroke
				(width 0.1524)
				(type default)
			)
			(layer "B.SilkS")
		)
		(fp_line
			(start -0.7874 0.406146)
			(end 0.7874 0.406146)
			(stroke
				(width 0.1524)
				(type default)
			)
			(layer "B.SilkS")
		)
		(fp_poly
			(pts
				(xy 0.508 0.2794) (xy 0.508 0.2286) (xy 0.635 0.2286) (xy 0.635 -0.254) (xy 0.5334 -0.254) (xy 0.5334 -0.2794)
				(xy -0.5334 -0.2794) (xy -0.5334 -0.254) (xy -0.635 -0.254) (xy -0.635 0.254) (xy -0.5334 0.254)
				(xy -0.5334 0.2794)
			)
			(stroke
				(width 0)
				(type default)
			)
			(fill no)
			(layer "B.CrtYd")
		)
		(pad "1" smd rect
			(at -0.40005 0 270)
			(size 0.4572 0.508)
			(layers "B.Cu" "B.Mask" "B.Paste")
			(net "T1_NODE2_EN")
		)
		(pad "2" smd rect
			(at 0.40005 0 270)
			(size 0.4572 0.508)
			(layers "B.Cu" "B.Mask" "B.Paste")
			(net "T1_NODE2_EN_R")
		)
	)
	(footprint ""
		(layer "B.Cu")
		(at 104.408224 -64.132206 180)
		(property "Reference" "R222"
			(at 4.652518 -0.896874 0)
			(unlocked yes)
			(layer "B.SilkS")
			(effects
				(font
					(size 0.7874 0.5842)
					(thickness 0.1524)
				)
				(justify left mirror)
			)
		)
		(property "Value" ""
			(at 0 0 0)
			(layer "B.Fab")
			(effects
				(font
					(size 1.27 1.27)
				)
				(justify mirror)
			)
		)
		(duplicate_pad_numbers_are_jumpers no)
		(fp_line
			(start 0.7874 0.4064)
			(end 0.7874 -0.4064)
			(stroke
				(width 0.1524)
				(type default)
			)
			(layer "B.SilkS")
		)
		(fp_line
			(start 0.7874 -0.4064)
			(end -0.7874 -0.4064)
			(stroke
				(width 0.1524)
				(type default)
			)
			(layer "B.SilkS")
		)
		(fp_line
			(start -0.7874 0.4064)
			(end 0.7874 0.4064)
			(stroke
				(width 0.1524)
				(type default)
			)
			(layer "B.SilkS")
		)
		(fp_line
			(start -0.7874 -0.4064)
			(end -0.7874 0.4064)
			(stroke
				(width 0.1524)
				(type default)
			)
			(layer "B.SilkS")
		)
		(fp_poly
			(pts
				(xy 0.508 0.2794) (xy 0.508 0.2286) (xy 0.635 0.2286) (xy 0.635 -0.254) (xy 0.5334 -0.254) (xy 0.5334 -0.2794)
				(xy -0.5334 -0.2794) (xy -0.5334 -0.254) (xy -0.635 -0.254) (xy -0.635 0.254) (xy -0.5334 0.254)
				(xy -0.5334 0.2794)
			)
			(stroke
				(width 0)
				(type default)
			)
			(fill no)
			(layer "B.CrtYd")
		)
		(pad "1" smd rect
			(at -0.40005 0)
			(size 0.4572 0.508)
			(layers "B.Cu" "B.Mask" "B.Paste")
			(net "XDP_CPU_NODE1_PG_RST_R")
		)
		(pad "2" smd rect
			(at 0.40005 0)
			(size 0.4572 0.508)
			(layers "B.Cu" "B.Mask" "B.Paste")
			(net "FM_CPU_NODE1_XDP_PG_RST")
		)
	)
	(footprint ""
		(layer "B.Cu")
		(at 128.889252 -141.45895)
		(property "Reference" "C199"
			(at 3.37566 -0.494538 0)
			(unlocked yes)
			(layer "B.SilkS")
			(effects
				(font
					(size 0.7874 0.5842)
					(thickness 0.1524)
				)
				(justify mirror)
			)
		)
		(property "Value" ""
			(at 0 0 0)
			(layer "B.Fab")
			(effects
				(font
					(size 1.27 1.27)
				)
				(justify mirror)
			)
		)
		(duplicate_pad_numbers_are_jumpers no)
		(fp_line
			(start -1.2954 -0.5842)
			(end -1.2954 0.5842)
			(stroke
				(width 0.1524)
				(type default)
			)
			(layer "B.SilkS")
		)
		(fp_line
			(start -1.2954 0.5842)
			(end 1.2954 0.5842)
			(stroke
				(width 0.1524)
				(type default)
			)
			(layer "B.SilkS")
		)
		(fp_line
			(start 0 -0.5842)
			(end 0 0.5842)
			(stroke
				(width 0.1524)
				(type default)
			)
			(layer "B.SilkS")
		)
		(fp_line
			(start 1.2954 -0.5842)
			(end -1.2954 -0.5842)
			(stroke
				(width 0.1524)
				(type default)
			)
			(layer "B.SilkS")
		)
		(fp_line
			(start 1.2954 0.5842)
			(end 1.2954 -0.5842)
			(stroke
				(width 0.1524)
				(type default)
			)
			(layer "B.SilkS")
		)
		(fp_poly
			(pts
				(xy -0.8636 -0.4572) (xy -0.8636 -0.3556) (xy -1.143 -0.3556) (xy -1.143 0.3556) (xy -0.8636 0.3556)
				(xy -0.8636 0.4572) (xy 0.8636 0.4572) (xy 0.8636 0.3556) (xy 1.143 0.3556) (xy 1.143 -0.3556) (xy 0.8636 -0.3556)
				(xy 0.8636 -0.4572)
			)
			(stroke
				(width 0)
				(type default)
			)
			(fill no)
			(layer "B.CrtYd")
		)
		(fp_line
			(start -0.884936 -0.504952)
			(end -0.884936 0.504952)
			(stroke
				(width 0.1)
				(type default)
			)
			(layer "B.Fab")
		)
		(fp_line
			(start -0.884936 0.504952)
			(end 0.884936 0.504952)
			(stroke
				(width 0.1)
				(type default)
			)
			(layer "B.Fab")
		)
		(fp_line
			(start 0.884936 -0.504952)
			(end -0.884936 -0.504952)
			(stroke
				(width 0.1)
				(type default)
			)
			(layer "B.Fab")
		)
		(fp_line
			(start 0.884936 0.504952)
			(end 0.884936 -0.504952)
			(stroke
				(width 0.1)
				(type default)
			)
			(layer "B.Fab")
		)
		(pad "1" smd rect
			(at -0.7366 0 90)
			(size 0.7112 0.8128)
			(layers "B.Cu" "B.Mask" "B.Paste")
			(net "P1V0_NODE1")
		)
		(pad "2" smd rect
			(at 0.7366 0 90)
			(size 0.7112 0.8128)
			(layers "B.Cu" "B.Mask" "B.Paste")
			(net "GND")
		)
	)
	(footprint ""
		(layer "B.Cu")
		(at 49.38776 -181.984142 -90)
		(property "Reference" "C609"
			(at 3.610356 10.422128 270)
			(unlocked yes)
			(layer "B.SilkS")
			(effects
				(font
					(size 0.7874 0.5842)
					(thickness 0.1524)
				)
				(justify left mirror)
			)
		)
		(property "Value" ""
			(at 0 0 90)
			(layer "B.Fab")
			(effects
				(font
					(size 1.27 1.27)
				)
				(justify mirror)
			)
		)
		(duplicate_pad_numbers_are_jumpers no)
		(fp_line
			(start -0.7874 0.4064)
			(end 0.7874 0.4064)
			(stroke
				(width 0.1524)
				(type default)
			)
			(layer "B.SilkS")
		)
		(fp_line
			(start 0.7874 0.4064)
			(end 0.7874 -0.4064)
			(stroke
				(width 0.1524)
				(type default)
			)
			(layer "B.SilkS")
		)
		(fp_line
			(start 0 0.381)
			(end 0 -0.381)
			(stroke
				(width 0.1524)
				(type default)
			)
			(layer "B.SilkS")
		)
		(fp_line
			(start -0.7874 -0.4064)
			(end -0.7874 0.4064)
			(stroke
				(width 0.1524)
				(type default)
			)
			(layer "B.SilkS")
		)
		(fp_line
			(start 0.7874 -0.4064)
			(end -0.7874 -0.4064)
			(stroke
				(width 0.1524)
				(type default)
			)
			(layer "B.SilkS")
		)
		(fp_poly
			(pts
				(xy 0.5334 0.254) (xy 0.635 0.254) (xy 0.635 0.2286) (xy 0.635 -0.254) (xy 0.5334 -0.254) (xy 0.5334 -0.2794)
				(xy -0.5334 -0.2794) (xy -0.5334 -0.254) (xy -0.635 -0.254) (xy -0.635 0.254) (xy -0.5334 0.254)
				(xy -0.5334 0.2794) (xy 0.508 0.2794) (xy 0.5334 0.2794)
			)
			(stroke
				(width 0)
				(type default)
			)
			(fill no)
			(layer "B.CrtYd")
		)
		(pad "1" smd rect
			(at -0.40005 0 90)
			(size 0.4572 0.508)
			(layers "B.Cu" "B.Mask" "B.Paste")
			(net "PSU4_DC_OK_R_BUF")
		)
		(pad "2" smd rect
			(at 0.40005 0 90)
			(size 0.4572 0.508)
			(layers "B.Cu" "B.Mask" "B.Paste")
			(net "GND")
		)
	)
	(footprint ""
		(layer "B.Cu")
		(at 69.268086 -132.677662 180)
		(property "Reference" "C290"
			(at 36.554664 -53.682646 0)
			(unlocked yes)
			(layer "B.SilkS")
			(effects
				(font
					(size 0.7874 0.5842)
					(thickness 0.1524)
				)
				(justify left mirror)
			)
		)
		(property "Value" ""
			(at 0 0 0)
			(layer "B.Fab")
			(effects
				(font
					(size 1.27 1.27)
				)
				(justify mirror)
			)
		)
		(duplicate_pad_numbers_are_jumpers no)
		(fp_line
			(start 0.7874 0.4064)
			(end 0.7874 -0.4064)
			(stroke
				(width 0.1524)
				(type default)
			)
			(layer "B.SilkS")
		)
		(fp_line
			(start 0.7874 -0.4064)
			(end -0.7874 -0.4064)
			(stroke
				(width 0.1524)
				(type default)
			)
			(layer "B.SilkS")
		)
		(fp_line
			(start 0 0.381)
			(end 0 -0.381)
			(stroke
				(width 0.1524)
				(type default)
			)
			(layer "B.SilkS")
		)
		(fp_line
			(start -0.7874 0.4064)
			(end 0.7874 0.4064)
			(stroke
				(width 0.1524)
				(type default)
			)
			(layer "B.SilkS")
		)
		(fp_line
			(start -0.7874 -0.4064)
			(end -0.7874 0.4064)
			(stroke
				(width 0.1524)
				(type default)
			)
			(layer "B.SilkS")
		)
		(fp_poly
			(pts
				(xy 0.5334 0.254) (xy 0.635 0.254) (xy 0.635 0.2286) (xy 0.635 -0.254) (xy 0.5334 -0.254) (xy 0.5334 -0.2794)
				(xy -0.5334 -0.2794) (xy -0.5334 -0.254) (xy -0.635 -0.254) (xy -0.635 0.254) (xy -0.5334 0.254)
				(xy -0.5334 0.2794) (xy 0.508 0.2794) (xy 0.5334 0.2794)
			)
			(stroke
				(width 0)
				(type default)
			)
			(fill no)
			(layer "B.CrtYd")
		)
		(pad "1" smd rect
			(at -0.40005 0)
			(size 0.4572 0.508)
			(layers "B.Cu" "B.Mask" "B.Paste")
			(net "P1V26_BMC_NODE1")
		)
		(pad "2" smd rect
			(at 0.40005 0)
			(size 0.4572 0.508)
			(layers "B.Cu" "B.Mask" "B.Paste")
			(net "GND")
		)
	)
	(footprint ""
		(layer "B.Cu")
		(at 57.838848 -76.50353 90)
		(property "Reference" "C45"
			(at -31.836106 -14.474698 270)
			(unlocked yes)
			(layer "B.SilkS")
			(effects
				(font
					(size 0.7874 0.5842)
					(thickness 0.1524)
				)
				(justify left mirror)
			)
		)
		(property "Value" ""
			(at 0 0 90)
			(layer "B.Fab")
			(effects
				(font
					(size 1.27 1.27)
				)
				(justify mirror)
			)
		)
		(duplicate_pad_numbers_are_jumpers no)
		(fp_line
			(start 0.7874 -0.4064)
			(end -0.7874 -0.4064)
			(stroke
				(width 0.1524)
				(type default)
			)
			(layer "B.SilkS")
		)
		(fp_line
			(start -0.7874 -0.4064)
			(end -0.7874 0.4064)
			(stroke
				(width 0.1524)
				(type default)
			)
			(layer "B.SilkS")
		)
		(fp_line
			(start 0 0.381)
			(end 0 -0.381)
			(stroke
				(width 0.1524)
				(type default)
			)
			(layer "B.SilkS")
		)
		(fp_line
			(start 0.7874 0.4064)
			(end 0.7874 -0.4064)
			(stroke
				(width 0.1524)
				(type default)
			)
			(layer "B.SilkS")
		)
		(fp_line
			(start -0.7874 0.4064)
			(end 0.7874 0.4064)
			(stroke
				(width 0.1524)
				(type default)
			)
			(layer "B.SilkS")
		)
		(fp_poly
			(pts
				(xy 0.5334 0.254) (xy 0.635 0.254) (xy 0.635 0.2286) (xy 0.635 -0.254) (xy 0.5334 -0.254) (xy 0.5334 -0.2794)
				(xy -0.5334 -0.2794) (xy -0.5334 -0.254) (xy -0.635 -0.254) (xy -0.635 0.254) (xy -0.5334 0.254)
				(xy -0.5334 0.2794) (xy 0.508 0.2794) (xy 0.5334 0.2794)
			)
			(stroke
				(width 0)
				(type default)
			)
			(fill no)
			(layer "B.CrtYd")
		)
		(pad "1" smd rect
			(at -0.40005 0 270)
			(size 0.4572 0.508)
			(layers "B.Cu" "B.Mask" "B.Paste")
			(net "P1V05_NODE1")
		)
		(pad "2" smd rect
			(at 0.40005 0 270)
			(size 0.4572 0.508)
			(layers "B.Cu" "B.Mask" "B.Paste")
			(net "GND")
		)
	)
	(footprint ""
		(layer "B.Cu")
		(at 165.011608 -184.067196 180)
		(property "Reference" "R1307"
			(at -7.505192 9.987534 0)
			(unlocked yes)
			(layer "B.SilkS")
			(effects
				(font
					(size 0.7874 0.5842)
					(thickness 0.1524)
				)
				(justify left mirror)
			)
		)
		(property "Value" ""
			(at 0 0 0)
			(layer "B.Fab")
			(effects
				(font
					(size 1.27 1.27)
				)
				(justify mirror)
			)
		)
		(duplicate_pad_numbers_are_jumpers no)
		(fp_line
			(start 0.7874 0.4064)
			(end 0.7874 -0.4064)
			(stroke
				(width 0.1524)
				(type default)
			)
			(layer "B.SilkS")
		)
		(fp_line
			(start 0.7874 -0.4064)
			(end -0.7874 -0.4064)
			(stroke
				(width 0.1524)
				(type default)
			)
			(layer "B.SilkS")
		)
		(fp_line
			(start -0.7874 0.4064)
			(end 0.7874 0.4064)
			(stroke
				(width 0.1524)
				(type default)
			)
			(layer "B.SilkS")
		)
		(fp_line
			(start -0.7874 -0.4064)
			(end -0.7874 0.4064)
			(stroke
				(width 0.1524)
				(type default)
			)
			(layer "B.SilkS")
		)
		(fp_poly
			(pts
				(xy 0.508 0.2794) (xy 0.508 0.2286) (xy 0.635 0.2286) (xy 0.635 -0.254) (xy 0.5334 -0.254) (xy 0.5334 -0.2794)
				(xy -0.5334 -0.2794) (xy -0.5334 -0.254) (xy -0.635 -0.254) (xy -0.635 0.254) (xy -0.5334 0.254)
				(xy -0.5334 0.2794)
			)
			(stroke
				(width 0)
				(type default)
			)
			(fill no)
			(layer "B.CrtYd")
		)
		(pad "1" smd rect
			(at -0.40005 0)
			(size 0.4572 0.508)
			(layers "B.Cu" "B.Mask" "B.Paste")
			(net "P3V3_NODE1")
		)
		(pad "2" smd rect
			(at 0.40005 0)
			(size 0.4572 0.508)
			(layers "B.Cu" "B.Mask" "B.Paste")
			(net "N54365776")
		)
	)
	(footprint ""
		(layer "B.Cu")
		(at 125.892052 -146.20875 180)
		(property "Reference" "C882"
			(at 3.260598 3.330194 0)
			(unlocked yes)
			(layer "B.SilkS")
			(effects
				(font
					(size 0.7874 0.5842)
					(thickness 0.1524)
				)
				(justify left mirror)
			)
		)
		(property "Value" ""
			(at 0 0 0)
			(layer "B.Fab")
			(effects
				(font
					(size 1.27 1.27)
				)
				(justify mirror)
			)
		)
		(duplicate_pad_numbers_are_jumpers no)
		(fp_line
			(start 0.7874 0.4064)
			(end 0.7874 -0.4064)
			(stroke
				(width 0.1524)
				(type default)
			)
			(layer "B.SilkS")
		)
		(fp_line
			(start 0.7874 -0.4064)
			(end -0.7874 -0.4064)
			(stroke
				(width 0.1524)
				(type default)
			)
			(layer "B.SilkS")
		)
		(fp_line
			(start 0 0.381)
			(end 0 -0.381)
			(stroke
				(width 0.1524)
				(type default)
			)
			(layer "B.SilkS")
		)
		(fp_line
			(start -0.7874 0.4064)
			(end 0.7874 0.4064)
			(stroke
				(width 0.1524)
				(type default)
			)
			(layer "B.SilkS")
		)
		(fp_line
			(start -0.7874 -0.4064)
			(end -0.7874 0.4064)
			(stroke
				(width 0.1524)
				(type default)
			)
			(layer "B.SilkS")
		)
		(fp_poly
			(pts
				(xy 0.5334 0.254) (xy 0.635 0.254) (xy 0.635 0.2286) (xy 0.635 -0.254) (xy 0.5334 -0.254) (xy 0.5334 -0.2794)
				(xy -0.5334 -0.2794) (xy -0.5334 -0.254) (xy -0.635 -0.254) (xy -0.635 0.254) (xy -0.5334 0.254)
				(xy -0.5334 0.2794) (xy 0.508 0.2794) (xy 0.5334 0.2794)
			)
			(stroke
				(width 0)
				(type default)
			)
			(fill no)
			(layer "B.CrtYd")
		)
		(pad "1" smd rect
			(at -0.40005 0)
			(size 0.4572 0.508)
			(layers "B.Cu" "B.Mask" "B.Paste")
			(net "P1V538_BMC_NODE1")
		)
		(pad "2" smd rect
			(at 0.40005 0)
			(size 0.4572 0.508)
			(layers "B.Cu" "B.Mask" "B.Paste")
			(net "GND")
		)
	)
	(footprint ""
		(layer "B.Cu")
		(at 65.079372 -80.514698 90)
		(property "Reference" "C66"
			(at -32.158686 -14.55039 270)
			(unlocked yes)
			(layer "B.SilkS")
			(effects
				(font
					(size 0.7874 0.5842)
					(thickness 0.1524)
				)
				(justify left mirror)
			)
		)
		(property "Value" ""
			(at 0 0 90)
			(layer "B.Fab")
			(effects
				(font
					(size 1.27 1.27)
				)
				(justify mirror)
			)
		)
		(duplicate_pad_numbers_are_jumpers no)
		(fp_line
			(start 0.7874 -0.4064)
			(end -0.7874 -0.4064)
			(stroke
				(width 0.1524)
				(type default)
			)
			(layer "B.SilkS")
		)
		(fp_line
			(start -0.7874 -0.4064)
			(end -0.7874 0.4064)
			(stroke
				(width 0.1524)
				(type default)
			)
			(layer "B.SilkS")
		)
		(fp_line
			(start 0 0.381)
			(end 0 -0.381)
			(stroke
				(width 0.1524)
				(type default)
			)
			(layer "B.SilkS")
		)
		(fp_line
			(start 0.7874 0.4064)
			(end 0.7874 -0.4064)
			(stroke
				(width 0.1524)
				(type default)
			)
			(layer "B.SilkS")
		)
		(fp_line
			(start -0.7874 0.4064)
			(end 0.7874 0.4064)
			(stroke
				(width 0.1524)
				(type default)
			)
			(layer "B.SilkS")
		)
		(fp_poly
			(pts
				(xy 0.5334 0.254) (xy 0.635 0.254) (xy 0.635 0.2286) (xy 0.635 -0.254) (xy 0.5334 -0.254) (xy 0.5334 -0.2794)
				(xy -0.5334 -0.2794) (xy -0.5334 -0.254) (xy -0.635 -0.254) (xy -0.635 0.254) (xy -0.5334 0.254)
				(xy -0.5334 0.2794) (xy 0.508 0.2794) (xy 0.5334 0.2794)
			)
			(stroke
				(width 0)
				(type default)
			)
			(fill no)
			(layer "B.CrtYd")
		)
		(pad "1" smd rect
			(at -0.40005 0 270)
			(size 0.4572 0.508)
			(layers "B.Cu" "B.Mask" "B.Paste")
			(net "PV_VCCP_NODE1")
		)
		(pad "2" smd rect
			(at 0.40005 0 270)
			(size 0.4572 0.508)
			(layers "B.Cu" "B.Mask" "B.Paste")
			(net "GND")
		)
	)
	(footprint ""
		(layer "B.Cu")
		(at 114.701574 -109.930692 180)
		(property "Reference" "PC121"
			(at -5.729732 -0.120904 0)
			(unlocked yes)
			(layer "B.SilkS")
			(effects
				(font
					(size 0.7874 0.5842)
					(thickness 0.1524)
				)
				(justify left mirror)
			)
		)
		(property "Value" ""
			(at 0 0 0)
			(layer "B.Fab")
			(effects
				(font
					(size 1.27 1.27)
				)
				(justify mirror)
			)
		)
		(duplicate_pad_numbers_are_jumpers no)
		(fp_line
			(start 1.905 0.8636)
			(end 1.905 -0.8636)
			(stroke
				(width 0.1524)
				(type default)
			)
			(layer "B.SilkS")
		)
		(fp_line
			(start 1.905 -0.8636)
			(end -1.905 -0.8636)
			(stroke
				(width 0.1524)
				(type default)
			)
			(layer "B.SilkS")
		)
		(fp_line
			(start 0 0.8382)
			(end 0 -0.8382)
			(stroke
				(width 0.1524)
				(type default)
			)
			(layer "B.SilkS")
		)
		(fp_line
			(start -1.905 0.8636)
			(end 1.905 0.8636)
			(stroke
				(width 0.1524)
				(type default)
			)
			(layer "B.SilkS")
		)
		(fp_line
			(start -1.905 -0.8636)
			(end -1.905 0.8636)
			(stroke
				(width 0.1524)
				(type default)
			)
			(layer "B.SilkS")
		)
		(fp_rect
			(start 1.524 0.7366)
			(end -1.524 -0.7366)
			(stroke
				(width 0)
				(type default)
			)
			(fill no)
			(layer "B.CrtYd")
		)
		(pad "1" smd rect
			(at -0.94996 0)
			(size 1.1176 1.3716)
			(layers "B.Cu" "B.Mask" "B.Paste")
			(net "GND")
		)
		(pad "2" smd rect
			(at 0.94996 0)
			(size 1.1176 1.3716)
			(layers "B.Cu" "B.Mask" "B.Paste")
			(net "PV_VCCP_NODE1")
		)
	)
	(footprint ""
		(layer "B.Cu")
		(at 41.48582 -150.22449 90)
		(property "Reference" "C395"
			(at 7.986014 -11.2649 270)
			(unlocked yes)
			(layer "B.SilkS")
			(effects
				(font
					(size 0.7874 0.5842)
					(thickness 0.1524)
				)
				(justify left mirror)
			)
		)
		(property "Value" ""
			(at 0 0 90)
			(layer "B.Fab")
			(effects
				(font
					(size 1.27 1.27)
				)
				(justify mirror)
			)
		)
		(duplicate_pad_numbers_are_jumpers no)
		(fp_line
			(start 0.7874 -0.4064)
			(end -0.7874 -0.4064)
			(stroke
				(width 0.1524)
				(type default)
			)
			(layer "B.SilkS")
		)
		(fp_line
			(start -0.7874 -0.4064)
			(end -0.7874 0.4064)
			(stroke
				(width 0.1524)
				(type default)
			)
			(layer "B.SilkS")
		)
		(fp_line
			(start 0 0.381)
			(end 0 -0.381)
			(stroke
				(width 0.1524)
				(type default)
			)
			(layer "B.SilkS")
		)
		(fp_line
			(start 0.7874 0.4064)
			(end 0.7874 -0.4064)
			(stroke
				(width 0.1524)
				(type default)
			)
			(layer "B.SilkS")
		)
		(fp_line
			(start -0.7874 0.4064)
			(end 0.7874 0.4064)
			(stroke
				(width 0.1524)
				(type default)
			)
			(layer "B.SilkS")
		)
		(fp_poly
			(pts
				(xy 0.5334 0.254) (xy 0.635 0.254) (xy 0.635 0.2286) (xy 0.635 -0.254) (xy 0.5334 -0.254) (xy 0.5334 -0.2794)
				(xy -0.5334 -0.2794) (xy -0.5334 -0.254) (xy -0.635 -0.254) (xy -0.635 0.254) (xy -0.5334 0.254)
				(xy -0.5334 0.2794) (xy 0.508 0.2794) (xy 0.5334 0.2794)
			)
			(stroke
				(width 0)
				(type default)
			)
			(fill no)
			(layer "B.CrtYd")
		)
		(pad "1" smd rect
			(at -0.40005 0 270)
			(size 0.4572 0.508)
			(layers "B.Cu" "B.Mask" "B.Paste")
			(net "P3V3_NODE1")
		)
		(pad "2" smd rect
			(at 0.40005 0 270)
			(size 0.4572 0.508)
			(layers "B.Cu" "B.Mask" "B.Paste")
			(net "GND")
		)
	)
	(footprint ""
		(layer "B.Cu")
		(at 113.01476 -188.126624 -90)
		(property "Reference" "C727"
			(at -4.080256 -0.709168 270)
			(unlocked yes)
			(layer "B.SilkS")
			(effects
				(font
					(size 0.7874 0.5842)
					(thickness 0.1524)
				)
				(justify left mirror)
			)
		)
		(property "Value" ""
			(at 0 0 90)
			(layer "B.Fab")
			(effects
				(font
					(size 1.27 1.27)
				)
				(justify mirror)
			)
		)
		(duplicate_pad_numbers_are_jumpers no)
		(fp_line
			(start -0.7874 0.4064)
			(end 0.7874 0.4064)
			(stroke
				(width 0.1524)
				(type default)
			)
			(layer "B.SilkS")
		)
		(fp_line
			(start 0.7874 0.4064)
			(end 0.7874 -0.4064)
			(stroke
				(width 0.1524)
				(type default)
			)
			(layer "B.SilkS")
		)
		(fp_line
			(start 0 0.381)
			(end 0 -0.381)
			(stroke
				(width 0.1524)
				(type default)
			)
			(layer "B.SilkS")
		)
		(fp_line
			(start -0.7874 -0.4064)
			(end -0.7874 0.4064)
			(stroke
				(width 0.1524)
				(type default)
			)
			(layer "B.SilkS")
		)
		(fp_line
			(start 0.7874 -0.4064)
			(end -0.7874 -0.4064)
			(stroke
				(width 0.1524)
				(type default)
			)
			(layer "B.SilkS")
		)
		(fp_poly
			(pts
				(xy 0.5334 0.254) (xy 0.635 0.254) (xy 0.635 0.2286) (xy 0.635 -0.254) (xy 0.5334 -0.254) (xy 0.5334 -0.2794)
				(xy -0.5334 -0.2794) (xy -0.5334 -0.254) (xy -0.635 -0.254) (xy -0.635 0.254) (xy -0.5334 0.254)
				(xy -0.5334 0.2794) (xy 0.508 0.2794) (xy 0.5334 0.2794)
			)
			(stroke
				(width 0)
				(type default)
			)
			(fill no)
			(layer "B.CrtYd")
		)
		(pad "1" smd rect
			(at -0.40005 0 90)
			(size 0.4572 0.508)
			(layers "B.Cu" "B.Mask" "B.Paste")
			(net "UART_T7_NODE2_TXD_R")
		)
		(pad "2" smd rect
			(at 0.40005 0 90)
			(size 0.4572 0.508)
			(layers "B.Cu" "B.Mask" "B.Paste")
			(net "GND")
		)
	)
	(footprint ""
		(layer "B.Cu")
		(at 74.02576 -188.126624 -90)
		(property "Reference" "C674"
			(at -4.318254 0.406146 270)
			(unlocked yes)
			(layer "B.SilkS")
			(effects
				(font
					(size 0.7874 0.5842)
					(thickness 0.1524)
				)
				(justify left mirror)
			)
		)
		(property "Value" ""
			(at 0 0 90)
			(layer "B.Fab")
			(effects
				(font
					(size 1.27 1.27)
				)
				(justify mirror)
			)
		)
		(duplicate_pad_numbers_are_jumpers no)
		(fp_line
			(start -0.7874 0.4064)
			(end 0.7874 0.4064)
			(stroke
				(width 0.1524)
				(type default)
			)
			(layer "B.SilkS")
		)
		(fp_line
			(start 0.7874 0.4064)
			(end 0.7874 -0.4064)
			(stroke
				(width 0.1524)
				(type default)
			)
			(layer "B.SilkS")
		)
		(fp_line
			(start 0 0.381)
			(end 0 -0.381)
			(stroke
				(width 0.1524)
				(type default)
			)
			(layer "B.SilkS")
		)
		(fp_line
			(start -0.7874 -0.4064)
			(end -0.7874 0.4064)
			(stroke
				(width 0.1524)
				(type default)
			)
			(layer "B.SilkS")
		)
		(fp_line
			(start 0.7874 -0.4064)
			(end -0.7874 -0.4064)
			(stroke
				(width 0.1524)
				(type default)
			)
			(layer "B.SilkS")
		)
		(fp_poly
			(pts
				(xy 0.5334 0.254) (xy 0.635 0.254) (xy 0.635 0.2286) (xy 0.635 -0.254) (xy 0.5334 -0.254) (xy 0.5334 -0.2794)
				(xy -0.5334 -0.2794) (xy -0.5334 -0.254) (xy -0.635 -0.254) (xy -0.635 0.254) (xy -0.5334 0.254)
				(xy -0.5334 0.2794) (xy 0.508 0.2794) (xy 0.5334 0.2794)
			)
			(stroke
				(width 0)
				(type default)
			)
			(fill no)
			(layer "B.CrtYd")
		)
		(pad "1" smd rect
			(at -0.40005 0 90)
			(size 0.4572 0.508)
			(layers "B.Cu" "B.Mask" "B.Paste")
			(net "UART_T3_NODE1_TXD_R")
		)
		(pad "2" smd rect
			(at 0.40005 0 90)
			(size 0.4572 0.508)
			(layers "B.Cu" "B.Mask" "B.Paste")
			(net "GND")
		)
	)
	(footprint ""
		(layer "B.Cu")
		(at 69.330062 -29.394658 -90)
		(property "Reference" "C194"
			(at -1.449832 0.256794 270)
			(unlocked yes)
			(layer "B.SilkS")
			(effects
				(font
					(size 0.7874 0.5842)
					(thickness 0.1524)
				)
				(justify left mirror)
			)
		)
		(property "Value" ""
			(at 0 0 90)
			(layer "B.Fab")
			(effects
				(font
					(size 1.27 1.27)
				)
				(justify mirror)
			)
		)
		(duplicate_pad_numbers_are_jumpers no)
		(fp_line
			(start -0.7874 0.406146)
			(end 0.7874 0.406146)
			(stroke
				(width 0.1524)
				(type default)
			)
			(layer "B.SilkS")
		)
		(fp_line
			(start 0.7874 0.406146)
			(end 0.7874 -0.406146)
			(stroke
				(width 0.1524)
				(type default)
			)
			(layer "B.SilkS")
		)
		(fp_line
			(start 0 0.381)
			(end 0 -0.381)
			(stroke
				(width 0.1524)
				(type default)
			)
			(layer "B.SilkS")
		)
		(fp_line
			(start -0.7874 -0.406146)
			(end -0.7874 0.406146)
			(stroke
				(width 0.1524)
				(type default)
			)
			(layer "B.SilkS")
		)
		(fp_line
			(start 0.7874 -0.406146)
			(end -0.7874 -0.406146)
			(stroke
				(width 0.1524)
				(type default)
			)
			(layer "B.SilkS")
		)
		(fp_poly
			(pts
				(xy 0.5334 0.254) (xy 0.635 0.254) (xy 0.635 0.2286) (xy 0.635 -0.254) (xy 0.5334 -0.254) (xy 0.5334 -0.2794)
				(xy -0.5334 -0.2794) (xy -0.5334 -0.254) (xy -0.635 -0.254) (xy -0.635 0.254) (xy -0.5334 0.254)
				(xy -0.5334 0.2794) (xy 0.508 0.2794) (xy 0.5334 0.2794)
			)
			(stroke
				(width 0)
				(type default)
			)
			(fill no)
			(layer "B.CrtYd")
		)
		(pad "1" smd rect
			(at -0.40005 0 90)
			(size 0.4572 0.508)
			(layers "B.Cu" "B.Mask" "B.Paste")
			(net "P1V5_NODE1_DDR3_VREF_A_A")
		)
		(pad "2" smd rect
			(at 0.40005 0 90)
			(size 0.4572 0.508)
			(layers "B.Cu" "B.Mask" "B.Paste")
			(net "GND")
		)
	)
	(footprint ""
		(layer "B.Cu")
		(at 57.65673 -68.727828 -90)
		(property "Reference" "C94"
			(at 34.283142 14.25194 270)
			(unlocked yes)
			(layer "B.SilkS")
			(effects
				(font
					(size 0.7874 0.5842)
					(thickness 0.1524)
				)
				(justify left mirror)
			)
		)
		(property "Value" ""
			(at 0 0 90)
			(layer "B.Fab")
			(effects
				(font
					(size 1.27 1.27)
				)
				(justify mirror)
			)
		)
		(duplicate_pad_numbers_are_jumpers no)
		(fp_line
			(start -0.7874 0.4064)
			(end 0.7874 0.4064)
			(stroke
				(width 0.1524)
				(type default)
			)
			(layer "B.SilkS")
		)
		(fp_line
			(start 0.7874 0.4064)
			(end 0.7874 -0.4064)
			(stroke
				(width 0.1524)
				(type default)
			)
			(layer "B.SilkS")
		)
		(fp_line
			(start 0 0.381)
			(end 0 -0.381)
			(stroke
				(width 0.1524)
				(type default)
			)
			(layer "B.SilkS")
		)
		(fp_line
			(start -0.7874 -0.4064)
			(end -0.7874 0.4064)
			(stroke
				(width 0.1524)
				(type default)
			)
			(layer "B.SilkS")
		)
		(fp_line
			(start 0.7874 -0.4064)
			(end -0.7874 -0.4064)
			(stroke
				(width 0.1524)
				(type default)
			)
			(layer "B.SilkS")
		)
		(fp_poly
			(pts
				(xy 0.5334 0.254) (xy 0.635 0.254) (xy 0.635 0.2286) (xy 0.635 -0.254) (xy 0.5334 -0.254) (xy 0.5334 -0.2794)
				(xy -0.5334 -0.2794) (xy -0.5334 -0.254) (xy -0.635 -0.254) (xy -0.635 0.254) (xy -0.5334 0.254)
				(xy -0.5334 0.2794) (xy 0.508 0.2794) (xy 0.5334 0.2794)
			)
			(stroke
				(width 0)
				(type default)
			)
			(fill no)
			(layer "B.CrtYd")
		)
		(pad "1" smd rect
			(at -0.40005 0 90)
			(size 0.4572 0.508)
			(layers "B.Cu" "B.Mask" "B.Paste")
			(net "P1V5_SFRPLL_NODE1")
		)
		(pad "2" smd rect
			(at 0.40005 0 90)
			(size 0.4572 0.508)
			(layers "B.Cu" "B.Mask" "B.Paste")
			(net "GND")
		)
	)
	(footprint ""
		(layer "B.Cu")
		(at 165.21938 -154.315922 180)
		(property "Reference" "C467"
			(at 1.083564 -0.624332 0)
			(unlocked yes)
			(layer "B.SilkS")
			(effects
				(font
					(size 0.7874 0.5842)
					(thickness 0.1524)
				)
				(justify left mirror)
			)
		)
		(property "Value" ""
			(at 0 0 0)
			(layer "B.Fab")
			(effects
				(font
					(size 1.27 1.27)
				)
				(justify mirror)
			)
		)
		(duplicate_pad_numbers_are_jumpers no)
		(fp_line
			(start 0.7874 0.4064)
			(end 0.7874 -0.4064)
			(stroke
				(width 0.1524)
				(type default)
			)
			(layer "B.SilkS")
		)
		(fp_line
			(start 0.7874 -0.4064)
			(end -0.7874 -0.4064)
			(stroke
				(width 0.1524)
				(type default)
			)
			(layer "B.SilkS")
		)
		(fp_line
			(start 0 0.381)
			(end 0 -0.381)
			(stroke
				(width 0.1524)
				(type default)
			)
			(layer "B.SilkS")
		)
		(fp_line
			(start -0.7874 0.4064)
			(end 0.7874 0.4064)
			(stroke
				(width 0.1524)
				(type default)
			)
			(layer "B.SilkS")
		)
		(fp_line
			(start -0.7874 -0.4064)
			(end -0.7874 0.4064)
			(stroke
				(width 0.1524)
				(type default)
			)
			(layer "B.SilkS")
		)
		(fp_poly
			(pts
				(xy 0.5334 0.254) (xy 0.635 0.254) (xy 0.635 0.2286) (xy 0.635 -0.254) (xy 0.5334 -0.254) (xy 0.5334 -0.2794)
				(xy -0.5334 -0.2794) (xy -0.5334 -0.254) (xy -0.635 -0.254) (xy -0.635 0.254) (xy -0.5334 0.254)
				(xy -0.5334 0.2794) (xy 0.508 0.2794) (xy 0.5334 0.2794)
			)
			(stroke
				(width 0)
				(type default)
			)
			(fill no)
			(layer "B.CrtYd")
		)
		(pad "1" smd rect
			(at -0.40005 0)
			(size 0.4572 0.508)
			(layers "B.Cu" "B.Mask" "B.Paste")
			(net "P1V05_LAN2")
		)
		(pad "2" smd rect
			(at 0.40005 0)
			(size 0.4572 0.508)
			(layers "B.Cu" "B.Mask" "B.Paste")
			(net "GND")
		)
	)
	(footprint ""
		(layer "B.Cu")
		(at 63.16726 -99.189032 -90)
		(property "Reference" "R70"
			(at -0.99441 -0.003302 270)
			(unlocked yes)
			(layer "B.SilkS")
			(effects
				(font
					(size 0.7874 0.5842)
					(thickness 0.1524)
				)
				(justify left mirror)
			)
		)
		(property "Value" ""
			(at 0 0 90)
			(layer "B.Fab")
			(effects
				(font
					(size 1.27 1.27)
				)
				(justify mirror)
			)
		)
		(duplicate_pad_numbers_are_jumpers no)
		(fp_line
			(start -0.7874 0.4064)
			(end 0.7874 0.4064)
			(stroke
				(width 0.1524)
				(type default)
			)
			(layer "B.SilkS")
		)
		(fp_line
			(start 0.7874 0.4064)
			(end 0.7874 -0.4064)
			(stroke
				(width 0.1524)
				(type default)
			)
			(layer "B.SilkS")
		)
		(fp_line
			(start -0.7874 -0.4064)
			(end -0.7874 0.4064)
			(stroke
				(width 0.1524)
				(type default)
			)
			(layer "B.SilkS")
		)
		(fp_line
			(start 0.7874 -0.4064)
			(end -0.7874 -0.4064)
			(stroke
				(width 0.1524)
				(type default)
			)
			(layer "B.SilkS")
		)
		(fp_poly
			(pts
				(xy 0.508 0.2794) (xy 0.508 0.2286) (xy 0.635 0.2286) (xy 0.635 -0.254) (xy 0.5334 -0.254) (xy 0.5334 -0.2794)
				(xy -0.5334 -0.2794) (xy -0.5334 -0.254) (xy -0.635 -0.254) (xy -0.635 0.254) (xy -0.5334 0.254)
				(xy -0.5334 0.2794)
			)
			(stroke
				(width 0)
				(type default)
			)
			(fill no)
			(layer "B.CrtYd")
		)
		(pad "1" smd rect
			(at -0.40005 0 90)
			(size 0.4572 0.508)
			(layers "B.Cu" "B.Mask" "B.Paste")
			(net "P3V3_NODE1")
		)
		(pad "2" smd rect
			(at 0.40005 0 90)
			(size 0.4572 0.508)
			(layers "B.Cu" "B.Mask" "B.Paste")
			(net "IRQ_CPU_NODE1_SERIAL")
		)
	)
	(footprint ""
		(layer "B.Cu")
		(at 66.194686 -118.758462 -90)
		(property "Reference" "R333"
			(at 5.056632 0.375158 270)
			(unlocked yes)
			(layer "B.SilkS")
			(effects
				(font
					(size 0.7874 0.5842)
					(thickness 0.1524)
				)
				(justify left mirror)
			)
		)
		(property "Value" ""
			(at 0 0 90)
			(layer "B.Fab")
			(effects
				(font
					(size 1.27 1.27)
				)
				(justify mirror)
			)
		)
		(duplicate_pad_numbers_are_jumpers no)
		(fp_line
			(start -0.7874 0.4064)
			(end 0.7874 0.4064)
			(stroke
				(width 0.1524)
				(type default)
			)
			(layer "B.SilkS")
		)
		(fp_line
			(start 0.7874 0.4064)
			(end 0.7874 -0.4064)
			(stroke
				(width 0.1524)
				(type default)
			)
			(layer "B.SilkS")
		)
		(fp_line
			(start -0.7874 -0.4064)
			(end -0.7874 0.4064)
			(stroke
				(width 0.1524)
				(type default)
			)
			(layer "B.SilkS")
		)
		(fp_line
			(start 0.7874 -0.4064)
			(end -0.7874 -0.4064)
			(stroke
				(width 0.1524)
				(type default)
			)
			(layer "B.SilkS")
		)
		(fp_poly
			(pts
				(xy 0.508 0.2794) (xy 0.508 0.2286) (xy 0.635 0.2286) (xy 0.635 -0.254) (xy 0.5334 -0.254) (xy 0.5334 -0.2794)
				(xy -0.5334 -0.2794) (xy -0.5334 -0.254) (xy -0.635 -0.254) (xy -0.635 0.254) (xy -0.5334 0.254)
				(xy -0.5334 0.2794)
			)
			(stroke
				(width 0)
				(type default)
			)
			(fill no)
			(layer "B.CrtYd")
		)
		(pad "1" smd rect
			(at -0.40005 0 90)
			(size 0.4572 0.508)
			(layers "B.Cu" "B.Mask" "B.Paste")
			(net "P3V3_NODE1")
		)
		(pad "2" smd rect
			(at 0.40005 0 90)
			(size 0.4572 0.508)
			(layers "B.Cu" "B.Mask" "B.Paste")
			(net "BMC_ROMA17")
		)
	)
	(footprint ""
		(layer "B.Cu")
		(at 167.902636 -173.284642 90)
		(property "Reference" "C918"
			(at 0.928116 -0.235966 270)
			(unlocked yes)
			(layer "B.SilkS")
			(effects
				(font
					(size 0.7874 0.5842)
					(thickness 0.1524)
				)
				(justify left mirror)
			)
		)
		(property "Value" ""
			(at 0 0 90)
			(layer "B.Fab")
			(effects
				(font
					(size 1.27 1.27)
				)
				(justify mirror)
			)
		)
		(duplicate_pad_numbers_are_jumpers no)
		(fp_line
			(start 0.7874 -0.4064)
			(end -0.7874 -0.4064)
			(stroke
				(width 0.1524)
				(type default)
			)
			(layer "B.SilkS")
		)
		(fp_line
			(start -0.7874 -0.4064)
			(end -0.7874 0.4064)
			(stroke
				(width 0.1524)
				(type default)
			)
			(layer "B.SilkS")
		)
		(fp_line
			(start 0 0.381)
			(end 0 -0.381)
			(stroke
				(width 0.1524)
				(type default)
			)
			(layer "B.SilkS")
		)
		(fp_line
			(start 0.7874 0.4064)
			(end 0.7874 -0.4064)
			(stroke
				(width 0.1524)
				(type default)
			)
			(layer "B.SilkS")
		)
		(fp_line
			(start -0.7874 0.4064)
			(end 0.7874 0.4064)
			(stroke
				(width 0.1524)
				(type default)
			)
			(layer "B.SilkS")
		)
		(fp_poly
			(pts
				(xy 0.5334 0.254) (xy 0.635 0.254) (xy 0.635 0.2286) (xy 0.635 -0.254) (xy 0.5334 -0.254) (xy 0.5334 -0.2794)
				(xy -0.5334 -0.2794) (xy -0.5334 -0.254) (xy -0.635 -0.254) (xy -0.635 0.254) (xy -0.5334 0.254)
				(xy -0.5334 0.2794) (xy 0.508 0.2794) (xy 0.5334 0.2794)
			)
			(stroke
				(width 0)
				(type default)
			)
			(fill no)
			(layer "B.CrtYd")
		)
		(pad "1" smd rect
			(at -0.40005 0 270)
			(size 0.4572 0.508)
			(layers "B.Cu" "B.Mask" "B.Paste")
			(net "P3V3_NODE1")
		)
		(pad "2" smd rect
			(at 0.40005 0 270)
			(size 0.4572 0.508)
			(layers "B.Cu" "B.Mask" "B.Paste")
			(net "GND")
		)
	)
	(footprint ""
		(layer "B.Cu")
		(at 76.570078 -129.388616 -90)
		(property "Reference" "R258"
			(at -1.582166 0.064516 270)
			(unlocked yes)
			(layer "B.SilkS")
			(effects
				(font
					(size 0.7874 0.5842)
					(thickness 0.1524)
				)
				(justify left mirror)
			)
		)
		(property "Value" ""
			(at 0 0 90)
			(layer "B.Fab")
			(effects
				(font
					(size 1.27 1.27)
				)
				(justify mirror)
			)
		)
		(duplicate_pad_numbers_are_jumpers no)
		(fp_line
			(start -0.7874 0.4064)
			(end 0.7874 0.4064)
			(stroke
				(width 0.1524)
				(type default)
			)
			(layer "B.SilkS")
		)
		(fp_line
			(start 0.7874 0.4064)
			(end 0.7874 -0.4064)
			(stroke
				(width 0.1524)
				(type default)
			)
			(layer "B.SilkS")
		)
		(fp_line
			(start -0.7874 -0.4064)
			(end -0.7874 0.4064)
			(stroke
				(width 0.1524)
				(type default)
			)
			(layer "B.SilkS")
		)
		(fp_line
			(start 0.7874 -0.4064)
			(end -0.7874 -0.4064)
			(stroke
				(width 0.1524)
				(type default)
			)
			(layer "B.SilkS")
		)
		(fp_poly
			(pts
				(xy 0.508 0.2794) (xy 0.508 0.2286) (xy 0.635 0.2286) (xy 0.635 -0.254) (xy 0.5334 -0.254) (xy 0.5334 -0.2794)
				(xy -0.5334 -0.2794) (xy -0.5334 -0.254) (xy -0.635 -0.254) (xy -0.635 0.254) (xy -0.5334 0.254)
				(xy -0.5334 0.2794)
			)
			(stroke
				(width 0)
				(type default)
			)
			(fill no)
			(layer "B.CrtYd")
		)
		(pad "1" smd rect
			(at -0.40005 0 90)
			(size 0.4572 0.508)
			(layers "B.Cu" "B.Mask" "B.Paste")
			(net "GND")
		)
		(pad "2" smd rect
			(at 0.40005 0 90)
			(size 0.4572 0.508)
			(layers "B.Cu" "B.Mask" "B.Paste")
			(net "LPC_CLK_AST")
		)
	)
	(footprint ""
		(layer "B.Cu")
		(at 74.223372 -80.514698 90)
		(property "Reference" "C87"
			(at -32.158686 -14.55039 270)
			(unlocked yes)
			(layer "B.SilkS")
			(effects
				(font
					(size 0.7874 0.5842)
					(thickness 0.1524)
				)
				(justify left mirror)
			)
		)
		(property "Value" ""
			(at 0 0 90)
			(layer "B.Fab")
			(effects
				(font
					(size 1.27 1.27)
				)
				(justify mirror)
			)
		)
		(duplicate_pad_numbers_are_jumpers no)
		(fp_line
			(start 0.7874 -0.4064)
			(end -0.7874 -0.4064)
			(stroke
				(width 0.1524)
				(type default)
			)
			(layer "B.SilkS")
		)
		(fp_line
			(start -0.7874 -0.4064)
			(end -0.7874 0.4064)
			(stroke
				(width 0.1524)
				(type default)
			)
			(layer "B.SilkS")
		)
		(fp_line
			(start 0 0.381)
			(end 0 -0.381)
			(stroke
				(width 0.1524)
				(type default)
			)
			(layer "B.SilkS")
		)
		(fp_line
			(start 0.7874 0.4064)
			(end 0.7874 -0.4064)
			(stroke
				(width 0.1524)
				(type default)
			)
			(layer "B.SilkS")
		)
		(fp_line
			(start -0.7874 0.4064)
			(end 0.7874 0.4064)
			(stroke
				(width 0.1524)
				(type default)
			)
			(layer "B.SilkS")
		)
		(fp_poly
			(pts
				(xy 0.5334 0.254) (xy 0.635 0.254) (xy 0.635 0.2286) (xy 0.635 -0.254) (xy 0.5334 -0.254) (xy 0.5334 -0.2794)
				(xy -0.5334 -0.2794) (xy -0.5334 -0.254) (xy -0.635 -0.254) (xy -0.635 0.254) (xy -0.5334 0.254)
				(xy -0.5334 0.2794) (xy 0.508 0.2794) (xy 0.5334 0.2794)
			)
			(stroke
				(width 0)
				(type default)
			)
			(fill no)
			(layer "B.CrtYd")
		)
		(pad "1" smd rect
			(at -0.40005 0 270)
			(size 0.4572 0.508)
			(layers "B.Cu" "B.Mask" "B.Paste")
			(net "PV_VCCP_NODE1")
		)
		(pad "2" smd rect
			(at 0.40005 0 270)
			(size 0.4572 0.508)
			(layers "B.Cu" "B.Mask" "B.Paste")
			(net "GND")
		)
	)
	(footprint ""
		(layer "B.Cu")
		(at 76.415392 -141.288262)
		(property "Reference" "TP6"
			(at 0 0 0)
			(layer "B.SilkS")
			(hide yes)
			(effects
				(font
					(size 1.27 1.27)
				)
				(justify mirror)
			)
		)
		(property "Value" ""
			(at 0 0 0)
			(layer "B.Fab")
			(effects
				(font
					(size 1.27 1.27)
				)
				(justify mirror)
			)
		)
		(duplicate_pad_numbers_are_jumpers no)
		(fp_poly
			(pts
				(arc
					(start 0 -0.381)
					(mid 0 0.381)
					(end 0 -0.381)
				)
			)
			(stroke
				(width 0)
				(type default)
			)
			(fill no)
			(layer "B.CrtYd")
		)
		(pad "1" smd circle
			(at 0 0 180)
			(size 0.762 0.762)
			(layers "B.Cu" "B.Mask" "B.Paste")
			(net "N3975090766")
		)
	)
	(footprint ""
		(layer "B.Cu")
		(at 135.36676 -184.951624 -90)
		(property "Reference" "C719"
			(at -4.357624 1.758188 270)
			(unlocked yes)
			(layer "B.SilkS")
			(effects
				(font
					(size 0.7874 0.5842)
					(thickness 0.1524)
				)
				(justify left mirror)
			)
		)
		(property "Value" ""
			(at 0 0 90)
			(layer "B.Fab")
			(effects
				(font
					(size 1.27 1.27)
				)
				(justify mirror)
			)
		)
		(duplicate_pad_numbers_are_jumpers no)
		(fp_line
			(start -0.7874 0.4064)
			(end 0.7874 0.4064)
			(stroke
				(width 0.1524)
				(type default)
			)
			(layer "B.SilkS")
		)
		(fp_line
			(start 0.7874 0.4064)
			(end 0.7874 -0.4064)
			(stroke
				(width 0.1524)
				(type default)
			)
			(layer "B.SilkS")
		)
		(fp_line
			(start 0 0.381)
			(end 0 -0.381)
			(stroke
				(width 0.1524)
				(type default)
			)
			(layer "B.SilkS")
		)
		(fp_line
			(start -0.7874 -0.4064)
			(end -0.7874 0.4064)
			(stroke
				(width 0.1524)
				(type default)
			)
			(layer "B.SilkS")
		)
		(fp_line
			(start 0.7874 -0.4064)
			(end -0.7874 -0.4064)
			(stroke
				(width 0.1524)
				(type default)
			)
			(layer "B.SilkS")
		)
		(fp_poly
			(pts
				(xy 0.5334 0.254) (xy 0.635 0.254) (xy 0.635 0.2286) (xy 0.635 -0.254) (xy 0.5334 -0.254) (xy 0.5334 -0.2794)
				(xy -0.5334 -0.2794) (xy -0.5334 -0.254) (xy -0.635 -0.254) (xy -0.635 0.254) (xy -0.5334 0.254)
				(xy -0.5334 0.2794) (xy 0.508 0.2794) (xy 0.5334 0.2794)
			)
			(stroke
				(width 0)
				(type default)
			)
			(fill no)
			(layer "B.CrtYd")
		)
		(pad "1" smd rect
			(at -0.40005 0 90)
			(size 0.4572 0.508)
			(layers "B.Cu" "B.Mask" "B.Paste")
			(net "UART_T9_NODE1_RXD")
		)
		(pad "2" smd rect
			(at 0.40005 0 90)
			(size 0.4572 0.508)
			(layers "B.Cu" "B.Mask" "B.Paste")
			(net "GND")
		)
	)
	(footprint ""
		(layer "B.Cu")
		(at 158.485078 -181.995318 90)
		(property "Reference" "R1175"
			(at -0.921258 3.197352 270)
			(unlocked yes)
			(layer "B.SilkS")
			(effects
				(font
					(size 0.7874 0.5842)
					(thickness 0.1524)
				)
				(justify left mirror)
			)
		)
		(property "Value" ""
			(at 0 0 90)
			(layer "B.Fab")
			(effects
				(font
					(size 1.27 1.27)
				)
				(justify mirror)
			)
		)
		(duplicate_pad_numbers_are_jumpers no)
		(fp_line
			(start 0.7874 -0.4064)
			(end -0.7874 -0.4064)
			(stroke
				(width 0.1524)
				(type default)
			)
			(layer "B.SilkS")
		)
		(fp_line
			(start -0.7874 -0.4064)
			(end -0.7874 0.4064)
			(stroke
				(width 0.1524)
				(type default)
			)
			(layer "B.SilkS")
		)
		(fp_line
			(start 0.7874 0.4064)
			(end 0.7874 -0.4064)
			(stroke
				(width 0.1524)
				(type default)
			)
			(layer "B.SilkS")
		)
		(fp_line
			(start -0.7874 0.4064)
			(end 0.7874 0.4064)
			(stroke
				(width 0.1524)
				(type default)
			)
			(layer "B.SilkS")
		)
		(fp_poly
			(pts
				(xy 0.508 0.2794) (xy 0.508 0.2286) (xy 0.635 0.2286) (xy 0.635 -0.254) (xy 0.5334 -0.254) (xy 0.5334 -0.2794)
				(xy -0.5334 -0.2794) (xy -0.5334 -0.254) (xy -0.635 -0.254) (xy -0.635 0.254) (xy -0.5334 0.254)
				(xy -0.5334 0.2794)
			)
			(stroke
				(width 0)
				(type default)
			)
			(fill no)
			(layer "B.CrtYd")
		)
		(pad "1" smd rect
			(at -0.40005 0 270)
			(size 0.4572 0.508)
			(layers "B.Cu" "B.Mask" "B.Paste")
			(net "CPLD_UART_RTS_P4_R_N")
		)
		(pad "2" smd rect
			(at 0.40005 0 270)
			(size 0.4572 0.508)
			(layers "B.Cu" "B.Mask" "B.Paste")
			(net "CPLD_UART_RTS_P4_N")
		)
	)
	(footprint ""
		(layer "B.Cu")
		(at 162.57778 -157.795722 -90)
		(property "Reference" "C465"
			(at -2.314448 0.620776 270)
			(unlocked yes)
			(layer "B.SilkS")
			(effects
				(font
					(size 0.7874 0.5842)
					(thickness 0.1524)
				)
				(justify left mirror)
			)
		)
		(property "Value" ""
			(at 0 0 90)
			(layer "B.Fab")
			(effects
				(font
					(size 1.27 1.27)
				)
				(justify mirror)
			)
		)
		(duplicate_pad_numbers_are_jumpers no)
		(fp_line
			(start -0.7874 0.4064)
			(end 0.7874 0.4064)
			(stroke
				(width 0.1524)
				(type default)
			)
			(layer "B.SilkS")
		)
		(fp_line
			(start 0.7874 0.4064)
			(end 0.7874 -0.4064)
			(stroke
				(width 0.1524)
				(type default)
			)
			(layer "B.SilkS")
		)
		(fp_line
			(start 0 0.381)
			(end 0 -0.381)
			(stroke
				(width 0.1524)
				(type default)
			)
			(layer "B.SilkS")
		)
		(fp_line
			(start -0.7874 -0.4064)
			(end -0.7874 0.4064)
			(stroke
				(width 0.1524)
				(type default)
			)
			(layer "B.SilkS")
		)
		(fp_line
			(start 0.7874 -0.4064)
			(end -0.7874 -0.4064)
			(stroke
				(width 0.1524)
				(type default)
			)
			(layer "B.SilkS")
		)
		(fp_poly
			(pts
				(xy 0.5334 0.254) (xy 0.635 0.254) (xy 0.635 0.2286) (xy 0.635 -0.254) (xy 0.5334 -0.254) (xy 0.5334 -0.2794)
				(xy -0.5334 -0.2794) (xy -0.5334 -0.254) (xy -0.635 -0.254) (xy -0.635 0.254) (xy -0.5334 0.254)
				(xy -0.5334 0.2794) (xy 0.508 0.2794) (xy 0.5334 0.2794)
			)
			(stroke
				(width 0)
				(type default)
			)
			(fill no)
			(layer "B.CrtYd")
		)
		(pad "1" smd rect
			(at -0.40005 0 90)
			(size 0.4572 0.508)
			(layers "B.Cu" "B.Mask" "B.Paste")
			(net "P1V05_LAN2")
		)
		(pad "2" smd rect
			(at 0.40005 0 90)
			(size 0.4572 0.508)
			(layers "B.Cu" "B.Mask" "B.Paste")
			(net "GND")
		)
	)
	(footprint ""
		(layer "B.Cu")
		(at 63.936118 -85.90915 90)
		(property "Reference" "C74"
			(at 1.344422 1.12649 270)
			(unlocked yes)
			(layer "B.SilkS")
			(effects
				(font
					(size 0.7874 0.5842)
					(thickness 0.1524)
				)
				(justify mirror)
			)
		)
		(property "Value" ""
			(at 0 0 90)
			(layer "B.Fab")
			(effects
				(font
					(size 1.27 1.27)
				)
				(justify mirror)
			)
		)
		(duplicate_pad_numbers_are_jumpers no)
		(fp_line
			(start 1.2954 -0.5842)
			(end -1.2954 -0.5842)
			(stroke
				(width 0.1524)
				(type default)
			)
			(layer "B.SilkS")
		)
		(fp_line
			(start 0 -0.5842)
			(end 0 0.5842)
			(stroke
				(width 0.1524)
				(type default)
			)
			(layer "B.SilkS")
		)
		(fp_line
			(start -1.2954 -0.5842)
			(end -1.2954 0.5842)
			(stroke
				(width 0.1524)
				(type default)
			)
			(layer "B.SilkS")
		)
		(fp_line
			(start 1.2954 0.5842)
			(end 1.2954 -0.5842)
			(stroke
				(width 0.1524)
				(type default)
			)
			(layer "B.SilkS")
		)
		(fp_line
			(start -1.2954 0.5842)
			(end 1.2954 0.5842)
			(stroke
				(width 0.1524)
				(type default)
			)
			(layer "B.SilkS")
		)
		(fp_poly
			(pts
				(xy -0.8636 -0.4572) (xy -0.8636 -0.3556) (xy -1.143 -0.3556) (xy -1.143 0.3556) (xy -0.8636 0.3556)
				(xy -0.8636 0.4572) (xy 0.8636 0.4572) (xy 0.8636 0.3556) (xy 1.143 0.3556) (xy 1.143 -0.3556) (xy 0.8636 -0.3556)
				(xy 0.8636 -0.4572)
			)
			(stroke
				(width 0)
				(type default)
			)
			(fill no)
			(layer "B.CrtYd")
		)
		(fp_line
			(start 0.884936 -0.504952)
			(end -0.884936 -0.504952)
			(stroke
				(width 0.1)
				(type default)
			)
			(layer "B.Fab")
		)
		(fp_line
			(start -0.884936 -0.504952)
			(end -0.884936 0.504952)
			(stroke
				(width 0.1)
				(type default)
			)
			(layer "B.Fab")
		)
		(fp_line
			(start 0.884936 0.504952)
			(end 0.884936 -0.504952)
			(stroke
				(width 0.1)
				(type default)
			)
			(layer "B.Fab")
		)
		(fp_line
			(start -0.884936 0.504952)
			(end 0.884936 0.504952)
			(stroke
				(width 0.1)
				(type default)
			)
			(layer "B.Fab")
		)
		(pad "1" smd rect
			(at -0.7366 0 180)
			(size 0.7112 0.8128)
			(layers "B.Cu" "B.Mask" "B.Paste")
			(net "P1V8_SUS_NODE1")
		)
		(pad "2" smd rect
			(at 0.7366 0 180)
			(size 0.7112 0.8128)
			(layers "B.Cu" "B.Mask" "B.Paste")
			(net "GND")
		)
	)
	(footprint ""
		(layer "B.Cu")
		(at 42.551858 -73.494138 180)
		(property "Reference" "R38"
			(at 0.957326 -1.619504 0)
			(unlocked yes)
			(layer "B.SilkS")
			(effects
				(font
					(size 0.7874 0.5842)
					(thickness 0.1524)
				)
				(justify left mirror)
			)
		)
		(property "Value" ""
			(at 0 0 0)
			(layer "B.Fab")
			(effects
				(font
					(size 1.27 1.27)
				)
				(justify mirror)
			)
		)
		(duplicate_pad_numbers_are_jumpers no)
		(fp_line
			(start 0.7874 0.4064)
			(end 0.7874 -0.4064)
			(stroke
				(width 0.1524)
				(type default)
			)
			(layer "B.SilkS")
		)
		(fp_line
			(start 0.7874 -0.4064)
			(end -0.7874 -0.4064)
			(stroke
				(width 0.1524)
				(type default)
			)
			(layer "B.SilkS")
		)
		(fp_line
			(start -0.7874 0.4064)
			(end 0.7874 0.4064)
			(stroke
				(width 0.1524)
				(type default)
			)
			(layer "B.SilkS")
		)
		(fp_line
			(start -0.7874 -0.4064)
			(end -0.7874 0.4064)
			(stroke
				(width 0.1524)
				(type default)
			)
			(layer "B.SilkS")
		)
		(fp_poly
			(pts
				(xy 0.508 0.2794) (xy 0.508 0.2286) (xy 0.635 0.2286) (xy 0.635 -0.254) (xy 0.5334 -0.254) (xy 0.5334 -0.2794)
				(xy -0.5334 -0.2794) (xy -0.5334 -0.254) (xy -0.635 -0.254) (xy -0.635 0.254) (xy -0.5334 0.254)
				(xy -0.5334 0.2794)
			)
			(stroke
				(width 0)
				(type default)
			)
			(fill no)
			(layer "B.CrtYd")
		)
		(pad "1" smd rect
			(at -0.40005 0)
			(size 0.4572 0.508)
			(layers "B.Cu" "B.Mask" "B.Paste")
			(net "PD_CPU_NODE1_AL5")
		)
		(pad "2" smd rect
			(at 0.40005 0)
			(size 0.4572 0.508)
			(layers "B.Cu" "B.Mask" "B.Paste")
			(net "GND")
		)
	)
	(footprint ""
		(layer "B.Cu")
		(at 30.16377 -104.991662 90)
		(property "Reference" "C818"
			(at -0.009652 -3.212592 270)
			(unlocked yes)
			(layer "B.SilkS")
			(effects
				(font
					(size 0.7874 0.5842)
					(thickness 0.1524)
				)
				(justify left mirror)
			)
		)
		(property "Value" ""
			(at 0 0 90)
			(layer "B.Fab")
			(effects
				(font
					(size 1.27 1.27)
				)
				(justify mirror)
			)
		)
		(duplicate_pad_numbers_are_jumpers no)
		(fp_line
			(start 1.905 -0.8636)
			(end -1.905 -0.8636)
			(stroke
				(width 0.1524)
				(type default)
			)
			(layer "B.SilkS")
		)
		(fp_line
			(start -1.905 -0.8636)
			(end -1.905 0.8636)
			(stroke
				(width 0.1524)
				(type default)
			)
			(layer "B.SilkS")
		)
		(fp_line
			(start 0 0.8382)
			(end 0 -0.8382)
			(stroke
				(width 0.1524)
				(type default)
			)
			(layer "B.SilkS")
		)
		(fp_line
			(start 1.905 0.8636)
			(end 1.905 -0.8636)
			(stroke
				(width 0.1524)
				(type default)
			)
			(layer "B.SilkS")
		)
		(fp_line
			(start -1.905 0.8636)
			(end 1.905 0.8636)
			(stroke
				(width 0.1524)
				(type default)
			)
			(layer "B.SilkS")
		)
		(fp_rect
			(start 1.524 0.7366)
			(end -1.524 -0.7366)
			(stroke
				(width 0)
				(type default)
			)
			(fill no)
			(layer "B.CrtYd")
		)
		(pad "1" smd rect
			(at -0.94996 0 270)
			(size 1.1176 1.3716)
			(layers "B.Cu" "B.Mask" "B.Paste")
			(net "P1V8_STB_NODE1")
		)
		(pad "2" smd rect
			(at 0.94996 0 270)
			(size 1.1176 1.3716)
			(layers "B.Cu" "B.Mask" "B.Paste")
			(net "GND")
		)
	)
	(footprint ""
		(layer "B.Cu")
		(at 55.22976 -176.315624 90)
		(property "Reference" "U63"
			(at -4.683252 4.289552 0)
			(unlocked yes)
			(layer "B.SilkS")
			(effects
				(font
					(size 0.7874 0.5842)
					(thickness 0.1524)
				)
				(justify left mirror)
			)
		)
		(property "Value" ""
			(at 0 0 90)
			(layer "B.Fab")
			(effects
				(font
					(size 1.27 1.27)
				)
				(justify mirror)
			)
		)
		(duplicate_pad_numbers_are_jumpers no)
		(fp_line
			(start 3.9624 -2.0066)
			(end -3.9624 -2.0066)
			(stroke
				(width 0.1524)
				(type default)
			)
			(layer "B.SilkS")
		)
		(fp_line
			(start -3.9624 -2.0066)
			(end -3.9624 2.0066)
			(stroke
				(width 0.1524)
				(type default)
			)
			(layer "B.SilkS")
		)
		(fp_line
			(start 3.9624 -0.5842)
			(end 3.9624 -2.0066)
			(stroke
				(width 0.1524)
				(type default)
			)
			(layer "B.SilkS")
		)
		(fp_line
			(start 3.3782 0)
			(end 3.9624 -0.5842)
			(stroke
				(width 0.1524)
				(type default)
			)
			(layer "B.SilkS")
		)
		(fp_line
			(start 3.9624 0.5842)
			(end 3.3782 0)
			(stroke
				(width 0.1524)
				(type default)
			)
			(layer "B.SilkS")
		)
		(fp_line
			(start 3.9624 2.0066)
			(end 3.9624 0.5842)
			(stroke
				(width 0.1524)
				(type default)
			)
			(layer "B.SilkS")
		)
		(fp_line
			(start -3.9624 2.0066)
			(end 3.9624 2.0066)
			(stroke
				(width 0.1524)
				(type default)
			)
			(layer "B.SilkS")
		)
		(fp_circle
			(center 3.429 1.524)
			(end 3.429 1.778)
			(stroke
				(width 0.1524)
				(type default)
			)
			(fill no)
			(layer "B.SilkS")
		)
		(fp_poly
			(pts
				(xy 3.962654 3.6703) (xy 3.974846 -3.6703) (xy -3.9624 -3.6703) (xy -3.9624 3.6703)
			)
			(stroke
				(width 0)
				(type default)
			)
			(fill no)
			(layer "B.CrtYd")
		)
		(pad "1" smd rect
			(at 3.57505 2.921 270)
			(size 0.3556 1.4986)
			(layers "B.Cu" "B.Mask" "B.Paste")
			(net "PCA9535_INT_N")
		)
		(pad "2" smd rect
			(at 2.925064 2.921 270)
			(size 0.3556 1.4986)
			(layers "B.Cu" "B.Mask" "B.Paste")
			(net "N21699710")
		)
		(pad "3" smd rect
			(at 2.275078 2.921 270)
			(size 0.3556 1.4986)
			(layers "B.Cu" "B.Mask" "B.Paste")
			(net "N21700864")
		)
		(pad "4" smd rect
			(at 1.625092 2.921 270)
			(size 0.3556 1.4986)
			(layers "B.Cu" "B.Mask" "B.Paste")
			(net "PSU1_AC_OK")
		)
		(pad "5" smd rect
			(at 0.975106 2.921 270)
			(size 0.3556 1.4986)
			(layers "B.Cu" "B.Mask" "B.Paste")
			(net "PSU2_AC_OK")
		)
		(pad "6" smd rect
			(at 0.32512 2.921 270)
			(size 0.3556 1.4986)
			(layers "B.Cu" "B.Mask" "B.Paste")
			(net "PSU3_AC_OK")
		)
		(pad "7" smd rect
			(at -0.32512 2.921 270)
			(size 0.3556 1.4986)
			(layers "B.Cu" "B.Mask" "B.Paste")
			(net "PSU4_AC_OK")
		)
		(pad "8" smd rect
			(at -0.975106 2.921 270)
			(size 0.3556 1.4986)
			(layers "B.Cu" "B.Mask" "B.Paste")
			(net "PSU5_AC_OK")
		)
		(pad "9" smd rect
			(at -1.625092 2.921 270)
			(size 0.3556 1.4986)
			(layers "B.Cu" "B.Mask" "B.Paste")
			(net "PSU6_AC_OK")
		)
		(pad "10" smd rect
			(at -2.275078 2.921 270)
			(size 0.3556 1.4986)
			(layers "B.Cu" "B.Mask" "B.Paste")
			(net "PSU1_DC_OK")
		)
		(pad "11" smd rect
			(at -2.925064 2.921 270)
			(size 0.3556 1.4986)
			(layers "B.Cu" "B.Mask" "B.Paste")
			(net "PSU2_DC_OK")
		)
		(pad "12" smd rect
			(at -3.57505 2.921 270)
			(size 0.3556 1.4986)
			(layers "B.Cu" "B.Mask" "B.Paste")
			(net "GND")
		)
		(pad "13" smd rect
			(at -3.57505 -2.921 270)
			(size 0.3556 1.4986)
			(layers "B.Cu" "B.Mask" "B.Paste")
			(net "PSU3_DC_OK")
		)
		(pad "14" smd rect
			(at -2.925064 -2.921 270)
			(size 0.3556 1.4986)
			(layers "B.Cu" "B.Mask" "B.Paste")
			(net "PSU4_DC_OK")
		)
		(pad "15" smd rect
			(at -2.275078 -2.921 270)
			(size 0.3556 1.4986)
			(layers "B.Cu" "B.Mask" "B.Paste")
			(net "PSU5_DC_OK")
		)
		(pad "16" smd rect
			(at -1.625092 -2.921 270)
			(size 0.3556 1.4986)
			(layers "B.Cu" "B.Mask" "B.Paste")
			(net "PSU6_DC_OK")
		)
		(pad "17" smd rect
			(at -0.975106 -2.921 270)
			(size 0.3556 1.4986)
			(layers "B.Cu" "B.Mask" "B.Paste")
			(net "PSU_ALERT_N")
		)
		(pad "18" smd rect
			(at -0.32512 -2.921 270)
			(size 0.3556 1.4986)
			(layers "B.Cu" "B.Mask" "B.Paste")
			(net "Net_48")
		)
		(pad "19" smd rect
			(at 0.32512 -2.921 270)
			(size 0.3556 1.4986)
			(layers "B.Cu" "B.Mask" "B.Paste")
			(net "CPLD_THRMTRIP_LOG_N")
		)
		(pad "20" smd rect
			(at 0.975106 -2.921 270)
			(size 0.3556 1.4986)
			(layers "B.Cu" "B.Mask" "B.Paste")
			(net "Net_294")
		)
		(pad "21" smd rect
			(at 1.625092 -2.921 270)
			(size 0.3556 1.4986)
			(layers "B.Cu" "B.Mask" "B.Paste")
			(net "N21699710")
		)
		(pad "22" smd rect
			(at 2.275078 -2.921 270)
			(size 0.3556 1.4986)
			(layers "B.Cu" "B.Mask" "B.Paste")
			(net "I2C_COM3_SCL")
		)
		(pad "23" smd rect
			(at 2.925064 -2.921 270)
			(size 0.3556 1.4986)
			(layers "B.Cu" "B.Mask" "B.Paste")
			(net "I2C_COM3_SDA")
		)
		(pad "24" smd rect
			(at 3.57505 -2.921 270)
			(size 0.3556 1.4986)
			(layers "B.Cu" "B.Mask" "B.Paste")
			(net "P3V3_NODE1")
		)
	)
	(footprint ""
		(layer "B.Cu")
		(at 70.665086 -131.153662 90)
		(property "Reference" "C279"
			(at -55.911242 -38.443916 270)
			(unlocked yes)
			(layer "B.SilkS")
			(effects
				(font
					(size 0.7874 0.5842)
					(thickness 0.1524)
				)
				(justify left mirror)
			)
		)
		(property "Value" ""
			(at 0 0 90)
			(layer "B.Fab")
			(effects
				(font
					(size 1.27 1.27)
				)
				(justify mirror)
			)
		)
		(duplicate_pad_numbers_are_jumpers no)
		(fp_line
			(start 0.7874 -0.4064)
			(end -0.7874 -0.4064)
			(stroke
				(width 0.1524)
				(type default)
			)
			(layer "B.SilkS")
		)
		(fp_line
			(start -0.7874 -0.4064)
			(end -0.7874 0.4064)
			(stroke
				(width 0.1524)
				(type default)
			)
			(layer "B.SilkS")
		)
		(fp_line
			(start 0 0.381)
			(end 0 -0.381)
			(stroke
				(width 0.1524)
				(type default)
			)
			(layer "B.SilkS")
		)
		(fp_line
			(start 0.7874 0.4064)
			(end 0.7874 -0.4064)
			(stroke
				(width 0.1524)
				(type default)
			)
			(layer "B.SilkS")
		)
		(fp_line
			(start -0.7874 0.4064)
			(end 0.7874 0.4064)
			(stroke
				(width 0.1524)
				(type default)
			)
			(layer "B.SilkS")
		)
		(fp_poly
			(pts
				(xy 0.5334 0.254) (xy 0.635 0.254) (xy 0.635 0.2286) (xy 0.635 -0.254) (xy 0.5334 -0.254) (xy 0.5334 -0.2794)
				(xy -0.5334 -0.2794) (xy -0.5334 -0.254) (xy -0.635 -0.254) (xy -0.635 0.254) (xy -0.5334 0.254)
				(xy -0.5334 0.2794) (xy 0.508 0.2794) (xy 0.5334 0.2794)
			)
			(stroke
				(width 0)
				(type default)
			)
			(fill no)
			(layer "B.CrtYd")
		)
		(pad "1" smd rect
			(at -0.40005 0 270)
			(size 0.4572 0.508)
			(layers "B.Cu" "B.Mask" "B.Paste")
			(net "P3V3_NODE1")
		)
		(pad "2" smd rect
			(at 0.40005 0 270)
			(size 0.4572 0.508)
			(layers "B.Cu" "B.Mask" "B.Paste")
			(net "GND")
		)
	)
	(footprint ""
		(layer "B.Cu")
		(at 50.974498 -96.696784 -90)
		(property "Reference" "R79"
			(at -6.405118 4.4958 270)
			(unlocked yes)
			(layer "B.SilkS")
			(effects
				(font
					(size 0.7874 0.5842)
					(thickness 0.1524)
				)
				(justify left mirror)
			)
		)
		(property "Value" ""
			(at 0 0 90)
			(layer "B.Fab")
			(effects
				(font
					(size 1.27 1.27)
				)
				(justify mirror)
			)
		)
		(duplicate_pad_numbers_are_jumpers no)
		(fp_line
			(start -0.7874 0.4064)
			(end 0.7874 0.4064)
			(stroke
				(width 0.1524)
				(type default)
			)
			(layer "B.SilkS")
		)
		(fp_line
			(start 0.7874 0.4064)
			(end 0.7874 -0.4064)
			(stroke
				(width 0.1524)
				(type default)
			)
			(layer "B.SilkS")
		)
		(fp_line
			(start -0.7874 -0.4064)
			(end -0.7874 0.4064)
			(stroke
				(width 0.1524)
				(type default)
			)
			(layer "B.SilkS")
		)
		(fp_line
			(start 0.7874 -0.4064)
			(end -0.7874 -0.4064)
			(stroke
				(width 0.1524)
				(type default)
			)
			(layer "B.SilkS")
		)
		(fp_poly
			(pts
				(xy 0.508 0.2794) (xy 0.508 0.2286) (xy 0.635 0.2286) (xy 0.635 -0.254) (xy 0.5334 -0.254) (xy 0.5334 -0.2794)
				(xy -0.5334 -0.2794) (xy -0.5334 -0.254) (xy -0.635 -0.254) (xy -0.635 0.254) (xy -0.5334 0.254)
				(xy -0.5334 0.2794)
			)
			(stroke
				(width 0)
				(type default)
			)
			(fill no)
			(layer "B.CrtYd")
		)
		(pad "1" smd rect
			(at -0.40005 0 90)
			(size 0.4572 0.508)
			(layers "B.Cu" "B.Mask" "B.Paste")
			(net "GND")
		)
		(pad "2" smd rect
			(at 0.40005 0 90)
			(size 0.4572 0.508)
			(layers "B.Cu" "B.Mask" "B.Paste")
			(net "PD_CPU_NODE1_DFX_GPIO_GRP0_7")
		)
	)
	(footprint ""
		(layer "B.Cu")
		(at 163.128452 -100.83419 180)
		(property "Reference" "C374"
			(at -4.541012 0.095504 0)
			(unlocked yes)
			(layer "B.SilkS")
			(effects
				(font
					(size 0.7874 0.5842)
					(thickness 0.1524)
				)
				(justify left mirror)
			)
		)
		(property "Value" ""
			(at 0 0 0)
			(layer "B.Fab")
			(effects
				(font
					(size 1.27 1.27)
				)
				(justify mirror)
			)
		)
		(duplicate_pad_numbers_are_jumpers no)
		(fp_line
			(start 0.7874 0.4064)
			(end 0.7874 -0.4064)
			(stroke
				(width 0.1524)
				(type default)
			)
			(layer "B.SilkS")
		)
		(fp_line
			(start 0.7874 -0.4064)
			(end -0.7874 -0.4064)
			(stroke
				(width 0.1524)
				(type default)
			)
			(layer "B.SilkS")
		)
		(fp_line
			(start 0 0.381)
			(end 0 -0.381)
			(stroke
				(width 0.1524)
				(type default)
			)
			(layer "B.SilkS")
		)
		(fp_line
			(start -0.7874 0.4064)
			(end 0.7874 0.4064)
			(stroke
				(width 0.1524)
				(type default)
			)
			(layer "B.SilkS")
		)
		(fp_line
			(start -0.7874 -0.4064)
			(end -0.7874 0.4064)
			(stroke
				(width 0.1524)
				(type default)
			)
			(layer "B.SilkS")
		)
		(fp_poly
			(pts
				(xy 0.5334 0.254) (xy 0.635 0.254) (xy 0.635 0.2286) (xy 0.635 -0.254) (xy 0.5334 -0.254) (xy 0.5334 -0.2794)
				(xy -0.5334 -0.2794) (xy -0.5334 -0.254) (xy -0.635 -0.254) (xy -0.635 0.254) (xy -0.5334 0.254)
				(xy -0.5334 0.2794) (xy 0.508 0.2794) (xy 0.5334 0.2794)
			)
			(stroke
				(width 0)
				(type default)
			)
			(fill no)
			(layer "B.CrtYd")
		)
		(pad "1" smd rect
			(at -0.40005 0)
			(size 0.4572 0.508)
			(layers "B.Cu" "B.Mask" "B.Paste")
			(net "GND")
		)
		(pad "2" smd rect
			(at 0.40005 0)
			(size 0.4572 0.508)
			(layers "B.Cu" "B.Mask" "B.Paste")
			(net "P1V05_NODE1")
		)
	)
	(footprint ""
		(layer "B.Cu")
		(at 72.319896 -125.124972 -90)
		(property "Reference" "L17"
			(at 2.831846 -8.211566 270)
			(unlocked yes)
			(layer "B.SilkS")
			(effects
				(font
					(size 0.7874 0.5842)
					(thickness 0.1524)
				)
				(justify mirror)
			)
		)
		(property "Value" ""
			(at 0 0 90)
			(layer "B.Fab")
			(effects
				(font
					(size 1.27 1.27)
				)
				(justify mirror)
			)
		)
		(duplicate_pad_numbers_are_jumpers no)
		(fp_line
			(start -1.2954 0.635)
			(end 1.2954 0.635)
			(stroke
				(width 0.1524)
				(type default)
			)
			(layer "B.SilkS")
		)
		(fp_line
			(start -0.127 -0.5842)
			(end -0.127 0.5842)
			(stroke
				(width 0.1524)
				(type default)
			)
			(layer "B.SilkS")
		)
		(fp_line
			(start 0.127 -0.5842)
			(end 0.127 0.5842)
			(stroke
				(width 0.1524)
				(type default)
			)
			(layer "B.SilkS")
		)
		(fp_line
			(start -1.2954 -0.635)
			(end -1.2954 0.635)
			(stroke
				(width 0.1524)
				(type default)
			)
			(layer "B.SilkS")
		)
		(fp_line
			(start 1.2954 -0.635)
			(end 1.2954 0.635)
			(stroke
				(width 0.1524)
				(type default)
			)
			(layer "B.SilkS")
		)
		(fp_line
			(start 1.2954 -0.635)
			(end -1.2954 -0.635)
			(stroke
				(width 0.1524)
				(type default)
			)
			(layer "B.SilkS")
		)
		(fp_poly
			(pts
				(xy 0.9144 0.508) (xy 0.9144 0.3556) (xy 1.143 0.3556) (xy 1.143 -0.3556) (xy 0.9144 -0.3556) (xy 0.9144 -0.508)
				(xy -0.9144 -0.508) (xy -0.9144 -0.3556) (xy -1.143 -0.3556) (xy -1.143 0.3556) (xy -0.9144 0.3556)
				(xy -0.9144 0.508)
			)
			(stroke
				(width 0)
				(type default)
			)
			(fill no)
			(layer "B.CrtYd")
		)
		(pad "1" smd rect
			(at -0.7366 0)
			(size 0.7112 0.8128)
			(layers "B.Cu" "B.Mask" "B.Paste")
			(net "BMC_NODE1_VCC_1V8_PCIE")
		)
		(pad "2" smd rect
			(at 0.7366 0)
			(size 0.7112 0.8128)
			(layers "B.Cu" "B.Mask" "B.Paste")
			(net "P1V8_NODE1")
		)
	)
	(footprint ""
		(layer "B.Cu")
		(at 63.166498 -96.696784 -90)
		(property "Reference" "R66"
			(at -6.314948 5.033264 270)
			(unlocked yes)
			(layer "B.SilkS")
			(effects
				(font
					(size 0.7874 0.5842)
					(thickness 0.1524)
				)
				(justify left mirror)
			)
		)
		(property "Value" ""
			(at 0 0 90)
			(layer "B.Fab")
			(effects
				(font
					(size 1.27 1.27)
				)
				(justify mirror)
			)
		)
		(duplicate_pad_numbers_are_jumpers no)
		(fp_line
			(start -0.7874 0.4064)
			(end 0.7874 0.4064)
			(stroke
				(width 0.1524)
				(type default)
			)
			(layer "B.SilkS")
		)
		(fp_line
			(start 0.7874 0.4064)
			(end 0.7874 -0.4064)
			(stroke
				(width 0.1524)
				(type default)
			)
			(layer "B.SilkS")
		)
		(fp_line
			(start -0.7874 -0.4064)
			(end -0.7874 0.4064)
			(stroke
				(width 0.1524)
				(type default)
			)
			(layer "B.SilkS")
		)
		(fp_line
			(start 0.7874 -0.4064)
			(end -0.7874 -0.4064)
			(stroke
				(width 0.1524)
				(type default)
			)
			(layer "B.SilkS")
		)
		(fp_poly
			(pts
				(xy 0.508 0.2794) (xy 0.508 0.2286) (xy 0.635 0.2286) (xy 0.635 -0.254) (xy 0.5334 -0.254) (xy 0.5334 -0.2794)
				(xy -0.5334 -0.2794) (xy -0.5334 -0.254) (xy -0.635 -0.254) (xy -0.635 0.254) (xy -0.5334 0.254)
				(xy -0.5334 0.2794)
			)
			(stroke
				(width 0)
				(type default)
			)
			(fill no)
			(layer "B.CrtYd")
		)
		(pad "1" smd rect
			(at -0.40005 0 90)
			(size 0.4572 0.508)
			(layers "B.Cu" "B.Mask" "B.Paste")
			(net "IRQ_CPU_NODE1_SERIAL")
		)
		(pad "2" smd rect
			(at 0.40005 0 90)
			(size 0.4572 0.508)
			(layers "B.Cu" "B.Mask" "B.Paste")
			(net "IRQ_CPU_NODE1_SERIAL_R")
		)
	)
	(footprint ""
		(layer "B.Cu")
		(at 156.828998 -155.89123)
		(property "Reference" "C469"
			(at -3.464814 -0.180594 0)
			(unlocked yes)
			(layer "B.SilkS")
			(effects
				(font
					(size 0.7874 0.5842)
					(thickness 0.1524)
				)
				(justify left mirror)
			)
		)
		(property "Value" ""
			(at 0 0 0)
			(layer "B.Fab")
			(effects
				(font
					(size 1.27 1.27)
				)
				(justify mirror)
			)
		)
		(duplicate_pad_numbers_are_jumpers no)
		(fp_line
			(start -0.7874 -0.4064)
			(end -0.7874 0.4064)
			(stroke
				(width 0.1524)
				(type default)
			)
			(layer "B.SilkS")
		)
		(fp_line
			(start -0.7874 0.4064)
			(end 0.7874 0.4064)
			(stroke
				(width 0.1524)
				(type default)
			)
			(layer "B.SilkS")
		)
		(fp_line
			(start 0 0.381)
			(end 0 -0.381)
			(stroke
				(width 0.1524)
				(type default)
			)
			(layer "B.SilkS")
		)
		(fp_line
			(start 0.7874 -0.4064)
			(end -0.7874 -0.4064)
			(stroke
				(width 0.1524)
				(type default)
			)
			(layer "B.SilkS")
		)
		(fp_line
			(start 0.7874 0.4064)
			(end 0.7874 -0.4064)
			(stroke
				(width 0.1524)
				(type default)
			)
			(layer "B.SilkS")
		)
		(fp_poly
			(pts
				(xy 0.5334 0.254) (xy 0.635 0.254) (xy 0.635 0.2286) (xy 0.635 -0.254) (xy 0.5334 -0.254) (xy 0.5334 -0.2794)
				(xy -0.5334 -0.2794) (xy -0.5334 -0.254) (xy -0.635 -0.254) (xy -0.635 0.254) (xy -0.5334 0.254)
				(xy -0.5334 0.2794) (xy 0.508 0.2794) (xy 0.5334 0.2794)
			)
			(stroke
				(width 0)
				(type default)
			)
			(fill no)
			(layer "B.CrtYd")
		)
		(pad "1" smd rect
			(at -0.40005 0 180)
			(size 0.4572 0.508)
			(layers "B.Cu" "B.Mask" "B.Paste")
			(net "P1V9_LAN2")
		)
		(pad "2" smd rect
			(at 0.40005 0 180)
			(size 0.4572 0.508)
			(layers "B.Cu" "B.Mask" "B.Paste")
			(net "GND")
		)
	)
	(footprint ""
		(layer "B.Cu")
		(at 52.885086 -123.152662 90)
		(property "Reference" "C296"
			(at -55.125874 -42.30497 270)
			(unlocked yes)
			(layer "B.SilkS")
			(effects
				(font
					(size 0.7874 0.5842)
					(thickness 0.1524)
				)
				(justify left mirror)
			)
		)
		(property "Value" ""
			(at 0 0 90)
			(layer "B.Fab")
			(effects
				(font
					(size 1.27 1.27)
				)
				(justify mirror)
			)
		)
		(duplicate_pad_numbers_are_jumpers no)
		(fp_line
			(start 0.7874 -0.4064)
			(end -0.7874 -0.4064)
			(stroke
				(width 0.1524)
				(type default)
			)
			(layer "B.SilkS")
		)
		(fp_line
			(start -0.7874 -0.4064)
			(end -0.7874 0.4064)
			(stroke
				(width 0.1524)
				(type default)
			)
			(layer "B.SilkS")
		)
		(fp_line
			(start 0 0.381)
			(end 0 -0.381)
			(stroke
				(width 0.1524)
				(type default)
			)
			(layer "B.SilkS")
		)
		(fp_line
			(start 0.7874 0.4064)
			(end 0.7874 -0.4064)
			(stroke
				(width 0.1524)
				(type default)
			)
			(layer "B.SilkS")
		)
		(fp_line
			(start -0.7874 0.4064)
			(end 0.7874 0.4064)
			(stroke
				(width 0.1524)
				(type default)
			)
			(layer "B.SilkS")
		)
		(fp_poly
			(pts
				(xy 0.5334 0.254) (xy 0.635 0.254) (xy 0.635 0.2286) (xy 0.635 -0.254) (xy 0.5334 -0.254) (xy 0.5334 -0.2794)
				(xy -0.5334 -0.2794) (xy -0.5334 -0.254) (xy -0.635 -0.254) (xy -0.635 0.254) (xy -0.5334 0.254)
				(xy -0.5334 0.2794) (xy 0.508 0.2794) (xy 0.5334 0.2794)
			)
			(stroke
				(width 0)
				(type default)
			)
			(fill no)
			(layer "B.CrtYd")
		)
		(pad "1" smd rect
			(at -0.40005 0 270)
			(size 0.4572 0.508)
			(layers "B.Cu" "B.Mask" "B.Paste")
			(net "BMC_NODE1_V1PLLAV12")
		)
		(pad "2" smd rect
			(at 0.40005 0 270)
			(size 0.4572 0.508)
			(layers "B.Cu" "B.Mask" "B.Paste")
			(net "GND")
		)
	)
	(footprint ""
		(layer "B.Cu")
		(at 137.65276 -184.951624 90)
		(property "Reference" "R867"
			(at 4.357624 -1.938528 270)
			(unlocked yes)
			(layer "B.SilkS")
			(effects
				(font
					(size 0.7874 0.5842)
					(thickness 0.1524)
				)
				(justify left mirror)
			)
		)
		(property "Value" ""
			(at 0 0 90)
			(layer "B.Fab")
			(effects
				(font
					(size 1.27 1.27)
				)
				(justify mirror)
			)
		)
		(duplicate_pad_numbers_are_jumpers no)
		(fp_line
			(start 0.7874 -0.4064)
			(end -0.7874 -0.4064)
			(stroke
				(width 0.1524)
				(type default)
			)
			(layer "B.SilkS")
		)
		(fp_line
			(start -0.7874 -0.4064)
			(end -0.7874 0.4064)
			(stroke
				(width 0.1524)
				(type default)
			)
			(layer "B.SilkS")
		)
		(fp_line
			(start 0.7874 0.4064)
			(end 0.7874 -0.4064)
			(stroke
				(width 0.1524)
				(type default)
			)
			(layer "B.SilkS")
		)
		(fp_line
			(start -0.7874 0.4064)
			(end 0.7874 0.4064)
			(stroke
				(width 0.1524)
				(type default)
			)
			(layer "B.SilkS")
		)
		(fp_poly
			(pts
				(xy 0.508 0.2794) (xy 0.508 0.2286) (xy 0.635 0.2286) (xy 0.635 -0.254) (xy 0.5334 -0.254) (xy 0.5334 -0.2794)
				(xy -0.5334 -0.2794) (xy -0.5334 -0.254) (xy -0.635 -0.254) (xy -0.635 0.254) (xy -0.5334 0.254)
				(xy -0.5334 0.2794)
			)
			(stroke
				(width 0)
				(type default)
			)
			(fill no)
			(layer "B.CrtYd")
		)
		(pad "1" smd rect
			(at -0.40005 0 270)
			(size 0.4572 0.508)
			(layers "B.Cu" "B.Mask" "B.Paste")
			(net "T9_NODE3_EN")
		)
		(pad "2" smd rect
			(at 0.40005 0 270)
			(size 0.4572 0.508)
			(layers "B.Cu" "B.Mask" "B.Paste")
			(net "T9_NODE3_EN_R")
		)
	)
	(footprint ""
		(layer "B.Cu")
		(at 72.081644 -21.11248 90)
		(property "Reference" "C168"
			(at -5.822188 -0.810006 270)
			(unlocked yes)
			(layer "B.SilkS")
			(effects
				(font
					(size 0.7874 0.5842)
					(thickness 0.1524)
				)
				(justify left mirror)
			)
		)
		(property "Value" ""
			(at 0 0 90)
			(layer "B.Fab")
			(effects
				(font
					(size 1.27 1.27)
				)
				(justify mirror)
			)
		)
		(duplicate_pad_numbers_are_jumpers no)
		(fp_line
			(start 0.7874 -0.4064)
			(end -0.7874 -0.4064)
			(stroke
				(width 0.1524)
				(type default)
			)
			(layer "B.SilkS")
		)
		(fp_line
			(start -0.7874 -0.4064)
			(end -0.7874 0.4064)
			(stroke
				(width 0.1524)
				(type default)
			)
			(layer "B.SilkS")
		)
		(fp_line
			(start 0 0.381)
			(end 0 -0.381)
			(stroke
				(width 0.1524)
				(type default)
			)
			(layer "B.SilkS")
		)
		(fp_line
			(start 0.7874 0.4064)
			(end 0.7874 -0.4064)
			(stroke
				(width 0.1524)
				(type default)
			)
			(layer "B.SilkS")
		)
		(fp_line
			(start -0.7874 0.4064)
			(end 0.7874 0.4064)
			(stroke
				(width 0.1524)
				(type default)
			)
			(layer "B.SilkS")
		)
		(fp_poly
			(pts
				(xy 0.5334 0.254) (xy 0.635 0.254) (xy 0.635 0.2286) (xy 0.635 -0.254) (xy 0.5334 -0.254) (xy 0.5334 -0.2794)
				(xy -0.5334 -0.2794) (xy -0.5334 -0.254) (xy -0.635 -0.254) (xy -0.635 0.254) (xy -0.5334 0.254)
				(xy -0.5334 0.2794) (xy 0.508 0.2794) (xy 0.5334 0.2794)
			)
			(stroke
				(width 0)
				(type default)
			)
			(fill no)
			(layer "B.CrtYd")
		)
		(pad "1" smd rect
			(at -0.40005 0 270)
			(size 0.4572 0.508)
			(layers "B.Cu" "B.Mask" "B.Paste")
			(net "PV_VDDR_NODE1")
		)
		(pad "2" smd rect
			(at 0.40005 0 270)
			(size 0.4572 0.508)
			(layers "B.Cu" "B.Mask" "B.Paste")
			(net "GND")
		)
	)
	(footprint ""
		(layer "B.Cu")
		(at 37.929312 -156.14269 180)
		(property "Reference" "C401"
			(at 6.960616 9.003792 0)
			(unlocked yes)
			(layer "B.SilkS")
			(effects
				(font
					(size 0.7874 0.5842)
					(thickness 0.1524)
				)
				(justify left mirror)
			)
		)
		(property "Value" ""
			(at 0 0 0)
			(layer "B.Fab")
			(effects
				(font
					(size 1.27 1.27)
				)
				(justify mirror)
			)
		)
		(duplicate_pad_numbers_are_jumpers no)
		(fp_line
			(start 0.7874 0.4064)
			(end 0.7874 -0.4064)
			(stroke
				(width 0.1524)
				(type default)
			)
			(layer "B.SilkS")
		)
		(fp_line
			(start 0.7874 -0.4064)
			(end -0.7874 -0.4064)
			(stroke
				(width 0.1524)
				(type default)
			)
			(layer "B.SilkS")
		)
		(fp_line
			(start 0 0.381)
			(end 0 -0.381)
			(stroke
				(width 0.1524)
				(type default)
			)
			(layer "B.SilkS")
		)
		(fp_line
			(start -0.7874 0.4064)
			(end 0.7874 0.4064)
			(stroke
				(width 0.1524)
				(type default)
			)
			(layer "B.SilkS")
		)
		(fp_line
			(start -0.7874 -0.4064)
			(end -0.7874 0.4064)
			(stroke
				(width 0.1524)
				(type default)
			)
			(layer "B.SilkS")
		)
		(fp_poly
			(pts
				(xy 0.5334 0.254) (xy 0.635 0.254) (xy 0.635 0.2286) (xy 0.635 -0.254) (xy 0.5334 -0.254) (xy 0.5334 -0.2794)
				(xy -0.5334 -0.2794) (xy -0.5334 -0.254) (xy -0.635 -0.254) (xy -0.635 0.254) (xy -0.5334 0.254)
				(xy -0.5334 0.2794) (xy 0.508 0.2794) (xy 0.5334 0.2794)
			)
			(stroke
				(width 0)
				(type default)
			)
			(fill no)
			(layer "B.CrtYd")
		)
		(pad "1" smd rect
			(at -0.40005 0)
			(size 0.4572 0.508)
			(layers "B.Cu" "B.Mask" "B.Paste")
			(net "P1V9_LAN1")
		)
		(pad "2" smd rect
			(at 0.40005 0)
			(size 0.4572 0.508)
			(layers "B.Cu" "B.Mask" "B.Paste")
			(net "GND")
		)
	)
	(footprint ""
		(layer "B.Cu")
		(at 107.42676 -185.205624 -90)
		(property "Reference" "C607"
			(at -3.957828 -0.28448 270)
			(unlocked yes)
			(layer "B.SilkS")
			(effects
				(font
					(size 0.7874 0.5842)
					(thickness 0.1524)
				)
				(justify left mirror)
			)
		)
		(property "Value" ""
			(at 0 0 90)
			(layer "B.Fab")
			(effects
				(font
					(size 1.27 1.27)
				)
				(justify mirror)
			)
		)
		(duplicate_pad_numbers_are_jumpers no)
		(fp_line
			(start -0.7874 0.406146)
			(end 0.7874 0.406146)
			(stroke
				(width 0.1524)
				(type default)
			)
			(layer "B.SilkS")
		)
		(fp_line
			(start 0.7874 0.406146)
			(end 0.7874 -0.406146)
			(stroke
				(width 0.1524)
				(type default)
			)
			(layer "B.SilkS")
		)
		(fp_line
			(start 0 0.381)
			(end 0 -0.381)
			(stroke
				(width 0.1524)
				(type default)
			)
			(layer "B.SilkS")
		)
		(fp_line
			(start -0.7874 -0.406146)
			(end -0.7874 0.406146)
			(stroke
				(width 0.1524)
				(type default)
			)
			(layer "B.SilkS")
		)
		(fp_line
			(start 0.7874 -0.406146)
			(end -0.7874 -0.406146)
			(stroke
				(width 0.1524)
				(type default)
			)
			(layer "B.SilkS")
		)
		(fp_poly
			(pts
				(xy 0.5334 0.254) (xy 0.635 0.254) (xy 0.635 0.2286) (xy 0.635 -0.254) (xy 0.5334 -0.254) (xy 0.5334 -0.2794)
				(xy -0.5334 -0.2794) (xy -0.5334 -0.254) (xy -0.635 -0.254) (xy -0.635 0.254) (xy -0.5334 0.254)
				(xy -0.5334 0.2794) (xy 0.508 0.2794) (xy 0.5334 0.2794)
			)
			(stroke
				(width 0)
				(type default)
			)
			(fill no)
			(layer "B.CrtYd")
		)
		(pad "1" smd rect
			(at -0.40005 0 90)
			(size 0.4572 0.508)
			(layers "B.Cu" "B.Mask" "B.Paste")
			(net "PSU_ALERT_N")
		)
		(pad "2" smd rect
			(at 0.40005 0 90)
			(size 0.4572 0.508)
			(layers "B.Cu" "B.Mask" "B.Paste")
			(net "GND")
		)
	)
	(footprint ""
		(layer "B.Cu")
		(at 49.32299 -88.495886 90)
		(property "Reference" "R99"
			(at 0.90297 0.28575 270)
			(unlocked yes)
			(layer "B.SilkS")
			(effects
				(font
					(size 0.7874 0.5842)
					(thickness 0.1524)
				)
				(justify left mirror)
			)
		)
		(property "Value" ""
			(at 0 0 90)
			(layer "B.Fab")
			(effects
				(font
					(size 1.27 1.27)
				)
				(justify mirror)
			)
		)
		(duplicate_pad_numbers_are_jumpers no)
		(fp_line
			(start 0.7874 -0.4064)
			(end -0.7874 -0.4064)
			(stroke
				(width 0.1524)
				(type default)
			)
			(layer "B.SilkS")
		)
		(fp_line
			(start -0.7874 -0.4064)
			(end -0.7874 0.4064)
			(stroke
				(width 0.1524)
				(type default)
			)
			(layer "B.SilkS")
		)
		(fp_line
			(start 0.7874 0.4064)
			(end 0.7874 -0.4064)
			(stroke
				(width 0.1524)
				(type default)
			)
			(layer "B.SilkS")
		)
		(fp_line
			(start -0.7874 0.4064)
			(end 0.7874 0.4064)
			(stroke
				(width 0.1524)
				(type default)
			)
			(layer "B.SilkS")
		)
		(fp_poly
			(pts
				(xy 0.508 0.2794) (xy 0.508 0.2286) (xy 0.635 0.2286) (xy 0.635 -0.254) (xy 0.5334 -0.254) (xy 0.5334 -0.2794)
				(xy -0.5334 -0.2794) (xy -0.5334 -0.254) (xy -0.635 -0.254) (xy -0.635 0.254) (xy -0.5334 0.254)
				(xy -0.5334 0.2794)
			)
			(stroke
				(width 0)
				(type default)
			)
			(fill no)
			(layer "B.CrtYd")
		)
		(pad "1" smd rect
			(at -0.40005 0 270)
			(size 0.4572 0.508)
			(layers "B.Cu" "B.Mask" "B.Paste")
			(net "PD_NODE1_NTB_CLKINN")
		)
		(pad "2" smd rect
			(at 0.40005 0 270)
			(size 0.4572 0.508)
			(layers "B.Cu" "B.Mask" "B.Paste")
			(net "GND")
		)
	)
	(footprint ""
		(layer "B.Cu")
		(at 144.909032 -39.726616)
		(property "Reference" "R816"
			(at 1.24714 17.425924 0)
			(unlocked yes)
			(layer "B.SilkS")
			(effects
				(font
					(size 0.7874 0.5842)
					(thickness 0.1524)
				)
				(justify left mirror)
			)
		)
		(property "Value" ""
			(at 0 0 0)
			(layer "B.Fab")
			(effects
				(font
					(size 1.27 1.27)
				)
				(justify mirror)
			)
		)
		(duplicate_pad_numbers_are_jumpers no)
		(fp_line
			(start -0.7874 -0.4064)
			(end -0.7874 0.4064)
			(stroke
				(width 0.1524)
				(type default)
			)
			(layer "B.SilkS")
		)
		(fp_line
			(start -0.7874 0.4064)
			(end 0.7874 0.4064)
			(stroke
				(width 0.1524)
				(type default)
			)
			(layer "B.SilkS")
		)
		(fp_line
			(start 0.7874 -0.4064)
			(end -0.7874 -0.4064)
			(stroke
				(width 0.1524)
				(type default)
			)
			(layer "B.SilkS")
		)
		(fp_line
			(start 0.7874 0.4064)
			(end 0.7874 -0.4064)
			(stroke
				(width 0.1524)
				(type default)
			)
			(layer "B.SilkS")
		)
		(fp_poly
			(pts
				(xy 0.508 0.2794) (xy 0.508 0.2286) (xy 0.635 0.2286) (xy 0.635 -0.254) (xy 0.5334 -0.254) (xy 0.5334 -0.2794)
				(xy -0.5334 -0.2794) (xy -0.5334 -0.254) (xy -0.635 -0.254) (xy -0.635 0.254) (xy -0.5334 0.254)
				(xy -0.5334 0.2794)
			)
			(stroke
				(width 0)
				(type default)
			)
			(fill no)
			(layer "B.CrtYd")
		)
		(pad "1" smd rect
			(at -0.40005 0 180)
			(size 0.4572 0.508)
			(layers "B.Cu" "B.Mask" "B.Paste")
			(net "SIO_JTAG_CPLD2_TCK_R")
		)
		(pad "2" smd rect
			(at 0.40005 0 180)
			(size 0.4572 0.508)
			(layers "B.Cu" "B.Mask" "B.Paste")
			(net "P3V3_NODE1")
		)
	)
	(footprint ""
		(layer "B.Cu")
		(at 32.639 -187.7314 180)
		(property "Reference" "R1331"
			(at -1.3462 -1.01727 0)
			(unlocked yes)
			(layer "B.SilkS")
			(effects
				(font
					(size 0.7874 0.5842)
					(thickness 0.1524)
				)
				(justify left mirror)
			)
		)
		(property "Value" ""
			(at 0 0 0)
			(layer "B.Fab")
			(effects
				(font
					(size 1.27 1.27)
				)
				(justify mirror)
			)
		)
		(duplicate_pad_numbers_are_jumpers no)
		(fp_line
			(start 0.7874 0.4064)
			(end 0.7874 -0.4064)
			(stroke
				(width 0.1524)
				(type default)
			)
			(layer "B.SilkS")
		)
		(fp_line
			(start 0.7874 -0.4064)
			(end -0.7874 -0.4064)
			(stroke
				(width 0.1524)
				(type default)
			)
			(layer "B.SilkS")
		)
		(fp_line
			(start -0.7874 0.4064)
			(end 0.7874 0.4064)
			(stroke
				(width 0.1524)
				(type default)
			)
			(layer "B.SilkS")
		)
		(fp_line
			(start -0.7874 -0.4064)
			(end -0.7874 0.4064)
			(stroke
				(width 0.1524)
				(type default)
			)
			(layer "B.SilkS")
		)
		(fp_poly
			(pts
				(xy 0.508 0.2794) (xy 0.508 0.2286) (xy 0.635 0.2286) (xy 0.635 -0.254) (xy 0.5334 -0.254) (xy 0.5334 -0.2794)
				(xy -0.5334 -0.2794) (xy -0.5334 -0.254) (xy -0.635 -0.254) (xy -0.635 0.254) (xy -0.5334 0.254)
				(xy -0.5334 0.2794)
			)
			(stroke
				(width 0)
				(type default)
			)
			(fill no)
			(layer "B.CrtYd")
		)
		(pad "1" smd rect
			(at -0.40005 0)
			(size 0.4572 0.508)
			(layers "B.Cu" "B.Mask" "B.Paste")
			(net "UART_RI_P6_L_N_R")
		)
		(pad "2" smd rect
			(at 0.40005 0)
			(size 0.4572 0.508)
			(layers "B.Cu" "B.Mask" "B.Paste")
			(net "UART_RI_P6_L_N")
		)
	)
	(footprint ""
		(layer "B.Cu")
		(at 141.233652 -137.24255)
		(property "Reference" "C330"
			(at 4.0894 -2.773172 0)
			(unlocked yes)
			(layer "B.SilkS")
			(effects
				(font
					(size 0.7874 0.5842)
					(thickness 0.1524)
				)
				(justify left mirror)
			)
		)
		(property "Value" ""
			(at 0 0 0)
			(layer "B.Fab")
			(effects
				(font
					(size 1.27 1.27)
				)
				(justify mirror)
			)
		)
		(duplicate_pad_numbers_are_jumpers no)
		(fp_line
			(start -0.7874 -0.4064)
			(end -0.7874 0.4064)
			(stroke
				(width 0.1524)
				(type default)
			)
			(layer "B.SilkS")
		)
		(fp_line
			(start -0.7874 0.4064)
			(end 0.7874 0.4064)
			(stroke
				(width 0.1524)
				(type default)
			)
			(layer "B.SilkS")
		)
		(fp_line
			(start 0 0.381)
			(end 0 -0.381)
			(stroke
				(width 0.1524)
				(type default)
			)
			(layer "B.SilkS")
		)
		(fp_line
			(start 0.7874 -0.4064)
			(end -0.7874 -0.4064)
			(stroke
				(width 0.1524)
				(type default)
			)
			(layer "B.SilkS")
		)
		(fp_line
			(start 0.7874 0.4064)
			(end 0.7874 -0.4064)
			(stroke
				(width 0.1524)
				(type default)
			)
			(layer "B.SilkS")
		)
		(fp_poly
			(pts
				(xy 0.5334 0.254) (xy 0.635 0.254) (xy 0.635 0.2286) (xy 0.635 -0.254) (xy 0.5334 -0.254) (xy 0.5334 -0.2794)
				(xy -0.5334 -0.2794) (xy -0.5334 -0.254) (xy -0.635 -0.254) (xy -0.635 0.254) (xy -0.5334 0.254)
				(xy -0.5334 0.2794) (xy 0.508 0.2794) (xy 0.5334 0.2794)
			)
			(stroke
				(width 0)
				(type default)
			)
			(fill no)
			(layer "B.CrtYd")
		)
		(pad "1" smd rect
			(at -0.40005 0 180)
			(size 0.4572 0.508)
			(layers "B.Cu" "B.Mask" "B.Paste")
			(net "P1V0_NODE1")
		)
		(pad "2" smd rect
			(at 0.40005 0 180)
			(size 0.4572 0.508)
			(layers "B.Cu" "B.Mask" "B.Paste")
			(net "GND")
		)
	)
	(footprint ""
		(layer "B.Cu")
		(at 137.970006 -40.49141 180)
		(property "Reference" "R1065"
			(at 4.172458 -18.34261 0)
			(unlocked yes)
			(layer "B.SilkS")
			(effects
				(font
					(size 0.7874 0.5842)
					(thickness 0.1524)
				)
				(justify left mirror)
			)
		)
		(property "Value" ""
			(at 0 0 0)
			(layer "B.Fab")
			(effects
				(font
					(size 1.27 1.27)
				)
				(justify mirror)
			)
		)
		(duplicate_pad_numbers_are_jumpers no)
		(fp_line
			(start 0.7874 0.4064)
			(end 0.7874 -0.4064)
			(stroke
				(width 0.1524)
				(type default)
			)
			(layer "B.SilkS")
		)
		(fp_line
			(start 0.7874 -0.4064)
			(end -0.7874 -0.4064)
			(stroke
				(width 0.1524)
				(type default)
			)
			(layer "B.SilkS")
		)
		(fp_line
			(start -0.7874 0.4064)
			(end 0.7874 0.4064)
			(stroke
				(width 0.1524)
				(type default)
			)
			(layer "B.SilkS")
		)
		(fp_line
			(start -0.7874 -0.4064)
			(end -0.7874 0.4064)
			(stroke
				(width 0.1524)
				(type default)
			)
			(layer "B.SilkS")
		)
		(fp_poly
			(pts
				(xy 0.508 0.2794) (xy 0.508 0.2286) (xy 0.635 0.2286) (xy 0.635 -0.254) (xy 0.5334 -0.254) (xy 0.5334 -0.2794)
				(xy -0.5334 -0.2794) (xy -0.5334 -0.254) (xy -0.635 -0.254) (xy -0.635 0.254) (xy -0.5334 0.254)
				(xy -0.5334 0.2794)
			)
			(stroke
				(width 0)
				(type default)
			)
			(fill no)
			(layer "B.CrtYd")
		)
		(pad "1" smd rect
			(at -0.40005 0)
			(size 0.4572 0.508)
			(layers "B.Cu" "B.Mask" "B.Paste")
			(net "SIO_JTAG_CPLD2_TMS_R")
		)
		(pad "2" smd rect
			(at 0.40005 0)
			(size 0.4572 0.508)
			(layers "B.Cu" "B.Mask" "B.Paste")
			(net "P3V3_NODE1")
		)
	)
	(footprint ""
		(layer "B.Cu")
		(at 37.912802 -150.910798 180)
		(property "Reference" "C426"
			(at 6.961378 10.661396 0)
			(unlocked yes)
			(layer "B.SilkS")
			(effects
				(font
					(size 0.7874 0.5842)
					(thickness 0.1524)
				)
				(justify left mirror)
			)
		)
		(property "Value" ""
			(at 0 0 0)
			(layer "B.Fab")
			(effects
				(font
					(size 1.27 1.27)
				)
				(justify mirror)
			)
		)
		(duplicate_pad_numbers_are_jumpers no)
		(fp_line
			(start 0.7874 0.4064)
			(end 0.7874 -0.4064)
			(stroke
				(width 0.1524)
				(type default)
			)
			(layer "B.SilkS")
		)
		(fp_line
			(start 0.7874 -0.4064)
			(end -0.7874 -0.4064)
			(stroke
				(width 0.1524)
				(type default)
			)
			(layer "B.SilkS")
		)
		(fp_line
			(start 0 0.381)
			(end 0 -0.381)
			(stroke
				(width 0.1524)
				(type default)
			)
			(layer "B.SilkS")
		)
		(fp_line
			(start -0.7874 0.4064)
			(end 0.7874 0.4064)
			(stroke
				(width 0.1524)
				(type default)
			)
			(layer "B.SilkS")
		)
		(fp_line
			(start -0.7874 -0.4064)
			(end -0.7874 0.4064)
			(stroke
				(width 0.1524)
				(type default)
			)
			(layer "B.SilkS")
		)
		(fp_poly
			(pts
				(xy 0.5334 0.254) (xy 0.635 0.254) (xy 0.635 0.2286) (xy 0.635 -0.254) (xy 0.5334 -0.254) (xy 0.5334 -0.2794)
				(xy -0.5334 -0.2794) (xy -0.5334 -0.254) (xy -0.635 -0.254) (xy -0.635 0.254) (xy -0.5334 0.254)
				(xy -0.5334 0.2794) (xy 0.508 0.2794) (xy 0.5334 0.2794)
			)
			(stroke
				(width 0)
				(type default)
			)
			(fill no)
			(layer "B.CrtYd")
		)
		(pad "1" smd rect
			(at -0.40005 0)
			(size 0.4572 0.508)
			(layers "B.Cu" "B.Mask" "B.Paste")
			(net "P1V9_LAN1")
		)
		(pad "2" smd rect
			(at 0.40005 0)
			(size 0.4572 0.508)
			(layers "B.Cu" "B.Mask" "B.Paste")
			(net "GND")
		)
	)
	(footprint ""
		(layer "B.Cu")
		(at 135.196834 -39.407084 180)
		(property "Reference" "R1191"
			(at 5.415788 -18.226532 0)
			(unlocked yes)
			(layer "B.SilkS")
			(effects
				(font
					(size 0.7874 0.5842)
					(thickness 0.1524)
				)
				(justify left mirror)
			)
		)
		(property "Value" ""
			(at 0 0 0)
			(layer "B.Fab")
			(effects
				(font
					(size 1.27 1.27)
				)
				(justify mirror)
			)
		)
		(duplicate_pad_numbers_are_jumpers no)
		(fp_line
			(start 0.7874 0.4064)
			(end 0.7874 -0.4064)
			(stroke
				(width 0.1524)
				(type default)
			)
			(layer "B.SilkS")
		)
		(fp_line
			(start 0.7874 -0.4064)
			(end -0.7874 -0.4064)
			(stroke
				(width 0.1524)
				(type default)
			)
			(layer "B.SilkS")
		)
		(fp_line
			(start -0.7874 0.4064)
			(end 0.7874 0.4064)
			(stroke
				(width 0.1524)
				(type default)
			)
			(layer "B.SilkS")
		)
		(fp_line
			(start -0.7874 -0.4064)
			(end -0.7874 0.4064)
			(stroke
				(width 0.1524)
				(type default)
			)
			(layer "B.SilkS")
		)
		(fp_poly
			(pts
				(xy 0.508 0.2794) (xy 0.508 0.2286) (xy 0.635 0.2286) (xy 0.635 -0.254) (xy 0.5334 -0.254) (xy 0.5334 -0.2794)
				(xy -0.5334 -0.2794) (xy -0.5334 -0.254) (xy -0.635 -0.254) (xy -0.635 0.254) (xy -0.5334 0.254)
				(xy -0.5334 0.2794)
			)
			(stroke
				(width 0)
				(type default)
			)
			(fill no)
			(layer "B.CrtYd")
		)
		(pad "1" smd rect
			(at -0.40005 0)
			(size 0.4572 0.508)
			(layers "B.Cu" "B.Mask" "B.Paste")
			(net "SIO_JTAG_CPLD2_TMS")
		)
		(pad "2" smd rect
			(at 0.40005 0)
			(size 0.4572 0.508)
			(layers "B.Cu" "B.Mask" "B.Paste")
			(net "GND")
		)
	)
	(footprint ""
		(layer "B.Cu")
		(at 67.670172 -148.280628)
		(property "Reference" "PJ18"
			(at -0.278892 -0.415036 270)
			(unlocked yes)
			(layer "B.SilkS")
			(effects
				(font
					(size 0.7874 0.5842)
					(thickness 0.1524)
				)
				(justify left mirror)
			)
		)
		(property "Value" ""
			(at 0 0 0)
			(layer "B.Fab")
			(effects
				(font
					(size 1.27 1.27)
				)
				(justify mirror)
			)
		)
		(duplicate_pad_numbers_are_jumpers no)
		(fp_poly
			(pts
				(xy -0.2794 0.907796) (xy -0.254 0.907796) (xy -0.254 1.0414) (xy 0.254 1.0414) (xy 0.254 1.034796)
				(xy 0.254 0.933196) (xy 0.2794 0.933196) (xy 0.2794 -0.133604) (xy 0.254 -0.133604) (xy 0.254 -0.235204)
				(xy -0.254 -0.235204) (xy -0.254 -0.133604) (xy -0.2794 -0.133604)
			)
			(stroke
				(width 0)
				(type default)
			)
			(fill no)
			(layer "B.CrtYd")
		)
		(pad "1" smd custom
			(at 0 -0.000254 180)
			(size 0.127 0.127)
			(layers "B.Cu" "B.Mask" "B.Paste")
			(net "Net_466")
			(options
				(clearance outline)
				(anchor circle)
			)
			(primitives
				(gr_poly
					(pts
						(xy -0.127 -0.508) (xy -0.127 0.0508) (xy -0.254 0.0508) (xy -0.254 0.508) (xy 0.254 0.508) (xy 0.254 0.0508)
						(xy 0.127 0.0508) (xy 0.127 -0.508)
					)
					(width 0)
					(fill yes)
				)
			)
		)
		(pad "2" smd rect
			(at 0 0.799846 90)
			(size 0.4572 0.508)
			(layers "B.Cu" "B.Mask" "B.Paste")
			(net "BMC_DEBUG_RXD")
		)
		(zone
			(layer "B.Cu")
			(hatch none 0.5)
			(connect_pads
				(clearance 0)
			)
			(min_thickness 0.25)
			(keepout
				(tracks allowed)
				(vias not_allowed)
				(pads allowed)
				(copperpour not_allowed)
				(footprints allowed)
			)
			(placement
				(enabled no)
				(sheetname "")
			)
			(fill
				(thermal_gap 0.5)
				(thermal_bridge_width 0.5)
				(island_removal_mode 0)
			)
			(polygon
				(pts
					(xy 67.974972 -147.195032) (xy 67.365372 -147.195032) (xy 67.365372 -148.566632) (xy 67.974972 -148.566632)
				)
			)
		)
	)
	(footprint ""
		(layer "B.Cu")
		(at 158.48076 -184.951624 -90)
		(property "Reference" "C669"
			(at -4.230624 1.999488 270)
			(unlocked yes)
			(layer "B.SilkS")
			(effects
				(font
					(size 0.7874 0.5842)
					(thickness 0.1524)
				)
				(justify left mirror)
			)
		)
		(property "Value" ""
			(at 0 0 90)
			(layer "B.Fab")
			(effects
				(font
					(size 1.27 1.27)
				)
				(justify mirror)
			)
		)
		(duplicate_pad_numbers_are_jumpers no)
		(fp_line
			(start -0.7874 0.4064)
			(end 0.7874 0.4064)
			(stroke
				(width 0.1524)
				(type default)
			)
			(layer "B.SilkS")
		)
		(fp_line
			(start 0.7874 0.4064)
			(end 0.7874 -0.4064)
			(stroke
				(width 0.1524)
				(type default)
			)
			(layer "B.SilkS")
		)
		(fp_line
			(start 0 0.381)
			(end 0 -0.381)
			(stroke
				(width 0.1524)
				(type default)
			)
			(layer "B.SilkS")
		)
		(fp_line
			(start -0.7874 -0.4064)
			(end -0.7874 0.4064)
			(stroke
				(width 0.1524)
				(type default)
			)
			(layer "B.SilkS")
		)
		(fp_line
			(start 0.7874 -0.4064)
			(end -0.7874 -0.4064)
			(stroke
				(width 0.1524)
				(type default)
			)
			(layer "B.SilkS")
		)
		(fp_poly
			(pts
				(xy 0.5334 0.254) (xy 0.635 0.254) (xy 0.635 0.2286) (xy 0.635 -0.254) (xy 0.5334 -0.254) (xy 0.5334 -0.2794)
				(xy -0.5334 -0.2794) (xy -0.5334 -0.254) (xy -0.635 -0.254) (xy -0.635 0.254) (xy -0.5334 0.254)
				(xy -0.5334 0.2794) (xy 0.508 0.2794) (xy 0.5334 0.2794)
			)
			(stroke
				(width 0)
				(type default)
			)
			(fill no)
			(layer "B.CrtYd")
		)
		(pad "1" smd rect
			(at -0.40005 0 90)
			(size 0.4572 0.508)
			(layers "B.Cu" "B.Mask" "B.Paste")
			(net "T12_NODE4_EN_R")
		)
		(pad "2" smd rect
			(at 0.40005 0 90)
			(size 0.4572 0.508)
			(layers "B.Cu" "B.Mask" "B.Paste")
			(net "GND")
		)
	)
	(footprint ""
		(layer "B.Cu")
		(at 161.65576 -187.872624 90)
		(property "Reference" "R827"
			(at 4.565396 -4.179062 270)
			(unlocked yes)
			(layer "B.SilkS")
			(effects
				(font
					(size 0.7874 0.5842)
					(thickness 0.1524)
				)
				(justify left mirror)
			)
		)
		(property "Value" ""
			(at 0 0 90)
			(layer "B.Fab")
			(effects
				(font
					(size 1.27 1.27)
				)
				(justify mirror)
			)
		)
		(duplicate_pad_numbers_are_jumpers no)
		(fp_line
			(start 0.7874 -0.4064)
			(end -0.7874 -0.4064)
			(stroke
				(width 0.1524)
				(type default)
			)
			(layer "B.SilkS")
		)
		(fp_line
			(start -0.7874 -0.4064)
			(end -0.7874 0.4064)
			(stroke
				(width 0.1524)
				(type default)
			)
			(layer "B.SilkS")
		)
		(fp_line
			(start 0.7874 0.4064)
			(end 0.7874 -0.4064)
			(stroke
				(width 0.1524)
				(type default)
			)
			(layer "B.SilkS")
		)
		(fp_line
			(start -0.7874 0.4064)
			(end 0.7874 0.4064)
			(stroke
				(width 0.1524)
				(type default)
			)
			(layer "B.SilkS")
		)
		(fp_poly
			(pts
				(xy 0.508 0.2794) (xy 0.508 0.2286) (xy 0.635 0.2286) (xy 0.635 -0.254) (xy 0.5334 -0.254) (xy 0.5334 -0.2794)
				(xy -0.5334 -0.2794) (xy -0.5334 -0.254) (xy -0.635 -0.254) (xy -0.635 0.254) (xy -0.5334 0.254)
				(xy -0.5334 0.2794)
			)
			(stroke
				(width 0)
				(type default)
			)
			(fill no)
			(layer "B.CrtYd")
		)
		(pad "1" smd rect
			(at -0.40005 0 270)
			(size 0.4572 0.508)
			(layers "B.Cu" "B.Mask" "B.Paste")
			(net "FAN4_TACH")
		)
		(pad "2" smd rect
			(at 0.40005 0 270)
			(size 0.4572 0.508)
			(layers "B.Cu" "B.Mask" "B.Paste")
			(net "FAN4_TACH_R")
		)
	)
	(footprint ""
		(layer "B.Cu")
		(at 91.102434 -187.842398)
		(property "Reference" "C675"
			(at -2.352294 -3.283966 0)
			(unlocked yes)
			(layer "B.SilkS")
			(effects
				(font
					(size 0.7874 0.5842)
					(thickness 0.1524)
				)
				(justify left mirror)
			)
		)
		(property "Value" ""
			(at 0 0 0)
			(layer "B.Fab")
			(effects
				(font
					(size 1.27 1.27)
				)
				(justify mirror)
			)
		)
		(duplicate_pad_numbers_are_jumpers no)
		(fp_line
			(start -0.7874 -0.4064)
			(end -0.7874 0.4064)
			(stroke
				(width 0.1524)
				(type default)
			)
			(layer "B.SilkS")
		)
		(fp_line
			(start -0.7874 0.4064)
			(end 0.7874 0.4064)
			(stroke
				(width 0.1524)
				(type default)
			)
			(layer "B.SilkS")
		)
		(fp_line
			(start 0 0.381)
			(end 0 -0.381)
			(stroke
				(width 0.1524)
				(type default)
			)
			(layer "B.SilkS")
		)
		(fp_line
			(start 0.7874 -0.4064)
			(end -0.7874 -0.4064)
			(stroke
				(width 0.1524)
				(type default)
			)
			(layer "B.SilkS")
		)
		(fp_line
			(start 0.7874 0.4064)
			(end 0.7874 -0.4064)
			(stroke
				(width 0.1524)
				(type default)
			)
			(layer "B.SilkS")
		)
		(fp_poly
			(pts
				(xy 0.5334 0.254) (xy 0.635 0.254) (xy 0.635 0.2286) (xy 0.635 -0.254) (xy 0.5334 -0.254) (xy 0.5334 -0.2794)
				(xy -0.5334 -0.2794) (xy -0.5334 -0.254) (xy -0.635 -0.254) (xy -0.635 0.254) (xy -0.5334 0.254)
				(xy -0.5334 0.2794) (xy 0.508 0.2794) (xy 0.5334 0.2794)
			)
			(stroke
				(width 0)
				(type default)
			)
			(fill no)
			(layer "B.CrtYd")
		)
		(pad "1" smd rect
			(at -0.40005 0 180)
			(size 0.4572 0.508)
			(layers "B.Cu" "B.Mask" "B.Paste")
			(net "UART_T5_NODE1_TXD_R")
		)
		(pad "2" smd rect
			(at 0.40005 0 180)
			(size 0.4572 0.508)
			(layers "B.Cu" "B.Mask" "B.Paste")
			(net "GND")
		)
	)
	(footprint ""
		(layer "B.Cu")
		(at 137.668508 -46.952154 90)
		(property "Reference" "R1132"
			(at 3.212846 11.910822 270)
			(unlocked yes)
			(layer "B.SilkS")
			(effects
				(font
					(size 0.7874 0.5842)
					(thickness 0.1524)
				)
				(justify left mirror)
			)
		)
		(property "Value" ""
			(at 0 0 90)
			(layer "B.Fab")
			(effects
				(font
					(size 1.27 1.27)
				)
				(justify mirror)
			)
		)
		(duplicate_pad_numbers_are_jumpers no)
		(fp_line
			(start 0.7874 -0.4064)
			(end -0.7874 -0.4064)
			(stroke
				(width 0.1524)
				(type default)
			)
			(layer "B.SilkS")
		)
		(fp_line
			(start -0.7874 -0.4064)
			(end -0.7874 0.4064)
			(stroke
				(width 0.1524)
				(type default)
			)
			(layer "B.SilkS")
		)
		(fp_line
			(start 0.7874 0.4064)
			(end 0.7874 -0.4064)
			(stroke
				(width 0.1524)
				(type default)
			)
			(layer "B.SilkS")
		)
		(fp_line
			(start -0.7874 0.4064)
			(end 0.7874 0.4064)
			(stroke
				(width 0.1524)
				(type default)
			)
			(layer "B.SilkS")
		)
		(fp_poly
			(pts
				(xy 0.508 0.2794) (xy 0.508 0.2286) (xy 0.635 0.2286) (xy 0.635 -0.254) (xy 0.5334 -0.254) (xy 0.5334 -0.2794)
				(xy -0.5334 -0.2794) (xy -0.5334 -0.254) (xy -0.635 -0.254) (xy -0.635 0.254) (xy -0.5334 0.254)
				(xy -0.5334 0.2794)
			)
			(stroke
				(width 0)
				(type default)
			)
			(fill no)
			(layer "B.CrtYd")
		)
		(pad "1" smd rect
			(at -0.40005 0 270)
			(size 0.4572 0.508)
			(layers "B.Cu" "B.Mask" "B.Paste")
			(net "P5V_NODE1")
		)
		(pad "2" smd rect
			(at 0.40005 0 270)
			(size 0.4572 0.508)
			(layers "B.Cu" "B.Mask" "B.Paste")
			(net "UART_DTR_P3_R_N")
		)
	)
	(footprint ""
		(layer "B.Cu")
		(at 104.408224 -69.273674)
		(property "Reference" "R226"
			(at -4.704334 2.793746 0)
			(unlocked yes)
			(layer "B.SilkS")
			(effects
				(font
					(size 0.7874 0.5842)
					(thickness 0.1524)
				)
				(justify left mirror)
			)
		)
		(property "Value" ""
			(at 0 0 0)
			(layer "B.Fab")
			(effects
				(font
					(size 1.27 1.27)
				)
				(justify mirror)
			)
		)
		(duplicate_pad_numbers_are_jumpers no)
		(fp_line
			(start -0.7874 -0.4064)
			(end -0.7874 0.4064)
			(stroke
				(width 0.1524)
				(type default)
			)
			(layer "B.SilkS")
		)
		(fp_line
			(start -0.7874 0.4064)
			(end 0.7874 0.4064)
			(stroke
				(width 0.1524)
				(type default)
			)
			(layer "B.SilkS")
		)
		(fp_line
			(start 0.7874 -0.4064)
			(end -0.7874 -0.4064)
			(stroke
				(width 0.1524)
				(type default)
			)
			(layer "B.SilkS")
		)
		(fp_line
			(start 0.7874 0.4064)
			(end 0.7874 -0.4064)
			(stroke
				(width 0.1524)
				(type default)
			)
			(layer "B.SilkS")
		)
		(fp_poly
			(pts
				(xy 0.508 0.2794) (xy 0.508 0.2286) (xy 0.635 0.2286) (xy 0.635 -0.254) (xy 0.5334 -0.254) (xy 0.5334 -0.2794)
				(xy -0.5334 -0.2794) (xy -0.5334 -0.254) (xy -0.635 -0.254) (xy -0.635 0.254) (xy -0.5334 0.254)
				(xy -0.5334 0.2794)
			)
			(stroke
				(width 0)
				(type default)
			)
			(fill no)
			(layer "B.CrtYd")
		)
		(pad "1" smd rect
			(at -0.40005 0 180)
			(size 0.4572 0.508)
			(layers "B.Cu" "B.Mask" "B.Paste")
			(net "P3V3_STB_NODE1")
		)
		(pad "2" smd rect
			(at 0.40005 0 180)
			(size 0.4572 0.508)
			(layers "B.Cu" "B.Mask" "B.Paste")
			(net "XDP_CPU_NODE1_PWROK_STALL_L")
		)
	)
	(footprint ""
		(layer "B.Cu")
		(at 61.34735 -71.022718 -90)
		(property "Reference" "C107"
			(at 33.04921 14.61262 270)
			(unlocked yes)
			(layer "B.SilkS")
			(effects
				(font
					(size 0.7874 0.5842)
					(thickness 0.1524)
				)
				(justify left mirror)
			)
		)
		(property "Value" ""
			(at 0 0 90)
			(layer "B.Fab")
			(effects
				(font
					(size 1.27 1.27)
				)
				(justify mirror)
			)
		)
		(duplicate_pad_numbers_are_jumpers no)
		(fp_line
			(start -0.7874 0.4064)
			(end 0.7874 0.4064)
			(stroke
				(width 0.1524)
				(type default)
			)
			(layer "B.SilkS")
		)
		(fp_line
			(start 0.7874 0.4064)
			(end 0.7874 -0.4064)
			(stroke
				(width 0.1524)
				(type default)
			)
			(layer "B.SilkS")
		)
		(fp_line
			(start 0 0.381)
			(end 0 -0.381)
			(stroke
				(width 0.1524)
				(type default)
			)
			(layer "B.SilkS")
		)
		(fp_line
			(start -0.7874 -0.4064)
			(end -0.7874 0.4064)
			(stroke
				(width 0.1524)
				(type default)
			)
			(layer "B.SilkS")
		)
		(fp_line
			(start 0.7874 -0.4064)
			(end -0.7874 -0.4064)
			(stroke
				(width 0.1524)
				(type default)
			)
			(layer "B.SilkS")
		)
		(fp_poly
			(pts
				(xy 0.5334 0.254) (xy 0.635 0.254) (xy 0.635 0.2286) (xy 0.635 -0.254) (xy 0.5334 -0.254) (xy 0.5334 -0.2794)
				(xy -0.5334 -0.2794) (xy -0.5334 -0.254) (xy -0.635 -0.254) (xy -0.635 0.254) (xy -0.5334 0.254)
				(xy -0.5334 0.2794) (xy 0.508 0.2794) (xy 0.5334 0.2794)
			)
			(stroke
				(width 0)
				(type default)
			)
			(fill no)
			(layer "B.CrtYd")
		)
		(pad "1" smd rect
			(at -0.40005 0 90)
			(size 0.4572 0.508)
			(layers "B.Cu" "B.Mask" "B.Paste")
			(net "P1V05_NODE1")
		)
		(pad "2" smd rect
			(at 0.40005 0 90)
			(size 0.4572 0.508)
			(layers "B.Cu" "B.Mask" "B.Paste")
			(net "GND")
		)
	)
	(footprint ""
		(layer "B.Cu")
		(at 70.966584 -88.83142 180)
		(property "Reference" "R87"
			(at -3.025648 -0.075184 0)
			(unlocked yes)
			(layer "B.SilkS")
			(effects
				(font
					(size 0.7874 0.5842)
					(thickness 0.1524)
				)
				(justify left mirror)
			)
		)
		(property "Value" ""
			(at 0 0 0)
			(layer "B.Fab")
			(effects
				(font
					(size 1.27 1.27)
				)
				(justify mirror)
			)
		)
		(duplicate_pad_numbers_are_jumpers no)
		(fp_line
			(start 0.7874 0.4064)
			(end 0.7874 -0.4064)
			(stroke
				(width 0.1524)
				(type default)
			)
			(layer "B.SilkS")
		)
		(fp_line
			(start 0.7874 -0.4064)
			(end -0.7874 -0.4064)
			(stroke
				(width 0.1524)
				(type default)
			)
			(layer "B.SilkS")
		)
		(fp_line
			(start -0.7874 0.4064)
			(end 0.7874 0.4064)
			(stroke
				(width 0.1524)
				(type default)
			)
			(layer "B.SilkS")
		)
		(fp_line
			(start -0.7874 -0.4064)
			(end -0.7874 0.4064)
			(stroke
				(width 0.1524)
				(type default)
			)
			(layer "B.SilkS")
		)
		(fp_poly
			(pts
				(xy 0.508 0.2794) (xy 0.508 0.2286) (xy 0.635 0.2286) (xy 0.635 -0.254) (xy 0.5334 -0.254) (xy 0.5334 -0.2794)
				(xy -0.5334 -0.2794) (xy -0.5334 -0.254) (xy -0.635 -0.254) (xy -0.635 0.254) (xy -0.5334 0.254)
				(xy -0.5334 0.2794)
			)
			(stroke
				(width 0)
				(type default)
			)
			(fill no)
			(layer "B.CrtYd")
		)
		(pad "1" smd rect
			(at -0.40005 0)
			(size 0.4572 0.508)
			(layers "B.Cu" "B.Mask" "B.Paste")
			(net "H_CPU_NODE1_ERR1")
		)
		(pad "2" smd rect
			(at 0.40005 0)
			(size 0.4572 0.508)
			(layers "B.Cu" "B.Mask" "B.Paste")
			(net "H_CPU_NODE1_ERR1_R")
		)
	)
	(footprint ""
		(layer "B.Cu")
		(at 126.039626 -41.214294 180)
		(property "Reference" "R1138"
			(at -2.611374 3.513836 0)
			(unlocked yes)
			(layer "B.SilkS")
			(effects
				(font
					(size 0.7874 0.5842)
					(thickness 0.1524)
				)
				(justify left mirror)
			)
		)
		(property "Value" ""
			(at 0 0 0)
			(layer "B.Fab")
			(effects
				(font
					(size 1.27 1.27)
				)
				(justify mirror)
			)
		)
		(duplicate_pad_numbers_are_jumpers no)
		(fp_line
			(start 0.7874 0.4064)
			(end 0.7874 -0.4064)
			(stroke
				(width 0.1524)
				(type default)
			)
			(layer "B.SilkS")
		)
		(fp_line
			(start 0.7874 -0.4064)
			(end -0.7874 -0.4064)
			(stroke
				(width 0.1524)
				(type default)
			)
			(layer "B.SilkS")
		)
		(fp_line
			(start -0.7874 0.4064)
			(end 0.7874 0.4064)
			(stroke
				(width 0.1524)
				(type default)
			)
			(layer "B.SilkS")
		)
		(fp_line
			(start -0.7874 -0.4064)
			(end -0.7874 0.4064)
			(stroke
				(width 0.1524)
				(type default)
			)
			(layer "B.SilkS")
		)
		(fp_poly
			(pts
				(xy 0.508 0.2794) (xy 0.508 0.2286) (xy 0.635 0.2286) (xy 0.635 -0.254) (xy 0.5334 -0.254) (xy 0.5334 -0.2794)
				(xy -0.5334 -0.2794) (xy -0.5334 -0.254) (xy -0.635 -0.254) (xy -0.635 0.254) (xy -0.5334 0.254)
				(xy -0.5334 0.2794)
			)
			(stroke
				(width 0)
				(type default)
			)
			(fill no)
			(layer "B.CrtYd")
		)
		(pad "1" smd rect
			(at -0.40005 0)
			(size 0.4572 0.508)
			(layers "B.Cu" "B.Mask" "B.Paste")
			(net "P3V3_NODE1")
		)
		(pad "2" smd rect
			(at 0.40005 0)
			(size 0.4572 0.508)
			(layers "B.Cu" "B.Mask" "B.Paste")
			(net "SIO_PIN45")
		)
	)
	(footprint ""
		(layer "B.Cu")
		(at 41.697402 -159.164782 -90)
		(property "Reference" "C408"
			(at -7.088378 6.84276 270)
			(unlocked yes)
			(layer "B.SilkS")
			(effects
				(font
					(size 0.7874 0.5842)
					(thickness 0.1524)
				)
				(justify left mirror)
			)
		)
		(property "Value" ""
			(at 0 0 90)
			(layer "B.Fab")
			(effects
				(font
					(size 1.27 1.27)
				)
				(justify mirror)
			)
		)
		(duplicate_pad_numbers_are_jumpers no)
		(fp_line
			(start -0.7874 0.4064)
			(end 0.7874 0.4064)
			(stroke
				(width 0.1524)
				(type default)
			)
			(layer "B.SilkS")
		)
		(fp_line
			(start 0.7874 0.4064)
			(end 0.7874 -0.4064)
			(stroke
				(width 0.1524)
				(type default)
			)
			(layer "B.SilkS")
		)
		(fp_line
			(start 0 0.381)
			(end 0 -0.381)
			(stroke
				(width 0.1524)
				(type default)
			)
			(layer "B.SilkS")
		)
		(fp_line
			(start -0.7874 -0.4064)
			(end -0.7874 0.4064)
			(stroke
				(width 0.1524)
				(type default)
			)
			(layer "B.SilkS")
		)
		(fp_line
			(start 0.7874 -0.4064)
			(end -0.7874 -0.4064)
			(stroke
				(width 0.1524)
				(type default)
			)
			(layer "B.SilkS")
		)
		(fp_poly
			(pts
				(xy 0.5334 0.254) (xy 0.635 0.254) (xy 0.635 0.2286) (xy 0.635 -0.254) (xy 0.5334 -0.254) (xy 0.5334 -0.2794)
				(xy -0.5334 -0.2794) (xy -0.5334 -0.254) (xy -0.635 -0.254) (xy -0.635 0.254) (xy -0.5334 0.254)
				(xy -0.5334 0.2794) (xy 0.508 0.2794) (xy 0.5334 0.2794)
			)
			(stroke
				(width 0)
				(type default)
			)
			(fill no)
			(layer "B.CrtYd")
		)
		(pad "1" smd rect
			(at -0.40005 0 90)
			(size 0.4572 0.508)
			(layers "B.Cu" "B.Mask" "B.Paste")
			(net "P1V9_LAN1")
		)
		(pad "2" smd rect
			(at 0.40005 0 90)
			(size 0.4572 0.508)
			(layers "B.Cu" "B.Mask" "B.Paste")
			(net "GND")
		)
	)
	(footprint ""
		(layer "B.Cu")
		(at 64.899286 -121.044462 90)
		(property "Reference" "R337"
			(at -7.37235 10.060432 270)
			(unlocked yes)
			(layer "B.SilkS")
			(effects
				(font
					(size 0.7874 0.5842)
					(thickness 0.1524)
				)
				(justify left mirror)
			)
		)
		(property "Value" ""
			(at 0 0 90)
			(layer "B.Fab")
			(effects
				(font
					(size 1.27 1.27)
				)
				(justify mirror)
			)
		)
		(duplicate_pad_numbers_are_jumpers no)
		(fp_line
			(start 0.7874 -0.4064)
			(end -0.7874 -0.4064)
			(stroke
				(width 0.1524)
				(type default)
			)
			(layer "B.SilkS")
		)
		(fp_line
			(start -0.7874 -0.4064)
			(end -0.7874 0.4064)
			(stroke
				(width 0.1524)
				(type default)
			)
			(layer "B.SilkS")
		)
		(fp_line
			(start 0.7874 0.4064)
			(end 0.7874 -0.4064)
			(stroke
				(width 0.1524)
				(type default)
			)
			(layer "B.SilkS")
		)
		(fp_line
			(start -0.7874 0.4064)
			(end 0.7874 0.4064)
			(stroke
				(width 0.1524)
				(type default)
			)
			(layer "B.SilkS")
		)
		(fp_poly
			(pts
				(xy 0.508 0.2794) (xy 0.508 0.2286) (xy 0.635 0.2286) (xy 0.635 -0.254) (xy 0.5334 -0.254) (xy 0.5334 -0.2794)
				(xy -0.5334 -0.2794) (xy -0.5334 -0.254) (xy -0.635 -0.254) (xy -0.635 0.254) (xy -0.5334 0.254)
				(xy -0.5334 0.2794)
			)
			(stroke
				(width 0)
				(type default)
			)
			(fill no)
			(layer "B.CrtYd")
		)
		(pad "1" smd rect
			(at -0.40005 0 270)
			(size 0.4572 0.508)
			(layers "B.Cu" "B.Mask" "B.Paste")
			(net "P3V3_NODE1")
		)
		(pad "2" smd rect
			(at 0.40005 0 270)
			(size 0.4572 0.508)
			(layers "B.Cu" "B.Mask" "B.Paste")
			(net "BMC_ROMA21")
		)
	)
	(footprint ""
		(layer "B.Cu")
		(at 168.265856 -171.85513 180)
		(property "Reference" "C919"
			(at -4.778756 -0.232918 0)
			(unlocked yes)
			(layer "B.SilkS")
			(effects
				(font
					(size 0.7874 0.5842)
					(thickness 0.1524)
				)
				(justify left mirror)
			)
		)
		(property "Value" ""
			(at 0 0 0)
			(layer "B.Fab")
			(effects
				(font
					(size 1.27 1.27)
				)
				(justify mirror)
			)
		)
		(duplicate_pad_numbers_are_jumpers no)
		(fp_line
			(start 0.7874 0.4064)
			(end 0.7874 -0.4064)
			(stroke
				(width 0.1524)
				(type default)
			)
			(layer "B.SilkS")
		)
		(fp_line
			(start 0.7874 -0.4064)
			(end -0.7874 -0.4064)
			(stroke
				(width 0.1524)
				(type default)
			)
			(layer "B.SilkS")
		)
		(fp_line
			(start 0 0.381)
			(end 0 -0.381)
			(stroke
				(width 0.1524)
				(type default)
			)
			(layer "B.SilkS")
		)
		(fp_line
			(start -0.7874 0.4064)
			(end 0.7874 0.4064)
			(stroke
				(width 0.1524)
				(type default)
			)
			(layer "B.SilkS")
		)
		(fp_line
			(start -0.7874 -0.4064)
			(end -0.7874 0.4064)
			(stroke
				(width 0.1524)
				(type default)
			)
			(layer "B.SilkS")
		)
		(fp_poly
			(pts
				(xy 0.5334 0.254) (xy 0.635 0.254) (xy 0.635 0.2286) (xy 0.635 -0.254) (xy 0.5334 -0.254) (xy 0.5334 -0.2794)
				(xy -0.5334 -0.2794) (xy -0.5334 -0.254) (xy -0.635 -0.254) (xy -0.635 0.254) (xy -0.5334 0.254)
				(xy -0.5334 0.2794) (xy 0.508 0.2794) (xy 0.5334 0.2794)
			)
			(stroke
				(width 0)
				(type default)
			)
			(fill no)
			(layer "B.CrtYd")
		)
		(pad "1" smd rect
			(at -0.40005 0)
			(size 0.4572 0.508)
			(layers "B.Cu" "B.Mask" "B.Paste")
			(net "GND")
		)
		(pad "2" smd rect
			(at 0.40005 0)
			(size 0.4572 0.508)
			(layers "B.Cu" "B.Mask" "B.Paste")
			(net "N54365835")
		)
	)
	(footprint ""
		(layer "B.Cu")
		(at 63.215266 -76.034392)
		(property "Reference" "C47"
			(at -13.728446 30.440884 0)
			(unlocked yes)
			(layer "B.SilkS")
			(effects
				(font
					(size 0.7874 0.5842)
					(thickness 0.1524)
				)
				(justify left mirror)
			)
		)
		(property "Value" ""
			(at 0 0 0)
			(layer "B.Fab")
			(effects
				(font
					(size 1.27 1.27)
				)
				(justify mirror)
			)
		)
		(duplicate_pad_numbers_are_jumpers no)
		(fp_line
			(start -0.7874 -0.4064)
			(end -0.7874 0.4064)
			(stroke
				(width 0.1524)
				(type default)
			)
			(layer "B.SilkS")
		)
		(fp_line
			(start -0.7874 0.4064)
			(end 0.7874 0.4064)
			(stroke
				(width 0.1524)
				(type default)
			)
			(layer "B.SilkS")
		)
		(fp_line
			(start 0 0.381)
			(end 0 -0.381)
			(stroke
				(width 0.1524)
				(type default)
			)
			(layer "B.SilkS")
		)
		(fp_line
			(start 0.7874 -0.4064)
			(end -0.7874 -0.4064)
			(stroke
				(width 0.1524)
				(type default)
			)
			(layer "B.SilkS")
		)
		(fp_line
			(start 0.7874 0.4064)
			(end 0.7874 -0.4064)
			(stroke
				(width 0.1524)
				(type default)
			)
			(layer "B.SilkS")
		)
		(fp_poly
			(pts
				(xy 0.5334 0.254) (xy 0.635 0.254) (xy 0.635 0.2286) (xy 0.635 -0.254) (xy 0.5334 -0.254) (xy 0.5334 -0.2794)
				(xy -0.5334 -0.2794) (xy -0.5334 -0.254) (xy -0.635 -0.254) (xy -0.635 0.254) (xy -0.5334 0.254)
				(xy -0.5334 0.2794) (xy 0.508 0.2794) (xy 0.5334 0.2794)
			)
			(stroke
				(width 0)
				(type default)
			)
			(fill no)
			(layer "B.CrtYd")
		)
		(pad "1" smd rect
			(at -0.40005 0 180)
			(size 0.4572 0.508)
			(layers "B.Cu" "B.Mask" "B.Paste")
			(net "P1V05_NODE1")
		)
		(pad "2" smd rect
			(at 0.40005 0 180)
			(size 0.4572 0.508)
			(layers "B.Cu" "B.Mask" "B.Paste")
			(net "GND")
		)
	)
	(footprint ""
		(layer "B.Cu")
		(at 142.07236 -176.061624 180)
		(property "Reference" "R733"
			(at 1.287272 0.298196 0)
			(unlocked yes)
			(layer "B.SilkS")
			(effects
				(font
					(size 0.7874 0.5842)
					(thickness 0.1524)
				)
				(justify left mirror)
			)
		)
		(property "Value" ""
			(at 0 0 0)
			(layer "B.Fab")
			(effects
				(font
					(size 1.27 1.27)
				)
				(justify mirror)
			)
		)
		(duplicate_pad_numbers_are_jumpers no)
		(fp_line
			(start 0.7874 0.4064)
			(end 0.7874 -0.4064)
			(stroke
				(width 0.1524)
				(type default)
			)
			(layer "B.SilkS")
		)
		(fp_line
			(start 0.7874 -0.4064)
			(end -0.7874 -0.4064)
			(stroke
				(width 0.1524)
				(type default)
			)
			(layer "B.SilkS")
		)
		(fp_line
			(start -0.7874 0.4064)
			(end 0.7874 0.4064)
			(stroke
				(width 0.1524)
				(type default)
			)
			(layer "B.SilkS")
		)
		(fp_line
			(start -0.7874 -0.4064)
			(end -0.7874 0.4064)
			(stroke
				(width 0.1524)
				(type default)
			)
			(layer "B.SilkS")
		)
		(fp_poly
			(pts
				(xy 0.508 0.2794) (xy 0.508 0.2286) (xy 0.635 0.2286) (xy 0.635 -0.254) (xy 0.5334 -0.254) (xy 0.5334 -0.2794)
				(xy -0.5334 -0.2794) (xy -0.5334 -0.254) (xy -0.635 -0.254) (xy -0.635 0.254) (xy -0.5334 0.254)
				(xy -0.5334 0.2794)
			)
			(stroke
				(width 0)
				(type default)
			)
			(fill no)
			(layer "B.CrtYd")
		)
		(pad "1" smd rect
			(at -0.40005 0)
			(size 0.4572 0.508)
			(layers "B.Cu" "B.Mask" "B.Paste")
			(net "T10_NODE2_EN")
		)
		(pad "2" smd rect
			(at 0.40005 0)
			(size 0.4572 0.508)
			(layers "B.Cu" "B.Mask" "B.Paste")
			(net "P5V_NODE1")
		)
	)
	(footprint ""
		(layer "B.Cu")
		(at 70.690994 -121.063258 90)
		(property "Reference" "R254"
			(at -7.391146 9.837928 270)
			(unlocked yes)
			(layer "B.SilkS")
			(effects
				(font
					(size 0.7874 0.5842)
					(thickness 0.1524)
				)
				(justify left mirror)
			)
		)
		(property "Value" ""
			(at 0 0 90)
			(layer "B.Fab")
			(effects
				(font
					(size 1.27 1.27)
				)
				(justify mirror)
			)
		)
		(duplicate_pad_numbers_are_jumpers no)
		(fp_line
			(start 0.7874 -0.4064)
			(end -0.7874 -0.4064)
			(stroke
				(width 0.1524)
				(type default)
			)
			(layer "B.SilkS")
		)
		(fp_line
			(start -0.7874 -0.4064)
			(end -0.7874 0.4064)
			(stroke
				(width 0.1524)
				(type default)
			)
			(layer "B.SilkS")
		)
		(fp_line
			(start 0.7874 0.4064)
			(end 0.7874 -0.4064)
			(stroke
				(width 0.1524)
				(type default)
			)
			(layer "B.SilkS")
		)
		(fp_line
			(start -0.7874 0.4064)
			(end 0.7874 0.4064)
			(stroke
				(width 0.1524)
				(type default)
			)
			(layer "B.SilkS")
		)
		(fp_poly
			(pts
				(xy 0.508 0.2794) (xy 0.508 0.2286) (xy 0.635 0.2286) (xy 0.635 -0.254) (xy 0.5334 -0.254) (xy 0.5334 -0.2794)
				(xy -0.5334 -0.2794) (xy -0.5334 -0.254) (xy -0.635 -0.254) (xy -0.635 0.254) (xy -0.5334 0.254)
				(xy -0.5334 0.2794)
			)
			(stroke
				(width 0)
				(type default)
			)
			(fill no)
			(layer "B.CrtYd")
		)
		(pad "1" smd rect
			(at -0.40005 0 270)
			(size 0.4572 0.508)
			(layers "B.Cu" "B.Mask" "B.Paste")
			(net "FM_CPLD_NODE1_BMC_PERST_L")
		)
		(pad "2" smd rect
			(at 0.40005 0 270)
			(size 0.4572 0.508)
			(layers "B.Cu" "B.Mask" "B.Paste")
			(net "RST_BMC_NODE1_PERST_L")
		)
	)
	(footprint ""
		(layer "B.Cu")
		(at 164.021008 -168.149524 -90)
		(property "Reference" "R1061"
			(at 4.91871 -1.245362 270)
			(unlocked yes)
			(layer "B.SilkS")
			(effects
				(font
					(size 0.7874 0.5842)
					(thickness 0.1524)
				)
				(justify left mirror)
			)
		)
		(property "Value" ""
			(at 0 0 90)
			(layer "B.Fab")
			(effects
				(font
					(size 1.27 1.27)
				)
				(justify mirror)
			)
		)
		(duplicate_pad_numbers_are_jumpers no)
		(fp_line
			(start -0.7874 0.4064)
			(end 0.7874 0.4064)
			(stroke
				(width 0.1524)
				(type default)
			)
			(layer "B.SilkS")
		)
		(fp_line
			(start 0.7874 0.4064)
			(end 0.7874 -0.4064)
			(stroke
				(width 0.1524)
				(type default)
			)
			(layer "B.SilkS")
		)
		(fp_line
			(start -0.7874 -0.4064)
			(end -0.7874 0.4064)
			(stroke
				(width 0.1524)
				(type default)
			)
			(layer "B.SilkS")
		)
		(fp_line
			(start 0.7874 -0.4064)
			(end -0.7874 -0.4064)
			(stroke
				(width 0.1524)
				(type default)
			)
			(layer "B.SilkS")
		)
		(fp_poly
			(pts
				(xy 0.508 0.2794) (xy 0.508 0.2286) (xy 0.635 0.2286) (xy 0.635 -0.254) (xy 0.5334 -0.254) (xy 0.5334 -0.2794)
				(xy -0.5334 -0.2794) (xy -0.5334 -0.254) (xy -0.635 -0.254) (xy -0.635 0.254) (xy -0.5334 0.254)
				(xy -0.5334 0.2794)
			)
			(stroke
				(width 0)
				(type default)
			)
			(fill no)
			(layer "B.CrtYd")
		)
		(pad "1" smd rect
			(at -0.40005 0 90)
			(size 0.4572 0.508)
			(layers "B.Cu" "B.Mask" "B.Paste")
			(net "CPLD_UART_RI_P3_LS_N")
		)
		(pad "2" smd rect
			(at 0.40005 0 90)
			(size 0.4572 0.508)
			(layers "B.Cu" "B.Mask" "B.Paste")
			(net "CPLD_UART_RI_P3_N")
		)
	)
	(footprint ""
		(layer "B.Cu")
		(at 137.970006 -39.47541 180)
		(property "Reference" "R1190"
			(at 4.172458 -18.307812 0)
			(unlocked yes)
			(layer "B.SilkS")
			(effects
				(font
					(size 0.7874 0.5842)
					(thickness 0.1524)
				)
				(justify left mirror)
			)
		)
		(property "Value" ""
			(at 0 0 0)
			(layer "B.Fab")
			(effects
				(font
					(size 1.27 1.27)
				)
				(justify mirror)
			)
		)
		(duplicate_pad_numbers_are_jumpers no)
		(fp_line
			(start 0.7874 0.4064)
			(end 0.7874 -0.4064)
			(stroke
				(width 0.1524)
				(type default)
			)
			(layer "B.SilkS")
		)
		(fp_line
			(start 0.7874 -0.4064)
			(end -0.7874 -0.4064)
			(stroke
				(width 0.1524)
				(type default)
			)
			(layer "B.SilkS")
		)
		(fp_line
			(start -0.7874 0.4064)
			(end 0.7874 0.4064)
			(stroke
				(width 0.1524)
				(type default)
			)
			(layer "B.SilkS")
		)
		(fp_line
			(start -0.7874 -0.4064)
			(end -0.7874 0.4064)
			(stroke
				(width 0.1524)
				(type default)
			)
			(layer "B.SilkS")
		)
		(fp_poly
			(pts
				(xy 0.508 0.2794) (xy 0.508 0.2286) (xy 0.635 0.2286) (xy 0.635 -0.254) (xy 0.5334 -0.254) (xy 0.5334 -0.2794)
				(xy -0.5334 -0.2794) (xy -0.5334 -0.254) (xy -0.635 -0.254) (xy -0.635 0.254) (xy -0.5334 0.254)
				(xy -0.5334 0.2794)
			)
			(stroke
				(width 0)
				(type default)
			)
			(fill no)
			(layer "B.CrtYd")
		)
		(pad "1" smd rect
			(at -0.40005 0)
			(size 0.4572 0.508)
			(layers "B.Cu" "B.Mask" "B.Paste")
			(net "SIO_JTAG_CPLD2_TMS_R")
		)
		(pad "2" smd rect
			(at 0.40005 0)
			(size 0.4572 0.508)
			(layers "B.Cu" "B.Mask" "B.Paste")
			(net "SIO_JTAG_CPLD2_TMS")
		)
	)
	(footprint ""
		(layer "B.Cu")
		(at 114.721132 -166.980362)
		(property "Reference" "R1243"
			(at -1.797812 -0.2413 0)
			(unlocked yes)
			(layer "B.SilkS")
			(effects
				(font
					(size 0.7874 0.5842)
					(thickness 0.1524)
				)
				(justify left mirror)
			)
		)
		(property "Value" ""
			(at 0 0 0)
			(layer "B.Fab")
			(effects
				(font
					(size 1.27 1.27)
				)
				(justify mirror)
			)
		)
		(duplicate_pad_numbers_are_jumpers no)
		(fp_line
			(start -0.7874 -0.4064)
			(end -0.7874 0.4064)
			(stroke
				(width 0.1524)
				(type default)
			)
			(layer "B.SilkS")
		)
		(fp_line
			(start -0.7874 0.4064)
			(end 0.7874 0.4064)
			(stroke
				(width 0.1524)
				(type default)
			)
			(layer "B.SilkS")
		)
		(fp_line
			(start 0.7874 -0.4064)
			(end -0.7874 -0.4064)
			(stroke
				(width 0.1524)
				(type default)
			)
			(layer "B.SilkS")
		)
		(fp_line
			(start 0.7874 0.4064)
			(end 0.7874 -0.4064)
			(stroke
				(width 0.1524)
				(type default)
			)
			(layer "B.SilkS")
		)
		(fp_poly
			(pts
				(xy 0.508 0.2794) (xy 0.508 0.2286) (xy 0.635 0.2286) (xy 0.635 -0.254) (xy 0.5334 -0.254) (xy 0.5334 -0.2794)
				(xy -0.5334 -0.2794) (xy -0.5334 -0.254) (xy -0.635 -0.254) (xy -0.635 0.254) (xy -0.5334 0.254)
				(xy -0.5334 0.2794)
			)
			(stroke
				(width 0)
				(type default)
			)
			(fill no)
			(layer "B.CrtYd")
		)
		(pad "1" smd rect
			(at -0.40005 0 180)
			(size 0.4572 0.508)
			(layers "B.Cu" "B.Mask" "B.Paste")
			(net "GND")
		)
		(pad "2" smd rect
			(at 0.40005 0 180)
			(size 0.4572 0.508)
			(layers "B.Cu" "B.Mask" "B.Paste")
			(net "PSU1_HUB_EN")
		)
	)
	(footprint ""
		(layer "B.Cu")
		(at 66.524886 -137.986262 180)
		(property "Reference" "C292"
			(at 37.331396 -55.008526 0)
			(unlocked yes)
			(layer "B.SilkS")
			(effects
				(font
					(size 0.7874 0.5842)
					(thickness 0.1524)
				)
				(justify left mirror)
			)
		)
		(property "Value" ""
			(at 0 0 0)
			(layer "B.Fab")
			(effects
				(font
					(size 1.27 1.27)
				)
				(justify mirror)
			)
		)
		(duplicate_pad_numbers_are_jumpers no)
		(fp_line
			(start 0.7874 0.4064)
			(end 0.7874 -0.4064)
			(stroke
				(width 0.1524)
				(type default)
			)
			(layer "B.SilkS")
		)
		(fp_line
			(start 0.7874 -0.4064)
			(end -0.7874 -0.4064)
			(stroke
				(width 0.1524)
				(type default)
			)
			(layer "B.SilkS")
		)
		(fp_line
			(start 0 0.381)
			(end 0 -0.381)
			(stroke
				(width 0.1524)
				(type default)
			)
			(layer "B.SilkS")
		)
		(fp_line
			(start -0.7874 0.4064)
			(end 0.7874 0.4064)
			(stroke
				(width 0.1524)
				(type default)
			)
			(layer "B.SilkS")
		)
		(fp_line
			(start -0.7874 -0.4064)
			(end -0.7874 0.4064)
			(stroke
				(width 0.1524)
				(type default)
			)
			(layer "B.SilkS")
		)
		(fp_poly
			(pts
				(xy 0.5334 0.254) (xy 0.635 0.254) (xy 0.635 0.2286) (xy 0.635 -0.254) (xy 0.5334 -0.254) (xy 0.5334 -0.2794)
				(xy -0.5334 -0.2794) (xy -0.5334 -0.254) (xy -0.635 -0.254) (xy -0.635 0.254) (xy -0.5334 0.254)
				(xy -0.5334 0.2794) (xy 0.508 0.2794) (xy 0.5334 0.2794)
			)
			(stroke
				(width 0)
				(type default)
			)
			(fill no)
			(layer "B.CrtYd")
		)
		(pad "1" smd rect
			(at -0.40005 0)
			(size 0.4572 0.508)
			(layers "B.Cu" "B.Mask" "B.Paste")
			(net "P1V26_BMC_NODE1")
		)
		(pad "2" smd rect
			(at 0.40005 0)
			(size 0.4572 0.508)
			(layers "B.Cu" "B.Mask" "B.Paste")
			(net "GND")
		)
	)
	(footprint ""
		(layer "B.Cu")
		(at 61.591952 -95.7961)
		(property "Reference" "R61"
			(at -3.892296 -7.642352 0)
			(unlocked yes)
			(layer "B.SilkS")
			(effects
				(font
					(size 0.7874 0.5842)
					(thickness 0.1524)
				)
				(justify left mirror)
			)
		)
		(property "Value" ""
			(at 0 0 0)
			(layer "B.Fab")
			(effects
				(font
					(size 1.27 1.27)
				)
				(justify mirror)
			)
		)
		(duplicate_pad_numbers_are_jumpers no)
		(fp_line
			(start -0.7874 -0.4064)
			(end -0.7874 0.4064)
			(stroke
				(width 0.1524)
				(type default)
			)
			(layer "B.SilkS")
		)
		(fp_line
			(start -0.7874 0.4064)
			(end 0.7874 0.4064)
			(stroke
				(width 0.1524)
				(type default)
			)
			(layer "B.SilkS")
		)
		(fp_line
			(start 0.7874 -0.4064)
			(end -0.7874 -0.4064)
			(stroke
				(width 0.1524)
				(type default)
			)
			(layer "B.SilkS")
		)
		(fp_line
			(start 0.7874 0.4064)
			(end 0.7874 -0.4064)
			(stroke
				(width 0.1524)
				(type default)
			)
			(layer "B.SilkS")
		)
		(fp_poly
			(pts
				(xy 0.508 0.2794) (xy 0.508 0.2286) (xy 0.635 0.2286) (xy 0.635 -0.254) (xy 0.5334 -0.254) (xy 0.5334 -0.2794)
				(xy -0.5334 -0.2794) (xy -0.5334 -0.254) (xy -0.635 -0.254) (xy -0.635 0.254) (xy -0.5334 0.254)
				(xy -0.5334 0.2794)
			)
			(stroke
				(width 0)
				(type default)
			)
			(fill no)
			(layer "B.CrtYd")
		)
		(pad "1" smd rect
			(at -0.40005 0 180)
			(size 0.4572 0.508)
			(layers "B.Cu" "B.Mask" "B.Paste")
			(net "LPC_CPU_NODE1_LAD2")
		)
		(pad "2" smd rect
			(at 0.40005 0 180)
			(size 0.4572 0.508)
			(layers "B.Cu" "B.Mask" "B.Paste")
			(net "LPC_CPU_NODE1_LAD2_R")
		)
	)
	(footprint ""
		(layer "B.Cu")
		(at 48.758602 -158.250382 180)
		(property "Reference" "C398"
			(at 11.821922 3.479292 0)
			(unlocked yes)
			(layer "B.SilkS")
			(effects
				(font
					(size 0.7874 0.5842)
					(thickness 0.1524)
				)
				(justify left mirror)
			)
		)
		(property "Value" ""
			(at 0 0 0)
			(layer "B.Fab")
			(effects
				(font
					(size 1.27 1.27)
				)
				(justify mirror)
			)
		)
		(duplicate_pad_numbers_are_jumpers no)
		(fp_line
			(start 0.7874 0.4064)
			(end 0.7874 -0.4064)
			(stroke
				(width 0.1524)
				(type default)
			)
			(layer "B.SilkS")
		)
		(fp_line
			(start 0.7874 -0.4064)
			(end -0.7874 -0.4064)
			(stroke
				(width 0.1524)
				(type default)
			)
			(layer "B.SilkS")
		)
		(fp_line
			(start 0 0.381)
			(end 0 -0.381)
			(stroke
				(width 0.1524)
				(type default)
			)
			(layer "B.SilkS")
		)
		(fp_line
			(start -0.7874 0.4064)
			(end 0.7874 0.4064)
			(stroke
				(width 0.1524)
				(type default)
			)
			(layer "B.SilkS")
		)
		(fp_line
			(start -0.7874 -0.4064)
			(end -0.7874 0.4064)
			(stroke
				(width 0.1524)
				(type default)
			)
			(layer "B.SilkS")
		)
		(fp_poly
			(pts
				(xy 0.5334 0.254) (xy 0.635 0.254) (xy 0.635 0.2286) (xy 0.635 -0.254) (xy 0.5334 -0.254) (xy 0.5334 -0.2794)
				(xy -0.5334 -0.2794) (xy -0.5334 -0.254) (xy -0.635 -0.254) (xy -0.635 0.254) (xy -0.5334 0.254)
				(xy -0.5334 0.2794) (xy 0.508 0.2794) (xy 0.5334 0.2794)
			)
			(stroke
				(width 0)
				(type default)
			)
			(fill no)
			(layer "B.CrtYd")
		)
		(pad "1" smd rect
			(at -0.40005 0)
			(size 0.4572 0.508)
			(layers "B.Cu" "B.Mask" "B.Paste")
			(net "P3V3_NODE1")
		)
		(pad "2" smd rect
			(at 0.40005 0)
			(size 0.4572 0.508)
			(layers "B.Cu" "B.Mask" "B.Paste")
			(net "GND")
		)
	)
	(footprint ""
		(layer "B.Cu")
		(at 117.45976 -188.126624 -90)
		(property "Reference" "C644"
			(at -4.080256 -0.814578 270)
			(unlocked yes)
			(layer "B.SilkS")
			(effects
				(font
					(size 0.7874 0.5842)
					(thickness 0.1524)
				)
				(justify left mirror)
			)
		)
		(property "Value" ""
			(at 0 0 90)
			(layer "B.Fab")
			(effects
				(font
					(size 1.27 1.27)
				)
				(justify mirror)
			)
		)
		(duplicate_pad_numbers_are_jumpers no)
		(fp_line
			(start -0.7874 0.4064)
			(end 0.7874 0.4064)
			(stroke
				(width 0.1524)
				(type default)
			)
			(layer "B.SilkS")
		)
		(fp_line
			(start 0.7874 0.4064)
			(end 0.7874 -0.4064)
			(stroke
				(width 0.1524)
				(type default)
			)
			(layer "B.SilkS")
		)
		(fp_line
			(start 0 0.381)
			(end 0 -0.381)
			(stroke
				(width 0.1524)
				(type default)
			)
			(layer "B.SilkS")
		)
		(fp_line
			(start -0.7874 -0.4064)
			(end -0.7874 0.4064)
			(stroke
				(width 0.1524)
				(type default)
			)
			(layer "B.SilkS")
		)
		(fp_line
			(start 0.7874 -0.4064)
			(end -0.7874 -0.4064)
			(stroke
				(width 0.1524)
				(type default)
			)
			(layer "B.SilkS")
		)
		(fp_poly
			(pts
				(xy 0.5334 0.254) (xy 0.635 0.254) (xy 0.635 0.2286) (xy 0.635 -0.254) (xy 0.5334 -0.254) (xy 0.5334 -0.2794)
				(xy -0.5334 -0.2794) (xy -0.5334 -0.254) (xy -0.635 -0.254) (xy -0.635 0.254) (xy -0.5334 0.254)
				(xy -0.5334 0.2794) (xy 0.508 0.2794) (xy 0.5334 0.2794)
			)
			(stroke
				(width 0)
				(type default)
			)
			(fill no)
			(layer "B.CrtYd")
		)
		(pad "1" smd rect
			(at -0.40005 0 90)
			(size 0.4572 0.508)
			(layers "B.Cu" "B.Mask" "B.Paste")
			(net "T7_NODE4_EN_R")
		)
		(pad "2" smd rect
			(at 0.40005 0 90)
			(size 0.4572 0.508)
			(layers "B.Cu" "B.Mask" "B.Paste")
			(net "GND")
		)
	)
	(footprint ""
		(layer "B.Cu")
		(at 122.860054 -32.106108 180)
		(property "Reference" "C487"
			(at 2.833624 -1.068324 0)
			(unlocked yes)
			(layer "B.SilkS")
			(effects
				(font
					(size 0.7874 0.5842)
					(thickness 0.1524)
				)
				(justify left mirror)
			)
		)
		(property "Value" ""
			(at 0 0 0)
			(layer "B.Fab")
			(effects
				(font
					(size 1.27 1.27)
				)
				(justify mirror)
			)
		)
		(duplicate_pad_numbers_are_jumpers no)
		(fp_line
			(start 0.7874 0.4064)
			(end 0.7874 -0.4064)
			(stroke
				(width 0.1524)
				(type default)
			)
			(layer "B.SilkS")
		)
		(fp_line
			(start 0.7874 -0.4064)
			(end -0.7874 -0.4064)
			(stroke
				(width 0.1524)
				(type default)
			)
			(layer "B.SilkS")
		)
		(fp_line
			(start 0 0.381)
			(end 0 -0.381)
			(stroke
				(width 0.1524)
				(type default)
			)
			(layer "B.SilkS")
		)
		(fp_line
			(start -0.7874 0.4064)
			(end 0.7874 0.4064)
			(stroke
				(width 0.1524)
				(type default)
			)
			(layer "B.SilkS")
		)
		(fp_line
			(start -0.7874 -0.4064)
			(end -0.7874 0.4064)
			(stroke
				(width 0.1524)
				(type default)
			)
			(layer "B.SilkS")
		)
		(fp_poly
			(pts
				(xy 0.5334 0.254) (xy 0.635 0.254) (xy 0.635 0.2286) (xy 0.635 -0.254) (xy 0.5334 -0.254) (xy 0.5334 -0.2794)
				(xy -0.5334 -0.2794) (xy -0.5334 -0.254) (xy -0.635 -0.254) (xy -0.635 0.254) (xy -0.5334 0.254)
				(xy -0.5334 0.2794) (xy 0.508 0.2794) (xy 0.5334 0.2794)
			)
			(stroke
				(width 0)
				(type default)
			)
			(fill no)
			(layer "B.CrtYd")
		)
		(pad "1" smd rect
			(at -0.40005 0)
			(size 0.4572 0.508)
			(layers "B.Cu" "B.Mask" "B.Paste")
			(net "SIO_VCCH")
		)
		(pad "2" smd rect
			(at 0.40005 0)
			(size 0.4572 0.508)
			(layers "B.Cu" "B.Mask" "B.Paste")
			(net "GND")
		)
	)
	(footprint ""
		(layer "B.Cu")
		(at 108.56976 -185.205624 -90)
		(property "Reference" "C736"
			(at -3.957828 -0.41656 270)
			(unlocked yes)
			(layer "B.SilkS")
			(effects
				(font
					(size 0.7874 0.5842)
					(thickness 0.1524)
				)
				(justify left mirror)
			)
		)
		(property "Value" ""
			(at 0 0 90)
			(layer "B.Fab")
			(effects
				(font
					(size 1.27 1.27)
				)
				(justify mirror)
			)
		)
		(duplicate_pad_numbers_are_jumpers no)
		(fp_line
			(start -0.7874 0.4064)
			(end 0.7874 0.4064)
			(stroke
				(width 0.1524)
				(type default)
			)
			(layer "B.SilkS")
		)
		(fp_line
			(start 0.7874 0.4064)
			(end 0.7874 -0.4064)
			(stroke
				(width 0.1524)
				(type default)
			)
			(layer "B.SilkS")
		)
		(fp_line
			(start 0 0.381)
			(end 0 -0.381)
			(stroke
				(width 0.1524)
				(type default)
			)
			(layer "B.SilkS")
		)
		(fp_line
			(start -0.7874 -0.4064)
			(end -0.7874 0.4064)
			(stroke
				(width 0.1524)
				(type default)
			)
			(layer "B.SilkS")
		)
		(fp_line
			(start 0.7874 -0.4064)
			(end -0.7874 -0.4064)
			(stroke
				(width 0.1524)
				(type default)
			)
			(layer "B.SilkS")
		)
		(fp_poly
			(pts
				(xy 0.5334 0.254) (xy 0.635 0.254) (xy 0.635 0.2286) (xy 0.635 -0.254) (xy 0.5334 -0.254) (xy 0.5334 -0.2794)
				(xy -0.5334 -0.2794) (xy -0.5334 -0.254) (xy -0.635 -0.254) (xy -0.635 0.254) (xy -0.5334 0.254)
				(xy -0.5334 0.2794) (xy 0.508 0.2794) (xy 0.5334 0.2794)
			)
			(stroke
				(width 0)
				(type default)
			)
			(fill no)
			(layer "B.CrtYd")
		)
		(pad "1" smd rect
			(at -0.40005 0 90)
			(size 0.4572 0.508)
			(layers "B.Cu" "B.Mask" "B.Paste")
			(net "UART_T7_NODE4_RXD")
		)
		(pad "2" smd rect
			(at 0.40005 0 90)
			(size 0.4572 0.508)
			(layers "B.Cu" "B.Mask" "B.Paste")
			(net "GND")
		)
	)
	(footprint ""
		(layer "B.Cu")
		(at 125.80112 -150.935944 180)
		(property "Reference" "C200"
			(at 0.53086 -2.598166 0)
			(unlocked yes)
			(layer "B.SilkS")
			(effects
				(font
					(size 0.7874 0.5842)
					(thickness 0.1524)
				)
				(justify mirror)
			)
		)
		(property "Value" ""
			(at 0 0 0)
			(layer "B.Fab")
			(effects
				(font
					(size 1.27 1.27)
				)
				(justify mirror)
			)
		)
		(duplicate_pad_numbers_are_jumpers no)
		(fp_line
			(start 1.2954 0.5842)
			(end 1.2954 -0.5842)
			(stroke
				(width 0.1524)
				(type default)
			)
			(layer "B.SilkS")
		)
		(fp_line
			(start 1.2954 -0.5842)
			(end -1.2954 -0.5842)
			(stroke
				(width 0.1524)
				(type default)
			)
			(layer "B.SilkS")
		)
		(fp_line
			(start 0 -0.5842)
			(end 0 0.5842)
			(stroke
				(width 0.1524)
				(type default)
			)
			(layer "B.SilkS")
		)
		(fp_line
			(start -1.2954 0.5842)
			(end 1.2954 0.5842)
			(stroke
				(width 0.1524)
				(type default)
			)
			(layer "B.SilkS")
		)
		(fp_line
			(start -1.2954 -0.5842)
			(end -1.2954 0.5842)
			(stroke
				(width 0.1524)
				(type default)
			)
			(layer "B.SilkS")
		)
		(fp_poly
			(pts
				(xy -0.8636 -0.4572) (xy -0.8636 -0.3556) (xy -1.143 -0.3556) (xy -1.143 0.3556) (xy -0.8636 0.3556)
				(xy -0.8636 0.4572) (xy 0.8636 0.4572) (xy 0.8636 0.3556) (xy 1.143 0.3556) (xy 1.143 -0.3556) (xy 0.8636 -0.3556)
				(xy 0.8636 -0.4572)
			)
			(stroke
				(width 0)
				(type default)
			)
			(fill no)
			(layer "B.CrtYd")
		)
		(fp_line
			(start 0.884936 0.504952)
			(end 0.884936 -0.504952)
			(stroke
				(width 0.1)
				(type default)
			)
			(layer "B.Fab")
		)
		(fp_line
			(start 0.884936 -0.504952)
			(end -0.884936 -0.504952)
			(stroke
				(width 0.1)
				(type default)
			)
			(layer "B.Fab")
		)
		(fp_line
			(start -0.884936 0.504952)
			(end 0.884936 0.504952)
			(stroke
				(width 0.1)
				(type default)
			)
			(layer "B.Fab")
		)
		(fp_line
			(start -0.884936 -0.504952)
			(end -0.884936 0.504952)
			(stroke
				(width 0.1)
				(type default)
			)
			(layer "B.Fab")
		)
		(pad "1" smd rect
			(at -0.7366 0 270)
			(size 0.7112 0.8128)
			(layers "B.Cu" "B.Mask" "B.Paste")
			(net "P1V0_NODE1")
		)
		(pad "2" smd rect
			(at 0.7366 0 270)
			(size 0.7112 0.8128)
			(layers "B.Cu" "B.Mask" "B.Paste")
			(net "GND")
		)
	)
	(footprint ""
		(layer "B.Cu")
		(at 56.755538 -61.878718 180)
		(property "Reference" "C118"
			(at 14.695678 -30.534102 0)
			(unlocked yes)
			(layer "B.SilkS")
			(effects
				(font
					(size 0.7874 0.5842)
					(thickness 0.1524)
				)
				(justify left mirror)
			)
		)
		(property "Value" ""
			(at 0 0 0)
			(layer "B.Fab")
			(effects
				(font
					(size 1.27 1.27)
				)
				(justify mirror)
			)
		)
		(duplicate_pad_numbers_are_jumpers no)
		(fp_line
			(start 0.7874 0.4064)
			(end 0.7874 -0.4064)
			(stroke
				(width 0.1524)
				(type default)
			)
			(layer "B.SilkS")
		)
		(fp_line
			(start 0.7874 -0.4064)
			(end -0.7874 -0.4064)
			(stroke
				(width 0.1524)
				(type default)
			)
			(layer "B.SilkS")
		)
		(fp_line
			(start 0 0.381)
			(end 0 -0.381)
			(stroke
				(width 0.1524)
				(type default)
			)
			(layer "B.SilkS")
		)
		(fp_line
			(start -0.7874 0.4064)
			(end 0.7874 0.4064)
			(stroke
				(width 0.1524)
				(type default)
			)
			(layer "B.SilkS")
		)
		(fp_line
			(start -0.7874 -0.4064)
			(end -0.7874 0.4064)
			(stroke
				(width 0.1524)
				(type default)
			)
			(layer "B.SilkS")
		)
		(fp_poly
			(pts
				(xy 0.5334 0.254) (xy 0.635 0.254) (xy 0.635 0.2286) (xy 0.635 -0.254) (xy 0.5334 -0.254) (xy 0.5334 -0.2794)
				(xy -0.5334 -0.2794) (xy -0.5334 -0.254) (xy -0.635 -0.254) (xy -0.635 0.254) (xy -0.5334 0.254)
				(xy -0.5334 0.2794) (xy 0.508 0.2794) (xy 0.5334 0.2794)
			)
			(stroke
				(width 0)
				(type default)
			)
			(fill no)
			(layer "B.CrtYd")
		)
		(pad "1" smd rect
			(at -0.40005 0)
			(size 0.4572 0.508)
			(layers "B.Cu" "B.Mask" "B.Paste")
			(net "PV_VDDR_NODE1")
		)
		(pad "2" smd rect
			(at 0.40005 0)
			(size 0.4572 0.508)
			(layers "B.Cu" "B.Mask" "B.Paste")
			(net "GND")
		)
	)
	(footprint ""
		(layer "B.Cu")
		(at 156.83738 -148.727922)
		(property "Reference" "C444"
			(at 1.003554 3.515106 0)
			(unlocked yes)
			(layer "B.SilkS")
			(effects
				(font
					(size 0.7874 0.5842)
					(thickness 0.1524)
				)
				(justify left mirror)
			)
		)
		(property "Value" ""
			(at 0 0 0)
			(layer "B.Fab")
			(effects
				(font
					(size 1.27 1.27)
				)
				(justify mirror)
			)
		)
		(duplicate_pad_numbers_are_jumpers no)
		(fp_line
			(start -0.7874 -0.4064)
			(end -0.7874 0.4064)
			(stroke
				(width 0.1524)
				(type default)
			)
			(layer "B.SilkS")
		)
		(fp_line
			(start -0.7874 0.4064)
			(end 0.7874 0.4064)
			(stroke
				(width 0.1524)
				(type default)
			)
			(layer "B.SilkS")
		)
		(fp_line
			(start 0 0.381)
			(end 0 -0.381)
			(stroke
				(width 0.1524)
				(type default)
			)
			(layer "B.SilkS")
		)
		(fp_line
			(start 0.7874 -0.4064)
			(end -0.7874 -0.4064)
			(stroke
				(width 0.1524)
				(type default)
			)
			(layer "B.SilkS")
		)
		(fp_line
			(start 0.7874 0.4064)
			(end 0.7874 -0.4064)
			(stroke
				(width 0.1524)
				(type default)
			)
			(layer "B.SilkS")
		)
		(fp_poly
			(pts
				(xy 0.5334 0.254) (xy 0.635 0.254) (xy 0.635 0.2286) (xy 0.635 -0.254) (xy 0.5334 -0.254) (xy 0.5334 -0.2794)
				(xy -0.5334 -0.2794) (xy -0.5334 -0.254) (xy -0.635 -0.254) (xy -0.635 0.254) (xy -0.5334 0.254)
				(xy -0.5334 0.2794) (xy 0.508 0.2794) (xy 0.5334 0.2794)
			)
			(stroke
				(width 0)
				(type default)
			)
			(fill no)
			(layer "B.CrtYd")
		)
		(pad "1" smd rect
			(at -0.40005 0 180)
			(size 0.4572 0.508)
			(layers "B.Cu" "B.Mask" "B.Paste")
			(net "P3V3_NODE1")
		)
		(pad "2" smd rect
			(at 0.40005 0 180)
			(size 0.4572 0.508)
			(layers "B.Cu" "B.Mask" "B.Paste")
			(net "GND")
		)
	)
	(footprint ""
		(layer "B.Cu")
		(at 59.821572 -84.070698 90)
		(property "Reference" "R98"
			(at 0.918718 0.078994 270)
			(unlocked yes)
			(layer "B.SilkS")
			(effects
				(font
					(size 0.7874 0.5842)
					(thickness 0.1524)
				)
				(justify left mirror)
			)
		)
		(property "Value" ""
			(at 0 0 90)
			(layer "B.Fab")
			(effects
				(font
					(size 1.27 1.27)
				)
				(justify mirror)
			)
		)
		(duplicate_pad_numbers_are_jumpers no)
		(fp_line
			(start 0.7874 -0.4064)
			(end -0.7874 -0.4064)
			(stroke
				(width 0.1524)
				(type default)
			)
			(layer "B.SilkS")
		)
		(fp_line
			(start -0.7874 -0.4064)
			(end -0.7874 0.4064)
			(stroke
				(width 0.1524)
				(type default)
			)
			(layer "B.SilkS")
		)
		(fp_line
			(start 0.7874 0.4064)
			(end 0.7874 -0.4064)
			(stroke
				(width 0.1524)
				(type default)
			)
			(layer "B.SilkS")
		)
		(fp_line
			(start -0.7874 0.4064)
			(end 0.7874 0.4064)
			(stroke
				(width 0.1524)
				(type default)
			)
			(layer "B.SilkS")
		)
		(fp_poly
			(pts
				(xy 0.508 0.2794) (xy 0.508 0.2286) (xy 0.635 0.2286) (xy 0.635 -0.254) (xy 0.5334 -0.254) (xy 0.5334 -0.2794)
				(xy -0.5334 -0.2794) (xy -0.5334 -0.254) (xy -0.635 -0.254) (xy -0.635 0.254) (xy -0.5334 0.254)
				(xy -0.5334 0.2794)
			)
			(stroke
				(width 0)
				(type default)
			)
			(fill no)
			(layer "B.CrtYd")
		)
		(pad "1" smd rect
			(at -0.40005 0 270)
			(size 0.4572 0.508)
			(layers "B.Cu" "B.Mask" "B.Paste")
			(net "A_CPU_NODE1_HV_GPIO_RCOMP")
		)
		(pad "2" smd rect
			(at 0.40005 0 270)
			(size 0.4572 0.508)
			(layers "B.Cu" "B.Mask" "B.Paste")
			(net "GND")
		)
	)
	(footprint ""
		(layer "B.Cu")
		(at 69.262498 -96.696784 -90)
		(property "Reference" "R90"
			(at 3.227832 0.289052 270)
			(unlocked yes)
			(layer "B.SilkS")
			(effects
				(font
					(size 0.7874 0.5842)
					(thickness 0.1524)
				)
				(justify left mirror)
			)
		)
		(property "Value" ""
			(at 0 0 90)
			(layer "B.Fab")
			(effects
				(font
					(size 1.27 1.27)
				)
				(justify mirror)
			)
		)
		(duplicate_pad_numbers_are_jumpers no)
		(fp_line
			(start -0.7874 0.4064)
			(end 0.7874 0.4064)
			(stroke
				(width 0.1524)
				(type default)
			)
			(layer "B.SilkS")
		)
		(fp_line
			(start 0.7874 0.4064)
			(end 0.7874 -0.4064)
			(stroke
				(width 0.1524)
				(type default)
			)
			(layer "B.SilkS")
		)
		(fp_line
			(start -0.7874 -0.4064)
			(end -0.7874 0.4064)
			(stroke
				(width 0.1524)
				(type default)
			)
			(layer "B.SilkS")
		)
		(fp_line
			(start 0.7874 -0.4064)
			(end -0.7874 -0.4064)
			(stroke
				(width 0.1524)
				(type default)
			)
			(layer "B.SilkS")
		)
		(fp_poly
			(pts
				(xy 0.508 0.2794) (xy 0.508 0.2286) (xy 0.635 0.2286) (xy 0.635 -0.254) (xy 0.5334 -0.254) (xy 0.5334 -0.2794)
				(xy -0.5334 -0.2794) (xy -0.5334 -0.254) (xy -0.635 -0.254) (xy -0.635 0.254) (xy -0.5334 0.254)
				(xy -0.5334 0.2794)
			)
			(stroke
				(width 0)
				(type default)
			)
			(fill no)
			(layer "B.CrtYd")
		)
		(pad "1" smd rect
			(at -0.40005 0 90)
			(size 0.4572 0.508)
			(layers "B.Cu" "B.Mask" "B.Paste")
			(net "P3V3_NODE1")
		)
		(pad "2" smd rect
			(at 0.40005 0 90)
			(size 0.4572 0.508)
			(layers "B.Cu" "B.Mask" "B.Paste")
			(net "NODE1_BIOS_MB_REV_ID1")
		)
	)
	(footprint ""
		(layer "B.Cu")
		(at 105.191814 -110.95482)
		(property "Reference" "PC125"
			(at -3.119374 0.028956 0)
			(unlocked yes)
			(layer "B.SilkS")
			(effects
				(font
					(size 0.7874 0.5842)
					(thickness 0.1524)
				)
				(justify left mirror)
			)
		)
		(property "Value" ""
			(at 0 0 0)
			(layer "B.Fab")
			(effects
				(font
					(size 1.27 1.27)
				)
				(justify mirror)
			)
		)
		(duplicate_pad_numbers_are_jumpers no)
		(fp_line
			(start -1.905 -0.8636)
			(end -1.905 0.8636)
			(stroke
				(width 0.1524)
				(type default)
			)
			(layer "B.SilkS")
		)
		(fp_line
			(start -1.905 0.8636)
			(end 1.905 0.8636)
			(stroke
				(width 0.1524)
				(type default)
			)
			(layer "B.SilkS")
		)
		(fp_line
			(start 0 0.8382)
			(end 0 -0.8382)
			(stroke
				(width 0.1524)
				(type default)
			)
			(layer "B.SilkS")
		)
		(fp_line
			(start 1.905 -0.8636)
			(end -1.905 -0.8636)
			(stroke
				(width 0.1524)
				(type default)
			)
			(layer "B.SilkS")
		)
		(fp_line
			(start 1.905 0.8636)
			(end 1.905 -0.8636)
			(stroke
				(width 0.1524)
				(type default)
			)
			(layer "B.SilkS")
		)
		(fp_rect
			(start 1.524 0.7366)
			(end -1.524 -0.7366)
			(stroke
				(width 0)
				(type default)
			)
			(fill no)
			(layer "B.CrtYd")
		)
		(pad "1" smd rect
			(at -0.94996 0 180)
			(size 1.1176 1.3716)
			(layers "B.Cu" "B.Mask" "B.Paste")
			(net "GND")
		)
		(pad "2" smd rect
			(at 0.94996 0 180)
			(size 1.1176 1.3716)
			(layers "B.Cu" "B.Mask" "B.Paste")
			(net "PV_VCCP_NODE1")
		)
	)
	(footprint ""
		(layer "B.Cu")
		(at 70.867016 -124.98197 -90)
		(property "Reference" "C276"
			(at 2.34315 -8.641334 270)
			(unlocked yes)
			(layer "B.SilkS")
			(effects
				(font
					(size 0.7874 0.5842)
					(thickness 0.1524)
				)
				(justify mirror)
			)
		)
		(property "Value" ""
			(at 0 0 90)
			(layer "B.Fab")
			(effects
				(font
					(size 1.27 1.27)
				)
				(justify mirror)
			)
		)
		(duplicate_pad_numbers_are_jumpers no)
		(fp_line
			(start -1.2954 0.5842)
			(end 1.2954 0.5842)
			(stroke
				(width 0.1524)
				(type default)
			)
			(layer "B.SilkS")
		)
		(fp_line
			(start 1.2954 0.5842)
			(end 1.2954 -0.5842)
			(stroke
				(width 0.1524)
				(type default)
			)
			(layer "B.SilkS")
		)
		(fp_line
			(start -1.2954 -0.5842)
			(end -1.2954 0.5842)
			(stroke
				(width 0.1524)
				(type default)
			)
			(layer "B.SilkS")
		)
		(fp_line
			(start 0 -0.5842)
			(end 0 0.5842)
			(stroke
				(width 0.1524)
				(type default)
			)
			(layer "B.SilkS")
		)
		(fp_line
			(start 1.2954 -0.5842)
			(end -1.2954 -0.5842)
			(stroke
				(width 0.1524)
				(type default)
			)
			(layer "B.SilkS")
		)
		(fp_poly
			(pts
				(xy -0.8636 -0.4572) (xy -0.8636 -0.3556) (xy -1.143 -0.3556) (xy -1.143 0.3556) (xy -0.8636 0.3556)
				(xy -0.8636 0.4572) (xy 0.8636 0.4572) (xy 0.8636 0.3556) (xy 1.143 0.3556) (xy 1.143 -0.3556) (xy 0.8636 -0.3556)
				(xy 0.8636 -0.4572)
			)
			(stroke
				(width 0)
				(type default)
			)
			(fill no)
			(layer "B.CrtYd")
		)
		(fp_line
			(start -0.884936 0.504952)
			(end 0.884936 0.504952)
			(stroke
				(width 0.1)
				(type default)
			)
			(layer "B.Fab")
		)
		(fp_line
			(start 0.884936 0.504952)
			(end 0.884936 -0.504952)
			(stroke
				(width 0.1)
				(type default)
			)
			(layer "B.Fab")
		)
		(fp_line
			(start -0.884936 -0.504952)
			(end -0.884936 0.504952)
			(stroke
				(width 0.1)
				(type default)
			)
			(layer "B.Fab")
		)
		(fp_line
			(start 0.884936 -0.504952)
			(end -0.884936 -0.504952)
			(stroke
				(width 0.1)
				(type default)
			)
			(layer "B.Fab")
		)
		(pad "1" smd rect
			(at -0.7366 0)
			(size 0.7112 0.8128)
			(layers "B.Cu" "B.Mask" "B.Paste")
			(net "BMC_NODE1_VCC_1V8_PCIE")
		)
		(pad "2" smd rect
			(at 0.7366 0)
			(size 0.7112 0.8128)
			(layers "B.Cu" "B.Mask" "B.Paste")
			(net "GND")
		)
	)
	(footprint ""
		(layer "B.Cu")
		(at 65.706498 -99.181158 -90)
		(property "Reference" "R75"
			(at -1.095756 -0.127 270)
			(unlocked yes)
			(layer "B.SilkS")
			(effects
				(font
					(size 0.7874 0.5842)
					(thickness 0.1524)
				)
				(justify left mirror)
			)
		)
		(property "Value" ""
			(at 0 0 90)
			(layer "B.Fab")
			(effects
				(font
					(size 1.27 1.27)
				)
				(justify mirror)
			)
		)
		(duplicate_pad_numbers_are_jumpers no)
		(fp_line
			(start -0.7874 0.4064)
			(end 0.7874 0.4064)
			(stroke
				(width 0.1524)
				(type default)
			)
			(layer "B.SilkS")
		)
		(fp_line
			(start 0.7874 0.4064)
			(end 0.7874 -0.4064)
			(stroke
				(width 0.1524)
				(type default)
			)
			(layer "B.SilkS")
		)
		(fp_line
			(start -0.7874 -0.4064)
			(end -0.7874 0.4064)
			(stroke
				(width 0.1524)
				(type default)
			)
			(layer "B.SilkS")
		)
		(fp_line
			(start 0.7874 -0.4064)
			(end -0.7874 -0.4064)
			(stroke
				(width 0.1524)
				(type default)
			)
			(layer "B.SilkS")
		)
		(fp_poly
			(pts
				(xy 0.508 0.2794) (xy 0.508 0.2286) (xy 0.635 0.2286) (xy 0.635 -0.254) (xy 0.5334 -0.254) (xy 0.5334 -0.2794)
				(xy -0.5334 -0.2794) (xy -0.5334 -0.254) (xy -0.635 -0.254) (xy -0.635 0.254) (xy -0.5334 0.254)
				(xy -0.5334 0.2794)
			)
			(stroke
				(width 0)
				(type default)
			)
			(fill no)
			(layer "B.CrtYd")
		)
		(pad "1" smd rect
			(at -0.40005 0 90)
			(size 0.4572 0.508)
			(layers "B.Cu" "B.Mask" "B.Paste")
			(net "P3V3_SUS_NODE1")
		)
		(pad "2" smd rect
			(at 0.40005 0 90)
			(size 0.4572 0.508)
			(layers "B.Cu" "B.Mask" "B.Paste")
			(net "SPC_CPU_NODE1_RI_L")
		)
	)
	(footprint ""
		(layer "B.Cu")
		(at 62.506606 -121.057416 90)
		(property "Reference" "R316"
			(at -7.385304 10.219182 270)
			(unlocked yes)
			(layer "B.SilkS")
			(effects
				(font
					(size 0.7874 0.5842)
					(thickness 0.1524)
				)
				(justify left mirror)
			)
		)
		(property "Value" ""
			(at 0 0 90)
			(layer "B.Fab")
			(effects
				(font
					(size 1.27 1.27)
				)
				(justify mirror)
			)
		)
		(duplicate_pad_numbers_are_jumpers no)
		(fp_line
			(start 0.7874 -0.4064)
			(end -0.7874 -0.4064)
			(stroke
				(width 0.1524)
				(type default)
			)
			(layer "B.SilkS")
		)
		(fp_line
			(start -0.7874 -0.4064)
			(end -0.7874 0.4064)
			(stroke
				(width 0.1524)
				(type default)
			)
			(layer "B.SilkS")
		)
		(fp_line
			(start 0.7874 0.4064)
			(end 0.7874 -0.4064)
			(stroke
				(width 0.1524)
				(type default)
			)
			(layer "B.SilkS")
		)
		(fp_line
			(start -0.7874 0.4064)
			(end 0.7874 0.4064)
			(stroke
				(width 0.1524)
				(type default)
			)
			(layer "B.SilkS")
		)
		(fp_poly
			(pts
				(xy 0.508 0.2794) (xy 0.508 0.2286) (xy 0.635 0.2286) (xy 0.635 -0.254) (xy 0.5334 -0.254) (xy 0.5334 -0.2794)
				(xy -0.5334 -0.2794) (xy -0.5334 -0.254) (xy -0.635 -0.254) (xy -0.635 0.254) (xy -0.5334 0.254)
				(xy -0.5334 0.2794)
			)
			(stroke
				(width 0)
				(type default)
			)
			(fill no)
			(layer "B.CrtYd")
		)
		(pad "1" smd rect
			(at -0.40005 0 270)
			(size 0.4572 0.508)
			(layers "B.Cu" "B.Mask" "B.Paste")
			(net "P3V3_NODE1")
		)
		(pad "2" smd rect
			(at 0.40005 0 270)
			(size 0.4572 0.508)
			(layers "B.Cu" "B.Mask" "B.Paste")
			(net "BMC_ROMA0")
		)
	)
	(footprint ""
		(layer "B.Cu")
		(at 77.780134 -20.939506 90)
		(property "Reference" "C178"
			(at -4.176014 -0.653542 270)
			(unlocked yes)
			(layer "B.SilkS")
			(effects
				(font
					(size 0.7874 0.5842)
					(thickness 0.1524)
				)
				(justify mirror)
			)
		)
		(property "Value" ""
			(at 0 0 90)
			(layer "B.Fab")
			(effects
				(font
					(size 1.27 1.27)
				)
				(justify mirror)
			)
		)
		(duplicate_pad_numbers_are_jumpers no)
		(fp_line
			(start 1.2954 -0.5842)
			(end -1.2954 -0.5842)
			(stroke
				(width 0.1524)
				(type default)
			)
			(layer "B.SilkS")
		)
		(fp_line
			(start 0 -0.5842)
			(end 0 0.5842)
			(stroke
				(width 0.1524)
				(type default)
			)
			(layer "B.SilkS")
		)
		(fp_line
			(start -1.2954 -0.5842)
			(end -1.2954 0.5842)
			(stroke
				(width 0.1524)
				(type default)
			)
			(layer "B.SilkS")
		)
		(fp_line
			(start 1.2954 0.5842)
			(end 1.2954 -0.5842)
			(stroke
				(width 0.1524)
				(type default)
			)
			(layer "B.SilkS")
		)
		(fp_line
			(start -1.2954 0.5842)
			(end 1.2954 0.5842)
			(stroke
				(width 0.1524)
				(type default)
			)
			(layer "B.SilkS")
		)
		(fp_poly
			(pts
				(xy -0.8636 -0.4572) (xy -0.8636 -0.3556) (xy -1.143 -0.3556) (xy -1.143 0.3556) (xy -0.8636 0.3556)
				(xy -0.8636 0.4572) (xy 0.8636 0.4572) (xy 0.8636 0.3556) (xy 1.143 0.3556) (xy 1.143 -0.3556) (xy 0.8636 -0.3556)
				(xy 0.8636 -0.4572)
			)
			(stroke
				(width 0)
				(type default)
			)
			(fill no)
			(layer "B.CrtYd")
		)
		(fp_line
			(start 0.884936 -0.504952)
			(end -0.884936 -0.504952)
			(stroke
				(width 0.1)
				(type default)
			)
			(layer "B.Fab")
		)
		(fp_line
			(start -0.884936 -0.504952)
			(end -0.884936 0.504952)
			(stroke
				(width 0.1)
				(type default)
			)
			(layer "B.Fab")
		)
		(fp_line
			(start 0.884936 0.504952)
			(end 0.884936 -0.504952)
			(stroke
				(width 0.1)
				(type default)
			)
			(layer "B.Fab")
		)
		(fp_line
			(start -0.884936 0.504952)
			(end 0.884936 0.504952)
			(stroke
				(width 0.1)
				(type default)
			)
			(layer "B.Fab")
		)
		(pad "1" smd rect
			(at -0.7366 0 180)
			(size 0.7112 0.8128)
			(layers "B.Cu" "B.Mask" "B.Paste")
			(net "PV_VDDR_NODE1")
		)
		(pad "2" smd rect
			(at 0.7366 0 180)
			(size 0.7112 0.8128)
			(layers "B.Cu" "B.Mask" "B.Paste")
			(net "GND")
		)
	)
	(footprint ""
		(layer "B.Cu")
		(at 54.736238 -70.502018)
		(property "Reference" "L8"
			(at -14.047978 31.472632 0)
			(unlocked yes)
			(layer "B.SilkS")
			(effects
				(font
					(size 0.7874 0.5842)
					(thickness 0.1524)
				)
				(justify left mirror)
			)
		)
		(property "Value" ""
			(at 0 0 0)
			(layer "B.Fab")
			(effects
				(font
					(size 1.27 1.27)
				)
				(justify mirror)
			)
		)
		(duplicate_pad_numbers_are_jumpers no)
		(fp_line
			(start -0.7874 -0.4064)
			(end -0.7874 0.4064)
			(stroke
				(width 0.1524)
				(type default)
			)
			(layer "B.SilkS")
		)
		(fp_line
			(start -0.7874 0.4064)
			(end 0.7874 0.4064)
			(stroke
				(width 0.1524)
				(type default)
			)
			(layer "B.SilkS")
		)
		(fp_line
			(start -0.0889 0.4064)
			(end -0.0889 -0.4064)
			(stroke
				(width 0.1524)
				(type default)
			)
			(layer "B.SilkS")
		)
		(fp_line
			(start 0.0889 0.4064)
			(end 0.0889 -0.4064)
			(stroke
				(width 0.1524)
				(type default)
			)
			(layer "B.SilkS")
		)
		(fp_line
			(start 0.7874 -0.4064)
			(end -0.7874 -0.4064)
			(stroke
				(width 0.1524)
				(type default)
			)
			(layer "B.SilkS")
		)
		(fp_line
			(start 0.7874 0.4064)
			(end 0.7874 -0.4064)
			(stroke
				(width 0.1524)
				(type default)
			)
			(layer "B.SilkS")
		)
		(fp_poly
			(pts
				(xy 0.5334 0.254) (xy 0.635 0.254) (xy 0.635 0.2286) (xy 0.635 -0.254) (xy 0.5334 -0.254) (xy 0.5334 -0.2794)
				(xy -0.5334 -0.2794) (xy -0.5334 -0.254) (xy -0.635 -0.254) (xy -0.635 0.254) (xy -0.5334 0.254)
				(xy -0.5334 0.2794) (xy 0.508 0.2794) (xy 0.5334 0.2794)
			)
			(stroke
				(width 0)
				(type default)
			)
			(fill no)
			(layer "B.CrtYd")
		)
		(pad "1" smd rect
			(at -0.40005 0 180)
			(size 0.4572 0.508)
			(layers "B.Cu" "B.Mask" "B.Paste")
			(net "P1V5_SUS_NODE1")
		)
		(pad "2" smd rect
			(at 0.40005 0 180)
			(size 0.4572 0.508)
			(layers "B.Cu" "B.Mask" "B.Paste")
			(net "P1V5_SFRPLL_NODE1")
		)
	)
	(footprint ""
		(layer "B.Cu")
		(at 73.12787 -21.11248 90)
		(property "Reference" "C162"
			(at -5.822188 -0.810006 270)
			(unlocked yes)
			(layer "B.SilkS")
			(effects
				(font
					(size 0.7874 0.5842)
					(thickness 0.1524)
				)
				(justify left mirror)
			)
		)
		(property "Value" ""
			(at 0 0 90)
			(layer "B.Fab")
			(effects
				(font
					(size 1.27 1.27)
				)
				(justify mirror)
			)
		)
		(duplicate_pad_numbers_are_jumpers no)
		(fp_line
			(start 0.7874 -0.4064)
			(end -0.7874 -0.4064)
			(stroke
				(width 0.1524)
				(type default)
			)
			(layer "B.SilkS")
		)
		(fp_line
			(start -0.7874 -0.4064)
			(end -0.7874 0.4064)
			(stroke
				(width 0.1524)
				(type default)
			)
			(layer "B.SilkS")
		)
		(fp_line
			(start 0 0.381)
			(end 0 -0.381)
			(stroke
				(width 0.1524)
				(type default)
			)
			(layer "B.SilkS")
		)
		(fp_line
			(start 0.7874 0.4064)
			(end 0.7874 -0.4064)
			(stroke
				(width 0.1524)
				(type default)
			)
			(layer "B.SilkS")
		)
		(fp_line
			(start -0.7874 0.4064)
			(end 0.7874 0.4064)
			(stroke
				(width 0.1524)
				(type default)
			)
			(layer "B.SilkS")
		)
		(fp_poly
			(pts
				(xy 0.5334 0.254) (xy 0.635 0.254) (xy 0.635 0.2286) (xy 0.635 -0.254) (xy 0.5334 -0.254) (xy 0.5334 -0.2794)
				(xy -0.5334 -0.2794) (xy -0.5334 -0.254) (xy -0.635 -0.254) (xy -0.635 0.254) (xy -0.5334 0.254)
				(xy -0.5334 0.2794) (xy 0.508 0.2794) (xy 0.5334 0.2794)
			)
			(stroke
				(width 0)
				(type default)
			)
			(fill no)
			(layer "B.CrtYd")
		)
		(pad "1" smd rect
			(at -0.40005 0 270)
			(size 0.4572 0.508)
			(layers "B.Cu" "B.Mask" "B.Paste")
			(net "PV_VDDR_NODE1")
		)
		(pad "2" smd rect
			(at 0.40005 0 270)
			(size 0.4572 0.508)
			(layers "B.Cu" "B.Mask" "B.Paste")
			(net "GND")
		)
	)
	(footprint ""
		(layer "B.Cu")
		(at 49.38776 -188.126624 -90)
		(property "Reference" "R856"
			(at -4.318254 0.532892 270)
			(unlocked yes)
			(layer "B.SilkS")
			(effects
				(font
					(size 0.7874 0.5842)
					(thickness 0.1524)
				)
				(justify left mirror)
			)
		)
		(property "Value" ""
			(at 0 0 90)
			(layer "B.Fab")
			(effects
				(font
					(size 1.27 1.27)
				)
				(justify mirror)
			)
		)
		(duplicate_pad_numbers_are_jumpers no)
		(fp_line
			(start -0.7874 0.4064)
			(end 0.7874 0.4064)
			(stroke
				(width 0.1524)
				(type default)
			)
			(layer "B.SilkS")
		)
		(fp_line
			(start 0.7874 0.4064)
			(end 0.7874 -0.4064)
			(stroke
				(width 0.1524)
				(type default)
			)
			(layer "B.SilkS")
		)
		(fp_line
			(start -0.7874 -0.4064)
			(end -0.7874 0.4064)
			(stroke
				(width 0.1524)
				(type default)
			)
			(layer "B.SilkS")
		)
		(fp_line
			(start 0.7874 -0.4064)
			(end -0.7874 -0.4064)
			(stroke
				(width 0.1524)
				(type default)
			)
			(layer "B.SilkS")
		)
		(fp_poly
			(pts
				(xy 0.508 0.2794) (xy 0.508 0.2286) (xy 0.635 0.2286) (xy 0.635 -0.254) (xy 0.5334 -0.254) (xy 0.5334 -0.2794)
				(xy -0.5334 -0.2794) (xy -0.5334 -0.254) (xy -0.635 -0.254) (xy -0.635 0.254) (xy -0.5334 0.254)
				(xy -0.5334 0.2794)
			)
			(stroke
				(width 0)
				(type default)
			)
			(fill no)
			(layer "B.CrtYd")
		)
		(pad "1" smd rect
			(at -0.40005 0 90)
			(size 0.4572 0.508)
			(layers "B.Cu" "B.Mask" "B.Paste")
			(net "PSU4_DC_OK_R")
		)
		(pad "2" smd rect
			(at 0.40005 0 90)
			(size 0.4572 0.508)
			(layers "B.Cu" "B.Mask" "B.Paste")
			(net "GND")
		)
	)
	(footprint ""
		(layer "B.Cu")
		(at 171.846494 -122.004836 180)
		(property "Reference" "C785"
			(at 1.347724 3.800348 0)
			(unlocked yes)
			(layer "B.SilkS")
			(effects
				(font
					(size 0.7874 0.5842)
					(thickness 0.1524)
				)
				(justify mirror)
			)
		)
		(property "Value" ""
			(at 0 0 0)
			(layer "B.Fab")
			(effects
				(font
					(size 1.27 1.27)
				)
				(justify mirror)
			)
		)
		(duplicate_pad_numbers_are_jumpers no)
		(fp_line
			(start 1.2954 0.5842)
			(end 1.2954 -0.5842)
			(stroke
				(width 0.1524)
				(type default)
			)
			(layer "B.SilkS")
		)
		(fp_line
			(start 1.2954 -0.5842)
			(end -1.2954 -0.5842)
			(stroke
				(width 0.1524)
				(type default)
			)
			(layer "B.SilkS")
		)
		(fp_line
			(start 0 -0.5842)
			(end 0 0.5842)
			(stroke
				(width 0.1524)
				(type default)
			)
			(layer "B.SilkS")
		)
		(fp_line
			(start -1.2954 0.5842)
			(end 1.2954 0.5842)
			(stroke
				(width 0.1524)
				(type default)
			)
			(layer "B.SilkS")
		)
		(fp_line
			(start -1.2954 -0.5842)
			(end -1.2954 0.5842)
			(stroke
				(width 0.1524)
				(type default)
			)
			(layer "B.SilkS")
		)
		(fp_poly
			(pts
				(xy -0.8636 -0.4572) (xy -0.8636 -0.3556) (xy -1.143 -0.3556) (xy -1.143 0.3556) (xy -0.8636 0.3556)
				(xy -0.8636 0.4572) (xy 0.8636 0.4572) (xy 0.8636 0.3556) (xy 1.143 0.3556) (xy 1.143 -0.3556) (xy 0.8636 -0.3556)
				(xy 0.8636 -0.4572)
			)
			(stroke
				(width 0)
				(type default)
			)
			(fill no)
			(layer "B.CrtYd")
		)
		(fp_line
			(start 0.884936 0.504952)
			(end 0.884936 -0.504952)
			(stroke
				(width 0.1)
				(type default)
			)
			(layer "B.Fab")
		)
		(fp_line
			(start 0.884936 -0.504952)
			(end -0.884936 -0.504952)
			(stroke
				(width 0.1)
				(type default)
			)
			(layer "B.Fab")
		)
		(fp_line
			(start -0.884936 0.504952)
			(end 0.884936 0.504952)
			(stroke
				(width 0.1)
				(type default)
			)
			(layer "B.Fab")
		)
		(fp_line
			(start -0.884936 -0.504952)
			(end -0.884936 0.504952)
			(stroke
				(width 0.1)
				(type default)
			)
			(layer "B.Fab")
		)
		(pad "1" smd rect
			(at -0.7366 0 270)
			(size 0.7112 0.8128)
			(layers "B.Cu" "B.Mask" "B.Paste")
			(net "P3V3_STB_NODE1")
		)
		(pad "2" smd rect
			(at 0.7366 0 270)
			(size 0.7112 0.8128)
			(layers "B.Cu" "B.Mask" "B.Paste")
			(net "GND")
		)
	)
	(footprint ""
		(layer "B.Cu")
		(at 62.027054 -82.117184 -90)
		(property "Reference" "C75"
			(at 30.982666 14.217904 270)
			(unlocked yes)
			(layer "B.SilkS")
			(effects
				(font
					(size 0.7874 0.5842)
					(thickness 0.1524)
				)
				(justify mirror)
			)
		)
		(property "Value" ""
			(at 0 0 90)
			(layer "B.Fab")
			(effects
				(font
					(size 1.27 1.27)
				)
				(justify mirror)
			)
		)
		(duplicate_pad_numbers_are_jumpers no)
		(fp_line
			(start -1.2954 0.5842)
			(end 1.2954 0.5842)
			(stroke
				(width 0.1524)
				(type default)
			)
			(layer "B.SilkS")
		)
		(fp_line
			(start 1.2954 0.5842)
			(end 1.2954 -0.5842)
			(stroke
				(width 0.1524)
				(type default)
			)
			(layer "B.SilkS")
		)
		(fp_line
			(start -1.2954 -0.5842)
			(end -1.2954 0.5842)
			(stroke
				(width 0.1524)
				(type default)
			)
			(layer "B.SilkS")
		)
		(fp_line
			(start 0 -0.5842)
			(end 0 0.5842)
			(stroke
				(width 0.1524)
				(type default)
			)
			(layer "B.SilkS")
		)
		(fp_line
			(start 1.2954 -0.5842)
			(end -1.2954 -0.5842)
			(stroke
				(width 0.1524)
				(type default)
			)
			(layer "B.SilkS")
		)
		(fp_poly
			(pts
				(xy -0.8636 -0.4572) (xy -0.8636 -0.3556) (xy -1.143 -0.3556) (xy -1.143 0.3556) (xy -0.8636 0.3556)
				(xy -0.8636 0.4572) (xy 0.8636 0.4572) (xy 0.8636 0.3556) (xy 1.143 0.3556) (xy 1.143 -0.3556) (xy 0.8636 -0.3556)
				(xy 0.8636 -0.4572)
			)
			(stroke
				(width 0)
				(type default)
			)
			(fill no)
			(layer "B.CrtYd")
		)
		(fp_line
			(start -0.884936 0.504952)
			(end 0.884936 0.504952)
			(stroke
				(width 0.1)
				(type default)
			)
			(layer "B.Fab")
		)
		(fp_line
			(start 0.884936 0.504952)
			(end 0.884936 -0.504952)
			(stroke
				(width 0.1)
				(type default)
			)
			(layer "B.Fab")
		)
		(fp_line
			(start -0.884936 -0.504952)
			(end -0.884936 0.504952)
			(stroke
				(width 0.1)
				(type default)
			)
			(layer "B.Fab")
		)
		(fp_line
			(start 0.884936 -0.504952)
			(end -0.884936 -0.504952)
			(stroke
				(width 0.1)
				(type default)
			)
			(layer "B.Fab")
		)
		(pad "1" smd rect
			(at -0.7366 0)
			(size 0.7112 0.8128)
			(layers "B.Cu" "B.Mask" "B.Paste")
			(net "P1V8_SUS_NODE1")
		)
		(pad "2" smd rect
			(at 0.7366 0)
			(size 0.7112 0.8128)
			(layers "B.Cu" "B.Mask" "B.Paste")
			(net "GND")
		)
	)
	(footprint ""
		(layer "B.Cu")
		(at 37.92474 -147.577302)
		(property "Reference" "R554"
			(at -2.549652 0.339852 0)
			(unlocked yes)
			(layer "B.SilkS")
			(effects
				(font
					(size 0.7874 0.5842)
					(thickness 0.1524)
				)
				(justify left mirror)
			)
		)
		(property "Value" ""
			(at 0 0 0)
			(layer "B.Fab")
			(effects
				(font
					(size 1.27 1.27)
				)
				(justify mirror)
			)
		)
		(duplicate_pad_numbers_are_jumpers no)
		(fp_line
			(start -0.7874 -0.4064)
			(end -0.7874 0.4064)
			(stroke
				(width 0.1524)
				(type default)
			)
			(layer "B.SilkS")
		)
		(fp_line
			(start -0.7874 0.4064)
			(end 0.7874 0.4064)
			(stroke
				(width 0.1524)
				(type default)
			)
			(layer "B.SilkS")
		)
		(fp_line
			(start 0.7874 -0.4064)
			(end -0.7874 -0.4064)
			(stroke
				(width 0.1524)
				(type default)
			)
			(layer "B.SilkS")
		)
		(fp_line
			(start 0.7874 0.4064)
			(end 0.7874 -0.4064)
			(stroke
				(width 0.1524)
				(type default)
			)
			(layer "B.SilkS")
		)
		(fp_poly
			(pts
				(xy 0.508 0.2794) (xy 0.508 0.2286) (xy 0.635 0.2286) (xy 0.635 -0.254) (xy 0.5334 -0.254) (xy 0.5334 -0.2794)
				(xy -0.5334 -0.2794) (xy -0.5334 -0.254) (xy -0.635 -0.254) (xy -0.635 0.254) (xy -0.5334 0.254)
				(xy -0.5334 0.2794)
			)
			(stroke
				(width 0)
				(type default)
			)
			(fill no)
			(layer "B.CrtYd")
		)
		(pad "1" smd rect
			(at -0.40005 0 180)
			(size 0.4572 0.508)
			(layers "B.Cu" "B.Mask" "B.Paste")
			(net "GND")
		)
		(pad "2" smd rect
			(at 0.40005 0 180)
			(size 0.4572 0.508)
			(layers "B.Cu" "B.Mask" "B.Paste")
			(net "LAN1_NC_SI_CLK_IN")
		)
	)
	(footprint ""
		(layer "B.Cu")
		(at 134.985252 -151.31415 90)
		(property "Reference" "C864"
			(at 1.48336 1.756664 270)
			(unlocked yes)
			(layer "B.SilkS")
			(effects
				(font
					(size 0.7874 0.5842)
					(thickness 0.1524)
				)
				(justify left mirror)
			)
		)
		(property "Value" ""
			(at 0 0 90)
			(layer "B.Fab")
			(effects
				(font
					(size 1.27 1.27)
				)
				(justify mirror)
			)
		)
		(duplicate_pad_numbers_are_jumpers no)
		(fp_line
			(start 0.7874 -0.4064)
			(end -0.7874 -0.4064)
			(stroke
				(width 0.1524)
				(type default)
			)
			(layer "B.SilkS")
		)
		(fp_line
			(start -0.7874 -0.4064)
			(end -0.7874 0.4064)
			(stroke
				(width 0.1524)
				(type default)
			)
			(layer "B.SilkS")
		)
		(fp_line
			(start 0 0.381)
			(end 0 -0.381)
			(stroke
				(width 0.1524)
				(type default)
			)
			(layer "B.SilkS")
		)
		(fp_line
			(start 0.7874 0.4064)
			(end 0.7874 -0.4064)
			(stroke
				(width 0.1524)
				(type default)
			)
			(layer "B.SilkS")
		)
		(fp_line
			(start -0.7874 0.4064)
			(end 0.7874 0.4064)
			(stroke
				(width 0.1524)
				(type default)
			)
			(layer "B.SilkS")
		)
		(fp_poly
			(pts
				(xy 0.5334 0.254) (xy 0.635 0.254) (xy 0.635 0.2286) (xy 0.635 -0.254) (xy 0.5334 -0.254) (xy 0.5334 -0.2794)
				(xy -0.5334 -0.2794) (xy -0.5334 -0.254) (xy -0.635 -0.254) (xy -0.635 0.254) (xy -0.5334 0.254)
				(xy -0.5334 0.2794) (xy 0.508 0.2794) (xy 0.5334 0.2794)
			)
			(stroke
				(width 0)
				(type default)
			)
			(fill no)
			(layer "B.CrtYd")
		)
		(pad "1" smd rect
			(at -0.40005 0 270)
			(size 0.4572 0.508)
			(layers "B.Cu" "B.Mask" "B.Paste")
			(net "P1V0_NODE1")
		)
		(pad "2" smd rect
			(at 0.40005 0 270)
			(size 0.4572 0.508)
			(layers "B.Cu" "B.Mask" "B.Paste")
			(net "GND")
		)
	)
	(footprint ""
		(layer "B.Cu")
		(at 144.909032 -34.646616)
		(property "Reference" "R1194"
			(at 1.24714 17.425924 0)
			(unlocked yes)
			(layer "B.SilkS")
			(effects
				(font
					(size 0.7874 0.5842)
					(thickness 0.1524)
				)
				(justify left mirror)
			)
		)
		(property "Value" ""
			(at 0 0 0)
			(layer "B.Fab")
			(effects
				(font
					(size 1.27 1.27)
				)
				(justify mirror)
			)
		)
		(duplicate_pad_numbers_are_jumpers no)
		(fp_line
			(start -0.7874 -0.4064)
			(end -0.7874 0.4064)
			(stroke
				(width 0.1524)
				(type default)
			)
			(layer "B.SilkS")
		)
		(fp_line
			(start -0.7874 0.4064)
			(end 0.7874 0.4064)
			(stroke
				(width 0.1524)
				(type default)
			)
			(layer "B.SilkS")
		)
		(fp_line
			(start 0.7874 -0.4064)
			(end -0.7874 -0.4064)
			(stroke
				(width 0.1524)
				(type default)
			)
			(layer "B.SilkS")
		)
		(fp_line
			(start 0.7874 0.4064)
			(end 0.7874 -0.4064)
			(stroke
				(width 0.1524)
				(type default)
			)
			(layer "B.SilkS")
		)
		(fp_poly
			(pts
				(xy 0.508 0.2794) (xy 0.508 0.2286) (xy 0.635 0.2286) (xy 0.635 -0.254) (xy 0.5334 -0.254) (xy 0.5334 -0.2794)
				(xy -0.5334 -0.2794) (xy -0.5334 -0.254) (xy -0.635 -0.254) (xy -0.635 0.254) (xy -0.5334 0.254)
				(xy -0.5334 0.2794)
			)
			(stroke
				(width 0)
				(type default)
			)
			(fill no)
			(layer "B.CrtYd")
		)
		(pad "1" smd rect
			(at -0.40005 0 180)
			(size 0.4572 0.508)
			(layers "B.Cu" "B.Mask" "B.Paste")
			(net "SIO_CPLD_RSV3_R")
		)
		(pad "2" smd rect
			(at 0.40005 0 180)
			(size 0.4572 0.508)
			(layers "B.Cu" "B.Mask" "B.Paste")
			(net "P3V3_NODE1")
		)
	)
	(footprint ""
		(layer "B.Cu")
		(at 162.089592 -107.398566)
		(property "Reference" "L34"
			(at 1.326642 1.183386 270)
			(unlocked yes)
			(layer "B.SilkS")
			(effects
				(font
					(size 0.7874 0.5842)
					(thickness 0.1524)
				)
				(justify left mirror)
			)
		)
		(property "Value" ""
			(at 0 0 0)
			(layer "B.Fab")
			(effects
				(font
					(size 1.27 1.27)
				)
				(justify mirror)
			)
		)
		(duplicate_pad_numbers_are_jumpers no)
		(fp_line
			(start -0.700024 -1.459992)
			(end -0.700024 1.439926)
			(stroke
				(width 0.1524)
				(type default)
			)
			(layer "B.SilkS")
		)
		(fp_line
			(start -0.700024 0.195326)
			(end 0.700024 0.195326)
			(stroke
				(width 0.1524)
				(type default)
			)
			(layer "B.SilkS")
		)
		(fp_line
			(start -0.700024 1.439926)
			(end 0.700024 1.439926)
			(stroke
				(width 0.1524)
				(type default)
			)
			(layer "B.SilkS")
		)
		(fp_line
			(start 0.700024 -1.459992)
			(end -0.700024 -1.459992)
			(stroke
				(width 0.1524)
				(type default)
			)
			(layer "B.SilkS")
		)
		(fp_line
			(start 0.700024 -0.139192)
			(end -0.700024 -0.139192)
			(stroke
				(width 0.1524)
				(type default)
			)
			(layer "B.SilkS")
		)
		(fp_line
			(start 0.700024 1.439926)
			(end 0.700024 -1.459992)
			(stroke
				(width 0.1524)
				(type default)
			)
			(layer "B.SilkS")
		)
		(fp_poly
			(pts
				(xy 0.700024 1.100074) (xy 0.5842 1.100074) (xy 0.5842 1.3716) (xy -0.5842 1.3716) (xy -0.5842 1.100074)
				(xy -0.700024 1.100074) (xy -0.700024 -1.100074) (xy -0.5842 -1.100074) (xy -0.5842 -1.3716) (xy 0.5842 -1.3716)
				(xy 0.5842 -1.100074) (xy 0.700024 -1.100074)
			)
			(stroke
				(width 0)
				(type default)
			)
			(fill no)
			(layer "B.CrtYd")
		)
		(fp_line
			(start -0.700024 -1.100074)
			(end -0.700024 1.100074)
			(stroke
				(width 0.1)
				(type default)
			)
			(layer "B.Fab")
		)
		(fp_line
			(start -0.700024 1.100074)
			(end 0.700024 1.100074)
			(stroke
				(width 0.1)
				(type default)
			)
			(layer "B.Fab")
		)
		(fp_line
			(start 0.700024 -1.100074)
			(end -0.700024 -1.100074)
			(stroke
				(width 0.1)
				(type default)
			)
			(layer "B.Fab")
		)
		(fp_line
			(start 0.700024 1.100074)
			(end 0.700024 -1.100074)
			(stroke
				(width 0.1)
				(type default)
			)
			(layer "B.Fab")
		)
		(pad "1" smd rect
			(at 0 -0.899922 270)
			(size 0.8128 1.016)
			(layers "B.Cu" "B.Mask" "B.Paste")
			(net "P3V3_NODE1")
		)
		(pad "2" smd rect
			(at 0 0.899922 270)
			(size 0.8128 1.016)
			(layers "B.Cu" "B.Mask" "B.Paste")
			(net "P3V3_USB_NODE1")
		)
	)
	(footprint ""
		(layer "B.Cu")
		(at 48.75022 -159.29229 180)
		(property "Reference" "C394"
			(at 11.81354 3.457194 0)
			(unlocked yes)
			(layer "B.SilkS")
			(effects
				(font
					(size 0.7874 0.5842)
					(thickness 0.1524)
				)
				(justify left mirror)
			)
		)
		(property "Value" ""
			(at 0 0 0)
			(layer "B.Fab")
			(effects
				(font
					(size 1.27 1.27)
				)
				(justify mirror)
			)
		)
		(duplicate_pad_numbers_are_jumpers no)
		(fp_line
			(start 0.7874 0.4064)
			(end 0.7874 -0.4064)
			(stroke
				(width 0.1524)
				(type default)
			)
			(layer "B.SilkS")
		)
		(fp_line
			(start 0.7874 -0.4064)
			(end -0.7874 -0.4064)
			(stroke
				(width 0.1524)
				(type default)
			)
			(layer "B.SilkS")
		)
		(fp_line
			(start 0 0.381)
			(end 0 -0.381)
			(stroke
				(width 0.1524)
				(type default)
			)
			(layer "B.SilkS")
		)
		(fp_line
			(start -0.7874 0.4064)
			(end 0.7874 0.4064)
			(stroke
				(width 0.1524)
				(type default)
			)
			(layer "B.SilkS")
		)
		(fp_line
			(start -0.7874 -0.4064)
			(end -0.7874 0.4064)
			(stroke
				(width 0.1524)
				(type default)
			)
			(layer "B.SilkS")
		)
		(fp_poly
			(pts
				(xy 0.5334 0.254) (xy 0.635 0.254) (xy 0.635 0.2286) (xy 0.635 -0.254) (xy 0.5334 -0.254) (xy 0.5334 -0.2794)
				(xy -0.5334 -0.2794) (xy -0.5334 -0.254) (xy -0.635 -0.254) (xy -0.635 0.254) (xy -0.5334 0.254)
				(xy -0.5334 0.2794) (xy 0.508 0.2794) (xy 0.5334 0.2794)
			)
			(stroke
				(width 0)
				(type default)
			)
			(fill no)
			(layer "B.CrtYd")
		)
		(pad "1" smd rect
			(at -0.40005 0)
			(size 0.4572 0.508)
			(layers "B.Cu" "B.Mask" "B.Paste")
			(net "P3V3_NODE1")
		)
		(pad "2" smd rect
			(at 0.40005 0)
			(size 0.4572 0.508)
			(layers "B.Cu" "B.Mask" "B.Paste")
			(net "GND")
		)
	)
	(footprint ""
		(layer "B.Cu")
		(at 60.615322 -92.042234 90)
		(property "Reference" "R59"
			(at -1.062228 2.519426 270)
			(unlocked yes)
			(layer "B.SilkS")
			(effects
				(font
					(size 0.7874 0.5842)
					(thickness 0.1524)
				)
				(justify left mirror)
			)
		)
		(property "Value" ""
			(at 0 0 90)
			(layer "B.Fab")
			(effects
				(font
					(size 1.27 1.27)
				)
				(justify mirror)
			)
		)
		(duplicate_pad_numbers_are_jumpers no)
		(fp_line
			(start 0.7874 -0.4064)
			(end -0.7874 -0.4064)
			(stroke
				(width 0.1524)
				(type default)
			)
			(layer "B.SilkS")
		)
		(fp_line
			(start -0.7874 -0.4064)
			(end -0.7874 0.4064)
			(stroke
				(width 0.1524)
				(type default)
			)
			(layer "B.SilkS")
		)
		(fp_line
			(start 0.7874 0.4064)
			(end 0.7874 -0.4064)
			(stroke
				(width 0.1524)
				(type default)
			)
			(layer "B.SilkS")
		)
		(fp_line
			(start -0.7874 0.4064)
			(end 0.7874 0.4064)
			(stroke
				(width 0.1524)
				(type default)
			)
			(layer "B.SilkS")
		)
		(fp_poly
			(pts
				(xy 0.508 0.2794) (xy 0.508 0.2286) (xy 0.635 0.2286) (xy 0.635 -0.254) (xy 0.5334 -0.254) (xy 0.5334 -0.2794)
				(xy -0.5334 -0.2794) (xy -0.5334 -0.254) (xy -0.635 -0.254) (xy -0.635 0.254) (xy -0.5334 0.254)
				(xy -0.5334 0.2794)
			)
			(stroke
				(width 0)
				(type default)
			)
			(fill no)
			(layer "B.CrtYd")
		)
		(pad "1" smd rect
			(at -0.40005 0 270)
			(size 0.4572 0.508)
			(layers "B.Cu" "B.Mask" "B.Paste")
			(net "SPI_CPU_NODE1_SCLK_R")
		)
		(pad "2" smd rect
			(at 0.40005 0 270)
			(size 0.4572 0.508)
			(layers "B.Cu" "B.Mask" "B.Paste")
			(net "SPI_CPU_NODE1_SCLK")
		)
	)
	(footprint ""
		(layer "B.Cu")
		(at 116.44376 -188.126624 90)
		(property "Reference" "R955"
			(at 4.080256 0.69088 270)
			(unlocked yes)
			(layer "B.SilkS")
			(effects
				(font
					(size 0.7874 0.5842)
					(thickness 0.1524)
				)
				(justify left mirror)
			)
		)
		(property "Value" ""
			(at 0 0 90)
			(layer "B.Fab")
			(effects
				(font
					(size 1.27 1.27)
				)
				(justify mirror)
			)
		)
		(duplicate_pad_numbers_are_jumpers no)
		(fp_line
			(start 0.7874 -0.4064)
			(end -0.7874 -0.4064)
			(stroke
				(width 0.1524)
				(type default)
			)
			(layer "B.SilkS")
		)
		(fp_line
			(start -0.7874 -0.4064)
			(end -0.7874 0.4064)
			(stroke
				(width 0.1524)
				(type default)
			)
			(layer "B.SilkS")
		)
		(fp_line
			(start 0.7874 0.4064)
			(end 0.7874 -0.4064)
			(stroke
				(width 0.1524)
				(type default)
			)
			(layer "B.SilkS")
		)
		(fp_line
			(start -0.7874 0.4064)
			(end 0.7874 0.4064)
			(stroke
				(width 0.1524)
				(type default)
			)
			(layer "B.SilkS")
		)
		(fp_poly
			(pts
				(xy 0.508 0.2794) (xy 0.508 0.2286) (xy 0.635 0.2286) (xy 0.635 -0.254) (xy 0.5334 -0.254) (xy 0.5334 -0.2794)
				(xy -0.5334 -0.2794) (xy -0.5334 -0.254) (xy -0.635 -0.254) (xy -0.635 0.254) (xy -0.5334 0.254)
				(xy -0.5334 0.2794)
			)
			(stroke
				(width 0)
				(type default)
			)
			(fill no)
			(layer "B.CrtYd")
		)
		(pad "1" smd rect
			(at -0.40005 0 270)
			(size 0.4572 0.508)
			(layers "B.Cu" "B.Mask" "B.Paste")
			(net "UART_T7_NODE1_RXD")
		)
		(pad "2" smd rect
			(at 0.40005 0 270)
			(size 0.4572 0.508)
			(layers "B.Cu" "B.Mask" "B.Paste")
			(net "UART_T7_NODE1_RXD_R")
		)
	)
	(footprint ""
		(layer "B.Cu")
		(at 83.021678 -29.82214)
		(property "Reference" "C174"
			(at -0.046482 1.340866 0)
			(unlocked yes)
			(layer "B.SilkS")
			(effects
				(font
					(size 0.7874 0.5842)
					(thickness 0.1524)
				)
				(justify mirror)
			)
		)
		(property "Value" ""
			(at 0 0 0)
			(layer "B.Fab")
			(effects
				(font
					(size 1.27 1.27)
				)
				(justify mirror)
			)
		)
		(duplicate_pad_numbers_are_jumpers no)
		(fp_line
			(start -1.2954 -0.5842)
			(end -1.2954 0.5842)
			(stroke
				(width 0.1524)
				(type default)
			)
			(layer "B.SilkS")
		)
		(fp_line
			(start -1.2954 0.5842)
			(end 1.2954 0.5842)
			(stroke
				(width 0.1524)
				(type default)
			)
			(layer "B.SilkS")
		)
		(fp_line
			(start 0 -0.5842)
			(end 0 0.5842)
			(stroke
				(width 0.1524)
				(type default)
			)
			(layer "B.SilkS")
		)
		(fp_line
			(start 1.2954 -0.5842)
			(end -1.2954 -0.5842)
			(stroke
				(width 0.1524)
				(type default)
			)
			(layer "B.SilkS")
		)
		(fp_line
			(start 1.2954 0.5842)
			(end 1.2954 -0.5842)
			(stroke
				(width 0.1524)
				(type default)
			)
			(layer "B.SilkS")
		)
		(fp_poly
			(pts
				(xy -0.8636 -0.4572) (xy -0.8636 -0.3556) (xy -1.143 -0.3556) (xy -1.143 0.3556) (xy -0.8636 0.3556)
				(xy -0.8636 0.4572) (xy 0.8636 0.4572) (xy 0.8636 0.3556) (xy 1.143 0.3556) (xy 1.143 -0.3556) (xy 0.8636 -0.3556)
				(xy 0.8636 -0.4572)
			)
			(stroke
				(width 0)
				(type default)
			)
			(fill no)
			(layer "B.CrtYd")
		)
		(fp_line
			(start -0.884936 -0.504952)
			(end -0.884936 0.504952)
			(stroke
				(width 0.1)
				(type default)
			)
			(layer "B.Fab")
		)
		(fp_line
			(start -0.884936 0.504952)
			(end 0.884936 0.504952)
			(stroke
				(width 0.1)
				(type default)
			)
			(layer "B.Fab")
		)
		(fp_line
			(start 0.884936 -0.504952)
			(end -0.884936 -0.504952)
			(stroke
				(width 0.1)
				(type default)
			)
			(layer "B.Fab")
		)
		(fp_line
			(start 0.884936 0.504952)
			(end 0.884936 -0.504952)
			(stroke
				(width 0.1)
				(type default)
			)
			(layer "B.Fab")
		)
		(pad "1" smd rect
			(at -0.7366 0 90)
			(size 0.7112 0.8128)
			(layers "B.Cu" "B.Mask" "B.Paste")
			(net "PV_VDDR_NODE1")
		)
		(pad "2" smd rect
			(at 0.7366 0 90)
			(size 0.7112 0.8128)
			(layers "B.Cu" "B.Mask" "B.Paste")
			(net "GND")
		)
	)
	(footprint ""
		(layer "B.Cu")
		(at 37.25545 -104.654096 90)
		(property "Reference" "C822"
			(at 1.103376 1.638046 270)
			(unlocked yes)
			(layer "B.SilkS")
			(effects
				(font
					(size 0.7874 0.5842)
					(thickness 0.1524)
				)
				(justify left mirror)
			)
		)
		(property "Value" ""
			(at 0 0 90)
			(layer "B.Fab")
			(effects
				(font
					(size 1.27 1.27)
				)
				(justify mirror)
			)
		)
		(duplicate_pad_numbers_are_jumpers no)
		(fp_line
			(start 0.7874 -0.4064)
			(end -0.7874 -0.4064)
			(stroke
				(width 0.1524)
				(type default)
			)
			(layer "B.SilkS")
		)
		(fp_line
			(start -0.7874 -0.4064)
			(end -0.7874 0.4064)
			(stroke
				(width 0.1524)
				(type default)
			)
			(layer "B.SilkS")
		)
		(fp_line
			(start 0 0.381)
			(end 0 -0.381)
			(stroke
				(width 0.1524)
				(type default)
			)
			(layer "B.SilkS")
		)
		(fp_line
			(start 0.7874 0.4064)
			(end 0.7874 -0.4064)
			(stroke
				(width 0.1524)
				(type default)
			)
			(layer "B.SilkS")
		)
		(fp_line
			(start -0.7874 0.4064)
			(end 0.7874 0.4064)
			(stroke
				(width 0.1524)
				(type default)
			)
			(layer "B.SilkS")
		)
		(fp_poly
			(pts
				(xy 0.5334 0.254) (xy 0.635 0.254) (xy 0.635 0.2286) (xy 0.635 -0.254) (xy 0.5334 -0.254) (xy 0.5334 -0.2794)
				(xy -0.5334 -0.2794) (xy -0.5334 -0.254) (xy -0.635 -0.254) (xy -0.635 0.254) (xy -0.5334 0.254)
				(xy -0.5334 0.2794) (xy 0.508 0.2794) (xy 0.5334 0.2794)
			)
			(stroke
				(width 0)
				(type default)
			)
			(fill no)
			(layer "B.CrtYd")
		)
		(pad "1" smd rect
			(at -0.40005 0 270)
			(size 0.4572 0.508)
			(layers "B.Cu" "B.Mask" "B.Paste")
			(net "P1V5_SUS_NODE1")
		)
		(pad "2" smd rect
			(at 0.40005 0 270)
			(size 0.4572 0.508)
			(layers "B.Cu" "B.Mask" "B.Paste")
			(net "GND")
		)
	)
	(footprint ""
		(layer "B.Cu")
		(at 50.53076 -181.992524 -90)
		(property "Reference" "C606"
			(at 3.618738 10.515346 270)
			(unlocked yes)
			(layer "B.SilkS")
			(effects
				(font
					(size 0.7874 0.5842)
					(thickness 0.1524)
				)
				(justify left mirror)
			)
		)
		(property "Value" ""
			(at 0 0 90)
			(layer "B.Fab")
			(effects
				(font
					(size 1.27 1.27)
				)
				(justify mirror)
			)
		)
		(duplicate_pad_numbers_are_jumpers no)
		(fp_line
			(start -0.7874 0.4064)
			(end 0.7874 0.4064)
			(stroke
				(width 0.1524)
				(type default)
			)
			(layer "B.SilkS")
		)
		(fp_line
			(start 0.7874 0.4064)
			(end 0.7874 -0.4064)
			(stroke
				(width 0.1524)
				(type default)
			)
			(layer "B.SilkS")
		)
		(fp_line
			(start 0 0.381)
			(end 0 -0.381)
			(stroke
				(width 0.1524)
				(type default)
			)
			(layer "B.SilkS")
		)
		(fp_line
			(start -0.7874 -0.4064)
			(end -0.7874 0.4064)
			(stroke
				(width 0.1524)
				(type default)
			)
			(layer "B.SilkS")
		)
		(fp_line
			(start 0.7874 -0.4064)
			(end -0.7874 -0.4064)
			(stroke
				(width 0.1524)
				(type default)
			)
			(layer "B.SilkS")
		)
		(fp_poly
			(pts
				(xy 0.5334 0.254) (xy 0.635 0.254) (xy 0.635 0.2286) (xy 0.635 -0.254) (xy 0.5334 -0.254) (xy 0.5334 -0.2794)
				(xy -0.5334 -0.2794) (xy -0.5334 -0.254) (xy -0.635 -0.254) (xy -0.635 0.254) (xy -0.5334 0.254)
				(xy -0.5334 0.2794) (xy 0.508 0.2794) (xy 0.5334 0.2794)
			)
			(stroke
				(width 0)
				(type default)
			)
			(fill no)
			(layer "B.CrtYd")
		)
		(pad "1" smd rect
			(at -0.40005 0 90)
			(size 0.4572 0.508)
			(layers "B.Cu" "B.Mask" "B.Paste")
			(net "PSU3_DC_OK_R_BUF")
		)
		(pad "2" smd rect
			(at 0.40005 0 90)
			(size 0.4572 0.508)
			(layers "B.Cu" "B.Mask" "B.Paste")
			(net "GND")
		)
	)
	(footprint ""
		(layer "B.Cu")
		(at 116.570252 -166.020242 90)
		(property "Reference" "R1245"
			(at -3.951986 1.640078 270)
			(unlocked yes)
			(layer "B.SilkS")
			(effects
				(font
					(size 0.7874 0.5842)
					(thickness 0.1524)
				)
				(justify left mirror)
			)
		)
		(property "Value" ""
			(at 0 0 90)
			(layer "B.Fab")
			(effects
				(font
					(size 1.27 1.27)
				)
				(justify mirror)
			)
		)
		(duplicate_pad_numbers_are_jumpers no)
		(fp_line
			(start 0.7874 -0.4064)
			(end -0.7874 -0.4064)
			(stroke
				(width 0.1524)
				(type default)
			)
			(layer "B.SilkS")
		)
		(fp_line
			(start -0.7874 -0.4064)
			(end -0.7874 0.4064)
			(stroke
				(width 0.1524)
				(type default)
			)
			(layer "B.SilkS")
		)
		(fp_line
			(start 0.7874 0.4064)
			(end 0.7874 -0.4064)
			(stroke
				(width 0.1524)
				(type default)
			)
			(layer "B.SilkS")
		)
		(fp_line
			(start -0.7874 0.4064)
			(end 0.7874 0.4064)
			(stroke
				(width 0.1524)
				(type default)
			)
			(layer "B.SilkS")
		)
		(fp_poly
			(pts
				(xy 0.508 0.2794) (xy 0.508 0.2286) (xy 0.635 0.2286) (xy 0.635 -0.254) (xy 0.5334 -0.254) (xy 0.5334 -0.2794)
				(xy -0.5334 -0.2794) (xy -0.5334 -0.254) (xy -0.635 -0.254) (xy -0.635 0.254) (xy -0.5334 0.254)
				(xy -0.5334 0.2794)
			)
			(stroke
				(width 0)
				(type default)
			)
			(fill no)
			(layer "B.CrtYd")
		)
		(pad "1" smd rect
			(at -0.40005 0 270)
			(size 0.4572 0.508)
			(layers "B.Cu" "B.Mask" "B.Paste")
			(net "GND")
		)
		(pad "2" smd rect
			(at 0.40005 0 270)
			(size 0.4572 0.508)
			(layers "B.Cu" "B.Mask" "B.Paste")
			(net "PSU3_HUB_EN")
		)
	)
	(footprint ""
		(layer "B.Cu")
		(at 66.425572 -77.974698)
		(property "Reference" "R101"
			(at -13.110972 31.287974 0)
			(unlocked yes)
			(layer "B.SilkS")
			(effects
				(font
					(size 0.7874 0.5842)
					(thickness 0.1524)
				)
				(justify left mirror)
			)
		)
		(property "Value" ""
			(at 0 0 0)
			(layer "B.Fab")
			(effects
				(font
					(size 1.27 1.27)
				)
				(justify mirror)
			)
		)
		(duplicate_pad_numbers_are_jumpers no)
		(fp_line
			(start -0.7874 -0.4064)
			(end -0.7874 0.4064)
			(stroke
				(width 0.1524)
				(type default)
			)
			(layer "B.SilkS")
		)
		(fp_line
			(start -0.7874 0.4064)
			(end 0.7874 0.4064)
			(stroke
				(width 0.1524)
				(type default)
			)
			(layer "B.SilkS")
		)
		(fp_line
			(start 0.7874 -0.4064)
			(end -0.7874 -0.4064)
			(stroke
				(width 0.1524)
				(type default)
			)
			(layer "B.SilkS")
		)
		(fp_line
			(start 0.7874 0.4064)
			(end 0.7874 -0.4064)
			(stroke
				(width 0.1524)
				(type default)
			)
			(layer "B.SilkS")
		)
		(fp_poly
			(pts
				(xy 0.508 0.2794) (xy 0.508 0.2286) (xy 0.635 0.2286) (xy 0.635 -0.254) (xy 0.5334 -0.254) (xy 0.5334 -0.2794)
				(xy -0.5334 -0.2794) (xy -0.5334 -0.254) (xy -0.635 -0.254) (xy -0.635 0.254) (xy -0.5334 0.254)
				(xy -0.5334 0.2794)
			)
			(stroke
				(width 0)
				(type default)
			)
			(fill no)
			(layer "B.CrtYd")
		)
		(pad "1" smd rect
			(at -0.40005 0 180)
			(size 0.4572 0.508)
			(layers "B.Cu" "B.Mask" "B.Paste")
			(net "A_CPU_NODE1_LV_GPIO_RCOMP")
		)
		(pad "2" smd rect
			(at 0.40005 0 180)
			(size 0.4572 0.508)
			(layers "B.Cu" "B.Mask" "B.Paste")
			(net "GND")
		)
	)
	(footprint ""
		(layer "B.Cu")
		(at 133.08076 -187.872624 90)
		(property "Reference" "R962"
			(at 4.565396 -1.244092 270)
			(unlocked yes)
			(layer "B.SilkS")
			(effects
				(font
					(size 0.7874 0.5842)
					(thickness 0.1524)
				)
				(justify left mirror)
			)
		)
		(property "Value" ""
			(at 0 0 90)
			(layer "B.Fab")
			(effects
				(font
					(size 1.27 1.27)
				)
				(justify mirror)
			)
		)
		(duplicate_pad_numbers_are_jumpers no)
		(fp_line
			(start 0.7874 -0.4064)
			(end -0.7874 -0.4064)
			(stroke
				(width 0.1524)
				(type default)
			)
			(layer "B.SilkS")
		)
		(fp_line
			(start -0.7874 -0.4064)
			(end -0.7874 0.4064)
			(stroke
				(width 0.1524)
				(type default)
			)
			(layer "B.SilkS")
		)
		(fp_line
			(start 0.7874 0.4064)
			(end 0.7874 -0.4064)
			(stroke
				(width 0.1524)
				(type default)
			)
			(layer "B.SilkS")
		)
		(fp_line
			(start -0.7874 0.4064)
			(end 0.7874 0.4064)
			(stroke
				(width 0.1524)
				(type default)
			)
			(layer "B.SilkS")
		)
		(fp_poly
			(pts
				(xy 0.508 0.2794) (xy 0.508 0.2286) (xy 0.635 0.2286) (xy 0.635 -0.254) (xy 0.5334 -0.254) (xy 0.5334 -0.2794)
				(xy -0.5334 -0.2794) (xy -0.5334 -0.254) (xy -0.635 -0.254) (xy -0.635 0.254) (xy -0.5334 0.254)
				(xy -0.5334 0.2794)
			)
			(stroke
				(width 0)
				(type default)
			)
			(fill no)
			(layer "B.CrtYd")
		)
		(pad "1" smd rect
			(at -0.40005 0 270)
			(size 0.4572 0.508)
			(layers "B.Cu" "B.Mask" "B.Paste")
			(net "UART_T9_NODE2_RXD")
		)
		(pad "2" smd rect
			(at 0.40005 0 270)
			(size 0.4572 0.508)
			(layers "B.Cu" "B.Mask" "B.Paste")
			(net "UART_T9_NODE2_RXD_R")
		)
	)
	(footprint ""
		(layer "B.Cu")
		(at 60.81776 -185.205624 90)
		(property "Reference" "R916"
			(at 4.15163 0.143764 270)
			(unlocked yes)
			(layer "B.SilkS")
			(effects
				(font
					(size 0.7874 0.5842)
					(thickness 0.1524)
				)
				(justify left mirror)
			)
		)
		(property "Value" ""
			(at 0 0 90)
			(layer "B.Fab")
			(effects
				(font
					(size 1.27 1.27)
				)
				(justify mirror)
			)
		)
		(duplicate_pad_numbers_are_jumpers no)
		(fp_line
			(start 0.7874 -0.4064)
			(end -0.7874 -0.4064)
			(stroke
				(width 0.1524)
				(type default)
			)
			(layer "B.SilkS")
		)
		(fp_line
			(start -0.7874 -0.4064)
			(end -0.7874 0.4064)
			(stroke
				(width 0.1524)
				(type default)
			)
			(layer "B.SilkS")
		)
		(fp_line
			(start 0.7874 0.4064)
			(end 0.7874 -0.4064)
			(stroke
				(width 0.1524)
				(type default)
			)
			(layer "B.SilkS")
		)
		(fp_line
			(start -0.7874 0.4064)
			(end 0.7874 0.4064)
			(stroke
				(width 0.1524)
				(type default)
			)
			(layer "B.SilkS")
		)
		(fp_poly
			(pts
				(xy 0.508 0.2794) (xy 0.508 0.2286) (xy 0.635 0.2286) (xy 0.635 -0.254) (xy 0.5334 -0.254) (xy 0.5334 -0.2794)
				(xy -0.5334 -0.2794) (xy -0.5334 -0.254) (xy -0.635 -0.254) (xy -0.635 0.254) (xy -0.5334 0.254)
				(xy -0.5334 0.2794)
			)
			(stroke
				(width 0)
				(type default)
			)
			(fill no)
			(layer "B.CrtYd")
		)
		(pad "1" smd rect
			(at -0.40005 0 270)
			(size 0.4572 0.508)
			(layers "B.Cu" "B.Mask" "B.Paste")
			(net "UART_T1_NODE2_TXD")
		)
		(pad "2" smd rect
			(at 0.40005 0 270)
			(size 0.4572 0.508)
			(layers "B.Cu" "B.Mask" "B.Paste")
			(net "UART_T1_NODE2_TXD_R")
		)
	)
	(footprint ""
		(layer "B.Cu")
		(at 74.27468 -165.307518 90)
		(property "Reference" "R911"
			(at 0.469646 -2.643632 270)
			(unlocked yes)
			(layer "B.SilkS")
			(effects
				(font
					(size 0.7874 0.5842)
					(thickness 0.1524)
				)
				(justify left mirror)
			)
		)
		(property "Value" ""
			(at 0 0 90)
			(layer "B.Fab")
			(effects
				(font
					(size 1.27 1.27)
				)
				(justify mirror)
			)
		)
		(duplicate_pad_numbers_are_jumpers no)
		(fp_line
			(start 0.7874 -0.4064)
			(end -0.7874 -0.4064)
			(stroke
				(width 0.1524)
				(type default)
			)
			(layer "B.SilkS")
		)
		(fp_line
			(start -0.7874 -0.4064)
			(end -0.7874 0.4064)
			(stroke
				(width 0.1524)
				(type default)
			)
			(layer "B.SilkS")
		)
		(fp_line
			(start 0.7874 0.4064)
			(end 0.7874 -0.4064)
			(stroke
				(width 0.1524)
				(type default)
			)
			(layer "B.SilkS")
		)
		(fp_line
			(start -0.7874 0.4064)
			(end 0.7874 0.4064)
			(stroke
				(width 0.1524)
				(type default)
			)
			(layer "B.SilkS")
		)
		(fp_poly
			(pts
				(xy 0.508 0.2794) (xy 0.508 0.2286) (xy 0.635 0.2286) (xy 0.635 -0.254) (xy 0.5334 -0.254) (xy 0.5334 -0.2794)
				(xy -0.5334 -0.2794) (xy -0.5334 -0.254) (xy -0.635 -0.254) (xy -0.635 0.254) (xy -0.5334 0.254)
				(xy -0.5334 0.2794)
			)
			(stroke
				(width 0)
				(type default)
			)
			(fill no)
			(layer "B.CrtYd")
		)
		(pad "1" smd rect
			(at -0.40005 0 270)
			(size 0.4572 0.508)
			(layers "B.Cu" "B.Mask" "B.Paste")
			(net "UART_T3_NODE1_TXD")
		)
		(pad "2" smd rect
			(at 0.40005 0 270)
			(size 0.4572 0.508)
			(layers "B.Cu" "B.Mask" "B.Paste")
			(net "UART_T3_NODE1_TXD_R")
		)
	)
	(footprint ""
		(layer "B.Cu")
		(at 47.977044 -140.29563 90)
		(property "Reference" "C236"
			(at 1.116584 0.602996 270)
			(unlocked yes)
			(layer "B.SilkS")
			(effects
				(font
					(size 0.7874 0.5842)
					(thickness 0.1524)
				)
				(justify left mirror)
			)
		)
		(property "Value" ""
			(at 0 0 90)
			(layer "B.Fab")
			(effects
				(font
					(size 1.27 1.27)
				)
				(justify mirror)
			)
		)
		(duplicate_pad_numbers_are_jumpers no)
		(fp_line
			(start 0.7874 -0.4064)
			(end -0.7874 -0.4064)
			(stroke
				(width 0.1524)
				(type default)
			)
			(layer "B.SilkS")
		)
		(fp_line
			(start -0.7874 -0.4064)
			(end -0.7874 0.4064)
			(stroke
				(width 0.1524)
				(type default)
			)
			(layer "B.SilkS")
		)
		(fp_line
			(start 0 0.381)
			(end 0 -0.381)
			(stroke
				(width 0.1524)
				(type default)
			)
			(layer "B.SilkS")
		)
		(fp_line
			(start 0.7874 0.4064)
			(end 0.7874 -0.4064)
			(stroke
				(width 0.1524)
				(type default)
			)
			(layer "B.SilkS")
		)
		(fp_line
			(start -0.7874 0.4064)
			(end 0.7874 0.4064)
			(stroke
				(width 0.1524)
				(type default)
			)
			(layer "B.SilkS")
		)
		(fp_poly
			(pts
				(xy 0.5334 0.254) (xy 0.635 0.254) (xy 0.635 0.2286) (xy 0.635 -0.254) (xy 0.5334 -0.254) (xy 0.5334 -0.2794)
				(xy -0.5334 -0.2794) (xy -0.5334 -0.254) (xy -0.635 -0.254) (xy -0.635 0.254) (xy -0.5334 0.254)
				(xy -0.5334 0.2794) (xy 0.508 0.2794) (xy 0.5334 0.2794)
			)
			(stroke
				(width 0)
				(type default)
			)
			(fill no)
			(layer "B.CrtYd")
		)
		(pad "1" smd rect
			(at -0.40005 0 270)
			(size 0.4572 0.508)
			(layers "B.Cu" "B.Mask" "B.Paste")
			(net "P1V538_BMC_NODE1")
		)
		(pad "2" smd rect
			(at 0.40005 0 270)
			(size 0.4572 0.508)
			(layers "B.Cu" "B.Mask" "B.Paste")
			(net "GND")
		)
	)
	(footprint ""
		(layer "B.Cu")
		(at 121.40184 -143.940276 180)
		(property "Reference" "C186"
			(at 1.136396 1.219962 0)
			(unlocked yes)
			(layer "B.SilkS")
			(effects
				(font
					(size 0.7874 0.5842)
					(thickness 0.1524)
				)
				(justify left mirror)
			)
		)
		(property "Value" ""
			(at 0 0 0)
			(layer "B.Fab")
			(effects
				(font
					(size 1.27 1.27)
				)
				(justify mirror)
			)
		)
		(duplicate_pad_numbers_are_jumpers no)
		(fp_line
			(start 0.7874 0.406146)
			(end 0.7874 -0.406146)
			(stroke
				(width 0.1524)
				(type default)
			)
			(layer "B.SilkS")
		)
		(fp_line
			(start 0.7874 -0.406146)
			(end -0.7874 -0.406146)
			(stroke
				(width 0.1524)
				(type default)
			)
			(layer "B.SilkS")
		)
		(fp_line
			(start 0 0.381)
			(end 0 -0.381)
			(stroke
				(width 0.1524)
				(type default)
			)
			(layer "B.SilkS")
		)
		(fp_line
			(start -0.7874 0.406146)
			(end 0.7874 0.406146)
			(stroke
				(width 0.1524)
				(type default)
			)
			(layer "B.SilkS")
		)
		(fp_line
			(start -0.7874 -0.406146)
			(end -0.7874 0.406146)
			(stroke
				(width 0.1524)
				(type default)
			)
			(layer "B.SilkS")
		)
		(fp_poly
			(pts
				(xy 0.5334 0.254) (xy 0.635 0.254) (xy 0.635 0.2286) (xy 0.635 -0.254) (xy 0.5334 -0.254) (xy 0.5334 -0.2794)
				(xy -0.5334 -0.2794) (xy -0.5334 -0.254) (xy -0.635 -0.254) (xy -0.635 0.254) (xy -0.5334 0.254)
				(xy -0.5334 0.2794) (xy 0.508 0.2794) (xy 0.5334 0.2794)
			)
			(stroke
				(width 0)
				(type default)
			)
			(fill no)
			(layer "B.CrtYd")
		)
		(pad "1" smd rect
			(at -0.40005 0)
			(size 0.4572 0.508)
			(layers "B.Cu" "B.Mask" "B.Paste")
			(net "P2E_CPU_PCIE_SW_NODE1_RX_C_DN")
		)
		(pad "2" smd rect
			(at 0.40005 0)
			(size 0.4572 0.508)
			(layers "B.Cu" "B.Mask" "B.Paste")
			(net "P2E_CPU_PCIE_SW_NODE1_RX_DN")
		)
	)
	(footprint ""
		(layer "B.Cu")
		(at 76.487274 -94.131384 -90)
		(property "Reference" "R94"
			(at 3.075432 -0.409448 270)
			(unlocked yes)
			(layer "B.SilkS")
			(effects
				(font
					(size 0.7874 0.5842)
					(thickness 0.1524)
				)
				(justify left mirror)
			)
		)
		(property "Value" ""
			(at 0 0 90)
			(layer "B.Fab")
			(effects
				(font
					(size 1.27 1.27)
				)
				(justify mirror)
			)
		)
		(duplicate_pad_numbers_are_jumpers no)
		(fp_line
			(start -0.7874 0.4064)
			(end 0.7874 0.4064)
			(stroke
				(width 0.1524)
				(type default)
			)
			(layer "B.SilkS")
		)
		(fp_line
			(start 0.7874 0.4064)
			(end 0.7874 -0.4064)
			(stroke
				(width 0.1524)
				(type default)
			)
			(layer "B.SilkS")
		)
		(fp_line
			(start -0.7874 -0.4064)
			(end -0.7874 0.4064)
			(stroke
				(width 0.1524)
				(type default)
			)
			(layer "B.SilkS")
		)
		(fp_line
			(start 0.7874 -0.4064)
			(end -0.7874 -0.4064)
			(stroke
				(width 0.1524)
				(type default)
			)
			(layer "B.SilkS")
		)
		(fp_poly
			(pts
				(xy 0.508 0.2794) (xy 0.508 0.2286) (xy 0.635 0.2286) (xy 0.635 -0.254) (xy 0.5334 -0.254) (xy 0.5334 -0.2794)
				(xy -0.5334 -0.2794) (xy -0.5334 -0.254) (xy -0.635 -0.254) (xy -0.635 0.254) (xy -0.5334 0.254)
				(xy -0.5334 0.2794)
			)
			(stroke
				(width 0)
				(type default)
			)
			(fill no)
			(layer "B.CrtYd")
		)
		(pad "1" smd rect
			(at -0.40005 0 90)
			(size 0.4572 0.508)
			(layers "B.Cu" "B.Mask" "B.Paste")
			(net "P3V3_NODE1")
		)
		(pad "2" smd rect
			(at 0.40005 0 90)
			(size 0.4572 0.508)
			(layers "B.Cu" "B.Mask" "B.Paste")
			(net "NODE1_BIOS_MB_REV_ID2")
		)
	)
	(footprint ""
		(layer "B.Cu")
		(at 39.067486 -141.034262 180)
		(property "Reference" "C234"
			(at 2.529332 0.000254 0)
			(unlocked yes)
			(layer "B.SilkS")
			(effects
				(font
					(size 0.7874 0.5842)
					(thickness 0.1524)
				)
				(justify left mirror)
			)
		)
		(property "Value" ""
			(at 0 0 0)
			(layer "B.Fab")
			(effects
				(font
					(size 1.27 1.27)
				)
				(justify mirror)
			)
		)
		(duplicate_pad_numbers_are_jumpers no)
		(fp_line
			(start 0.7874 0.4064)
			(end 0.7874 -0.4064)
			(stroke
				(width 0.1524)
				(type default)
			)
			(layer "B.SilkS")
		)
		(fp_line
			(start 0.7874 -0.4064)
			(end -0.7874 -0.4064)
			(stroke
				(width 0.1524)
				(type default)
			)
			(layer "B.SilkS")
		)
		(fp_line
			(start 0 0.381)
			(end 0 -0.381)
			(stroke
				(width 0.1524)
				(type default)
			)
			(layer "B.SilkS")
		)
		(fp_line
			(start -0.7874 0.4064)
			(end 0.7874 0.4064)
			(stroke
				(width 0.1524)
				(type default)
			)
			(layer "B.SilkS")
		)
		(fp_line
			(start -0.7874 -0.4064)
			(end -0.7874 0.4064)
			(stroke
				(width 0.1524)
				(type default)
			)
			(layer "B.SilkS")
		)
		(fp_poly
			(pts
				(xy 0.5334 0.254) (xy 0.635 0.254) (xy 0.635 0.2286) (xy 0.635 -0.254) (xy 0.5334 -0.254) (xy 0.5334 -0.2794)
				(xy -0.5334 -0.2794) (xy -0.5334 -0.254) (xy -0.635 -0.254) (xy -0.635 0.254) (xy -0.5334 0.254)
				(xy -0.5334 0.2794) (xy 0.508 0.2794) (xy 0.5334 0.2794)
			)
			(stroke
				(width 0)
				(type default)
			)
			(fill no)
			(layer "B.CrtYd")
		)
		(pad "1" smd rect
			(at -0.40005 0)
			(size 0.4572 0.508)
			(layers "B.Cu" "B.Mask" "B.Paste")
			(net "P1V538_BMC_NODE1")
		)
		(pad "2" smd rect
			(at 0.40005 0)
			(size 0.4572 0.508)
			(layers "B.Cu" "B.Mask" "B.Paste")
			(net "GND")
		)
	)
	(footprint ""
		(layer "B.Cu")
		(at 71.10476 -185.129424 -90)
		(property "Reference" "C683"
			(at -4.15163 0.051562 270)
			(unlocked yes)
			(layer "B.SilkS")
			(effects
				(font
					(size 0.7874 0.5842)
					(thickness 0.1524)
				)
				(justify left mirror)
			)
		)
		(property "Value" ""
			(at 0 0 90)
			(layer "B.Fab")
			(effects
				(font
					(size 1.27 1.27)
				)
				(justify mirror)
			)
		)
		(duplicate_pad_numbers_are_jumpers no)
		(fp_line
			(start -0.7874 0.4064)
			(end 0.7874 0.4064)
			(stroke
				(width 0.1524)
				(type default)
			)
			(layer "B.SilkS")
		)
		(fp_line
			(start 0.7874 0.4064)
			(end 0.7874 -0.4064)
			(stroke
				(width 0.1524)
				(type default)
			)
			(layer "B.SilkS")
		)
		(fp_line
			(start 0 0.381)
			(end 0 -0.381)
			(stroke
				(width 0.1524)
				(type default)
			)
			(layer "B.SilkS")
		)
		(fp_line
			(start -0.7874 -0.4064)
			(end -0.7874 0.4064)
			(stroke
				(width 0.1524)
				(type default)
			)
			(layer "B.SilkS")
		)
		(fp_line
			(start 0.7874 -0.4064)
			(end -0.7874 -0.4064)
			(stroke
				(width 0.1524)
				(type default)
			)
			(layer "B.SilkS")
		)
		(fp_poly
			(pts
				(xy 0.5334 0.254) (xy 0.635 0.254) (xy 0.635 0.2286) (xy 0.635 -0.254) (xy 0.5334 -0.254) (xy 0.5334 -0.2794)
				(xy -0.5334 -0.2794) (xy -0.5334 -0.254) (xy -0.635 -0.254) (xy -0.635 0.254) (xy -0.5334 0.254)
				(xy -0.5334 0.2794) (xy 0.508 0.2794) (xy 0.5334 0.2794)
			)
			(stroke
				(width 0)
				(type default)
			)
			(fill no)
			(layer "B.CrtYd")
		)
		(pad "1" smd rect
			(at -0.40005 0 90)
			(size 0.4572 0.508)
			(layers "B.Cu" "B.Mask" "B.Paste")
			(net "UART_T3_NODE3_RXD")
		)
		(pad "2" smd rect
			(at 0.40005 0 90)
			(size 0.4572 0.508)
			(layers "B.Cu" "B.Mask" "B.Paste")
			(net "GND")
		)
	)
	(footprint ""
		(layer "B.Cu")
		(at 165.011608 -182.035196 180)
		(property "Reference" "R1174"
			(at -6.724904 9.031224 0)
			(unlocked yes)
			(layer "B.SilkS")
			(effects
				(font
					(size 0.7874 0.5842)
					(thickness 0.1524)
				)
				(justify left mirror)
			)
		)
		(property "Value" ""
			(at 0 0 0)
			(layer "B.Fab")
			(effects
				(font
					(size 1.27 1.27)
				)
				(justify mirror)
			)
		)
		(duplicate_pad_numbers_are_jumpers no)
		(fp_line
			(start 0.7874 0.4064)
			(end 0.7874 -0.4064)
			(stroke
				(width 0.1524)
				(type default)
			)
			(layer "B.SilkS")
		)
		(fp_line
			(start 0.7874 -0.4064)
			(end -0.7874 -0.4064)
			(stroke
				(width 0.1524)
				(type default)
			)
			(layer "B.SilkS")
		)
		(fp_line
			(start -0.7874 0.4064)
			(end 0.7874 0.4064)
			(stroke
				(width 0.1524)
				(type default)
			)
			(layer "B.SilkS")
		)
		(fp_line
			(start -0.7874 -0.4064)
			(end -0.7874 0.4064)
			(stroke
				(width 0.1524)
				(type default)
			)
			(layer "B.SilkS")
		)
		(fp_poly
			(pts
				(xy 0.508 0.2794) (xy 0.508 0.2286) (xy 0.635 0.2286) (xy 0.635 -0.254) (xy 0.5334 -0.254) (xy 0.5334 -0.2794)
				(xy -0.5334 -0.2794) (xy -0.5334 -0.254) (xy -0.635 -0.254) (xy -0.635 0.254) (xy -0.5334 0.254)
				(xy -0.5334 0.2794)
			)
			(stroke
				(width 0)
				(type default)
			)
			(fill no)
			(layer "B.CrtYd")
		)
		(pad "1" smd rect
			(at -0.40005 0)
			(size 0.4572 0.508)
			(layers "B.Cu" "B.Mask" "B.Paste")
			(net "CPLD_UART_RX_P4")
		)
		(pad "2" smd rect
			(at 0.40005 0)
			(size 0.4572 0.508)
			(layers "B.Cu" "B.Mask" "B.Paste")
			(net "GND")
		)
	)
	(footprint ""
		(layer "B.Cu")
		(at 125.917452 -138.53795 -90)
		(property "Reference" "C897"
			(at 3.90906 0.573786 270)
			(unlocked yes)
			(layer "B.SilkS")
			(effects
				(font
					(size 0.7874 0.5842)
					(thickness 0.1524)
				)
				(justify left mirror)
			)
		)
		(property "Value" ""
			(at 0 0 90)
			(layer "B.Fab")
			(effects
				(font
					(size 1.27 1.27)
				)
				(justify mirror)
			)
		)
		(duplicate_pad_numbers_are_jumpers no)
		(fp_line
			(start -0.7874 0.4064)
			(end 0.7874 0.4064)
			(stroke
				(width 0.1524)
				(type default)
			)
			(layer "B.SilkS")
		)
		(fp_line
			(start 0.7874 0.4064)
			(end 0.7874 -0.4064)
			(stroke
				(width 0.1524)
				(type default)
			)
			(layer "B.SilkS")
		)
		(fp_line
			(start 0 0.381)
			(end 0 -0.381)
			(stroke
				(width 0.1524)
				(type default)
			)
			(layer "B.SilkS")
		)
		(fp_line
			(start -0.7874 -0.4064)
			(end -0.7874 0.4064)
			(stroke
				(width 0.1524)
				(type default)
			)
			(layer "B.SilkS")
		)
		(fp_line
			(start 0.7874 -0.4064)
			(end -0.7874 -0.4064)
			(stroke
				(width 0.1524)
				(type default)
			)
			(layer "B.SilkS")
		)
		(fp_poly
			(pts
				(xy 0.5334 0.254) (xy 0.635 0.254) (xy 0.635 0.2286) (xy 0.635 -0.254) (xy 0.5334 -0.254) (xy 0.5334 -0.2794)
				(xy -0.5334 -0.2794) (xy -0.5334 -0.254) (xy -0.635 -0.254) (xy -0.635 0.254) (xy -0.5334 0.254)
				(xy -0.5334 0.2794) (xy 0.508 0.2794) (xy 0.5334 0.2794)
			)
			(stroke
				(width 0)
				(type default)
			)
			(fill no)
			(layer "B.CrtYd")
		)
		(pad "1" smd rect
			(at -0.40005 0 90)
			(size 0.4572 0.508)
			(layers "B.Cu" "B.Mask" "B.Paste")
			(net "P1V0_PCI_SW_A")
		)
		(pad "2" smd rect
			(at 0.40005 0 90)
			(size 0.4572 0.508)
			(layers "B.Cu" "B.Mask" "B.Paste")
			(net "GND")
		)
	)
	(footprint ""
		(layer "B.Cu")
		(at 35.86988 -63.732156 180)
		(property "Reference" "C20"
			(at 2.232406 0.057658 0)
			(unlocked yes)
			(layer "B.SilkS")
			(effects
				(font
					(size 0.7874 0.5842)
					(thickness 0.1524)
				)
				(justify left mirror)
			)
		)
		(property "Value" ""
			(at 0 0 0)
			(layer "B.Fab")
			(effects
				(font
					(size 1.27 1.27)
				)
				(justify mirror)
			)
		)
		(duplicate_pad_numbers_are_jumpers no)
		(fp_line
			(start 0.7874 0.4064)
			(end 0.7874 -0.4064)
			(stroke
				(width 0.1524)
				(type default)
			)
			(layer "B.SilkS")
		)
		(fp_line
			(start 0.7874 -0.4064)
			(end -0.7874 -0.4064)
			(stroke
				(width 0.1524)
				(type default)
			)
			(layer "B.SilkS")
		)
		(fp_line
			(start 0 0.381)
			(end 0 -0.381)
			(stroke
				(width 0.1524)
				(type default)
			)
			(layer "B.SilkS")
		)
		(fp_line
			(start -0.7874 0.4064)
			(end 0.7874 0.4064)
			(stroke
				(width 0.1524)
				(type default)
			)
			(layer "B.SilkS")
		)
		(fp_line
			(start -0.7874 -0.4064)
			(end -0.7874 0.4064)
			(stroke
				(width 0.1524)
				(type default)
			)
			(layer "B.SilkS")
		)
		(fp_poly
			(pts
				(xy 0.5334 0.254) (xy 0.635 0.254) (xy 0.635 0.2286) (xy 0.635 -0.254) (xy 0.5334 -0.254) (xy 0.5334 -0.2794)
				(xy -0.5334 -0.2794) (xy -0.5334 -0.254) (xy -0.635 -0.254) (xy -0.635 0.254) (xy -0.5334 0.254)
				(xy -0.5334 0.2794) (xy 0.508 0.2794) (xy 0.5334 0.2794)
			)
			(stroke
				(width 0)
				(type default)
			)
			(fill no)
			(layer "B.CrtYd")
		)
		(pad "1" smd rect
			(at -0.40005 0)
			(size 0.4572 0.508)
			(layers "B.Cu" "B.Mask" "B.Paste")
			(net "P2E_CPU_NIC1_NODE1_TX_C_DN")
		)
		(pad "2" smd rect
			(at 0.40005 0)
			(size 0.4572 0.508)
			(layers "B.Cu" "B.Mask" "B.Paste")
			(net "P2E_CPU_NIC1_NODE1_TX_DN")
		)
	)
	(footprint ""
		(layer "B.Cu")
		(at 123.89358 -130.473196 -90)
		(property "Reference" ""
			(at 0 0 90)
			(layer "B.SilkS")
			(hide yes)
			(effects
				(font
					(size 1.27 1.27)
				)
				(justify mirror)
			)
		)
		(property "Value" ""
			(at 0 0 90)
			(layer "B.Fab")
			(effects
				(font
					(size 1.27 1.27)
				)
				(justify mirror)
			)
		)
		(duplicate_pad_numbers_are_jumpers no)
		(fp_poly
			(pts
				(arc
					(start 0 -1.4986)
					(mid 0 1.4986)
					(end 0 -1.4986)
				)
			)
			(stroke
				(width 0)
				(type default)
			)
			(fill no)
			(layer "B.CrtYd")
		)
		(pad "1" smd circle
			(at 0 0 90)
			(size 0.9906 0.9906)
			(layers "B.Cu" "B.Mask" "B.Paste")
			(net "Net_33")
		)
		(zone
			(layer "B.Cu")
			(hatch none 0.5)
			(connect_pads
				(clearance 0)
			)
			(min_thickness 0.25)
			(keepout
				(tracks not_allowed)
				(vias allowed)
				(pads allowed)
				(copperpour not_allowed)
				(footprints allowed)
			)
			(placement
				(enabled no)
				(sheetname "")
			)
			(fill
				(thermal_gap 0.5)
				(thermal_bridge_width 0.5)
				(island_removal_mode 0)
			)
			(polygon
				(pts
					(arc
						(start 125.51918 -130.473196)
						(mid 122.26798 -130.473196)
						(end 125.51918 -130.473196)
					)
				)
			)
		)
	)
	(gr_poly
		(pts
			(xy 35.826954 -130.050794) (xy 34.617914 -130.050794) (xy 34.541714 -130.126994) (xy 34.541714 -131.439158)
			(xy 35.826954 -131.439158)
		)
		(stroke
			(width 0)
			(type solid)
		)
		(fill yes)
		(layer "F.Cu")
		(net "GND")
	)
	(gr_poly
		(pts
			(xy 16.87449 -131.04114) (xy 16.87449 -129.537206) (xy 16.819626 -129.482342) (xy 15.297404 -129.482342)
			(xy 15.260828 -129.518918) (xy 15.260828 -131.08686) (xy 16.82877 -131.08686)
		)
		(stroke
			(width 0)
			(type solid)
		)
		(fill yes)
		(layer "F.Cu")
		(net "GND")
	)
	(gr_poly
		(pts
			(xy 27.13736 -165.204394) (xy 27.13736 -163.147756) (xy 23.53818 -163.147756) (xy 23.39086 -163.295076)
			(xy 23.39086 -164.904166) (xy 23.71852 -165.231826) (xy 27.109928 -165.231826)
		)
		(stroke
			(width 0)
			(type solid)
		)
		(fill yes)
		(layer "F.Cu")
		(net "P1V9_LAN1")
	)
	(gr_poly
		(pts
			(xy 39.175436 -13.871702) (xy 39.175436 -13.582396) (xy 38.559486 -12.966446) (xy 38.424612 -12.966446)
			(xy 38.424612 -14.357858) (xy 38.532562 -14.465808) (xy 39.175436 -14.465808)
		)
		(stroke
			(width 0)
			(type solid)
		)
		(fill yes)
		(layer "F.Cu")
		(net "GND")
	)
	(gr_poly
		(pts
			(xy 63.227712 -111.969296) (xy 63.227712 -105.319322) (xy 63.160402 -105.252012) (xy 60.35294 -105.252012)
			(xy 60.177934 -105.427018) (xy 60.177934 -112.144048) (xy 63.05296 -112.144048)
		)
		(stroke
			(width 0)
			(type solid)
		)
		(fill yes)
		(layer "F.Cu")
		(net "GND")
	)
	(gr_poly
		(pts
			(xy 86.930484 -8.119618) (xy 86.930484 -1.966722) (xy 86.684104 -1.720342) (xy 84.464652 -1.720342)
			(xy 84.289646 -1.895348) (xy 84.289646 -8.612378) (xy 86.437724 -8.612378)
		)
		(stroke
			(width 0)
			(type solid)
		)
		(fill yes)
		(layer "F.Cu")
		(net "GND")
	)
	(gr_poly
		(pts
			(xy 140.651484 -160.918652) (xy 140.651484 -159.99968) (xy 140.46962 -159.817816) (xy 138.78687 -159.817816)
			(xy 138.78687 -160.981898) (xy 138.823446 -161.018474) (xy 140.551662 -161.018474)
		)
		(stroke
			(width 0)
			(type solid)
		)
		(fill yes)
		(layer "F.Cu")
		(net "GND")
	)
	(gr_poly
		(pts
			(xy 147.103592 -66.228214) (xy 147.103592 -62.460124) (xy 147.064984 -62.421516) (xy 143.261588 -62.421516)
			(xy 143.158464 -62.52464) (xy 143.158464 -66.322702) (xy 147.009104 -66.322702)
		)
		(stroke
			(width 0)
			(type solid)
		)
		(fill yes)
		(layer "F.Cu")
		(net "GND")
	)
	(gr_poly
		(pts
			(xy 12.86891 -125.90653) (xy 12.86891 -121.08942) (xy 12.784074 -121.004584) (xy 10.913872 -121.004584)
			(xy 10.847832 -121.070624) (xy 10.847832 -125.793246) (xy 11.02741 -125.972824) (xy 12.802616 -125.972824)
		)
		(stroke
			(width 0)
			(type solid)
		)
		(fill yes)
		(layer "F.Cu")
		(net "GND")
	)
	(gr_poly
		(pts
			(xy 14.605 -102.237286) (xy 14.605 -98.019362) (xy 14.04874 -97.463102) (xy 3.032252 -97.463102)
			(xy 2.3876 -98.107754) (xy 2.3876 -102.549452) (xy 2.80924 -102.971092) (xy 13.871194 -102.971092)
		)
		(stroke
			(width 0)
			(type solid)
		)
		(fill yes)
		(layer "F.Cu")
		(net "P12V_PDB")
	)
	(gr_poly
		(pts
			(xy 15.296134 -75.100688) (xy 15.296134 -69.140324) (xy 15.24508 -69.08927) (xy 13.444982 -69.08927)
			(xy 12.477242 -70.05701) (xy 12.477242 -75.236832) (xy 12.714986 -75.474576) (xy 14.922246 -75.474576)
		)
		(stroke
			(width 0)
			(type solid)
		)
		(fill yes)
		(layer "F.Cu")
		(net "N21581564")
	)
	(gr_poly
		(pts
			(xy 22.177248 -126.843536) (xy 22.177248 -126.291086) (xy 22.038564 -126.152402) (xy 20.282916 -126.152402)
			(xy 20.23237 -126.202948) (xy 20.23237 -126.980442) (xy 21.655532 -126.980442) (xy 22.040342 -126.980442)
		)
		(stroke
			(width 0)
			(type solid)
		)
		(fill yes)
		(layer "F.Cu")
		(net "SW_P1V05_NODE1_DRVL")
	)
	(gr_poly
		(pts
			(xy 27.262074 -157.504892) (xy 27.262074 -155.687522) (xy 27.07894 -155.504388) (xy 23.652226 -155.504388)
			(xy 23.31974 -155.836874) (xy 23.31974 -157.380686) (xy 23.5839 -157.644846) (xy 27.12212 -157.644846)
		)
		(stroke
			(width 0)
			(type solid)
		)
		(fill yes)
		(layer "F.Cu")
		(net "P1V9_LAN1")
	)
	(gr_poly
		(pts
			(xy 30.682184 -103.808784) (xy 30.682184 -102.634288) (xy 30.678882 -102.630986) (xy 28.64866 -102.630986)
			(xy 28.536138 -102.743508) (xy 28.536138 -103.689912) (xy 28.681426 -103.8352) (xy 30.655768 -103.8352)
		)
		(stroke
			(width 0)
			(type solid)
		)
		(fill yes)
		(layer "F.Cu")
		(net "P1V8_STB_NODE1")
	)
	(gr_poly
		(pts
			(xy 31.063692 -146.934174) (xy 31.063692 -144.251934) (xy 30.824932 -144.013174) (xy 28.312872 -144.013174)
			(xy 28.099512 -144.226534) (xy 28.099512 -146.670014) (xy 28.541472 -147.111974) (xy 30.885892 -147.111974)
		)
		(stroke
			(width 0)
			(type solid)
		)
		(fill yes)
		(layer "F.Cu")
		(net "LAN1_CTRL_P1V9_R")
	)
	(gr_poly
		(pts
			(xy 49.312068 -111.917734) (xy 49.312068 -110.863126) (xy 49.063656 -110.614714) (xy 47.02175 -110.614714)
			(xy 46.99762 -110.638844) (xy 46.99762 -111.56569) (xy 47.423578 -111.991648) (xy 49.238154 -111.991648)
		)
		(stroke
			(width 0)
			(type solid)
		)
		(fill yes)
		(layer "F.Cu")
		(net "SW_P3V3_STB_NODE1_BT")
	)
	(gr_poly
		(pts
			(xy 51.160426 -100.861368) (xy 51.160426 -98.945954) (xy 51.099466 -98.884994) (xy 49.160938 -98.884994)
			(xy 49.092358 -98.953574) (xy 49.092358 -100.929948) (xy 49.107852 -100.945442) (xy 51.076352 -100.945442)
		)
		(stroke
			(width 0)
			(type solid)
		)
		(fill yes)
		(layer "F.Cu")
		(net "GND")
	)
	(gr_poly
		(pts
			(xy 52.248562 -4.25704) (xy 52.248562 -1.742948) (xy 52.229766 -1.724152) (xy 49.3903 -1.724152)
			(xy 49.285144 -1.829308) (xy 49.285144 -4.233672) (xy 49.437798 -4.386326) (xy 52.119276 -4.386326)
		)
		(stroke
			(width 0)
			(type solid)
		)
		(fill yes)
		(layer "F.Cu")
		(net "P12V_AUX")
	)
	(gr_poly
		(pts
			(xy 54.917086 -122.035062) (xy 54.917086 -120.638062) (xy 54.790086 -120.511062) (xy 54.002686 -120.511062)
			(xy 53.850286 -120.663462) (xy 53.850286 -121.908062) (xy 54.028086 -122.085862) (xy 54.866286 -122.085862)
		)
		(stroke
			(width 0)
			(type solid)
		)
		(fill yes)
		(layer "F.Cu")
		(net "P3V3_NODE1")
	)
	(gr_poly
		(pts
			(xy 64.58458 -6.325108) (xy 64.58458 -1.965198) (xy 64.16802 -1.548638) (xy 53.362098 -1.548638)
			(xy 53.12156 -1.789176) (xy 53.12156 -6.1849) (xy 53.52034 -6.58368) (xy 64.326008 -6.58368)
		)
		(stroke
			(width 0)
			(type solid)
		)
		(fill yes)
		(layer "F.Cu")
		(net "GND")
	)
	(gr_poly
		(pts
			(xy 73.55078 -8.386064) (xy 73.55078 -7.331456) (xy 73.302368 -7.083044) (xy 71.260462 -7.083044)
			(xy 71.236332 -7.107174) (xy 71.236332 -8.03402) (xy 71.66229 -8.459978) (xy 73.476866 -8.459978)
		)
		(stroke
			(width 0)
			(type solid)
		)
		(fill yes)
		(layer "F.Cu")
		(net "SW_P3V3_NODE1_BT")
	)
	(gr_poly
		(pts
			(xy 76.675488 -101.605842) (xy 76.675488 -98.495358) (xy 76.630022 -98.449892) (xy 75.665838 -98.449892)
			(xy 75.438508 -98.677222) (xy 75.438508 -101.50602) (xy 75.58405 -101.651562) (xy 76.629768 -101.651562)
		)
		(stroke
			(width 0)
			(type solid)
		)
		(fill yes)
		(layer "F.Cu")
		(net "FM_OSC_NODE1_OSC_NC")
	)
	(gr_poly
		(pts
			(xy 77.684122 -154.079448) (xy 77.684122 -153.152602) (xy 77.258164 -152.726644) (xy 75.443588 -152.726644)
			(xy 75.369674 -152.800558) (xy 75.369674 -153.855166) (xy 75.618086 -154.103578) (xy 77.659992 -154.103578)
		)
		(stroke
			(width 0)
			(type solid)
		)
		(fill yes)
		(layer "F.Cu")
		(net "SW_P5V_STB_NODE1_BT")
	)
	(gr_poly
		(pts
			(xy 77.820774 -95.29064) (xy 77.820774 -94.323154) (xy 77.781404 -94.283784) (xy 76.286106 -94.283784)
			(xy 76.280264 -94.289626) (xy 76.280264 -95.332042) (xy 76.352908 -95.404686) (xy 77.706728 -95.404686)
		)
		(stroke
			(width 0)
			(type solid)
		)
		(fill yes)
		(layer "F.Cu")
		(net "P3V3_NODE1")
	)
	(gr_poly
		(pts
			(xy 94.13748 -139.004548) (xy 94.13748 -137.73658) (xy 94.11843 -137.71753) (xy 92.536518 -137.71753)
			(xy 92.516198 -137.73785) (xy 92.516198 -138.97102) (xy 92.61729 -139.072112) (xy 94.069916 -139.072112)
		)
		(stroke
			(width 0)
			(type solid)
		)
		(fill yes)
		(layer "F.Cu")
		(net "GND")
	)
	(gr_poly
		(pts
			(xy 96.714056 -129.776728) (xy 96.714056 -128.423162) (xy 96.550988 -128.260094) (xy 94.574106 -128.260094)
			(xy 94.26702 -128.56718) (xy 94.26702 -129.690368) (xy 94.45879 -129.882138) (xy 96.608646 -129.882138)
		)
		(stroke
			(width 0)
			(type solid)
		)
		(fill yes)
		(layer "F.Cu")
		(net "GND")
	)
	(gr_poly
		(pts
			(xy 100.0379 -8.45566) (xy 100.0379 -4.161536) (xy 99.826318 -3.949954) (xy 98.676714 -3.949954)
			(xy 98.517964 -4.108704) (xy 98.517964 -8.927084) (xy 98.61804 -9.02716) (xy 99.4664 -9.02716)
		)
		(stroke
			(width 0)
			(type solid)
		)
		(fill yes)
		(layer "F.Cu")
		(net "P3V3_NODE1")
	)
	(gr_poly
		(pts
			(xy 101.202744 -154.113992) (xy 101.202744 -153.187146) (xy 100.776786 -152.761188) (xy 98.96221 -152.761188)
			(xy 98.888296 -152.835102) (xy 98.888296 -153.88971) (xy 99.136708 -154.138122) (xy 101.178614 -154.138122)
		)
		(stroke
			(width 0)
			(type solid)
		)
		(fill yes)
		(layer "F.Cu")
		(net "SW_P1V8_STB_NODE1_BT")
	)
	(gr_poly
		(pts
			(xy 109.205014 -136.635998) (xy 109.205014 -133.16077) (xy 109.180376 -133.136132) (xy 105.81132 -133.136132)
			(xy 105.746042 -133.20141) (xy 105.746042 -136.632188) (xy 105.77068 -136.656826) (xy 109.184186 -136.656826)
		)
		(stroke
			(width 0)
			(type solid)
		)
		(fill yes)
		(layer "F.Cu")
		(net "GND")
	)
	(gr_poly
		(pts
			(xy 113.980976 -123.51385) (xy 113.980976 -123.04268) (xy 113.844578 -122.906282) (xy 111.652558 -122.906282)
			(xy 111.642906 -122.915934) (xy 111.642906 -123.512072) (xy 111.72952 -123.598686) (xy 113.89614 -123.598686)
		)
		(stroke
			(width 0)
			(type solid)
		)
		(fill yes)
		(layer "F.Cu")
		(net "VR_PVCCP_NODE1_UGATE1")
	)
	(gr_poly
		(pts
			(xy 118.103904 -47.842424) (xy 118.103904 -44.491402) (xy 117.90807 -44.295568) (xy 116.84 -44.295568)
			(xy 116.810536 -44.325032) (xy 116.810536 -47.881286) (xy 116.908834 -47.979584) (xy 117.966744 -47.979584)
		)
		(stroke
			(width 0)
			(type solid)
		)
		(fill yes)
		(layer "F.Cu")
		(net "N46114787")
	)
	(gr_poly
		(pts
			(xy 119.14886 -123.62434) (xy 119.14886 -120.632474) (xy 118.984014 -120.467628) (xy 114.36985 -120.467628)
			(xy 114.23777 -120.599708) (xy 114.23777 -123.744482) (xy 114.264186 -123.770898) (xy 119.002302 -123.770898)
		)
		(stroke
			(width 0)
			(type solid)
		)
		(fill yes)
		(layer "F.Cu")
		(net "GND")
	)
	(gr_poly
		(pts
			(xy 127.341122 -55.749444) (xy 127.341122 -55.127398) (xy 127.228092 -55.014368) (xy 126.048008 -55.014368)
			(xy 125.78842 -55.273956) (xy 125.78842 -55.78856) (xy 125.930406 -55.930546) (xy 127.16002 -55.930546)
		)
		(stroke
			(width 0)
			(type solid)
		)
		(fill yes)
		(layer "F.Cu")
		(net "GND")
	)
	(gr_poly
		(pts
			(xy 141.855952 -120.877838) (xy 141.855952 -119.386604) (xy 141.551152 -119.081804) (xy 138.242548 -119.081804)
			(xy 137.922508 -119.401844) (xy 137.922508 -121.005092) (xy 138.02741 -121.109994) (xy 141.623796 -121.109994)
		)
		(stroke
			(width 0)
			(type solid)
		)
		(fill yes)
		(layer "F.Cu")
		(net "P1V5_CLK_NODE1")
	)
	(gr_poly
		(pts
			(xy 144.144238 -159.517588) (xy 144.144238 -158.731458) (xy 143.50238 -158.0896) (xy 141.0335 -158.0896)
			(xy 140.92428 -158.19882) (xy 140.92428 -159.199326) (xy 141.415516 -159.690562) (xy 143.971264 -159.690562)
		)
		(stroke
			(width 0)
			(type solid)
		)
		(fill yes)
		(layer "F.Cu")
		(net "P3V3_NODE1")
	)
	(gr_poly
		(pts
			(xy 145.893028 -51.282346) (xy 145.893028 -49.199546) (xy 145.664428 -48.970946) (xy 144.521428 -48.970946)
			(xy 144.267428 -49.224946) (xy 144.267428 -51.460146) (xy 144.394428 -51.587146) (xy 145.588228 -51.587146)
		)
		(stroke
			(width 0)
			(type solid)
		)
		(fill yes)
		(layer "F.Cu")
		(net "P5V_NODE1")
	)
	(gr_poly
		(pts
			(xy 163.722812 -155.759658) (xy 163.722812 -150.482554) (xy 163.628324 -150.388066) (xy 158.43504 -150.388066)
			(xy 158.350966 -150.47214) (xy 158.350966 -155.759658) (xy 158.403544 -155.812236) (xy 163.670234 -155.812236)
		)
		(stroke
			(width 0)
			(type solid)
		)
		(fill yes)
		(layer "F.Cu")
		(net "GND")
	)
	(gr_poly
		(pts
			(xy 177.66538 -49.665128) (xy 177.66538 -47.15002) (xy 177.405284 -46.889924) (xy 171.442634 -46.889924)
			(xy 171.24934 -47.083218) (xy 171.24934 -49.746408) (xy 171.38142 -49.878488) (xy 177.45202 -49.878488)
		)
		(stroke
			(width 0)
			(type solid)
		)
		(fill yes)
		(layer "F.Cu")
		(net "P5V_NODE1")
	)
	(gr_poly
		(pts
			(xy 177.679858 -150.848314) (xy 177.679858 -141.914372) (xy 177.28311 -141.517624) (xy 175.55718 -141.517624)
			(xy 175.182276 -141.892528) (xy 175.182276 -149.56155) (xy 176.701958 -151.081232) (xy 177.44694 -151.081232)
		)
		(stroke
			(width 0)
			(type solid)
		)
		(fill yes)
		(layer "F.Cu")
		(net "GND")
	)
	(gr_poly
		(pts
			(xy 188.37402 -29.344874) (xy 188.37402 -26.04643) (xy 187.933838 -25.606248) (xy 184.214516 -25.606248)
			(xy 183.85282 -25.967944) (xy 183.85282 -29.39669) (xy 184.1881 -29.73197) (xy 187.986924 -29.73197)
		)
		(stroke
			(width 0)
			(type solid)
		)
		(fill yes)
		(layer "F.Cu")
		(net "GND")
	)
	(gr_poly
		(pts
			(xy 191.22136 -29.573474) (xy 191.22136 -25.20823) (xy 190.96736 -24.95423) (xy 188.984636 -24.95423)
			(xy 188.79058 -25.148286) (xy 188.79058 -29.616654) (xy 189.00902 -29.835094) (xy 190.95974 -29.835094)
		)
		(stroke
			(width 0)
			(type solid)
		)
		(fill yes)
		(layer "F.Cu")
		(net "P5V_NODE1")
	)
	(gr_poly
		(pts
			(xy 191.7446 -167.919146) (xy 191.7446 -165.624002) (xy 191.526414 -165.405816) (xy 189.060836 -165.405816)
			(xy 189.00394 -165.462712) (xy 189.00394 -167.834564) (xy 189.154562 -167.985186) (xy 191.67856 -167.985186)
		)
		(stroke
			(width 0)
			(type solid)
		)
		(fill yes)
		(layer "F.Cu")
		(net "GND")
	)
	(gr_poly
		(pts
			(xy 31.28899 -121.501916) (xy 31.28899 -119.774208) (xy 30.96895 -119.454168) (xy 29.71165 -119.454168)
			(xy 29.65704 -119.508778) (xy 29.65704 -120.927368) (xy 29.65704 -121.385076) (xy 30.06852 -121.796556)
			(xy 30.99435 -121.796556)
		)
		(stroke
			(width 0)
			(type solid)
		)
		(fill yes)
		(layer "F.Cu")
		(net "GND")
	)
	(gr_poly
		(pts
			(xy 34.284158 -126.952756) (xy 34.284158 -124.979684) (xy 34.14014 -124.835666) (xy 33.29178 -124.835666)
			(xy 32.94888 -125.178566) (xy 32.871664 -125.255782) (xy 32.871664 -126.933452) (xy 32.967168 -127.028956)
			(xy 34.207958 -127.028956)
		)
		(stroke
			(width 0)
			(type solid)
		)
		(fill yes)
		(layer "F.Cu")
		(net "GND")
	)
	(gr_poly
		(pts
			(xy 76.875132 -149.457664) (xy 76.834746 -149.417278) (xy 74.335894 -149.417278) (xy 73.081388 -149.417278)
			(xy 72.80021 -149.698456) (xy 72.80021 -151.941276) (xy 73.03008 -152.171146) (xy 74.443336 -152.171146)
			(xy 76.875132 -152.171146)
		)
		(stroke
			(width 0)
			(type solid)
		)
		(fill yes)
		(layer "F.Cu")
		(net "GND")
	)
	(gr_poly
		(pts
			(xy 88.000332 -158.516574) (xy 88.000332 -151.799544) (xy 86.487 -151.799544) (xy 85.430868 -152.855676)
			(xy 85.430868 -154.406092) (xy 85.378798 -154.458162) (xy 85.378798 -158.476696) (xy 85.593682 -158.69158)
			(xy 87.825326 -158.69158)
		)
		(stroke
			(width 0)
			(type solid)
		)
		(fill yes)
		(layer "F.Cu")
		(net "GND")
	)
	(gr_poly
		(pts
			(xy 94.458536 -136.851136) (xy 94.458536 -136.818116) (xy 94.458536 -135.79602) (xy 94.441518 -135.779002)
			(xy 91.6305 -135.779002) (xy 91.188286 -136.221216) (xy 91.188286 -137.386314) (xy 91.242134 -137.440162)
			(xy 93.86951 -137.440162)
		)
		(stroke
			(width 0)
			(type solid)
		)
		(fill yes)
		(layer "F.Cu")
		(net "PWRGD_NODE1_P1V05_SUS_PG")
	)
	(gr_poly
		(pts
			(xy 100.393754 -149.492208) (xy 100.353368 -149.451822) (xy 97.854516 -149.451822) (xy 97.02927 -149.451822)
			(xy 96.709484 -149.771608) (xy 96.709484 -151.924766) (xy 96.990408 -152.20569) (xy 97.961958 -152.20569)
			(xy 100.393754 -152.20569)
		)
		(stroke
			(width 0)
			(type solid)
		)
		(fill yes)
		(layer "F.Cu")
		(net "GND")
	)
	(gr_poly
		(pts
			(xy 8.177276 -3.803142) (xy 8.177276 -2.707132) (xy 8.06958 -2.599436) (xy 5.883402 -2.599436) (xy 5.75056 -2.732278)
			(xy 5.75056 -3.454654) (xy 5.839206 -3.5433) (xy 7.42315 -3.5433) (xy 7.695692 -3.815842) (xy 8.164576 -3.815842)
		)
		(stroke
			(width 0)
			(type solid)
		)
		(fill yes)
		(layer "F.Cu")
		(net "P3V3_STB_NODE1")
	)
	(gr_poly
		(pts
			(xy 20.085558 -76.680568) (xy 20.085558 -74.472546) (xy 19.984466 -74.371454) (xy 17.978882 -74.371454)
			(xy 17.757648 -74.15022) (xy 16.59509 -74.15022) (xy 16.043656 -74.701654) (xy 16.043656 -76.952094)
			(xy 16.2814 -77.189838) (xy 19.576288 -77.189838)
		)
		(stroke
			(width 0)
			(type solid)
		)
		(fill yes)
		(layer "F.Cu")
		(net "VCC5_CRTXX")
	)
	(gr_poly
		(pts
			(xy 32.206438 -125.701552) (xy 32.206438 -124.823982) (xy 32.69107 -124.33935) (xy 32.69107 -123.477274)
			(xy 32.64027 -123.426474) (xy 31.77667 -123.426474) (xy 31.49727 -123.705874) (xy 31.49727 -125.687074)
			(xy 31.54807 -125.737874) (xy 32.170116 -125.737874)
		)
		(stroke
			(width 0)
			(type solid)
		)
		(fill yes)
		(layer "F.Cu")
		(net "P5V_STB_NODE1")
	)
	(gr_poly
		(pts
			(xy 43.177968 -6.738112) (xy 43.024298 -6.584442) (xy 42.55135 -6.584442) (xy 41.804336 -6.584442)
			(xy 41.746932 -6.641846) (xy 41.746932 -7.31139) (xy 41.875202 -7.43966) (xy 42.385996 -7.43966)
			(xy 42.73042 -7.784084) (xy 43.177968 -7.784084)
		)
		(stroke
			(width 0)
			(type solid)
		)
		(fill yes)
		(layer "F.Cu")
		(net "SW_PV_VDDR_NODE1_DRVH")
	)
	(gr_poly
		(pts
			(xy 44.20362 -114.057176) (xy 44.20362 -112.64646) (xy 44.183554 -112.626394) (xy 43.276774 -112.626394)
			(xy 43.156632 -112.626394) (xy 43.101514 -112.681512) (xy 43.101514 -114.105436) (xy 43.117008 -114.12093)
			(xy 43.226228 -114.12093) (xy 44.139866 -114.12093)
		)
		(stroke
			(width 0)
			(type solid)
		)
		(fill yes)
		(layer "F.Cu")
		(net "GND")
	)
	(gr_poly
		(pts
			(xy 50.609246 -115.198144) (xy 51.02098 -114.78641) (xy 51.02098 -112.855248) (xy 50.712878 -112.547146)
			(xy 50.238406 -112.547146) (xy 47.80661 -112.547146) (xy 47.80661 -115.260628) (xy 47.846996 -115.301014)
			(xy 50.345848 -115.301014) (xy 50.506376 -115.301014)
		)
		(stroke
			(width 0)
			(type solid)
		)
		(fill yes)
		(layer "F.Cu")
		(net "GND")
	)
	(gr_poly
		(pts
			(xy 64.687196 -158.967932) (xy 64.687196 -152.740106) (xy 64.650366 -152.740106) (xy 64.503808 -152.593548)
			(xy 64.503808 -152.574244) (xy 61.628782 -152.574244) (xy 61.45403 -152.748996) (xy 61.45403 -158.715964)
			(xy 61.88075 -159.142684) (xy 64.51219 -159.142684)
		)
		(stroke
			(width 0)
			(type solid)
		)
		(fill yes)
		(layer "F.Cu")
		(net "GND")
	)
	(gr_poly
		(pts
			(xy 68.442332 -10.525506) (xy 68.442332 -9.11479) (xy 68.422266 -9.094724) (xy 67.515486 -9.094724)
			(xy 67.395344 -9.094724) (xy 67.340226 -9.149842) (xy 67.340226 -10.573766) (xy 67.35572 -10.58926)
			(xy 67.46494 -10.58926) (xy 68.378578 -10.58926)
		)
		(stroke
			(width 0)
			(type solid)
		)
		(fill yes)
		(layer "F.Cu")
		(net "GND")
	)
	(gr_poly
		(pts
			(xy 105.09885 -152.071324) (xy 105.09885 -150.6474) (xy 105.083356 -150.631906) (xy 104.974136 -150.631906)
			(xy 104.060498 -150.631906) (xy 103.996744 -150.69566) (xy 103.996744 -152.106376) (xy 104.01681 -152.126442)
			(xy 104.92359 -152.126442) (xy 105.043732 -152.126442)
		)
		(stroke
			(width 0)
			(type solid)
		)
		(fill yes)
		(layer "F.Cu")
		(net "GND")
	)
	(gr_poly
		(pts
			(xy 113.91138 -47.319438) (xy 113.91138 -45.964094) (xy 114.165888 -45.709586) (xy 114.165888 -44.354242)
			(xy 114.074956 -44.26331) (xy 112.974628 -44.26331) (xy 112.51057 -44.727368) (xy 112.51057 -47.219616)
			(xy 112.68329 -47.392336) (xy 113.838482 -47.392336)
		)
		(stroke
			(width 0)
			(type solid)
		)
		(fill yes)
		(layer "F.Cu")
		(net "N21550241")
	)
	(gr_poly
		(pts
			(xy 114.51463 -21.173694) (xy 114.51463 -20.060158) (xy 113.916206 -19.461734) (xy 113.916206 -18.994882)
			(xy 113.724944 -18.80362) (xy 112.992408 -18.80362) (xy 112.92205 -18.873978) (xy 112.92205 -21.02866)
			(xy 113.088674 -21.195284) (xy 114.49304 -21.195284)
		)
		(stroke
			(width 0)
			(type solid)
		)
		(fill yes)
		(layer "F.Cu")
		(net "PV_VTT_DDR_NODE1_REFOUT")
	)
	(gr_poly
		(pts
			(xy 114.7572 -18.275046) (xy 114.7572 -18.010378) (xy 114.752628 -18.00606) (xy 114.752628 -17.210532)
			(xy 114.660172 -17.118076) (xy 113.07826 -17.118076) (xy 112.89792 -17.298416) (xy 112.89792 -18.374106)
			(xy 113.02238 -18.498566) (xy 114.53368 -18.498566)
		)
		(stroke
			(width 0)
			(type solid)
		)
		(fill yes)
		(layer "F.Cu")
		(net "GND")
	)
	(gr_poly
		(pts
			(xy 116.488972 -48.087026) (xy 116.488972 -47.022512) (xy 116.488972 -46.371002) (xy 116.425472 -46.307502)
			(xy 114.426492 -46.307502) (xy 114.206274 -46.52772) (xy 114.206274 -47.63008) (xy 114.206274 -47.949866)
			(xy 114.392456 -48.136048) (xy 116.43995 -48.136048)
		)
		(stroke
			(width 0)
			(type solid)
		)
		(fill yes)
		(layer "F.Cu")
		(net "P3V3_NODE1")
	)
	(gr_poly
		(pts
			(xy 117.564916 -31.914592) (xy 117.679978 -31.79953) (xy 117.679978 -29.4386) (xy 117.583966 -29.342588)
			(xy 109.950758 -29.342588) (xy 109.682026 -29.61132) (xy 109.682026 -31.741872) (xy 109.682026 -31.898082)
			(xy 110.253272 -32.469328) (xy 117.01018 -32.469328)
		)
		(stroke
			(width 0)
			(type solid)
		)
		(fill yes)
		(layer "F.Cu")
		(net "GND")
	)
	(gr_poly
		(pts
			(xy 119.099076 -131.09321) (xy 119.099076 -129.280412) (xy 119.099076 -128.458722) (xy 118.951248 -128.310894)
			(xy 117.05844 -128.310894) (xy 116.652548 -128.716786) (xy 116.652548 -129.145792) (xy 116.652548 -130.827272)
			(xy 117.201442 -131.376166) (xy 118.81612 -131.376166)
		)
		(stroke
			(width 0)
			(type solid)
		)
		(fill yes)
		(layer "F.Cu")
		(net "P12V_AUX")
	)
	(gr_poly
		(pts
			(xy 137.296652 -69.385942) (xy 137.296652 -68.509642) (xy 137.296652 -66.782442) (xy 137.239502 -66.725292)
			(xy 137.093452 -66.579242) (xy 135.696452 -66.579242) (xy 135.556752 -66.718942) (xy 135.556752 -69.195442)
			(xy 135.848852 -69.487542) (xy 137.195052 -69.487542)
		)
		(stroke
			(width 0)
			(type solid)
		)
		(fill yes)
		(layer "F.Cu")
		(net "SATA_VCONT_NODE1")
	)
	(gr_poly
		(pts
			(xy 184.63006 -151.115522) (xy 184.63006 -150.095204) (xy 184.275984 -149.741128) (xy 181.50586 -149.741128)
			(xy 181.505606 -149.740874) (xy 180.62702 -149.740874) (xy 180.35016 -150.017734) (xy 180.35016 -151.177244)
			(xy 180.457602 -151.284686) (xy 184.460896 -151.284686)
		)
		(stroke
			(width 0)
			(type solid)
		)
		(fill yes)
		(layer "F.Cu")
		(net "LAN2_CTRL_P1V9_R")
	)
	(gr_poly
		(pts
			(xy 191.21628 -116.13769) (xy 191.21628 -112.93602) (xy 191.064642 -112.784128) (xy 189.159642 -112.784128)
			(xy 188.880242 -113.063528) (xy 188.880242 -116.035328) (xy 188.880242 -116.419376) (xy 189.080394 -116.619528)
			(xy 189.464442 -116.619528) (xy 190.734442 -116.619528)
		)
		(stroke
			(width 0)
			(type solid)
		)
		(fill yes)
		(layer "F.Cu")
		(net "P12V_NODE1_PWRGD_EN")
	)
	(gr_poly
		(pts
			(xy 39.9542 -78.347316) (xy 39.9542 -75.280266) (xy 39.646352 -74.972418) (xy 38.190678 -74.972418)
			(xy 36.642548 -74.972418) (xy 36.467796 -75.14717) (xy 36.467796 -76.127102) (xy 36.467796 -78.36281)
			(xy 36.788598 -78.683612) (xy 38.291008 -78.683612) (xy 39.617904 -78.683612)
		)
		(stroke
			(width 0)
			(type solid)
		)
		(fill yes)
		(layer "F.Cu")
		(net "P1V8_VCCASFRHPLL_NODE1")
	)
	(gr_poly
		(pts
			(xy 75.656186 -14.011656) (xy 76.22032 -13.447522) (xy 76.22032 -9.50087) (xy 75.734926 -9.015476)
			(xy 75.349862 -9.015476) (xy 74.477118 -9.015476) (xy 72.045322 -9.015476) (xy 72.045322 -11.728958)
			(xy 72.045322 -13.839444) (xy 72.21855 -14.012672) (xy 75.65517 -14.012672)
		)
		(stroke
			(width 0)
			(type solid)
		)
		(fill yes)
		(layer "F.Cu")
		(net "GND")
	)
	(gr_poly
		(pts
			(xy 77.123544 -157.677612) (xy 77.123544 -156.160724) (xy 77.67955 -155.604718) (xy 77.717904 -155.566364)
			(xy 77.717904 -154.396948) (xy 77.686916 -154.36596) (xy 72.760078 -154.36596) (xy 72.629522 -154.496516)
			(xy 72.629522 -157.67812) (xy 72.749918 -157.798516) (xy 77.00264 -157.798516)
		)
		(stroke
			(width 0)
			(type solid)
		)
		(fill yes)
		(layer "F.Cu")
		(net "SW_P5V_STB_NODE1_PH")
	)
	(gr_poly
		(pts
			(xy 83.044284 -143.48714) (xy 83.044284 -142.444216) (xy 82.99323 -142.393162) (xy 82.394552 -142.393162)
			(xy 80.870552 -142.393162) (xy 80.824578 -142.393162) (xy 80.633824 -142.583916) (xy 80.633824 -143.844772)
			(xy 80.731614 -143.942562) (xy 81.073752 -143.942562) (xy 82.588862 -143.942562)
		)
		(stroke
			(width 0)
			(type solid)
		)
		(fill yes)
		(layer "F.Cu")
		(net "P5V_STB_NODE1")
	)
	(gr_poly
		(pts
			(xy 84.024724 -8.604504) (xy 84.024724 -1.965706) (xy 83.739228 -1.68021) (xy 80.15224 -1.68021)
			(xy 79.802736 -1.68021) (xy 79.534258 -1.68021) (xy 79.318866 -1.895602) (xy 79.318866 -8.653018)
			(xy 79.41818 -8.752332) (xy 79.902812 -8.752332) (xy 83.876896 -8.752332)
		)
		(stroke
			(width 0)
			(type solid)
		)
		(fill yes)
		(layer "F.Cu")
		(net "P3V3_NODE1")
	)
	(gr_poly
		(pts
			(xy 85.870034 -95.520764) (xy 85.870034 -92.279724) (xy 85.580474 -91.990164) (xy 83.574128 -91.990164)
			(xy 83.574128 -92.127578) (xy 83.574128 -92.421456) (xy 83.580478 -92.427806) (xy 83.585812 -92.427806)
			(xy 83.585812 -95.76943) (xy 83.708748 -95.892366) (xy 85.498432 -95.892366)
		)
		(stroke
			(width 0)
			(type solid)
		)
		(fill yes)
		(layer "F.Cu")
		(net "GND")
	)
	(gr_poly
		(pts
			(xy 92.971112 -158.51632) (xy 92.971112 -151.758904) (xy 92.871798 -151.65959) (xy 92.387166 -151.65959)
			(xy 88.413082 -151.65959) (xy 88.265254 -151.807418) (xy 88.265254 -158.446216) (xy 88.55075 -158.731712)
			(xy 92.137738 -158.731712) (xy 92.487242 -158.731712) (xy 92.75572 -158.731712)
		)
		(stroke
			(width 0)
			(type solid)
		)
		(fill yes)
		(layer "F.Cu")
		(net "P1V8_STB_NODE1")
	)
	(gr_poly
		(pts
			(xy 111.857282 -41.131998) (xy 111.857282 -39.747698) (xy 111.857282 -34.540698) (xy 111.425482 -34.108898)
			(xy 104.681782 -34.108898) (xy 104.557322 -34.233358) (xy 104.557322 -39.440358) (xy 104.558592 -39.441628)
			(xy 104.558592 -40.993568) (xy 105.126282 -41.561258) (xy 111.428022 -41.561258)
		)
		(stroke
			(width 0)
			(type solid)
		)
		(fill yes)
		(layer "F.Cu")
		(net "GND")
	)
	(gr_poly
		(pts
			(xy 143.608806 -123.222766) (xy 143.608806 -121.619518) (xy 143.563848 -121.57456) (xy 140.522198 -121.57456)
			(xy 140.52169 -121.575068) (xy 140.308584 -121.575068) (xy 140.19276 -121.690892) (xy 140.19276 -121.903998)
			(xy 140.19276 -123.238006) (xy 140.40231 -123.447556) (xy 143.384016 -123.447556)
		)
		(stroke
			(width 0)
			(type solid)
		)
		(fill yes)
		(layer "F.Cu")
		(net "P1V5_CLK_NODE1_R")
	)
	(gr_poly
		(pts
			(xy 170.71848 -55.356252) (xy 170.71848 -47.66056) (xy 170.716448 -47.658528) (xy 170.94454 -47.430436)
			(xy 170.94454 -46.829472) (xy 170.393614 -46.278546) (xy 167.55872 -46.278546) (xy 166.9923 -46.844966)
			(xy 166.9923 -55.523638) (xy 167.25646 -55.787798) (xy 170.286934 -55.787798)
		)
		(stroke
			(width 0)
			(type solid)
		)
		(fill yes)
		(layer "F.Cu")
		(net "GND")
	)
	(gr_poly
		(pts
			(xy 184.5564 -178.689) (xy 184.5564 -174.0916) (xy 184.5564 -173.1772) (xy 184.4802 -173.101) (xy 183.0832 -173.101)
			(xy 182.8546 -173.3296) (xy 182.8546 -177.7492) (xy 182.8546 -178.5366) (xy 183.1848 -178.8668) (xy 183.9722 -178.8668)
			(xy 184.3786 -178.8668)
		)
		(stroke
			(width 0)
			(type solid)
		)
		(fill yes)
		(layer "F.Cu")
		(net "POWER_SW2_PWR_CTR_12V")
	)
	(gr_poly
		(pts
			(xy 187.0202 -178.6382) (xy 187.0202 -174.117) (xy 187.0202 -173.3804) (xy 186.7154 -173.0756) (xy 185.039 -173.0756)
			(xy 184.8993 -173.2153) (xy 184.8993 -174.1297) (xy 184.8866 -174.1424) (xy 184.8866 -178.5874) (xy 185.166 -178.8668)
			(xy 186.7916 -178.8668)
		)
		(stroke
			(width 0)
			(type solid)
		)
		(fill yes)
		(layer "F.Cu")
		(net "POWER_SW2_PWR_CTR_12V_R")
	)
	(gr_poly
		(pts
			(xy 13.309092 -11.386312) (xy 13.309092 -6.412992) (xy 13.001752 -6.105652) (xy 11.917172 -6.105652)
			(xy 11.660632 -6.362192) (xy 11.660632 -9.654032) (xy 10.779252 -10.535412) (xy 10.182352 -10.535412)
			(xy 10.131552 -10.586212) (xy 10.131552 -11.292332) (xy 10.306812 -11.467592) (xy 13.227812 -11.467592)
		)
		(stroke
			(width 0)
			(type solid)
		)
		(fill yes)
		(layer "F.Cu")
		(net "PV_VDDR_NODE1_VREF_R")
	)
	(gr_poly
		(pts
			(xy 19.126708 -149.069552) (xy 19.126708 -147.90166) (xy 18.483072 -147.258024) (xy 18.483072 -139.889992)
			(xy 18.483072 -138.954256) (xy 18.064734 -138.535918) (xy 16.08328 -138.535918) (xy 15.909036 -138.710162)
			(xy 15.909036 -141.141704) (xy 15.909036 -147.460716) (xy 17.78 -149.33168) (xy 18.86458 -149.33168)
		)
		(stroke
			(width 0)
			(type solid)
		)
		(fill yes)
		(layer "F.Cu")
		(net "GND")
	)
	(gr_poly
		(pts
			(xy 21.64588 -73.835006) (xy 21.64588 -72.291956) (xy 21.43506 -72.081136) (xy 20.766786 -72.081136)
			(xy 20.62226 -72.225662) (xy 20.62226 -72.766428) (xy 20.373086 -73.015602) (xy 19.315938 -73.015602)
			(xy 19.14906 -73.18248) (xy 19.14906 -73.83907) (xy 19.324574 -74.014584) (xy 21.466302 -74.014584)
		)
		(stroke
			(width 0)
			(type solid)
		)
		(fill yes)
		(layer "F.Cu")
		(net "P5V_NODE1")
	)
	(gr_poly
		(pts
			(xy 41.935146 -83.30438) (xy 41.937178 -83.30438) (xy 42.011346 -83.230212) (xy 42.011346 -82.068162)
			(xy 41.8719 -81.928716) (xy 41.8719 -81.54924) (xy 41.864788 -81.542128) (xy 40.215566 -81.542128)
			(xy 39.830502 -81.927192) (xy 39.830502 -83.099402) (xy 40.287448 -83.556348) (xy 41.683178 -83.556348)
		)
		(stroke
			(width 0)
			(type solid)
		)
		(fill yes)
		(layer "F.Cu")
		(net "GND")
	)
	(gr_poly
		(pts
			(xy 44.717462 -175.7045) (xy 44.956984 -175.464978) (xy 45.805598 -175.464978) (xy 46.033182 -175.237394)
			(xy 46.033182 -174.600616) (xy 45.687488 -174.254922) (xy 43.94073 -174.254922) (xy 43.94073 -175.40605)
			(xy 44.21378 -175.6791) (xy 44.21378 -176.522126) (xy 44.26585 -176.574196) (xy 44.717462 -176.574196)
		)
		(stroke
			(width 0)
			(type solid)
		)
		(fill yes)
		(layer "F.Cu")
		(net "P12V_AUX_EN")
	)
	(gr_poly
		(pts
			(xy 52.05222 -110.221776) (xy 52.05222 -106.853228) (xy 52.018946 -106.819954) (xy 48.678084 -106.819954)
			(xy 48.451008 -107.04703) (xy 47.715678 -107.04703) (xy 47.558198 -107.20451) (xy 47.558198 -108.557568)
			(xy 46.963838 -109.151928) (xy 46.963838 -110.321344) (xy 46.994826 -110.352332) (xy 51.921664 -110.352332)
		)
		(stroke
			(width 0)
			(type solid)
		)
		(fill yes)
		(layer "F.Cu")
		(net "SW_P3V3_STB_NODE1_PH")
	)
	(gr_poly
		(pts
			(xy 71.447406 -163.069778) (xy 71.447406 -160.74263) (xy 71.447406 -150.823676) (xy 70.892162 -150.268432)
			(xy 65.39611 -150.268432) (xy 65.02273 -150.641812) (xy 65.02273 -159.422338) (xy 65.438782 -159.83839)
			(xy 66.077084 -159.83839) (xy 66.55943 -160.320736) (xy 66.55943 -163.680648) (xy 70.836536 -163.680648)
		)
		(stroke
			(width 0)
			(type solid)
		)
		(fill yes)
		(layer "F.Cu")
		(net "P5V_STB_NODE1")
	)
	(gr_poly
		(pts
			(xy 77.357732 -98.067876) (xy 77.357732 -97.68586) (xy 77.04836 -97.376488) (xy 77.021182 -97.376488)
			(xy 76.93025 -97.285556) (xy 76.93025 -96.385126) (xy 76.82103 -96.275906) (xy 75.547728 -96.275906)
			(xy 75.511152 -96.312482) (xy 75.511152 -97.949512) (xy 75.729592 -98.167952) (xy 77.257656 -98.167952)
		)
		(stroke
			(width 0)
			(type solid)
		)
		(fill yes)
		(layer "F.Cu")
		(net "GND")
	)
	(gr_poly
		(pts
			(xy 95.46844 -8.955532) (xy 95.46844 -5.510022) (xy 95.25254 -5.294122) (xy 95.25254 -4.29133) (xy 95.132652 -4.171442)
			(xy 94.0816 -4.171442) (xy 93.8657 -4.387342) (xy 93.8657 -5.422392) (xy 94.5007 -6.057392) (xy 94.5007 -8.978646)
			(xy 94.54134 -9.019286) (xy 95.404686 -9.019286)
		)
		(stroke
			(width 0)
			(type solid)
		)
		(fill yes)
		(layer "F.Cu")
		(net "P5V_NODE1")
	)
	(gr_poly
		(pts
			(xy 99.046284 -141.042136) (xy 99.046284 -140.864844) (xy 99.046284 -138.740134) (xy 97.479612 -138.740134)
			(xy 97.467166 -138.75258) (xy 97.467166 -139.714986) (xy 97.467166 -140.015214) (xy 96.947228 -140.535152)
			(xy 96.947228 -141.053566) (xy 97.136712 -141.24305) (xy 97.63252 -141.24305) (xy 98.84537 -141.24305)
		)
		(stroke
			(width 0)
			(type solid)
		)
		(fill yes)
		(layer "F.Cu")
		(net "GND")
	)
	(gr_poly
		(pts
			(xy 102.85984 -117.703854) (xy 102.85984 -114.44224) (xy 103.64216 -113.65992) (xy 104.692958 -113.65992)
			(xy 104.8131 -113.539778) (xy 104.8131 -104.243632) (xy 104.42194 -103.852472) (xy 101.38918 -103.852472)
			(xy 100.8507 -104.390952) (xy 100.8507 -117.428772) (xy 101.135942 -117.714014) (xy 102.84968 -117.714014)
		)
		(stroke
			(width 0)
			(type solid)
		)
		(fill yes)
		(layer "F.Cu")
		(net "GND")
	)
	(gr_poly
		(pts
			(xy 106.586528 -127.37719) (xy 106.586528 -124.310648) (xy 106.444288 -124.168408) (xy 103.440992 -124.168408)
			(xy 102.449122 -124.168408) (xy 102.319836 -124.168408) (xy 102.238048 -124.250196) (xy 102.238048 -127.23114)
			(xy 102.33025 -127.323342) (xy 102.494842 -127.487934) (xy 103.425244 -127.487934) (xy 106.475784 -127.487934)
		)
		(stroke
			(width 0)
			(type solid)
		)
		(fill yes)
		(layer "F.Cu")
		(net "GND")
	)
	(gr_poly
		(pts
			(xy 169.80408 -159.445706) (xy 169.80408 -157.766004) (xy 169.554652 -157.516576) (xy 168.011856 -157.516576)
			(xy 167.351964 -156.856684) (xy 166.126414 -156.856684) (xy 166.003224 -156.733494) (xy 165.14445 -156.733494)
			(xy 165.124638 -156.753306) (xy 165.124638 -157.505146) (xy 167.165782 -159.54629) (xy 169.703496 -159.54629)
		)
		(stroke
			(width 0)
			(type solid)
		)
		(fill yes)
		(layer "F.Cu")
		(net "LAN2_CTRL_P1V9")
	)
	(gr_poly
		(pts
			(xy 186.34964 -148.702522) (xy 186.34964 -147.28571) (xy 186.0931 -147.02917) (xy 183.564784 -147.02917)
			(xy 183.18734 -146.651726) (xy 183.18734 -145.391632) (xy 183.098948 -145.30324) (xy 181.524656 -145.30324)
			(xy 180.72354 -146.10461) (xy 180.72354 -148.950934) (xy 180.7464 -148.973794) (xy 186.078368 -148.973794)
		)
		(stroke
			(width 0)
			(type solid)
		)
		(fill yes)
		(layer "F.Cu")
		(net "LAN2_CTRL_P1V9")
	)
	(gr_poly
		(pts
			(xy 194.193668 -27.366722) (xy 194.193668 -26.051764) (xy 193.96202 -25.820116) (xy 191.904112 -25.820116)
			(arc
				(start 191.804798 -25.919176)
				(mid 191.777179 -25.960416)
				(end 191.76746 -26.009092)
			)
			(xy 191.76746 -27.472132) (xy 191.917828 -27.6225) (xy 193.93789 -27.6225)
		)
		(stroke
			(width 0)
			(type solid)
		)
		(fill yes)
		(layer "F.Cu")
		(net "GND")
	)
	(gr_poly
		(pts
			(xy 12.949174 -120.524016) (xy 12.949174 -118.855998) (xy 13.55344 -118.251732) (xy 13.55344 -117.12448)
			(xy 13.467334 -117.038374) (xy 12.19708 -117.038374) (xy 10.885424 -118.35003) (xy 10.885424 -118.635272)
			(xy 10.885424 -118.688104) (xy 10.885424 -119.05488) (xy 10.885424 -120.631966) (xy 12.53744 -120.631966)
			(xy 12.841224 -120.631966)
		)
		(stroke
			(width 0)
			(type solid)
		)
		(fill yes)
		(layer "F.Cu")
		(net "P12V_AUX")
	)
	(gr_poly
		(pts
			(xy 107.628436 -131.597146) (xy 107.628436 -131.320286) (xy 107.628436 -131.108196) (xy 107.509056 -130.988816)
			(xy 107.509056 -129.949448) (xy 107.413298 -129.85369) (xy 105.38841 -129.85369) (xy 105.340404 -129.901696)
			(xy 105.340404 -130.74777) (xy 105.450894 -130.858514) (xy 106.210354 -130.858514) (xy 107.00385 -131.65201)
			(xy 107.573572 -131.65201)
		)
		(stroke
			(width 0)
			(type solid)
		)
		(fill yes)
		(layer "F.Cu")
		(net "VR_PVCCP_NODE1_PVCC")
	)
	(gr_poly
		(pts
			(xy 184.2262 -185.0644) (xy 184.2262 -184.6072) (xy 184.2262 -180.34) (xy 184.2262 -179.5526) (xy 183.9976 -179.324)
			(xy 183.1721 -179.324) (xy 182.2958 -180.2003) (xy 182.2831 -180.2003) (xy 182.0926 -180.3908) (xy 182.0926 -184.531)
			(xy 182.0926 -185.0898) (xy 182.1688 -185.166) (xy 184.1246 -185.166)
		)
		(stroke
			(width 0)
			(type solid)
		)
		(fill yes)
		(layer "F.Cu")
		(net "POWER_SW3_PWR_CTR_12V_R")
	)
	(gr_poly
		(pts
			(xy 15.425166 -129.16408) (xy 15.425166 -128.25095) (xy 15.263114 -128.088898) (xy 15.164054 -127.989838)
			(xy 15.164054 -126.324106) (xy 15.08379 -126.243842) (xy 14.17701 -126.243842) (xy 14.115542 -126.30531)
			(xy 14.115542 -127.594614) (xy 14.124686 -127.604012) (xy 14.124686 -128.186688) (xy 14.930374 -128.992376)
			(xy 15.10538 -129.167382) (xy 15.421864 -129.167382)
		)
		(stroke
			(width 0)
			(type solid)
		)
		(fill yes)
		(layer "F.Cu")
		(net "P5V_STB_NODE1")
	)
	(gr_poly
		(pts
			(xy 39.214806 -117.772434) (xy 39.214806 -115.139724) (xy 39.066978 -114.991896) (xy 36.325556 -114.991896)
			(xy 36.256468 -115.060984) (xy 36.256468 -115.72875) (xy 35.862006 -116.123212) (xy 34.684208 -116.123212)
			(xy 34.565844 -116.241576) (xy 34.565844 -117.898164) (xy 34.608008 -117.940328) (xy 36.473638 -117.940328)
			(xy 37.065458 -117.940328) (xy 39.046912 -117.940328)
		)
		(stroke
			(width 0)
			(type solid)
		)
		(fill yes)
		(layer "F.Cu")
		(net "FM_CPLD_NODE1_P1V5_EN_LV")
	)
	(gr_poly
		(pts
			(xy 59.445398 -112.98682) (xy 59.7154 -112.98682) (xy 59.871356 -112.830864) (xy 59.871356 -105.332276)
			(xy 59.75096 -105.21188) (xy 59.373516 -105.21188) (xy 55.786528 -105.21188) (xy 55.437024 -105.21188)
			(xy 55.168546 -105.21188) (xy 54.953154 -105.427272) (xy 54.953154 -112.184688) (xy 54.953154 -112.86109)
			(xy 55.103014 -113.01095) (xy 59.421268 -113.01095)
		)
		(stroke
			(width 0)
			(type solid)
		)
		(fill yes)
		(layer "F.Cu")
		(net "P3V3_STB_NODE1")
	)
	(gr_poly
		(pts
			(xy 65.319402 -103.334566) (xy 65.319402 -100.61575) (xy 65.188846 -100.485194) (xy 61.948822 -100.485194)
			(xy 61.658754 -100.775262)
			(arc
				(start 61.658754 -103.22306)
				(mid 61.695951 -103.312863)
				(end 61.785754 -103.35006)
			)
			(xy 65.303908 -103.35006)
		)
		(stroke
			(width 0)
			(type solid)
		)
		(fill yes)
		(layer "F.Cu")
		(net "P1V8_STB_NODE1")
	)
	(gr_poly
		(pts
			(xy 71.910448 -110.613952) (xy 71.910448 -106.107992) (xy 71.521828 -105.719372) (xy 69.4182 -105.719372)
			(xy 68.71843 -105.719372) (xy 68.29044 -106.147362) (xy 68.29044 -106.847132) (xy 68.29044 -107.097068)
			(xy 68.044314 -107.343194) (xy 67.396106 -107.991402) (xy 67.396106 -110.675166) (xy 67.70624 -110.9853)
			(xy 70.383654 -110.9853) (xy 71.5391 -110.9853)
		)
		(stroke
			(width 0)
			(type solid)
		)
		(fill yes)
		(layer "F.Cu")
		(net "P1V8_STB_NODE1")
	)
	(gr_poly
		(pts
			(arc
				(start 83.14182 -17.560544)
				(mid 83.231623 -17.523347)
				(end 83.26882 -17.433544)
			)
			(xy 83.26882 -15.806674) (xy 83.26374 -15.801594) (xy 67.75831 -15.801594) (xy 67.63258 -15.927324)
			(xy 67.63258 -17.530572) (xy 67.662552 -17.560544)
		)
		(stroke
			(width 0)
			(type solid)
		)
		(fill yes)
		(layer "F.Cu")
		(net "GND")
	)
	(gr_poly
		(pts
			(xy 119.271796 -26.319988) (xy 119.271796 -26.065734) (xy 119.271796 -23.057104) (xy 119.271796 -22.90572)
			(xy 119.046498 -22.680422) (xy 118.327932 -22.680422) (xy 118.251732 -22.756622) (xy 118.251732 -23.22322)
			(xy 118.44655 -23.418038) (xy 118.44655 -25.7556) (xy 118.294658 -25.907492) (xy 118.294658 -26.245312)
			(xy 118.399306 -26.34996) (xy 119.241824 -26.34996)
		)
		(stroke
			(width 0)
			(type solid)
		)
		(fill yes)
		(layer "F.Cu")
		(net "GND")
	)
	(gr_poly
		(pts
			(xy 120.99798 -114.993166) (xy 120.99798 -103.608378) (xy 120.743472 -103.35387) (xy 116.74348 -103.35387)
			(xy 116.498624 -103.598726)
			(arc
				(start 116.498624 -114.959384)
				(mid 116.535821 -115.049187)
				(end 116.625624 -115.086384)
			)
			(xy 120.904762 -115.086384)
		)
		(stroke
			(width 0)
			(type solid)
		)
		(fill yes)
		(layer "F.Cu")
		(net "GND")
	)
	(gr_poly
		(pts
			(xy 150.746968 -51.300888) (xy 150.746968 -48.490886) (xy 150.492968 -48.236886) (xy 146.657568 -48.236886)
			(xy 146.39036 -48.504094)
			(arc
				(start 146.39036 -51.363626)
				(mid 146.427557 -51.453429)
				(end 146.51736 -51.490626)
			)
			(xy 150.556976 -51.490626)
		)
		(stroke
			(width 0)
			(type solid)
		)
		(fill yes)
		(layer "F.Cu")
		(net "GND")
	)
	(gr_poly
		(pts
			(arc
				(start 161.946082 -142.692882)
				(mid 162.035998 -142.730201)
				(end 162.125914 -142.692882)
			)
			(xy 162.75304 -142.065756) (xy 162.75304 -141.121892) (xy 162.617404 -140.986256) (xy 161.3916 -140.986256)
			(xy 161.29508 -141.082776) (xy 161.29508 -142.04188)
		)
		(stroke
			(width 0)
			(type solid)
		)
		(fill yes)
		(layer "F.Cu")
		(net "GND")
	)
	(gr_poly
		(pts
			(arc
				(start 169.180002 -91.770962)
				(mid 169.269828 -91.808206)
				(end 169.35958 -91.770962)
			)
			(xy 170.140884 -90.989658) (xy 170.140884 -90.056716) (xy 170.056556 -89.972642) (xy 168.547288 -89.972642)
			(xy 168.398952 -90.121232) (xy 168.398952 -90.989658)
		)
		(stroke
			(width 0)
			(type solid)
		)
		(fill yes)
		(layer "F.Cu")
		(net "GND")
	)
	(gr_poly
		(pts
			(xy 175.26508 -161.461958)
			(arc
				(start 175.26508 -158.414466)
				(mid 175.227883 -158.324663)
				(end 175.13808 -158.287466)
			)
			(xy 173.220634 -158.287466) (xy 173.17212 -158.33598) (xy 173.17212 -161.632392) (xy 173.30928 -161.769552)
			(xy 174.957486 -161.769552)
		)
		(stroke
			(width 0)
			(type solid)
		)
		(fill yes)
		(layer "F.Cu")
		(net "P1V9_LAN2")
	)
	(gr_poly
		(pts
			(xy 199.0471 -151.117046) (xy 199.0471 -139.49807) (xy 198.762366 -139.213336) (xy 193.52006 -139.213336)
			(xy 193.30416 -139.429236) (xy 193.30416 -141.714728) (xy 193.314828 -141.72565) (xy 193.314828 -142.681452)
			(xy 193.3956 -142.762224) (xy 193.3956 -145.62582) (xy 193.65976 -145.88998) (xy 193.65976 -150.987506)
			(xy 193.90106 -151.228806) (xy 198.93534 -151.228806)
		)
		(stroke
			(width 0)
			(type solid)
		)
		(fill yes)
		(layer "F.Cu")
		(net "GND")
	)
	(gr_poly
		(pts
			(xy 19.594068 -129.420874) (xy 19.594068 -128.817624) (xy 19.594068 -128.658874) (xy 19.522948 -128.587754)
			(xy 18.8976 -128.587754) (xy 18.73377 -128.751584) (xy 18.355818 -129.129536) (xy 18.101818 -129.383536)
			(xy 17.179544 -129.383536) (xy 17.166336 -129.396744) (xy 17.166336 -129.431796) (xy 17.166336 -129.648458)
			(xy 17.170146 -129.652268) (xy 18.57375 -129.652268) (xy 19.362674 -129.652268)
		)
		(stroke
			(width 0)
			(type solid)
		)
		(fill yes)
		(layer "F.Cu")
		(net "SW_P1V05_NODE1_BT")
	)
	(gr_poly
		(pts
			(xy 31.238952 -125.694948) (xy 31.238952 -122.569732) (xy 31.098744 -122.429524) (xy 29.450284 -122.429524)
			(xy 28.977844 -122.901964) (xy 28.977844 -123.117864) (xy 28.977844 -124.098304) (xy 29.546804 -124.667264)
			(xy 29.84119 -124.667264) (xy 29.99867 -124.824744) (xy 29.99867 -125.687074) (xy 30.009084 -125.697488)
			(xy 30.76448 -125.697488) (xy 31.050484 -125.697488) (xy 31.236412 -125.697488)
		)
		(stroke
			(width 0)
			(type solid)
		)
		(fill yes)
		(layer "F.Cu")
		(net "P1V8_NODE1")
	)
	(gr_poly
		(pts
			(xy 36.217606 -104.672384) (xy 36.217606 -103.282242) (xy 36.193476 -103.258112) (xy 35.145218 -103.258112)
			(xy 34.800794 -103.602536) (xy 32.913828 -103.602536) (xy 32.878268 -103.638096) (xy 32.878268 -103.86695)
			(xy 34.38906 -103.86695) (xy 34.647886 -104.125776) (xy 35.45332 -104.125776) (xy 35.582606 -104.255062)
			(xy 35.582606 -104.590088) (xy 35.77082 -104.778302) (xy 36.111688 -104.778302)
		)
		(stroke
			(width 0)
			(type solid)
		)
		(fill yes)
		(layer "F.Cu")
		(net "P1V5_SUS_NODE1_ADJ")
	)
	(gr_poly
		(pts
			(xy 41.511982 -11.043412) (xy 41.511982 -10.788904) (xy 41.40073 -10.677652) (xy 41.042336 -10.319258)
			(xy 40.960802 -10.237724) (xy 40.125396 -10.237724) (xy 40.120824 -10.233152) (xy 39.21633 -10.233152)
			(xy 39.208202 -10.24128) (xy 39.208202 -10.36193) (xy 39.219124 -10.372852) (xy 40.477948 -10.372852)
			(xy 40.487346 -10.38225) (xy 41.24833 -11.143234) (xy 41.41216 -11.143234)
		)
		(stroke
			(width 0)
			(type solid)
		)
		(fill yes)
		(layer "F.Cu")
		(net "SW_PV_VDDR_NODE1_DRVH")
	)
	(gr_poly
		(pts
			(xy 84.83346 -145.847054) (xy 84.83346 -143.73987) (xy 84.578952 -143.485362) (xy 84.578952 -142.418562)
			(xy 84.565744 -142.405354) (xy 83.32216 -142.405354) (xy 83.304634 -142.42288) (xy 83.304634 -143.74368)
			(xy 83.29422 -143.754094) (xy 83.283552 -143.764762) (xy 83.029552 -144.018762) (xy 83.029552 -145.568162)
			(xy 83.029552 -145.949162) (xy 83.105752 -146.025362) (xy 84.655152 -146.025362)
		)
		(stroke
			(width 0)
			(type solid)
		)
		(fill yes)
		(layer "F.Cu")
		(net "P1V8_NODE1")
	)
	(gr_poly
		(pts
			(xy 88.32342 -85.007704) (xy 88.32342 -83.306412) (xy 88.262968 -83.24596)
			(arc
				(start 87.55888 -83.24596)
				(mid 87.419848 -83.226647)
				(end 87.291418 -83.170014)
			)
			(xy 87.260684 -83.150964) (xy 86.143846 -83.150964) (xy 85.90026 -83.39455) (xy 85.90026 -84.936584)
			(xy 86.12124 -85.157564) (xy 88.17356 -85.157564)
		)
		(stroke
			(width 0)
			(type solid)
		)
		(fill yes)
		(layer "F.Cu")
		(net "P1V05_SUS_NODE1")
	)
	(gr_poly
		(pts
			(xy 144.401032 -58.491882) (xy 144.401032 -58.487056) (xy 144.63014 -58.257948) (xy 146.003772 -58.257948)
			(xy 146.37258 -57.88914) (xy 146.37258 -56.204866) (xy 145.827496 -55.659782) (xy 144.058132 -55.659782)
			(xy 142.633192 -55.659782) (xy 142.503652 -55.789322) (xy 142.503652 -57.613042) (xy 142.249652 -57.867042)
			(xy 142.249652 -58.644282) (xy 142.734792 -59.129422) (xy 143.763492 -59.129422)
		)
		(stroke
			(width 0)
			(type solid)
		)
		(fill yes)
		(layer "F.Cu")
		(net "P1V0_SATA")
	)
	(gr_poly
		(pts
			(xy 32.016954 -188.736478)
			(arc
				(start 32.016954 -187.183268)
				(mid 31.979757 -187.093465)
				(end 31.889954 -187.056268)
			)
			(xy 30.920436 -187.056268) (xy 30.895036 -187.030868) (xy 30.363668 -187.030868) (xy 30.19425 -187.200286)
			(xy 30.19425 -188.6585) (xy 30.389576 -188.853826) (xy 31.899606 -188.853826)
		)
		(stroke
			(width 0)
			(type solid)
		)
		(fill yes)
		(layer "F.Cu")
		(net "GND")
	)
	(gr_poly
		(pts
			(xy 44.265342 -4.040886) (xy 48.73625 -4.040886) (xy 48.819054 -4.040886) (xy 49.020984 -3.838956)
			(xy 49.020984 -1.597914) (xy 48.878998 -1.455928) (xy 46.5709 -1.455928) (xy 45.099224 -1.455928)
			(xy 41.908984 -1.455928) (xy 41.890188 -1.437132) (xy 41.228264 -1.437132) (xy 40.980106 -1.68529)
			(xy 40.980106 -3.87985) (xy 41.142158 -4.041902) (xy 41.744138 -4.041902) (xy 44.264326 -4.041902)
		)
		(stroke
			(width 0)
			(type solid)
		)
		(fill yes)
		(layer "F.Cu")
		(net "GND")
	)
	(gr_poly
		(pts
			(xy 45.714666 -114.040412) (xy 45.714666 -111.071152) (xy 45.70349 -111.059976) (xy 45.507148 -111.059976)
			(xy 45.49648 -111.070644) (xy 45.49648 -111.894366) (xy 45.487336 -111.90351) (xy 45.487336 -112.057688)
			(xy 45.167042 -112.377982) (xy 45.105066 -112.439958) (xy 44.708826 -112.439958) (xy 44.514262 -112.439958)
			(xy 44.488862 -112.465358) (xy 44.488862 -114.03711) (xy 44.579794 -114.127788) (xy 45.62729 -114.127788)
		)
		(stroke
			(width 0)
			(type solid)
		)
		(fill yes)
		(layer "F.Cu")
		(net "P5V_STB_NODE1")
	)
	(gr_poly
		(pts
			(xy 48.361854 -17.127474) (xy 48.361854 -13.10513) (xy 48.30191 -13.045186) (xy 47.897796 -13.045186)
			(xy 45.750734 -13.045186) (xy 45.42282 -12.717272) (xy 45.42282 -11.6459) (xy 45.282358 -11.505438)
			(xy 43.494706 -11.505438) (xy 43.448478 -11.551412) (xy 43.448478 -13.49248) (xy 43.448478 -13.957046)
			(xy 43.448478 -16.1798) (xy 44.44492 -17.176242) (xy 47.835566 -17.176242) (xy 48.313086 -17.176242)
		)
		(stroke
			(width 0)
			(type solid)
		)
		(fill yes)
		(layer "F.Cu")
		(net "GND")
	)
	(gr_poly
		(pts
			(xy 69.953378 -10.508742) (xy 69.953378 -7.539482) (xy 69.942202 -7.528306) (xy 69.74586 -7.528306)
			(xy 69.735192 -7.538974) (xy 69.735192 -8.362696) (xy 69.726048 -8.37184) (xy 69.726048 -8.526018)
			(xy 69.405754 -8.846312) (xy 69.343778 -8.908288) (xy 68.947538 -8.908288) (xy 68.752974 -8.908288)
			(xy 68.727574 -8.933688) (xy 68.727574 -10.50544) (xy 68.818506 -10.596118) (xy 69.866002 -10.596118)
		)
		(stroke
			(width 0)
			(type solid)
		)
		(fill yes)
		(layer "F.Cu")
		(net "P5V_STB_NODE1")
	)
	(gr_poly
		(pts
			(xy 83.964526 -102.117398) (xy 83.964526 -99.128326) (xy 83.68919 -98.85299) (xy 80.61579 -98.85299)
			(xy 80.449928 -99.018852) (xy 78.895702 -99.018852) (xy 78.87716 -99.000056) (xy 78.794102 -99.000056)
			(xy 78.380336 -98.58629) (xy 77.271626 -98.58629) (xy 77.100176 -98.75774) (xy 77.100176 -100.970588)
			(xy 77.082142 -100.988622) (xy 77.082142 -101.771196) (xy 77.775562 -102.464616) (xy 83.617308 -102.464616)
		)
		(stroke
			(width 0)
			(type solid)
		)
		(fill yes)
		(layer "F.Cu")
		(net "P3V3_STB_NODE1")
	)
	(gr_poly
		(pts
			(xy 97.419668 -135.351012) (xy 97.509076 -135.261604) (xy 97.626424 -135.144256) (xy 99.414584 -135.144256)
			(xy 99.631754 -134.927086) (xy 99.631754 -134.030466) (xy 99.631754 -132.029708) (xy 97.606612 -132.029708)
			(xy 97.481898 -132.154422) (xy 97.481898 -133.03377) (xy 96.695006 -133.820662) (xy 92.669106 -133.820662)
			(xy 92.53474 -133.955028) (xy 92.53474 -135.326882) (xy 92.717112 -135.509254) (xy 97.261426 -135.509254)
		)
		(stroke
			(width 0)
			(type solid)
		)
		(fill yes)
		(layer "F.Cu")
		(net "GND")
	)
	(gr_poly
		(pts
			(arc
				(start 105.83418 -129.300478)
				(mid 105.923983 -129.263281)
				(end 105.96118 -129.173478)
			)
			(xy 105.96118 -129.14376) (xy 106.256582 -128.848358) (xy 106.256582 -128.150874) (xy 106.165142 -128.059434)
			(xy 104.74198 -128.059434) (xy 104.703372 -128.098042) (xy 104.703372 -129.079498) (xy 104.924352 -129.300478)
		)
		(stroke
			(width 0)
			(type solid)
		)
		(fill yes)
		(layer "F.Cu")
		(net "P5V_STB_NODE1")
	)
	(gr_poly
		(pts
			(xy 117.982238 -26.199338) (xy 117.982238 -25.682194) (xy 118.192042 -25.47239) (xy 118.192042 -23.661878)
			(xy 117.94236 -23.412196) (xy 116.32565 -23.412196) (xy 116.277644 -23.460202) (xy 116.277644 -24.743664)
			(xy 116.346986 -24.813006) (xy 116.882164 -24.813006) (xy 116.9543 -24.885142) (xy 116.9543 -25.283668)
			(xy 117.007386 -25.3365) (xy 117.007386 -26.349198) (xy 117.025674 -26.367486) (xy 117.81409 -26.367486)
		)
		(stroke
			(width 0)
			(type solid)
		)
		(fill yes)
		(layer "F.Cu")
		(net "PV_VTT_DDR_NODE1_REFIN")
	)
	(gr_poly
		(pts
			(arc
				(start 173.84014 -202.642978)
				(mid 173.929943 -202.605781)
				(end 173.96714 -202.515978)
			)
			(xy 173.96714 -200.39584) (xy 174.40656 -199.95642) (xy 174.40656 -199.29348) (xy 174.366428 -199.253348)
			(xy 173.47946 -199.253348) (xy 173.03242 -199.700388) (xy 173.03242 -202.602846) (xy 173.072552 -202.642978)
		)
		(stroke
			(width 0)
			(type solid)
		)
		(fill yes)
		(layer "F.Cu")
		(net "P3V3_NODE1")
	)
	(gr_poly
		(pts
			(xy 15.938754 -129.152904) (xy 15.938754 -128.279144) (xy 15.938754 -128.066546) (xy 15.938754 -127.891286)
			(xy 15.938754 -127.71374) (xy 15.934944 -127.70993) (xy 15.897352 -127.672338) (xy 15.897352 -126.89713)
			(xy 15.811246 -126.81077) (xy 15.546578 -126.81077) (xy 15.456916 -126.900432) (xy 15.456916 -127.78105)
			(xy 15.686278 -128.010412) (xy 15.686278 -128.18618) (xy 15.686278 -129.136648) (xy 15.716758 -129.167128)
			(xy 15.92453 -129.167128)
		)
		(stroke
			(width 0)
			(type solid)
		)
		(fill yes)
		(layer "F.Cu")
		(net "SW_P1V05_NODE1_DRVL")
	)
	(gr_poly
		(pts
			(xy 37.039042 -8.410194) (xy 37.039042 -7.824216) (xy 36.755324 -7.540498) (xy 36.625784 -7.410958)
			(xy 35.961574 -7.410958) (xy 35.620198 -7.410958) (xy 35.28822 -7.07898) (xy 35.121088 -7.07898)
			(xy 34.602674 -7.07898) (xy 34.388552 -7.293102) (xy 34.388552 -7.535926) (xy 34.388552 -7.53618)
			(xy 34.388552 -8.30199) (xy 34.388552 -8.425688) (xy 34.44875 -8.485886) (xy 36.668964 -8.485886)
			(xy 36.96335 -8.485886)
		)
		(stroke
			(width 0)
			(type solid)
		)
		(fill yes)
		(layer "F.Cu")
		(net "PV_VDDR_NODE1_VREF")
	)
	(gr_poly
		(pts
			(xy 64.94272 -17.111726) (xy 64.94272 -15.232126) (xy 64.778382 -15.067788) (xy 56.17083 -15.067788)
			(xy 56.162194 -15.059152) (xy 55.996586 -15.22476) (xy 55.984648 -15.22476) (xy 55.71998 -15.489428)
			(arc
				(start 55.71998 -17.183608)
				(mid 55.757177 -17.273411)
				(end 55.84698 -17.310608)
			)
			(xy 64.743838 -17.310608)
		)
		(stroke
			(width 0)
			(type solid)
		)
		(fill yes)
		(layer "F.Cu")
		(net "GND")
	)
	(gr_poly
		(pts
			(xy 82.369152 -146.025362) (xy 82.369152 -144.628362) (xy 82.242152 -144.501362) (xy 80.895952 -144.501362)
			(xy 80.337152 -143.942562) (xy 80.337152 -142.316962) (xy 80.718152 -141.935962) (xy 80.718152 -139.895072)
			(xy 80.108552 -139.285472) (xy 80.108552 -138.329162) (xy 80.108552 -138.22172) (xy 79.986632 -138.0998)
			(xy 79.010002 -138.0998) (xy 78.863952 -138.24585) (xy 78.863952 -144.940274) (xy 80.30464 -146.380962)
			(xy 82.013552 -146.380962)
		)
		(stroke
			(width 0)
			(type solid)
		)
		(fill yes)
		(layer "F.Cu")
		(net "GND")
	)
	(gr_poly
		(pts
			(xy 97.008696 -139.818364) (xy 97.008696 -138.708638) (xy 97.008696 -138.571478) (xy 96.965516 -138.528298)
			(xy 96.768666 -138.528298) (xy 96.055942 -138.528298) (xy 95.377508 -138.528298) (xy 95.223584 -138.682222)
			(arc
				(start 95.223584 -140.416788)
				(mid 95.260781 -140.506591)
				(end 95.350584 -140.543788)
			)
			(xy 96.283272 -140.543788)
		)
		(stroke
			(width 0)
			(type solid)
		)
		(fill yes)
		(layer "F.Cu")
		(net "P1V05_SUS_NODE1_ADJ_S")
	)
	(gr_poly
		(pts
			(xy 104.780842 -131.675378) (xy 106.016298 -131.675378) (xy 106.136694 -131.554982) (xy 106.136694 -131.211574)
			(xy 106.059224 -131.134104) (xy 104.959912 -131.134104) (xy 104.896412 -131.070604) (xy 104.896412 -130.872484)
			(xy 104.896412 -130.396234) (xy 104.829102 -130.328924) (xy 102.362 -130.328924) (xy 102.313994 -130.37693)
			(xy 102.313994 -130.992372) (xy 102.313994 -131.39166) (xy 102.602284 -131.67995) (xy 103.001572 -131.67995)
			(xy 104.77627 -131.67995)
		)
		(stroke
			(width 0)
			(type solid)
		)
		(fill yes)
		(layer "F.Cu")
		(net "VR_PVCCP_NODE1_EN")
	)
	(gr_poly
		(pts
			(xy 105.40238 -133.57098) (xy 105.40238 -133.442456) (xy 105.388156 -133.428232) (xy 104.45369 -133.428232)
			(xy 104.439466 -133.414008) (xy 104.439466 -133.171184) (xy 104.445562 -133.165088) (xy 105.26522 -133.165088)
			(xy 105.322116 -133.108192) (xy 105.322116 -132.611876) (xy 104.914192 -132.203952) (xy 103.76027 -132.203952)
			(xy 103.594154 -132.370068) (xy 103.594154 -132.867908) (xy 103.594154 -133.521704) (xy 103.649526 -133.577076)
			(xy 105.396284 -133.577076)
		)
		(stroke
			(width 0)
			(type solid)
		)
		(fill yes)
		(layer "F.Cu")
		(net "P5V_STB_NODE1")
	)
	(gr_poly
		(pts
			(xy 137.118852 -66.147442) (xy 137.118852 -65.509902) (xy 136.585452 -64.976502) (xy 136.486392 -64.877442)
			(xy 136.486392 -63.559182) (xy 136.483852 -63.556642) (xy 136.483852 -63.449962) (xy 136.280652 -63.246762)
			(xy 135.391652 -63.246762) (xy 135.389112 -63.249302) (xy 135.292592 -63.249302) (xy 134.832852 -63.709042)
			(xy 134.832852 -65.741042) (xy 134.832852 -66.020442) (xy 135.086852 -66.274442) (xy 136.483852 -66.274442)
			(xy 136.991852 -66.274442)
		)
		(stroke
			(width 0)
			(type solid)
		)
		(fill yes)
		(layer "F.Cu")
		(net "P1V8_NODE1")
	)
	(gr_poly
		(pts
			(arc
				(start 14.161262 -114.157506)
				(mid 14.188832 -114.116384)
				(end 14.1986 -114.067844)
			)
			(arc
				(start 14.1986 -104.699816)
				(mid 14.161403 -104.610013)
				(end 14.0716 -104.572816)
			)
			(xy 9.36498 -104.572816) (xy 9.01954 -104.918256) (xy 9.01954 -114.306096) (xy 9.292844 -114.5794)
			(xy 13.739368 -114.5794)
		)
		(stroke
			(width 0)
			(type solid)
		)
		(fill yes)
		(layer "F.Cu")
		(net "GND")
	)
	(gr_poly
		(pts
			(xy 23.732236 -149.558248) (xy 23.732236 -148.604986) (xy 23.52802 -148.40077) (xy 23.52802 -143.417036)
			(xy 23.227792 -143.116808) (xy 22.267926 -142.156942) (xy 22.267926 -139.32662) (xy 22.08784 -139.146534)
			(xy 19.340068 -139.146534) (xy 19.168872 -139.31773) (xy 19.168872 -139.803378) (xy 19.168872 -141.322806)
			(xy 19.144234 -141.347698) (xy 19.144234 -147.186904) (xy 19.704304 -147.746974) (xy 19.704304 -149.10562)
			(xy 20.645628 -150.046944) (xy 23.24354 -150.046944)
		)
		(stroke
			(width 0)
			(type solid)
		)
		(fill yes)
		(layer "F.Cu")
		(net "P3V3_NODE1")
	)
	(gr_poly
		(pts
			(xy 43.189144 -12.002516) (xy 43.189144 -11.959082) (xy 43.189144 -11.548618) (xy 43.14317 -11.502644)
			(xy 41.2369 -11.502644) (xy 40.980106 -11.24585) (xy 40.36949 -10.635488) (xy 40.268652 -10.635488)
			(xy 39.222172 -10.635488) (xy 39.204392 -10.653268) (xy 39.204392 -10.760202) (xy 39.224712 -10.780522)
			(xy 40.058086 -10.780522) (xy 40.088566 -10.811002) (xy 40.893492 -11.615928) (xy 41.296082 -12.018518)
			(xy 43.129708 -12.018518) (xy 43.173142 -12.018518)
		)
		(stroke
			(width 0)
			(type solid)
		)
		(fill yes)
		(layer "F.Cu")
		(net "SW_PV_VDDR_NODE1_DRVL")
	)
	(gr_poly
		(pts
			(xy 53.91785 -118.132098)
			(arc
				(start 53.91785 -116.967508)
				(mid 53.880653 -116.877705)
				(end 53.79085 -116.840508)
			)
			(xy 52.32019 -116.840508) (xy 52.121308 -117.03939) (xy 51.132994 -117.03939) (xy 50.98034 -117.192044)
			(xy 50.98034 -117.588792) (xy 51.08702 -117.695472) (xy 51.916838 -117.695472) (xy 52.435252 -118.213886)
			(xy 53.836062 -118.213886)
		)
		(stroke
			(width 0)
			(type solid)
		)
		(fill yes)
		(layer "F.Cu")
		(net "BMC_NODE1_OSC1_EN")
	)
	(gr_poly
		(pts
			(xy 100.642166 -157.858968) (xy 100.642166 -157.764988) (xy 100.642166 -156.195268) (xy 101.198172 -155.639262)
			(xy 101.236526 -155.600908) (xy 101.236526 -154.431492) (xy 101.205538 -154.400504) (xy 98.697542 -154.400504)
			(xy 98.58375 -154.286712) (xy 98.58375 -153.623518) (xy 98.444558 -153.484326) (xy 96.851216 -153.484326)
			(xy 96.01454 -153.484326) (xy 95.60052 -153.898346) (xy 95.60052 -157.764988) (xy 95.768414 -157.932882)
			(xy 96.969834 -157.932882) (xy 100.568252 -157.932882)
		)
		(stroke
			(width 0)
			(type solid)
		)
		(fill yes)
		(layer "F.Cu")
		(net "SW_P1V8_STB_NODE1_PH")
	)
	(gr_poly
		(pts
			(xy 102.193344 -151.807672) (xy 102.193344 -150.396194) (xy 102.188518 -150.396194) (xy 102.188518 -149.79904)
			(xy 102.188518 -148.91004) (xy 102.060502 -148.782024) (xy 100.88753 -148.782024) (xy 100.742242 -148.927312)
			(xy 100.742242 -149.537166) (xy 100.742242 -151.384254) (xy 100.742242 -151.989028) (xy 100.742242 -152.251918)
			(xy 100.89769 -152.407366) (xy 101.481128 -152.990804) (xy 101.481128 -153.025348) (xy 101.481128 -153.674572)
			(xy 101.498146 -153.69159) (xy 102.193344 -153.69159)
		)
		(stroke
			(width 0)
			(type solid)
		)
		(fill yes)
		(layer "F.Cu")
		(net "P12V_AUX")
	)
	(gr_poly
		(pts
			(xy 105.972864 -142.24889) (xy 105.972864 -140.61313) (xy 105.846118 -140.486384) (xy 105.340404 -140.486384)
			(xy 105.071672 -140.217652) (xy 105.071672 -139.206224) (xy 104.953054 -139.087606) (xy 103.412036 -139.087606)
			(xy 103.293672 -139.20597) (xy 103.293672 -139.721844) (xy 103.601774 -140.029946) (xy 103.601774 -140.43914)
			(xy 103.601774 -141.327886) (xy 103.50246 -141.4272) (xy 103.50246 -142.29969) (xy 103.530654 -142.327884)
			(xy 103.744268 -142.327884) (xy 105.89387 -142.327884)
		)
		(stroke
			(width 0)
			(type solid)
		)
		(fill yes)
		(layer "F.Cu")
		(net "AGND_PVCCP_NODE1")
	)
	(gr_poly
		(pts
			(xy 106.59872 -123.63704) (xy 106.59872 -122.920506) (xy 106.589322 -122.911108) (xy 105.313988 -122.911108)
			(xy 105.183432 -123.041664)
			(arc
				(start 104.134412 -123.041664)
				(mid 104.102246 -123.061727)
				(end 104.068372 -123.078748)
			)
			(arc
				(start 104.068372 -123.078748)
				(mid 104.013746 -123.125707)
				(end 103.993442 -123.194826)
			)
			(xy 103.993442 -123.641866) (xy 104.016302 -123.664726) (xy 106.571034 -123.664726)
		)
		(stroke
			(width 0)
			(type solid)
		)
		(fill yes)
		(layer "F.Cu")
		(net "VR_PVCCP_NODE1_LGATE1")
	)
	(gr_poly
		(pts
			(xy 167.16502 -96.173544) (xy 167.16502 -95.910654)
			(arc
				(start 167.159432 -95.892366)
				(mid 167.142459 -95.779844)
				(end 167.159432 -95.667322)
			)
			(xy 167.16502 -95.649034) (xy 167.16502 -94.862142) (xy 166.303198 -94.00032) (xy 165.838632 -94.00032)
			(xy 165.751764 -94.087188) (xy 165.751764 -94.384622) (xy 164.753798 -95.382588) (xy 164.753798 -96.18472)
			(xy 164.837872 -96.268794) (xy 167.06977 -96.268794)
		)
		(stroke
			(width 0)
			(type solid)
		)
		(fill yes)
		(layer "F.Cu")
		(net "USB_OC_PU")
	)
	(gr_poly
		(pts
			(arc
				(start 36.948618 -39.189914)
				(mid 36.982677 -39.146189)
				(end 36.994846 -39.092124)
			)
			(xy 36.994846 -37.411914) (xy 37.018722 -37.388038) (xy 37.018722 -33.653984) (xy 37.018722 -32.680402)
			(xy 36.6522 -32.31388) (xy 32.948626 -32.31388) (xy 32.19704 -33.065466) (xy 32.19704 -34.343594)
			(xy 32.19704 -39.18839) (xy 32.385762 -39.377112) (xy 35.029648 -39.377112) (xy 35.167062 -39.514526)
			(xy 36.555426 -39.514526)
		)
		(stroke
			(width 0)
			(type solid)
		)
		(fill yes)
		(layer "F.Cu")
		(net "GND")
	)
	(gr_poly
		(pts
			(xy 40.996362 -14.579092) (xy 40.996362 -12.613132) (xy 40.084502 -11.701272) (xy 40.084502 -11.185144)
			(xy 40.084502 -11.183874) (xy 39.946072 -11.045444) (xy 39.279068 -11.045444) (xy 39.229538 -11.094974)
			(xy 39.229538 -11.467592) (xy 39.229538 -11.878056) (xy 39.229538 -12.056364) (xy 39.53764 -12.364466)
			(xy 40.099488 -12.926314) (xy 40.099488 -13.250418) (xy 40.374824 -13.525754) (xy 40.374824 -14.578838)
			(xy 40.504618 -14.708632) (xy 40.73652 -14.708632) (xy 40.866822 -14.708632)
		)
		(stroke
			(width 0)
			(type solid)
		)
		(fill yes)
		(layer "F.Cu")
		(net "P5V_STB_NODE1")
	)
	(gr_poly
		(pts
			(xy 53.342286 -121.323862) (xy 53.342286 -120.511062) (xy 53.977286 -119.876062) (xy 53.977286 -118.707662)
			(xy 53.850286 -118.580662) (xy 52.224686 -118.580662) (xy 51.691286 -118.047262) (xy 51.030886 -118.047262)
			(xy 49.764696 -118.047262) (xy 49.750218 -118.032784) (xy 49.692814 -118.090188) (xy 49.692814 -118.526306)
			(xy 49.86274 -118.696232) (xy 51.095656 -118.696232) (xy 51.386486 -118.987062) (xy 51.488086 -119.088662)
			(xy 51.488086 -121.298462) (xy 51.665886 -121.476262) (xy 53.189886 -121.476262)
		)
		(stroke
			(width 0)
			(type solid)
		)
		(fill yes)
		(layer "F.Cu")
		(net "BMC_NODE1_OSC1_VDD")
	)
	(gr_poly
		(pts
			(xy 71.079868 -114.163348) (xy 71.871586 -114.163348) (xy 74.927714 -114.163348) (xy 75.26782 -113.823242)
			(xy 75.26782 -112.258348) (xy 74.545698 -111.536226) (xy 71.621396 -111.536226) (xy 70.936358 -111.536226)
			(xy 69.86397 -111.536226) (xy 68.933822 -111.536226) (xy 68.927472 -111.529876) (xy 68.878196 -111.529876)
			(xy 68.549774 -111.529876) (xy 68.531232 -111.548418) (xy 68.531232 -113.86058) (xy 68.810124 -114.139472)
			(xy 69.113908 -114.139472) (xy 69.14642 -114.171984) (xy 71.070978 -114.171984)
		)
		(stroke
			(width 0)
			(type solid)
		)
		(fill yes)
		(layer "F.Cu")
		(net "P1V8_NODE1")
	)
	(gr_poly
		(pts
			(xy 87.660734 -78.23454) (xy 87.660734 -75.723496) (xy 87.4776 -75.540362) (xy 85.663278 -75.540362)
			(xy 85.571584 -75.632056) (xy 85.571584 -78.417674)
			(arc
				(start 85.680296 -78.526386)
				(mid 85.724381 -78.555084)
				(end 85.776308 -78.56347)
			)
			(arc
				(start 85.776308 -78.56347)
				(mid 85.91215 -78.581597)
				(end 86.032848 -78.646528)
			)
			(xy 86.067646 -78.674214) (xy 87.22106 -78.674214)
		)
		(stroke
			(width 0)
			(type solid)
		)
		(fill yes)
		(layer "F.Cu")
		(net "P1V05_VCCPLLCPU0SIO_NODE1")
	)
	(gr_poly
		(pts
			(xy 102.703884 -153.682192) (xy 102.703884 -152.85847) (xy 102.713028 -152.849326) (xy 102.713028 -152.695148)
			(xy 103.033322 -152.374854) (xy 103.095298 -152.312878) (xy 103.491538 -152.312878) (xy 103.686102 -152.312878)
			(xy 103.711502 -152.287478) (xy 103.711502 -150.715726) (xy 103.711502 -149.954742) (xy 103.627174 -149.870414)
			(xy 102.61473 -149.870414) (xy 102.497128 -149.988016) (xy 102.497128 -150.700994) (xy 102.485698 -150.712424)
			(xy 102.485698 -153.681684) (xy 102.496874 -153.69286) (xy 102.693216 -153.69286)
		)
		(stroke
			(width 0)
			(type solid)
		)
		(fill yes)
		(layer "F.Cu")
		(net "P5V_STB_NODE1")
	)
	(gr_poly
		(pts
			(xy 114.607594 -66.803524) (xy 114.607594 -65.117726) (xy 114.499644 -65.009776) (xy 113.313972 -65.009776)
			(xy 112.774984 -65.548764)
			(arc
				(start 112.233964 -65.548764)
				(mid 112.185417 -65.558514)
				(end 112.144302 -65.586102)
			)
			(xy 112.018826 -65.711578) (xy 111.99749 -65.711578) (xy 111.99749 -65.987422) (xy 112.143794 -66.133726)
			(xy 112.336326 -66.133726) (xy 112.378744 -66.176144) (xy 112.60963 -66.176144) (xy 113.371884 -66.938144)
			(xy 114.472974 -66.938144)
		)
		(stroke
			(width 0)
			(type solid)
		)
		(fill yes)
		(layer "F.Cu")
		(net "P1V05_STB_NODE1_XDP_B")
	)
	(gr_poly
		(pts
			(xy 117.530372 -20.763992) (xy 117.530372 -19.440652) (xy 117.530372 -18.72742) (xy 117.455442 -18.65249)
			(xy 116.150898 -18.65249) (xy 116.03355 -18.769838) (xy 116.03355 -19.093688) (xy 116.252244 -19.312382)
			(xy 116.252244 -19.37512)
			(arc
				(start 116.252244 -21.076666)
				(mid 116.289441 -21.166469)
				(end 116.379244 -21.203666)
			)
			(xy 116.625624 -21.203666) (xy 117.090698 -21.203666)
		)
		(stroke
			(width 0)
			(type solid)
		)
		(fill yes)
		(layer "F.Cu")
		(net "P3V3_STB_NODE1")
	)
	(gr_poly
		(pts
			(xy 139.836652 -69.093842) (xy 139.963652 -68.966842) (xy 139.963652 -68.662042) (xy 139.963652 -68.433442)
			(xy 139.963652 -65.918842) (xy 139.963652 -62.566042) (xy 139.811252 -62.413642) (xy 139.252452 -62.413642)
			(xy 139.074652 -62.591442) (xy 138.211052 -63.455042) (xy 138.211052 -64.877442) (xy 137.642092 -65.446402)
			(xy 137.642092 -66.335402) (xy 137.642092 -66.642742) (xy 137.642092 -67.839082) (xy 137.642092 -68.702682)
			(xy 137.642092 -68.941442) (xy 137.832592 -69.131942) (xy 139.798552 -69.131942)
		)
		(stroke
			(width 0)
			(type solid)
		)
		(fill yes)
		(layer "F.Cu")
		(net "P1V0_SATA")
	)
	(gr_poly
		(pts
			(xy 26.429208 -125.660912) (xy 26.429208 -125.325886) (xy 26.429208 -121.130568) (xy 26.136092 -120.837452)
			(xy 25.204928 -120.837452) (xy 22.076918 -120.837452) (xy 21.919692 -120.994678) (xy 21.919692 -123.575572)
			(xy 21.752306 -123.742958) (xy 20.31365 -123.742958) (xy 20.209002 -123.847606) (xy 20.209002 -124.210064)
			(xy 20.20443 -124.214636) (xy 20.20443 -125.858524) (xy 20.241514 -125.895608) (xy 22.218396 -125.895608)
			(xy 22.682962 -125.895608) (xy 25.419812 -125.895608) (xy 25.859486 -125.895608) (xy 26.194512 -125.895608)
		)
		(stroke
			(width 0)
			(type solid)
		)
		(fill yes)
		(layer "F.Cu")
		(net "GND")
	)
	(gr_poly
		(pts
			(xy 40.110918 -9.562084) (xy 40.486584 -9.562084) (xy 40.517826 -9.530842) (xy 40.848026 -9.200642)
			(xy 41.0464 -9.002268) (xy 41.109646 -8.939022) (xy 41.935654 -8.939022) (xy 41.965118 -8.909558)
			(xy 41.965118 -8.764778) (xy 41.965118 -8.094218) (xy 41.803574 -7.932674) (xy 40.967406 -7.932674)
			(xy 40.816022 -8.084058) (xy 40.73525 -8.16483) (xy 39.479474 -9.420606) (xy 39.212012 -9.420606)
			(xy 39.194232 -9.438386) (xy 39.194232 -9.541002) (xy 39.219378 -9.566148) (xy 40.107108 -9.566148)
		)
		(stroke
			(width 0)
			(type solid)
		)
		(fill yes)
		(layer "F.Cu")
		(net "SW_PV_VDDR_NODE1_BT")
	)
	(gr_poly
		(pts
			(xy 99.10826 -138.145774) (xy 99.10826 -137.309352) (xy 99.60737 -136.810242) (xy 99.60737 -135.890762)
			(xy 99.20224 -135.485632) (xy 98.124264 -135.485632) (xy 97.80651 -135.803386) (xy 97.369376 -135.803386)
			(xy 96.241108 -135.803386) (xy 95.328994 -135.803386) (xy 95.308928 -135.823706) (xy 95.311214 -135.825992)
			(xy 95.311214 -137.301986) (xy 95.311214 -137.46226) (xy 95.194628 -137.578846) (xy 95.194628 -137.986262)
			(xy 95.372174 -138.163808) (xy 95.377 -138.163808) (xy 95.44558 -138.232388) (xy 99.021646 -138.232388)
		)
		(stroke
			(width 0)
			(type solid)
		)
		(fill yes)
		(layer "F.Cu")
		(net "P1V05_SUS_NODE1")
	)
	(gr_poly
		(pts
			(xy 111.03229 -132.618226) (xy 111.03229 -130.486658) (xy 111.052356 -130.466592) (xy 111.052356 -129.473452)
			(xy 111.052356 -128.750568) (xy 110.87989 -128.578102) (xy 109.542326 -128.578102) (xy 109.340396 -128.578102)
			(xy 109.294168 -128.62433) (xy 109.294168 -129.101596) (xy 109.47908 -129.286508) (xy 109.808772 -129.286508)
			(xy 110.032038 -129.509774) (xy 110.142274 -129.62001) (xy 110.142274 -131.62153) (xy 110.142274 -132.481066)
			(xy 109.613954 -133.009386) (xy 109.613954 -133.136132) (xy 109.624368 -133.146546) (xy 110.50397 -133.146546)
		)
		(stroke
			(width 0)
			(type solid)
		)
		(fill yes)
		(layer "F.Cu")
		(net "VR_PVCCP_NODE1_BOOT1")
	)
	(gr_poly
		(pts
			(xy 118.019322 -28.680664) (xy 118.019322 -26.727658) (xy 117.913658 -26.621994) (xy 116.843556 -26.621994)
			(xy 116.752878 -26.531316) (xy 116.752878 -25.44191) (xy 116.575332 -25.264364)
			(arc
				(start 115.90655 -25.264364)
				(mid 115.816747 -25.301561)
				(end 115.77955 -25.391364)
			)
			(xy 115.77955 -28.452572) (xy 115.754404 -28.477718) (xy 115.754404 -28.63723) (xy 115.865148 -28.747974)
			(xy 117.952012 -28.747974)
		)
		(stroke
			(width 0)
			(type solid)
		)
		(fill yes)
		(layer "F.Cu")
		(net "PV_VDDR_NODE1")
	)
	(gr_poly
		(pts
			(xy 65.983358 -163.83508) (xy 65.983358 -163.487354) (xy 65.983358 -161.31794) (xy 65.929764 -161.264346)
			(xy 65.908682 -161.264346) (xy 65.146682 -161.264346) (xy 65.031112 -161.379916) (xy 64.96939 -161.379916)
			(xy 64.798956 -161.550604) (xy 61.692028 -161.550604) (xy 61.648848 -161.593784) (xy 61.648594 -161.593784)
			(xy 61.53023 -161.712148) (xy 61.53023 -162.087052) (xy 61.545216 -162.102038) (xy 61.736478 -162.102038)
			(xy 61.98108 -162.34664) (xy 61.98108 -164.097462) (xy 62.027054 -164.143436) (xy 63.754762 -164.143436)
			(xy 65.675002 -164.143436)
		)
		(stroke
			(width 0)
			(type solid)
		)
		(fill yes)
		(layer "F.Cu")
		(net "P5V_NODE1")
	)
	(gr_poly
		(pts
			(xy 71.696834 -13.819632) (xy 71.696834 -11.684) (xy 71.696834 -9.836912) (xy 71.696834 -9.232138)
			(xy 71.696834 -8.969248) (xy 71.541386 -8.8138) (xy 70.957948 -8.230362) (xy 70.957948 -8.195818)
			(xy 70.957948 -7.546594) (xy 70.94093 -7.529576) (xy 70.245732 -7.529576) (xy 70.245732 -9.413494)
			(xy 70.245732 -10.824972) (xy 70.245732 -11.010392) (xy 69.88556 -11.370564) (xy 69.38772 -11.868404)
			(xy 69.38772 -12.100814) (xy 69.38772 -13.688822) (xy 69.48424 -13.785342) (xy 69.620384 -13.921486)
			(xy 71.59498 -13.921486)
		)
		(stroke
			(width 0)
			(type solid)
		)
		(fill yes)
		(layer "F.Cu")
		(net "P12V_AUX")
	)
	(gr_poly
		(pts
			(xy 76.290932 -6.690106) (xy 76.290932 -3.489452) (xy 76.290932 -3.321558) (xy 76.257658 -3.288284)
			(xy 71.870824 -3.288284) (xy 71.79691 -3.362198) (xy 71.79691 -3.456178) (xy 71.79691 -5.025898)
			(xy 71.240904 -5.581904) (xy 71.20255 -5.620258) (xy 71.20255 -5.812282) (xy 71.20255 -6.07568) (xy 71.206106 -6.079236)
			(xy 71.20255 -6.082792) (xy 71.20255 -6.316726) (xy 71.20255 -6.568694) (xy 71.213726 -6.57987) (xy 71.20255 -6.591046)
			(xy 71.20255 -6.789674) (xy 71.233538 -6.820662) (xy 76.160376 -6.820662)
		)
		(stroke
			(width 0)
			(type solid)
		)
		(fill yes)
		(layer "F.Cu")
		(net "SW_P3V3_NODE1_PH")
	)
	(gr_poly
		(pts
			(xy 84.563204 -140.184378) (xy 84.563204 -139.244832) (xy 84.563204 -139.13231) (xy 84.563204 -138.660378)
			(xy 84.784692 -138.43889) (xy 84.784692 -138.345926) (xy 84.784692 -137.86866) (xy 84.615274 -137.699242)
			(xy 84.615274 -137.224008) (xy 84.57692 -137.185654) (xy 84.162392 -137.185654) (xy 84.102956 -137.24509)
			(xy 84.102956 -138.218926) (xy 84.102956 -138.429238) (xy 84.308696 -138.634978) (xy 84.308696 -138.637772)
			(xy 84.31022 -138.639042) (xy 84.31022 -138.786108) (xy 84.31022 -140.189712) (xy 84.328508 -140.208)
			(xy 84.539582 -140.208)
		)
		(stroke
			(width 0)
			(type solid)
		)
		(fill yes)
		(layer "F.Cu")
		(net "P1V26_BMC_NODE1_ADJ")
	)
	(gr_poly
		(pts
			(xy 127.843788 -167.769032) (xy 130.47853 -167.769032) (xy 130.539236 -167.708326) (xy 130.539236 -167.529764)
			(xy 130.499358 -167.489886)
			(arc
				(start 129.775712 -167.489886)
				(mid 129.749747 -167.489122)
				(end 129.723896 -167.486584)
			)
			(xy 129.715514 -167.485314) (xy 129.616962 -167.485314) (xy 129.588514 -167.456866) (xy 128.96215 -167.456866)
			(xy 128.745488 -167.240204) (xy 128.745488 -167.06596) (xy 127.780796 -166.101268) (xy 127.166624 -166.101268)
			(xy 127.07239 -166.195502) (xy 127.07239 -167.93718) (xy 127.099568 -167.964358) (xy 127.648716 -167.964358)
		)
		(stroke
			(width 0)
			(type solid)
		)
		(fill yes)
		(layer "F.Cu")
		(net "P3V3_NODE1")
	)
	(gr_poly
		(pts
			(arc
				(start 27.178 -113.777014)
				(mid 27.267803 -113.739817)
				(end 27.305 -113.650014)
			)
			(xy 27.305 -106.403648) (xy 26.3779 -105.476548)
			(arc
				(start 24.22144 -105.476548)
				(mid 24.131637 -105.513745)
				(end 24.09444 -105.603548)
			)
			(xy 24.09444 -107.862624) (xy 23.999698 -107.957366) (xy 23.999698 -113.532412) (xy 24.2443 -113.777014)
		)
		(stroke
			(width 0)
			(type solid)
		)
		(fill yes)
		(layer "F.Cu")
		(net "GND")
	)
	(gr_poly
		(pts
			(xy 40.16629 -114.616992) (xy 40.16629 -113.990882) (xy 40.16629 -112.900714) (xy 39.942516 -112.67694)
			(xy 38.650672 -112.67694)
			(arc
				(start 38.60546 -112.67694)
				(mid 38.495988 -112.718813)
				(end 38.379654 -112.733074)
			)
			(arc
				(start 37.54628 -112.733074)
				(mid 37.442781 -112.721801)
				(end 37.344096 -112.688624)
			)
			(xy 37.318696 -112.67694) (xy 36.309046 -112.67694) (xy 36.244784 -112.741202) (xy 36.244784 -114.59972)
			(xy 36.28898 -114.64417) (xy 40.139112 -114.64417)
		)
		(stroke
			(width 0)
			(type solid)
		)
		(fill yes)
		(layer "F.Cu")
		(net "P1V5_NODE1")
	)
	(gr_poly
		(pts
			(xy 112.70869 -138.261344) (xy 112.70869 -137.71118) (xy 111.779304 -136.781794) (xy 111.552736 -136.781794)
			(xy 111.410242 -136.639046)
			(arc
				(start 111.302038 -136.639046)
				(mid 111.212235 -136.676243)
				(end 111.175038 -136.766046)
			)
			(xy 111.175038 -136.925558) (xy 111.18342 -136.933686) (xy 111.18342 -137.345928) (xy 111.175038 -137.354056)
			(xy 111.175038 -137.391648) (xy 111.070136 -137.49655) (xy 111.070136 -138.272266) (xy 111.083852 -138.286236)
			(xy 112.683798 -138.286236)
		)
		(stroke
			(width 0)
			(type solid)
		)
		(fill yes)
		(layer "F.Cu")
		(net "AGND_PVCCP_NODE1")
	)
	(gr_poly
		(pts
			(xy 141.894052 -28.733242) (xy 142.402052 -28.225242) (xy 144.561052 -28.225242) (xy 144.815052 -27.971242)
			(xy 144.815052 -26.955242) (xy 144.630902 -26.771092) (xy 144.500854 -26.771092) (xy 144.1323 -26.402538)
			(xy 144.1323 -26.014172) (xy 144.088612 -25.970484) (xy 143.326358 -25.970484) (xy 143.027146 -26.269696)
			(xy 141.94028 -26.269696) (xy 141.626082 -25.955498) (xy 141.019784 -25.955498) (xy 140.918438 -26.056844)
			(xy 140.918438 -27.066494) (xy 140.918438 -28.392628) (xy 141.386052 -28.860242) (xy 141.640052 -29.114242)
			(xy 141.640052 -30.968442) (xy 141.894052 -30.968442)
		)
		(stroke
			(width 0)
			(type solid)
		)
		(fill yes)
		(layer "F.Cu")
		(net "SIO_AVCC")
	)
	(gr_poly
		(pts
			(xy 183.228488 -161.616898) (xy 183.228488 -159.944308) (xy 183.206136 -159.944308)
			(arc
				(start 183.206136 -158.514796)
				(mid 183.168939 -158.424993)
				(end 183.079136 -158.387796)
			)
			(arc
				(start 180.757068 -158.387796)
				(mid 180.667265 -158.424993)
				(end 180.630068 -158.514796)
			)
			(xy 180.630068 -161.538158) (xy 180.772308 -161.680398) (xy 183.164988 -161.680398)
		)
		(stroke
			(width 0)
			(type solid)
		)
		(fill yes)
		(layer "F.Cu")
		(net "P1V9_LAN2")
	)
	(gr_poly
		(pts
			(xy 14.962632 -130.07975) (xy 14.962632 -129.521712) (xy 14.85138 -129.41046) (xy 14.845538 -129.41046)
			(xy 13.770864 -128.335786) (xy 13.770864 -126.295658) (xy 13.714476 -126.23927) (xy 12.476734 -126.23927)
			(xy 12.358624 -126.35738) (xy 12.358624 -129.76479) (xy 12.554966 -129.961132) (xy 13.502386 -129.961132)
			(arc
				(start 13.523976 -129.953004)
				(mid 13.657326 -129.928936)
				(end 13.790676 -129.953004)
			)
			(xy 13.812266 -129.961132) (xy 13.89888 -129.961132) (xy 14.049502 -130.111754) (xy 14.930628 -130.111754)
		)
		(stroke
			(width 0)
			(type solid)
		)
		(fill yes)
		(layer "F.Cu")
		(net "GND")
	)
	(gr_poly
		(pts
			(xy 17.591532 -126.62154) (xy 17.591532 -123.937014) (xy 17.546574 -123.892056) (xy 16.76527 -123.892056)
			(xy 16.198596 -123.325382) (xy 16.198596 -121.148348) (xy 16.198596 -119.29364) (xy 15.9131 -119.008144)
			(xy 13.441934 -119.008144) (xy 13.251434 -119.198644) (xy 13.251434 -121.208546) (xy 13.251434 -123.948952)
			(xy 13.251434 -125.75286) (xy 13.400278 -125.901704) (xy 16.751554 -125.901704) (xy 16.767556 -125.917706)
			(xy 16.787368 -125.937518) (xy 16.792194 -125.942344) (xy 16.792194 -125.971046) (xy 16.792448 -125.9713)
			(xy 16.792448 -126.598426) (xy 16.826992 -126.633224) (xy 17.579848 -126.633224)
		)
		(stroke
			(width 0)
			(type solid)
		)
		(fill yes)
		(layer "F.Cu")
		(net "SW_P1V05_NODE1_VIN_FLT")
	)
	(gr_poly
		(pts
			(xy 47.458122 -115.21567) (xy 47.458122 -113.368582) (xy 47.458122 -112.763808) (xy 47.458122 -112.500918)
			(xy 47.302674 -112.34547) (xy 46.719236 -111.762032) (xy 46.719236 -111.727488) (xy 46.719236 -111.078264)
			(xy 46.702218 -111.061246) (xy 46.00702 -111.061246) (xy 46.00702 -112.945164) (xy 46.00702 -114.356642)
			(xy 45.919898 -114.443764) (xy 45.026072 -114.443764) (xy 44.91863 -114.443764) (xy 44.905168 -114.457226)
			(xy 44.874942 -114.487452) (xy 44.874942 -115.185952) (xy 44.909486 -115.220496) (xy 45.123354 -115.220496)
			(xy 46.00702 -115.220496) (xy 47.125382 -115.220496) (xy 47.453296 -115.220496)
		)
		(stroke
			(width 0)
			(type solid)
		)
		(fill yes)
		(layer "F.Cu")
		(net "P12V_AUX")
	)
	(gr_poly
		(pts
			(xy 141.817852 -58.284872) (xy 141.817852 -55.857902) (xy 141.723872 -55.763922) (xy 140.712952 -55.763922)
			(xy 140.060172 -56.416702) (xy 140.060172 -57.224422) (xy 140.01496 -57.269634) (xy 140.01496 -57.338214)
			(xy 139.34821 -58.00471) (xy 138.880342 -58.472832)
			(arc
				(start 138.29792 -58.472832)
				(mid 138.208117 -58.510029)
				(end 138.17092 -58.599832)
			)
			(xy 138.17092 -59.110118) (xy 138.443716 -59.383168) (xy 138.47699 -59.383168) (xy 138.622786 -59.528964)
			(xy 140.57376 -59.528964)
		)
		(stroke
			(width 0)
			(type solid)
		)
		(fill yes)
		(layer "F.Cu")
		(net "P1V0_NODE1")
	)
	(gr_poly
		(pts
			(xy 189.018672 -151.105108) (xy 193.063114 -151.105108) (xy 193.3067 -150.861522) (xy 193.3067 -145.897854)
			(xy 193.06032 -145.651474) (xy 193.06032 -141.829282) (xy 193.049652 -141.81836) (xy 193.049652 -139.463526)
			(xy 192.79108 -139.204954) (xy 187.491116 -139.204954) (xy 187.26404 -139.43203) (xy 187.26404 -143.490696)
			(xy 186.214258 -144.540478) (xy 183.665114 -144.540478) (xy 183.632602 -144.57299) (xy 183.632602 -146.429476)
			(xy 183.957722 -146.754596) (xy 186.476132 -146.754596) (xy 186.780678 -147.059142) (xy 186.780678 -148.82495)
			(xy 185.3057 -150.299928) (xy 185.3057 -150.803356) (xy 185.6232 -151.120856) (xy 189.002924 -151.120856)
		)
		(stroke
			(width 0)
			(type solid)
		)
		(fill yes)
		(layer "F.Cu")
		(net "P1V9_LAN2")
	)
	(gr_poly
		(pts
			(xy 16.434562 -129.15265) (xy 16.434562 -128.27889) (xy 16.434562 -128.241552) (xy 16.434562 -128.139952)
			(xy 16.436594 -128.13792) (xy 16.554958 -128.019556) (xy 16.554958 -127.230632) (xy 16.554704 -127.230378)
			(xy 16.554704 -126.894082) (xy 16.523716 -126.863094) (xy 16.523716 -126.17958) (xy 16.515588 -126.171452)
			(xy 15.983712 -126.171452) (xy 15.966948 -126.188216) (xy 15.966948 -126.229872) (xy 15.966948 -126.428246)
			(xy 15.966948 -126.57455) (xy 16.182086 -126.789688) (xy 16.182086 -126.902718) (xy 16.182086 -127.011684)
			(xy 16.182086 -128.010158) (xy 16.182086 -128.185926) (xy 16.182086 -129.136394) (xy 16.212566 -129.166874)
			(xy 16.420338 -129.166874)
		)
		(stroke
			(width 0)
			(type solid)
		)
		(fill yes)
		(layer "F.Cu")
		(net "SW_P1V05_NODE1_DRVH")
	)
	(gr_poly
		(pts
			(xy 38.611556 -6.375146) (xy 38.611556 -4.61391)
			(arc
				(start 38.608762 -4.600702)
				(mid 38.60092 -4.55081)
				(end 38.598348 -4.500372)
			)
			(arc
				(start 38.598348 -4.284472)
				(mid 38.561151 -4.194669)
				(end 38.471348 -4.157472)
			)
			(arc
				(start 38.214808 -4.157472)
				(mid 38.125005 -4.194669)
				(end 38.087808 -4.284472)
			)
			(xy 38.087808 -6.377686) (xy 38.21811 -6.508242) (xy 38.47846 -6.508242)
		)
		(stroke
			(width 0)
			(type solid)
		)
		(fill yes)
		(layer "F.Cu")
		(net "P3V3_STB_NODE1")
	)
	(gr_poly
		(pts
			(xy 42.492676 -183.861202) (xy 42.492676 -181.694836) (xy 42.102786 -181.304946) (xy 40.557196 -181.304946)
			(xy 40.2844 -181.03215) (xy 40.2844 -176.457102) (xy 40.119554 -176.292256) (xy 35.767518 -176.292256)
			(xy 35.59937 -176.460404) (xy 35.59937 -176.844706)
			(arc
				(start 35.603942 -176.86147)
				(mid 35.617862 -176.963578)
				(end 35.603942 -177.065686)
			)
			(xy 35.59937 -177.08245) (xy 35.59937 -181.046628) (xy 35.592512 -181.053486) (xy 35.592512 -182.658258)
			(xy 35.592512 -182.933848) (xy 36.52266 -183.863996) (xy 39.980108 -183.863996) (xy 40.14978 -184.033668)
			(xy 42.32021 -184.033668)
		)
		(stroke
			(width 0)
			(type solid)
		)
		(fill yes)
		(layer "F.Cu")
		(net "VSENSE_HSC_NODE1")
	)
	(gr_poly
		(pts
			(xy 46.704758 -110.795562) (xy 46.704758 -109.171994) (xy 46.704758 -108.92409) (xy 46.707298 -108.92155)
			(xy 47.266606 -108.362242) (xy 47.266606 -107.925362) (xy 47.278036 -107.913932) (xy 47.278036 -106.838496)
			(xy 47.259748 -106.820208) (xy 46.328076 -106.820208) (xy 46.13021 -107.018074) (xy 46.13021 -107.968034)
			(xy 46.02607 -108.072174) (xy 46.001686 -108.096558) (xy 46.001686 -109.06887) (xy 45.988986 -109.08157)
			(xy 45.941488 -109.129068) (xy 45.047408 -109.129068) (xy 45.045376 -109.129068) (xy 45.012102 -109.162342)
			(xy 45.012102 -109.394244) (xy 45.012102 -110.377986) (xy 45.012102 -110.782862) (xy 45.025818 -110.796578)
			(xy 46.703742 -110.796578)
		)
		(stroke
			(width 0)
			(type solid)
		)
		(fill yes)
		(layer "F.Cu")
		(net "GND")
	)
	(gr_poly
		(pts
			(xy 61.586618 -161.296096) (xy 61.862208 -161.296096)
			(arc
				(start 61.869066 -161.295334)
				(mid 61.910722 -161.293053)
				(end 61.952378 -161.295334)
			)
			(xy 61.959236 -161.296096) (xy 64.693546 -161.296096) (xy 65.027302 -160.96234) (xy 65.964054 -160.96234)
			(xy 66.007488 -160.918906) (xy 66.007488 -160.574482) (xy 65.595246 -160.16224) (xy 63.204598 -160.16224)
			(xy 62.939422 -160.427416) (xy 62.253622 -160.427416) (xy 62.116462 -160.290256) (xy 61.893958 -160.067752)
			(xy 60.42406 -160.067752) (xy 60.06846 -160.423352) (xy 60.06846 -161.278316) (xy 60.09894 -161.308796)
			(xy 60.592462 -161.308796) (xy 60.622942 -161.339276) (xy 61.543438 -161.339276)
		)
		(stroke
			(width 0)
			(type solid)
		)
		(fill yes)
		(layer "F.Cu")
		(net "FM_CPLD_NODE1_P5V_EN_LV")
	)
	(gr_poly
		(pts
			(xy 70.94347 -7.263892) (xy 70.94347 -5.640324) (xy 70.94347 -5.39242) (xy 70.94601 -5.38988) (xy 71.505318 -4.830572)
			(xy 71.505318 -4.393692) (xy 71.516748 -4.382262) (xy 71.516748 -3.306826) (xy 71.49846 -3.288538)
			(xy 70.566788 -3.288538) (xy 70.368922 -3.486404) (xy 70.368922 -4.436364) (xy 70.264782 -4.540504)
			(xy 70.240398 -4.564888) (xy 70.240398 -5.5372) (xy 70.227698 -5.5499) (xy 70.1802 -5.597398) (xy 69.28612 -5.597398)
			(xy 69.284088 -5.597398) (xy 69.250814 -5.630672) (xy 69.250814 -5.862574) (xy 69.250814 -6.846316)
			(xy 69.250814 -7.251192) (xy 69.26453 -7.264908) (xy 70.942454 -7.264908)
		)
		(stroke
			(width 0)
			(type solid)
		)
		(fill yes)
		(layer "F.Cu")
		(net "GND")
	)
	(gr_poly
		(pts
			(xy 78.551532 -157.700218) (xy 78.551532 -156.750258) (xy 78.655672 -156.646118) (xy 78.680056 -156.621734)
			(xy 78.680056 -155.649422) (xy 78.692756 -155.636722) (xy 78.740254 -155.589224) (xy 79.634334 -155.589224)
			(xy 79.636366 -155.589224) (xy 79.66964 -155.55595) (xy 79.66964 -155.324048) (xy 79.66964 -154.340306)
			(xy 79.66964 -153.93543) (xy 79.655924 -153.921714) (xy 77.978 -153.921714) (xy 77.976984 -153.92273)
			(xy 77.976984 -155.546298) (xy 77.976984 -155.794202) (xy 77.974444 -155.796742) (xy 77.415136 -156.35605)
			(xy 77.415136 -156.79293) (xy 77.403706 -156.80436) (xy 77.403706 -157.879796) (xy 77.421994 -157.898084)
			(xy 78.353666 -157.898084)
		)
		(stroke
			(width 0)
			(type solid)
		)
		(fill yes)
		(layer "F.Cu")
		(net "GND")
	)
	(gr_poly
		(pts
			(xy 102.070154 -157.734762) (xy 102.070154 -156.784802) (xy 102.174294 -156.680662) (xy 102.198678 -156.656278)
			(xy 102.198678 -155.683966) (xy 102.211378 -155.671266) (xy 102.258876 -155.623768) (xy 103.152956 -155.623768)
			(xy 103.154988 -155.623768) (xy 103.188262 -155.590494) (xy 103.188262 -155.358592) (xy 103.188262 -154.37485)
			(xy 103.188262 -153.969974) (xy 103.174546 -153.956258) (xy 101.496622 -153.956258) (xy 101.495606 -153.957274)
			(xy 101.495606 -155.580842) (xy 101.495606 -155.828746) (xy 101.493066 -155.831286) (xy 100.933758 -156.390594)
			(xy 100.933758 -156.827474) (xy 100.922328 -156.838904) (xy 100.922328 -157.91434) (xy 100.940616 -157.932628)
			(xy 101.872288 -157.932628)
		)
		(stroke
			(width 0)
			(type solid)
		)
		(fill yes)
		(layer "F.Cu")
		(net "GND")
	)
	(gr_poly
		(pts
			(xy 25.338024 -147.272756) (xy 25.61209 -147.272756) (xy 25.8318 -147.053046) (xy 25.8318 -144.992598)
			(xy 26.111708 -144.712436) (xy 27.560016 -144.712436) (xy 27.75712 -144.515332) (xy 27.75712 -144.17167)
			(xy 28.172156 -143.75638) (xy 30.921198 -143.75638) (xy 31.06674 -143.610838) (xy 31.06674 -143.5227)
			(xy 31.06674 -143.217138) (xy 31.06674 -139.380214) (xy 30.83306 -139.146534) (xy 27.380692 -139.146534)
			(xy 26.943304 -138.709146) (xy 26.943304 -135.013954) (xy 26.301954 -134.372604) (xy 23.603712 -134.372604)
			(xy 22.676866 -135.299704) (xy 22.676866 -141.901672) (xy 23.880572 -143.105378) (xy 23.880572 -147.169124)
			(xy 23.98776 -147.276312) (xy 25.334468 -147.276312)
		)
		(stroke
			(width 0)
			(type solid)
		)
		(fill yes)
		(layer "F.Cu")
		(net "P1V9_LAN1")
	)
	(gr_poly
		(pts
			(arc
				(start 37.197792 -6.444488)
				(mid 37.287595 -6.407291)
				(end 37.324792 -6.317488)
			)
			(arc
				(start 37.324792 -4.987544)
				(mid 37.287595 -4.897741)
				(end 37.197792 -4.860544)
			)
			(xy 36.938966 -4.860544) (xy 36.85667 -4.94284)
			(arc
				(start 36.85667 -6.317488)
				(mid 36.893867 -6.407291)
				(end 36.98367 -6.444488)
			)
		)
		(stroke
			(width 0)
			(type solid)
		)
		(fill yes)
		(layer "F.Cu")
		(net "P3V3_STB_NODE1")
	)
	(gr_poly
		(pts
			(arc
				(start 60.530232 -120.891554)
				(mid 60.620035 -120.854357)
				(end 60.657232 -120.764554)
			)
			(arc
				(start 60.657232 -119.195596)
				(mid 60.620035 -119.105793)
				(end 60.530232 -119.068596)
			)
			(xy 60.226448 -119.068596) (xy 60.121292 -119.173752)
			(arc
				(start 60.121292 -120.764554)
				(mid 60.158489 -120.854357)
				(end 60.248292 -120.891554)
			)
		)
		(stroke
			(width 0)
			(type solid)
		)
		(fill yes)
		(layer "F.Cu")
		(net "P3V3_NODE1")
	)
	(gr_poly
		(pts
			(arc
				(start 61.66612 -120.88495)
				(mid 61.755923 -120.847753)
				(end 61.79312 -120.75795)
			)
			(xy 61.79312 -119.170958) (xy 61.684154 -119.061992)
			(arc
				(start 61.39434 -119.061992)
				(mid 61.304537 -119.099189)
				(end 61.26734 -119.188992)
			)
			(arc
				(start 61.26734 -120.75795)
				(mid 61.304537 -120.847753)
				(end 61.39434 -120.88495)
			)
		)
		(stroke
			(width 0)
			(type solid)
		)
		(fill yes)
		(layer "F.Cu")
		(net "P3V3_NODE1")
	)
	(gr_poly
		(pts
			(xy 65.121536 -120.790462)
			(arc
				(start 65.121536 -119.060976)
				(mid 65.084339 -118.971173)
				(end 64.994536 -118.933976)
			)
			(arc
				(start 64.82334 -118.933976)
				(mid 64.733537 -118.971173)
				(end 64.69634 -119.060976)
			)
			(arc
				(start 64.69634 -120.753632)
				(mid 64.733537 -120.843435)
				(end 64.82334 -120.880632)
			)
			(xy 65.03162 -120.880632)
		)
		(stroke
			(width 0)
			(type solid)
		)
		(fill yes)
		(layer "F.Cu")
		(net "P3V3_NODE1")
	)
	(gr_poly
		(pts
			(arc
				(start 66.326004 -120.899682)
				(mid 66.415807 -120.862485)
				(end 66.453004 -120.772682)
			)
			(xy 66.453004 -119.061992) (xy 66.344038 -118.953026)
			(arc
				(start 66.164968 -118.953026)
				(mid 66.075165 -118.990223)
				(end 66.037968 -119.080026)
			)
			(arc
				(start 66.037968 -120.772682)
				(mid 66.075165 -120.862485)
				(end 66.164968 -120.899682)
			)
		)
		(stroke
			(width 0)
			(type solid)
		)
		(fill yes)
		(layer "F.Cu")
		(net "P3V3_NODE1")
	)
	(gr_poly
		(pts
			(xy 88.780366 -81.857088) (xy 92.042996 -81.857088) (xy 92.09405 -81.806288) (xy 92.143834 -81.806288)
			(xy 92.220034 -81.730088) (xy 92.346018 -81.730088) (xy 92.8497 -81.226152) (xy 92.8497 -80.442562)
			(xy 92.521786 -80.114648) (xy 91.20378 -80.114648) (xy 90.986864 -80.331564) (xy 89.535254 -80.331564)
			(xy 89.519252 -80.315308) (xy 88.98128 -80.315308) (xy 88.979756 -80.313784)
			(arc
				(start 87.76462 -80.313784)
				(mid 87.674817 -80.350981)
				(end 87.63762 -80.440784)
			)
			(xy 87.63762 -82.136996) (xy 87.730076 -82.229452) (xy 88.408256 -82.229452)
		)
		(stroke
			(width 0)
			(type solid)
		)
		(fill yes)
		(layer "F.Cu")
		(net "GND")
	)
	(gr_poly
		(pts
			(arc
				(start 108.311442 -131.637532)
				(mid 108.44978 -131.664897)
				(end 108.528104 -131.547616)
			)
			(xy 108.528104 -131.433062) (xy 108.338112 -131.242816) (xy 108.338112 -130.670046) (xy 107.987592 -130.319526)
			(arc
				(start 107.890564 -130.319526)
				(mid 107.800761 -130.356723)
				(end 107.763564 -130.446526)
			)
			(xy 107.763564 -130.883406) (xy 107.882944 -131.002786) (xy 107.882944 -131.20878)
		)
		(stroke
			(width 0)
			(type solid)
		)
		(fill yes)
		(layer "F.Cu")
		(net "VR_PVCCP_NODE1_LGATE1")
	)
	(gr_poly
		(pts
			(xy 113.644172 -23.826724) (xy 113.644172 -23.22576) (xy 113.72342 -23.146512) (xy 117.825774 -23.146512)
			(xy 117.96014 -23.012146) (xy 117.96014 -22.554438) (xy 118.112794 -22.401784) (xy 119.590058 -22.401784)
			(xy 119.79656 -22.195282) (xy 119.79656 -20.712176) (xy 119.5578 -20.473416) (xy 118.195598 -20.473416)
			(xy 117.211094 -21.45792) (xy 117.196108 -21.45792) (xy 116.379244 -21.45792) (xy 113.685066 -21.45792)
			(xy 113.676684 -21.449792) (xy 112.983264 -21.449792) (xy 112.667796 -21.13407) (xy 112.667796 -21.108924)
			(xy 112.442498 -20.88388) (xy 110.918498 -20.88388) (xy 110.60684 -21.195538) (xy 110.60684 -23.649432)
			(xy 110.885224 -23.927816) (xy 113.54308 -23.927816)
		)
		(stroke
			(width 0)
			(type solid)
		)
		(fill yes)
		(layer "F.Cu")
		(net "GND")
	)
	(gr_poly
		(pts
			(arc
				(start 18.170398 -72.693784)
				(mid 18.381472 -72.645213)
				(end 18.592546 -72.693784)
			)
			(xy 18.618962 -72.706484) (xy 19.085814 -72.706484) (xy 20.26666 -72.706484) (xy 20.339812 -72.633332)
			(xy 20.339812 -72.19696) (xy 20.339812 -69.530722) (xy 19.864324 -69.055234) (xy 18.336006 -69.055234)
			(xy 17.690592 -68.40982) (xy 17.690592 -67.000374) (xy 17.57172 -66.881502) (xy 15.296388 -66.881502)
			(xy 15.109444 -67.068446) (xy 15.109444 -68.138294) (xy 15.754604 -68.783454) (xy 15.754604 -71.755508)
			(xy 16.70558 -72.706484) (xy 18.143982 -72.706484)
		)
		(stroke
			(width 0)
			(type solid)
		)
		(fill yes)
		(layer "F.Cu")
		(net "P5V_CRT")
	)
	(gr_poly
		(pts
			(xy 28.8163 -138.848846) (xy 30.87878 -138.848846) (xy 31.09214 -138.635486) (xy 31.09214 -133.677152)
			(xy 30.890972 -133.475984) (xy 29.516832 -133.475984) (xy 29.266896 -133.226048) (xy 28.551886 -132.511038)
			(xy 22.569678 -132.511038) (xy 21.688552 -132.511038) (xy 21.54428 -132.65531) (xy 21.54428 -133.15823)
			(xy 21.03374 -133.66877) (xy 19.44116 -133.66877) (xy 19.20748 -133.90245) (xy 19.20748 -138.61034)
			(xy 19.43608 -138.83894) (xy 20.472146 -138.83894) (xy 22.045422 -138.83894) (xy 22.259798 -138.624564)
			(xy 22.259798 -135.226806) (xy 23.44674 -134.039864) (xy 26.420318 -134.039864) (xy 27.205178 -134.824724)
			(xy 27.205178 -138.469624) (xy 27.586686 -138.851132) (xy 28.814014 -138.851132)
		)
		(stroke
			(width 0)
			(type solid)
		)
		(fill yes)
		(layer "F.Cu")
		(net "GND")
	)
	(gr_poly
		(pts
			(xy 79.185262 -153.647648) (xy 79.185262 -152.823926) (xy 79.194406 -152.814782) (xy 79.194406 -152.660604)
			(xy 79.576676 -152.278334) (xy 79.576676 -151.290782) (xy 79.824834 -151.042624) (xy 79.824834 -149.87905)
			(xy 79.662274 -149.71649) (xy 79.443834 -149.497796) (xy 77.228446 -149.497796) (xy 77.22362 -149.502622)
			(xy 77.22362 -152.217374) (xy 77.962506 -152.95626) (xy 77.962506 -153.418286) (xy 78.966314 -153.418286)
			(xy 78.966314 -152.258014) (xy 78.967076 -152.258014) (xy 78.967076 -153.419048) (xy 78.966314 -153.418286)
			(xy 77.962506 -153.418286) (xy 77.962506 -153.640028) (xy 77.979524 -153.657046) (xy 78.959964 -153.657046)
			(xy 78.968346 -153.64841) (xy 78.978252 -153.658316) (xy 79.174594 -153.658316)
		)
		(stroke
			(width 0)
			(type solid)
		)
		(fill yes)
		(layer "F.Cu")
		(net "P12V_AUX")
	)
	(gr_poly
		(pts
			(xy 95.955612 -133.564122) (xy 95.955612 -132.469382) (xy 95.957136 -132.467858) (xy 95.957136 -132.127244)
			(xy 95.97517 -132.109464) (xy 95.97517 -130.265424) (xy 95.86976 -130.160014) (xy 94.444312 -130.160014)
			(xy 94.391734 -130.212592) (xy 94.391734 -132.038344) (xy 94.713298 -132.359908) (xy 94.713298 -132.462016)
			(xy 94.720156 -132.46862)
			(arc
				(start 94.720156 -133.138164)
				(mid 94.718908 -133.169511)
				(end 94.715076 -133.200648)
			)
			(xy 94.713298 -133.210808)
			(arc
				(start 94.713298 -133.439408)
				(mid 94.750495 -133.529211)
				(end 94.840298 -133.566408)
			)
			(xy 95.95358 -133.566408)
		)
		(stroke
			(width 0)
			(type solid)
		)
		(fill yes)
		(layer "F.Cu")
		(net "P1V8_STB_NODE1")
	)
	(gr_poly
		(pts
			(xy 170.301666 -103.927148) (xy 170.301666 -97.951544) (xy 170.249596 -97.899474) (xy 169.66946 -97.899474)
			(arc
				(start 169.644314 -97.910904)
				(mid 169.349031 -97.992328)
				(end 169.043096 -97.977198)
			)
			(arc
				(start 169.043096 -97.977198)
				(mid 168.737294 -97.992292)
				(end 168.442132 -97.910904)
			)
			(xy 168.416986 -97.899474) (xy 164.336476 -97.899474) (xy 164.169852 -98.066098) (xy 164.169852 -103.91648)
			(xy 164.273992 -104.02062) (xy 170.208194 -104.02062)
		)
		(stroke
			(width 0)
			(type solid)
		)
		(fill yes)
		(layer "F.Cu")
		(net "GND")
	)
	(gr_poly
		(pts
			(arc
				(start 25.30094 -117.668802)
				(mid 25.390743 -117.631605)
				(end 25.42794 -117.541802)
			)
			(xy 25.42794 -114.538506) (xy 25.2222 -114.332766) (xy 23.972266 -114.332766) (xy 23.691596 -114.052096)
			(xy 23.691596 -110.935516) (xy 23.6728 -110.916466) (xy 23.6728 -107.440984) (xy 23.82266 -107.291124)
			(xy 23.82266 -105.647744) (xy 23.57374 -105.398824)
			(arc
				(start 16.08328 -105.398824)
				(mid 15.993477 -105.436021)
				(end 15.95628 -105.525824)
			)
			(xy 15.95628 -117.564662) (xy 16.06042 -117.668802)
		)
		(stroke
			(width 0)
			(type solid)
		)
		(fill yes)
		(layer "F.Cu")
		(net "P1V05_NODE1")
	)
	(gr_poly
		(pts
			(arc
				(start 50.872644 -140.119862)
				(mid 50.579528 -140.119862)
				(end 50.872644 -140.119862)
			)
		)
		(stroke
			(width 0)
			(type solid)
		)
		(fill yes)
		(layer "F.Cu")
		(net "GND")
	)
	(gr_poly
		(pts
			(arc
				(start 51.329844 -137.122662)
				(mid 51.036728 -137.122662)
				(end 51.329844 -137.122662)
			)
		)
		(stroke
			(width 0)
			(type solid)
		)
		(fill yes)
		(layer "F.Cu")
		(net "GND")
	)
	(gr_poly
		(pts
			(arc
				(start 53.006244 -139.967462)
				(mid 52.713128 -139.967462)
				(end 53.006244 -139.967462)
			)
		)
		(stroke
			(width 0)
			(type solid)
		)
		(fill yes)
		(layer "F.Cu")
		(net "GND")
	)
	(gr_poly
		(pts
			(arc
				(start 53.457602 -137.150348)
				(mid 53.164486 -137.150348)
				(end 53.457602 -137.150348)
			)
		)
		(stroke
			(width 0)
			(type solid)
		)
		(fill yes)
		(layer "F.Cu")
		(net "GND")
	)
	(gr_poly
		(pts
			(arc
				(start 54.661562 -131.188968)
				(mid 54.368446 -131.188968)
				(end 54.661562 -131.188968)
			)
		)
		(stroke
			(width 0)
			(type solid)
		)
		(fill yes)
		(layer "F.Cu")
		(net "GND")
	)
	(gr_poly
		(pts
			(arc
				(start -8.945372 -185.771282)
				(mid -9.270492 -185.771282)
				(end -8.945372 -185.771282)
			)
		)
		(stroke
			(width 0)
			(type solid)
		)
		(fill yes)
		(layer "F.Cu")
		(net "GND")
	)
	(gr_poly
		(pts
			(arc
				(start 11.6967 -5.477002)
				(mid 11.37158 -5.477002)
				(end 11.6967 -5.477002)
			)
		)
		(stroke
			(width 0)
			(type solid)
		)
		(fill yes)
		(layer "F.Cu")
		(net "GND")
	)
	(gr_poly
		(pts
			(arc
				(start 14.097 -4.305808)
				(mid 13.77188 -4.305808)
				(end 14.097 -4.305808)
			)
		)
		(stroke
			(width 0)
			(type solid)
		)
		(fill yes)
		(layer "F.Cu")
		(net "GND")
	)
	(gr_poly
		(pts
			(arc
				(start 15.281656 -6.584188)
				(mid 14.956536 -6.584188)
				(end 15.281656 -6.584188)
			)
		)
		(stroke
			(width 0)
			(type solid)
		)
		(fill yes)
		(layer "F.Cu")
		(net "GND")
	)
	(gr_poly
		(pts
			(arc
				(start 15.703042 -118.189756)
				(mid 15.377922 -118.189756)
				(end 15.703042 -118.189756)
			)
		)
		(stroke
			(width 0)
			(type solid)
		)
		(fill yes)
		(layer "F.Cu")
		(net "GND")
	)
	(gr_poly
		(pts
			(arc
				(start 16.24076 -157.92577)
				(mid 15.91564 -157.92577)
				(end 16.24076 -157.92577)
			)
		)
		(stroke
			(width 0)
			(type solid)
		)
		(fill yes)
		(layer "F.Cu")
		(net "GND")
	)
	(gr_poly
		(pts
			(arc
				(start 16.28902 -160.196022)
				(mid 15.9639 -160.196022)
				(end 16.28902 -160.196022)
			)
		)
		(stroke
			(width 0)
			(type solid)
		)
		(fill yes)
		(layer "F.Cu")
		(net "GND")
	)
	(gr_poly
		(pts
			(arc
				(start 16.43126 -118.285006)
				(mid 16.10614 -118.285006)
				(end 16.43126 -118.285006)
			)
		)
		(stroke
			(width 0)
			(type solid)
		)
		(fill yes)
		(layer "F.Cu")
		(net "GND")
	)
	(gr_poly
		(pts
			(arc
				(start 17.116298 -118.456202)
				(mid 16.791178 -118.456202)
				(end 17.116298 -118.456202)
			)
		)
		(stroke
			(width 0)
			(type solid)
		)
		(fill yes)
		(layer "F.Cu")
		(net "GND")
	)
	(gr_poly
		(pts
			(xy 18.17624 -128.74117) (xy 18.693892 -128.223772) (xy 19.58086 -128.223772) (xy 19.938492 -127.86614)
			(xy 19.938492 -126.186946) (xy 19.938492 -123.65101) (xy 20.084034 -123.505468) (xy 20.142708 -123.446794)
			(xy 21.341842 -123.446794) (xy 21.4503 -123.338336) (xy 21.4503 -123.198128) (xy 21.4503 -120.594628)
			(xy 21.323554 -120.467882) (xy 21.0439 -120.467882) (xy 19.372072 -120.467882) (xy 18.096738 -120.467882)
			(xy 17.93621 -120.62841) (xy 17.93621 -125.951234) (xy 17.93621 -126.900178) (xy 17.908016 -126.928372)
			(xy 17.813528 -127.02286) (xy 16.968216 -127.02286) (xy 16.911574 -127.079502) (xy 16.911574 -128.123442)
			(xy 16.68018 -128.354836) (xy 16.68018 -129.072894) (xy 16.715232 -129.107946) (xy 17.206468 -129.107946)
			(xy 17.809464 -129.107946)
		)
		(stroke
			(width 0)
			(type solid)
		)
		(fill yes)
		(layer "F.Cu")
		(net "SW_P1V05_NODE1_PH")
	)
	(gr_poly
		(pts
			(arc
				(start 18.67662 -39.204646)
				(mid 18.3515 -39.204646)
				(end 18.67662 -39.204646)
			)
		)
		(stroke
			(width 0)
			(type solid)
		)
		(fill yes)
		(layer "F.Cu")
		(net "GND")
	)
	(gr_poly
		(pts
			(arc
				(start 18.73758 -152.806146)
				(mid 18.41246 -152.806146)
				(end 18.73758 -152.806146)
			)
		)
		(stroke
			(width 0)
			(type solid)
		)
		(fill yes)
		(layer "F.Cu")
		(net "GND")
	)
	(gr_poly
		(pts
			(arc
				(start 18.75028 -155.240736)
				(mid 18.42516 -155.240736)
				(end 18.75028 -155.240736)
			)
		)
		(stroke
			(width 0)
			(type solid)
		)
		(fill yes)
		(layer "F.Cu")
		(net "GND")
	)
	(gr_poly
		(pts
			(arc
				(start 20.02282 -54.519068)
				(mid 19.6977 -54.519068)
				(end 20.02282 -54.519068)
			)
		)
		(stroke
			(width 0)
			(type solid)
		)
		(fill yes)
		(layer "F.Cu")
		(net "GND")
	)
	(gr_poly
		(pts
			(arc
				(start 20.7899 -66.379598)
				(mid 20.46478 -66.379598)
				(end 20.7899 -66.379598)
			)
		)
		(stroke
			(width 0)
			(type solid)
		)
		(fill yes)
		(layer "F.Cu")
		(net "GND")
	)
	(gr_poly
		(pts
			(arc
				(start 22.190964 -127.507238)
				(mid 21.865844 -127.507238)
				(end 22.190964 -127.507238)
			)
		)
		(stroke
			(width 0)
			(type solid)
		)
		(fill yes)
		(layer "F.Cu")
		(net "GND")
	)
	(gr_poly
		(pts
			(xy 30.641036 -102.320852)
			(arc
				(start 30.641036 -101.654356)
				(mid 30.603839 -101.564553)
				(end 30.514036 -101.527356)
			)
			(xy 29.148532 -101.527356)
			(arc
				(start 29.117544 -101.546914)
				(mid 28.85948 -101.62165)
				(end 28.601416 -101.546914)
			)
			(xy 28.570428 -101.527356) (xy 27.31643 -101.527356) (xy 27.187398 -101.656388) (xy 27.187398 -102.126796)
			(xy 27.217116 -102.156514) (xy 29.62402 -102.156514) (xy 29.806138 -102.338632) (xy 30.623256 -102.338632)
		)
		(stroke
			(width 0)
			(type solid)
		)
		(fill yes)
		(layer "F.Cu")
		(net "P5V_STB_NODE1")
	)
	(gr_poly
		(pts
			(arc
				(start 31.4452 -72.91324)
				(mid 31.12008 -72.91324)
				(end 31.4452 -72.91324)
			)
		)
		(stroke
			(width 0)
			(type solid)
		)
		(fill yes)
		(layer "F.Cu")
		(net "GND")
	)
	(gr_poly
		(pts
			(arc
				(start 32.2834 -63.54064)
				(mid 31.95828 -63.54064)
				(end 32.2834 -63.54064)
			)
		)
		(stroke
			(width 0)
			(type solid)
		)
		(fill yes)
		(layer "F.Cu")
		(net "GND")
	)
	(gr_poly
		(pts
			(arc
				(start 32.31134 -65.073276)
				(mid 31.98622 -65.073276)
				(end 32.31134 -65.073276)
			)
		)
		(stroke
			(width 0)
			(type solid)
		)
		(fill yes)
		(layer "F.Cu")
		(net "GND")
	)
	(gr_poly
		(pts
			(arc
				(start 33.0835 -72.92721)
				(mid 32.75838 -72.92721)
				(end 33.0835 -72.92721)
			)
		)
		(stroke
			(width 0)
			(type solid)
		)
		(fill yes)
		(layer "F.Cu")
		(net "GND")
	)
	(gr_poly
		(pts
			(arc
				(start 33.0962 -71.09206)
				(mid 32.77108 -71.09206)
				(end 33.0962 -71.09206)
			)
		)
		(stroke
			(width 0)
			(type solid)
		)
		(fill yes)
		(layer "F.Cu")
		(net "GND")
	)
	(gr_poly
		(pts
			(arc
				(start 33.2613 -68.370196)
				(mid 32.93618 -68.370196)
				(end 33.2613 -68.370196)
			)
		)
		(stroke
			(width 0)
			(type solid)
		)
		(fill yes)
		(layer "F.Cu")
		(net "GND")
	)
	(gr_poly
		(pts
			(arc
				(start 34.31286 -173.476412)
				(mid 33.98774 -173.476412)
				(end 34.31286 -173.476412)
			)
		)
		(stroke
			(width 0)
			(type solid)
		)
		(fill yes)
		(layer "F.Cu")
		(net "GND")
	)
	(gr_poly
		(pts
			(arc
				(start 38.395656 -97.233232)
				(mid 38.070536 -97.233232)
				(end 38.395656 -97.233232)
			)
		)
		(stroke
			(width 0)
			(type solid)
		)
		(fill yes)
		(layer "F.Cu")
		(net "GND")
	)
	(gr_poly
		(pts
			(arc
				(start 41.21912 -102.434644)
				(mid 40.894 -102.434644)
				(end 41.21912 -102.434644)
			)
		)
		(stroke
			(width 0)
			(type solid)
		)
		(fill yes)
		(layer "F.Cu")
		(net "GND")
	)
	(gr_poly
		(pts
			(arc
				(start 41.34358 -32.853376)
				(mid 41.01846 -32.853376)
				(end 41.34358 -32.853376)
			)
		)
		(stroke
			(width 0)
			(type solid)
		)
		(fill yes)
		(layer "F.Cu")
		(net "GND")
	)
	(gr_poly
		(pts
			(arc
				(start 42.822114 -96.659954)
				(mid 42.496994 -96.659954)
				(end 42.822114 -96.659954)
			)
		)
		(stroke
			(width 0)
			(type solid)
		)
		(fill yes)
		(layer "F.Cu")
		(net "GND")
	)
	(gr_poly
		(pts
			(arc
				(start 43.162982 -142.838932)
				(mid 42.837862 -142.838932)
				(end 43.162982 -142.838932)
			)
		)
		(stroke
			(width 0)
			(type solid)
		)
		(fill yes)
		(layer "F.Cu")
		(net "GND")
	)
	(gr_poly
		(pts
			(arc
				(start 44.48556 -97.379282)
				(mid 44.16044 -97.379282)
				(end 44.48556 -97.379282)
			)
		)
		(stroke
			(width 0)
			(type solid)
		)
		(fill yes)
		(layer "F.Cu")
		(net "GND")
	)
	(gr_poly
		(pts
			(arc
				(start 44.68622 -98.953828)
				(mid 44.3611 -98.953828)
				(end 44.68622 -98.953828)
			)
		)
		(stroke
			(width 0)
			(type solid)
		)
		(fill yes)
		(layer "F.Cu")
		(net "GND")
	)
	(gr_poly
		(pts
			(arc
				(start 45.1739 -24.804878)
				(mid 44.84878 -24.804878)
				(end 45.1739 -24.804878)
			)
		)
		(stroke
			(width 0)
			(type solid)
		)
		(fill yes)
		(layer "F.Cu")
		(net "GND")
	)
	(gr_poly
		(pts
			(arc
				(start 46.010068 -59.259978)
				(mid 45.689012 -59.259978)
				(end 46.010068 -59.259978)
			)
		)
		(stroke
			(width 0)
			(type solid)
		)
		(fill yes)
		(layer "F.Cu")
		(net "GND")
	)
	(gr_poly
		(pts
			(arc
				(start 46.94174 -24.184102)
				(mid 46.61662 -24.184102)
				(end 46.94174 -24.184102)
			)
		)
		(stroke
			(width 0)
			(type solid)
		)
		(fill yes)
		(layer "F.Cu")
		(net "GND")
	)
	(gr_poly
		(pts
			(arc
				(start 47.4218 -25.426162)
				(mid 47.09668 -25.426162)
				(end 47.4218 -25.426162)
			)
		)
		(stroke
			(width 0)
			(type solid)
		)
		(fill yes)
		(layer "F.Cu")
		(net "GND")
	)
	(gr_poly
		(pts
			(arc
				(start 48.128936 -59.128406)
				(mid 47.803816 -59.128406)
				(end 48.128936 -59.128406)
			)
		)
		(stroke
			(width 0)
			(type solid)
		)
		(fill yes)
		(layer "F.Cu")
		(net "GND")
	)
	(gr_poly
		(pts
			(arc
				(start 48.231298 -61.726064)
				(mid 47.906178 -61.726064)
				(end 48.231298 -61.726064)
			)
		)
		(stroke
			(width 0)
			(type solid)
		)
		(fill yes)
		(layer "F.Cu")
		(net "GND")
	)
	(gr_poly
		(pts
			(arc
				(start 49.567592 -178.936904)
				(mid 49.242472 -178.936904)
				(end 49.567592 -178.936904)
			)
		)
		(stroke
			(width 0)
			(type solid)
		)
		(fill yes)
		(layer "F.Cu")
		(net "GND")
	)
	(gr_poly
		(pts
			(arc
				(start 49.94656 -24.274272)
				(mid 49.62144 -24.274272)
				(end 49.94656 -24.274272)
			)
		)
		(stroke
			(width 0)
			(type solid)
		)
		(fill yes)
		(layer "F.Cu")
		(net "GND")
	)
	(gr_poly
		(pts
			(arc
				(start 49.9491 -31.797752)
				(mid 49.62398 -31.797752)
				(end 49.9491 -31.797752)
			)
		)
		(stroke
			(width 0)
			(type solid)
		)
		(fill yes)
		(layer "F.Cu")
		(net "GND")
	)
	(gr_poly
		(pts
			(arc
				(start 51.58486 -168.562782)
				(mid 51.25974 -168.562782)
				(end 51.58486 -168.562782)
			)
		)
		(stroke
			(width 0)
			(type solid)
		)
		(fill yes)
		(layer "F.Cu")
		(net "GND")
	)
	(gr_poly
		(pts
			(arc
				(start 52.7431 -153.027888)
				(mid 52.41798 -153.027888)
				(end 52.7431 -153.027888)
			)
		)
		(stroke
			(width 0)
			(type solid)
		)
		(fill yes)
		(layer "F.Cu")
		(net "GND")
	)
	(gr_poly
		(pts
			(arc
				(start 52.861464 -154.669744)
				(mid 52.536344 -154.669744)
				(end 52.861464 -154.669744)
			)
		)
		(stroke
			(width 0)
			(type solid)
		)
		(fill yes)
		(layer "F.Cu")
		(net "GND")
	)
	(gr_poly
		(pts
			(arc
				(start 53.9496 -155.17241)
				(mid 53.62448 -155.17241)
				(end 53.9496 -155.17241)
			)
		)
		(stroke
			(width 0)
			(type solid)
		)
		(fill yes)
		(layer "F.Cu")
		(net "GND")
	)
	(gr_poly
		(pts
			(arc
				(start 53.975508 -156.898086)
				(mid 53.650388 -156.898086)
				(end 53.975508 -156.898086)
			)
		)
		(stroke
			(width 0)
			(type solid)
		)
		(fill yes)
		(layer "F.Cu")
		(net "GND")
	)
	(gr_poly
		(pts
			(arc
				(start 55.757826 -150.645114)
				(mid 55.432706 -150.645114)
				(end 55.757826 -150.645114)
			)
		)
		(stroke
			(width 0)
			(type solid)
		)
		(fill yes)
		(layer "F.Cu")
		(net "GND")
	)
	(gr_poly
		(pts
			(arc
				(start 55.863744 -153.621994)
				(mid 55.538624 -153.621994)
				(end 55.863744 -153.621994)
			)
		)
		(stroke
			(width 0)
			(type solid)
		)
		(fill yes)
		(layer "F.Cu")
		(net "GND")
	)
	(gr_poly
		(pts
			(arc
				(start 60.99556 -25.63495)
				(mid 60.67044 -25.63495)
				(end 60.99556 -25.63495)
			)
		)
		(stroke
			(width 0)
			(type solid)
		)
		(fill yes)
		(layer "F.Cu")
		(net "GND")
	)
	(gr_poly
		(pts
			(arc
				(start 62.06998 -26.176478)
				(mid 61.74486 -26.176478)
				(end 62.06998 -26.176478)
			)
		)
		(stroke
			(width 0)
			(type solid)
		)
		(fill yes)
		(layer "F.Cu")
		(net "GND")
	)
	(gr_poly
		(pts
			(arc
				(start 67.2719 -24.616156)
				(mid 66.94678 -24.616156)
				(end 67.2719 -24.616156)
			)
		)
		(stroke
			(width 0)
			(type solid)
		)
		(fill yes)
		(layer "F.Cu")
		(net "GND")
	)
	(gr_poly
		(pts
			(arc
				(start 67.68338 -26.051764)
				(mid 67.35826 -26.051764)
				(end 67.68338 -26.051764)
			)
		)
		(stroke
			(width 0)
			(type solid)
		)
		(fill yes)
		(layer "F.Cu")
		(net "GND")
	)
	(gr_poly
		(pts
			(arc
				(start 71.0311 -26.641806)
				(mid 70.70598 -26.641806)
				(end 71.0311 -26.641806)
			)
		)
		(stroke
			(width 0)
			(type solid)
		)
		(fill yes)
		(layer "F.Cu")
		(net "GND")
	)
	(gr_poly
		(pts
			(arc
				(start 71.83628 -2.604262)
				(mid 71.51116 -2.604262)
				(end 71.83628 -2.604262)
			)
		)
		(stroke
			(width 0)
			(type solid)
		)
		(fill yes)
		(layer "F.Cu")
		(net "GND")
	)
	(gr_poly
		(pts
			(arc
				(start 72.382888 -120.099836)
				(mid 72.057768 -120.099836)
				(end 72.382888 -120.099836)
			)
		)
		(stroke
			(width 0)
			(type solid)
		)
		(fill yes)
		(layer "F.Cu")
		(net "GND")
	)
	(gr_poly
		(pts
			(arc
				(start 72.9869 -24.312118)
				(mid 72.66178 -24.312118)
				(end 72.9869 -24.312118)
			)
		)
		(stroke
			(width 0)
			(type solid)
		)
		(fill yes)
		(layer "F.Cu")
		(net "GND")
	)
	(gr_poly
		(pts
			(arc
				(start 74.159618 -118.569994)
				(mid 73.834498 -118.569994)
				(end 74.159618 -118.569994)
			)
		)
		(stroke
			(width 0)
			(type solid)
		)
		(fill yes)
		(layer "F.Cu")
		(net "GND")
	)
	(gr_poly
		(pts
			(arc
				(start 75.04176 -25.550622)
				(mid 74.71664 -25.550622)
				(end 75.04176 -25.550622)
			)
		)
		(stroke
			(width 0)
			(type solid)
		)
		(fill yes)
		(layer "F.Cu")
		(net "GND")
	)
	(gr_poly
		(pts
			(arc
				(start 75.21702 -24.691086)
				(mid 74.8919 -24.691086)
				(end 75.21702 -24.691086)
			)
		)
		(stroke
			(width 0)
			(type solid)
		)
		(fill yes)
		(layer "F.Cu")
		(net "GND")
	)
	(gr_poly
		(pts
			(arc
				(start 76.3905 -63.750698)
				(mid 76.069444 -63.750698)
				(end 76.3905 -63.750698)
			)
		)
		(stroke
			(width 0)
			(type solid)
		)
		(fill yes)
		(layer "F.Cu")
		(net "GND")
	)
	(gr_poly
		(pts
			(arc
				(start 76.96454 -24.18461)
				(mid 76.63942 -24.18461)
				(end 76.96454 -24.18461)
			)
		)
		(stroke
			(width 0)
			(type solid)
		)
		(fill yes)
		(layer "F.Cu")
		(net "GND")
	)
	(gr_poly
		(pts
			(arc
				(start 79.261208 -63.55842)
				(mid 78.940152 -63.55842)
				(end 79.261208 -63.55842)
			)
		)
		(stroke
			(width 0)
			(type solid)
		)
		(fill yes)
		(layer "F.Cu")
		(net "GND")
	)
	(gr_poly
		(pts
			(arc
				(start 80.12938 -23.584154)
				(mid 79.80426 -23.584154)
				(end 80.12938 -23.584154)
			)
		)
		(stroke
			(width 0)
			(type solid)
		)
		(fill yes)
		(layer "F.Cu")
		(net "GND")
	)
	(gr_poly
		(pts
			(arc
				(start 80.274668 -65.698624)
				(mid 79.953612 -65.698624)
				(end 80.274668 -65.698624)
			)
		)
		(stroke
			(width 0)
			(type solid)
		)
		(fill yes)
		(layer "F.Cu")
		(net "GND")
	)
	(gr_poly
		(pts
			(arc
				(start 82.20456 -23.961598)
				(mid 81.87944 -23.961598)
				(end 82.20456 -23.961598)
			)
		)
		(stroke
			(width 0)
			(type solid)
		)
		(fill yes)
		(layer "F.Cu")
		(net "GND")
	)
	(gr_poly
		(pts
			(arc
				(start 83.46186 -25.668478)
				(mid 83.13674 -25.668478)
				(end 83.46186 -25.668478)
			)
		)
		(stroke
			(width 0)
			(type solid)
		)
		(fill yes)
		(layer "F.Cu")
		(net "GND")
	)
	(gr_poly
		(pts
			(arc
				(start 87.73414 -25.836372)
				(mid 87.40902 -25.836372)
				(end 87.73414 -25.836372)
			)
		)
		(stroke
			(width 0)
			(type solid)
		)
		(fill yes)
		(layer "F.Cu")
		(net "GND")
	)
	(gr_poly
		(pts
			(xy 89.08288 -143.083788) (xy 89.08288 -139.53744) (xy 88.38692 -138.84148) (xy 85.997288 -138.84148)
			(xy 85.489288 -139.34948) (xy 85.489288 -140.351256) (xy 85.36813 -140.472414) (xy 81.96072 -140.472414)
			(xy 81.952592 -140.480542) (xy 81.90738 -140.480542) (xy 81.834228 -140.553948) (xy 81.834228 -141.689582)
			(xy 81.8134 -141.710156) (xy 81.8134 -142.10411) (xy 81.847944 -142.138908) (xy 82.59572 -142.138908)
			(xy 82.629502 -142.105126) (xy 84.574126 -142.105126) (xy 84.6201 -142.1511) (xy 84.671154 -142.1511)
			(xy 84.68106 -142.161006) (xy 84.97443 -142.161006) (xy 84.97824 -142.157196) (xy 85.29574 -142.157196)
			(xy 85.513926 -142.375382) (xy 85.53196 -142.375382) (xy 85.53196 -143.018256) (xy 85.7123 -143.198596)
			(xy 88.968072 -143.198596)
		)
		(stroke
			(width 0)
			(type solid)
		)
		(fill yes)
		(layer "F.Cu")
		(net "GND")
	)
	(gr_poly
		(pts
			(arc
				(start 89.517982 -26.772616)
				(mid 89.192862 -26.772616)
				(end 89.517982 -26.772616)
			)
		)
		(stroke
			(width 0)
			(type solid)
		)
		(fill yes)
		(layer "F.Cu")
		(net "GND")
	)
	(gr_poly
		(pts
			(arc
				(start 92.18676 -25.063196)
				(mid 91.86164 -25.063196)
				(end 92.18676 -25.063196)
			)
		)
		(stroke
			(width 0)
			(type solid)
		)
		(fill yes)
		(layer "F.Cu")
		(net "GND")
	)
	(gr_poly
		(pts
			(arc
				(start 93.95968 -105.5624)
				(mid 93.63456 -105.5624)
				(end 93.95968 -105.5624)
			)
		)
		(stroke
			(width 0)
			(type solid)
		)
		(fill yes)
		(layer "F.Cu")
		(net "GND")
	)
	(gr_poly
		(pts
			(arc
				(start 94.80804 -24.98217)
				(mid 94.48292 -24.98217)
				(end 94.80804 -24.98217)
			)
		)
		(stroke
			(width 0)
			(type solid)
		)
		(fill yes)
		(layer "F.Cu")
		(net "GND")
	)
	(gr_poly
		(pts
			(arc
				(start 95.12046 -126.13259)
				(mid 94.79534 -126.13259)
				(end 95.12046 -126.13259)
			)
		)
		(stroke
			(width 0)
			(type solid)
		)
		(fill yes)
		(layer "F.Cu")
		(net "GND")
	)
	(gr_poly
		(pts
			(arc
				(start 95.3008 -104.754934)
				(mid 94.97568 -104.754934)
				(end 95.3008 -104.754934)
			)
		)
		(stroke
			(width 0)
			(type solid)
		)
		(fill yes)
		(layer "F.Cu")
		(net "GND")
	)
	(gr_poly
		(pts
			(arc
				(start 95.70466 -109.32287)
				(mid 95.37954 -109.32287)
				(end 95.70466 -109.32287)
			)
		)
		(stroke
			(width 0)
			(type solid)
		)
		(fill yes)
		(layer "F.Cu")
		(net "GND")
	)
	(gr_poly
		(pts
			(arc
				(start 96.4692 -26.142442)
				(mid 96.14408 -26.142442)
				(end 96.4692 -26.142442)
			)
		)
		(stroke
			(width 0)
			(type solid)
		)
		(fill yes)
		(layer "F.Cu")
		(net "GND")
	)
	(gr_poly
		(pts
			(arc
				(start 97.72142 -25.080722)
				(mid 97.3963 -25.080722)
				(end 97.72142 -25.080722)
			)
		)
		(stroke
			(width 0)
			(type solid)
		)
		(fill yes)
		(layer "F.Cu")
		(net "GND")
	)
	(gr_poly
		(pts
			(arc
				(start 98.995738 -124.992638)
				(mid 98.670618 -124.992638)
				(end 98.995738 -124.992638)
			)
		)
		(stroke
			(width 0)
			(type solid)
		)
		(fill yes)
		(layer "F.Cu")
		(net "GND")
	)
	(gr_poly
		(pts
			(arc
				(start 99.70008 -33.449768)
				(mid 99.37496 -33.449768)
				(end 99.70008 -33.449768)
			)
		)
		(stroke
			(width 0)
			(type solid)
		)
		(fill yes)
		(layer "F.Cu")
		(net "GND")
	)
	(gr_poly
		(pts
			(arc
				(start 99.73056 -65.59931)
				(mid 99.40544 -65.59931)
				(end 99.73056 -65.59931)
			)
		)
		(stroke
			(width 0)
			(type solid)
		)
		(fill yes)
		(layer "F.Cu")
		(net "GND")
	)
	(gr_poly
		(pts
			(arc
				(start 99.89566 -69.224906)
				(mid 99.57054 -69.224906)
				(end 99.89566 -69.224906)
			)
		)
		(stroke
			(width 0)
			(type solid)
		)
		(fill yes)
		(layer "F.Cu")
		(net "GND")
	)
	(gr_poly
		(pts
			(arc
				(start 100.76434 -72.11822)
				(mid 100.43922 -72.11822)
				(end 100.76434 -72.11822)
			)
		)
		(stroke
			(width 0)
			(type solid)
		)
		(fill yes)
		(layer "F.Cu")
		(net "GND")
	)
	(gr_poly
		(pts
			(arc
				(start 101.46284 -24.339042)
				(mid 101.13772 -24.339042)
				(end 101.46284 -24.339042)
			)
		)
		(stroke
			(width 0)
			(type solid)
		)
		(fill yes)
		(layer "F.Cu")
		(net "GND")
	)
	(gr_poly
		(pts
			(arc
				(start 101.54666 -33.470342)
				(mid 101.22154 -33.470342)
				(end 101.54666 -33.470342)
			)
		)
		(stroke
			(width 0)
			(type solid)
		)
		(fill yes)
		(layer "F.Cu")
		(net "GND")
	)
	(gr_poly
		(pts
			(arc
				(start 101.58222 -65.34023)
				(mid 101.2571 -65.34023)
				(end 101.58222 -65.34023)
			)
		)
		(stroke
			(width 0)
			(type solid)
		)
		(fill yes)
		(layer "F.Cu")
		(net "GND")
	)
	(gr_poly
		(pts
			(arc
				(start 101.72446 -63.422784)
				(mid 101.39934 -63.422784)
				(end 101.72446 -63.422784)
			)
		)
		(stroke
			(width 0)
			(type solid)
		)
		(fill yes)
		(layer "F.Cu")
		(net "GND")
	)
	(gr_poly
		(pts
			(arc
				(start 101.830378 -173.743366)
				(mid 101.505258 -173.743366)
				(end 101.830378 -173.743366)
			)
		)
		(stroke
			(width 0)
			(type solid)
		)
		(fill yes)
		(layer "F.Cu")
		(net "GND")
	)
	(gr_poly
		(pts
			(arc
				(start 102.00386 -74.45883)
				(mid 101.67874 -74.45883)
				(end 102.00386 -74.45883)
			)
		)
		(stroke
			(width 0)
			(type solid)
		)
		(fill yes)
		(layer "F.Cu")
		(net "GND")
	)
	(gr_poly
		(pts
			(arc
				(start 102.18674 -23.826978)
				(mid 101.86162 -23.826978)
				(end 102.18674 -23.826978)
			)
		)
		(stroke
			(width 0)
			(type solid)
		)
		(fill yes)
		(layer "F.Cu")
		(net "GND")
	)
	(gr_poly
		(pts
			(arc
				(start 104.0638 -23.39213)
				(mid 103.73868 -23.39213)
				(end 104.0638 -23.39213)
			)
		)
		(stroke
			(width 0)
			(type solid)
		)
		(fill yes)
		(layer "F.Cu")
		(net "GND")
	)
	(gr_poly
		(pts
			(arc
				(start 105.784396 -176.091088)
				(mid 105.459276 -176.091088)
				(end 105.784396 -176.091088)
			)
		)
		(stroke
			(width 0)
			(type solid)
		)
		(fill yes)
		(layer "F.Cu")
		(net "GND")
	)
	(gr_poly
		(pts
			(arc
				(start 106.327956 -168.515284)
				(mid 106.002836 -168.515284)
				(end 106.327956 -168.515284)
			)
		)
		(stroke
			(width 0)
			(type solid)
		)
		(fill yes)
		(layer "F.Cu")
		(net "GND")
	)
	(gr_poly
		(pts
			(arc
				(start 107.41914 -63.672466)
				(mid 107.09402 -63.672466)
				(end 107.41914 -63.672466)
			)
		)
		(stroke
			(width 0)
			(type solid)
		)
		(fill yes)
		(layer "F.Cu")
		(net "GND")
	)
	(gr_poly
		(pts
			(arc
				(start 107.5309 -62.0522)
				(mid 107.20578 -62.0522)
				(end 107.5309 -62.0522)
			)
		)
		(stroke
			(width 0)
			(type solid)
		)
		(fill yes)
		(layer "F.Cu")
		(net "GND")
	)
	(gr_poly
		(pts
			(arc
				(start 110.366048 -163.860226)
				(mid 110.040928 -163.860226)
				(end 110.366048 -163.860226)
			)
		)
		(stroke
			(width 0)
			(type solid)
		)
		(fill yes)
		(layer "F.Cu")
		(net "GND")
	)
	(gr_poly
		(pts
			(arc
				(start 113.040922 -169.154602)
				(mid 112.715802 -169.154602)
				(end 113.040922 -169.154602)
			)
		)
		(stroke
			(width 0)
			(type solid)
		)
		(fill yes)
		(layer "F.Cu")
		(net "GND")
	)
	(gr_poly
		(pts
			(arc
				(start 113.934748 -67.382644)
				(mid 113.609628 -67.382644)
				(end 113.934748 -67.382644)
			)
		)
		(stroke
			(width 0)
			(type solid)
		)
		(fill yes)
		(layer "F.Cu")
		(net "GND")
	)
	(gr_poly
		(pts
			(arc
				(start 114.287808 -70.160134)
				(mid 113.962688 -70.160134)
				(end 114.287808 -70.160134)
			)
		)
		(stroke
			(width 0)
			(type solid)
		)
		(fill yes)
		(layer "F.Cu")
		(net "GND")
	)
	(gr_poly
		(pts
			(arc
				(start 115.428268 -74.27087)
				(mid 115.103148 -74.27087)
				(end 115.428268 -74.27087)
			)
		)
		(stroke
			(width 0)
			(type solid)
		)
		(fill yes)
		(layer "F.Cu")
		(net "GND")
	)
	(gr_poly
		(pts
			(arc
				(start 116.65966 -169.301922)
				(mid 116.33454 -169.301922)
				(end 116.65966 -169.301922)
			)
		)
		(stroke
			(width 0)
			(type solid)
		)
		(fill yes)
		(layer "F.Cu")
		(net "GND")
	)
	(gr_poly
		(pts
			(arc
				(start 118.539006 -171.533058)
				(mid 118.213886 -171.533058)
				(end 118.539006 -171.533058)
			)
		)
		(stroke
			(width 0)
			(type solid)
		)
		(fill yes)
		(layer "F.Cu")
		(net "GND")
	)
	(gr_poly
		(pts
			(xy 119.05742 -127.441706) (xy 119.05742 -124.3457) (xy 118.892574 -124.180854) (xy 118.171722 -124.180854)
			(xy 118.171468 -124.1806) (xy 115.619276 -124.1806) (xy 114.945668 -124.1806) (xy 114.873278 -124.10821)
			(xy 114.20983 -124.10821) (xy 111.373412 -124.10821) (xy 111.186214 -123.921012)
			(arc
				(start 111.186214 -123.220734)
				(mid 111.149017 -123.130931)
				(end 111.059214 -123.093734)
			)
			(xy 110.493556 -123.093734) (xy 110.431326 -123.155964) (xy 110.431326 -127.219202) (xy 110.585758 -127.37338)
			(xy 111.152178 -127.37338) (xy 111.238284 -127.459486) (xy 112.64773 -127.459486) (xy 115.619276 -127.459486)
			(xy 117.937534 -127.459486) (xy 119.03964 -127.459486)
		)
		(stroke
			(width 0)
			(type solid)
		)
		(fill yes)
		(layer "F.Cu")
		(net "SW_VR_PVCCP_NODE1_VIN_FLT")
	)
	(gr_poly
		(pts
			(arc
				(start 119.0879 -101.98227)
				(mid 118.76278 -101.98227)
				(end 119.0879 -101.98227)
			)
		)
		(stroke
			(width 0)
			(type solid)
		)
		(fill yes)
		(layer "F.Cu")
		(net "GND")
	)
	(gr_poly
		(pts
			(arc
				(start 120.59158 -140.629386)
				(mid 120.26646 -140.629386)
				(end 120.59158 -140.629386)
			)
		)
		(stroke
			(width 0)
			(type solid)
		)
		(fill yes)
		(layer "F.Cu")
		(net "GND")
	)
	(gr_poly
		(pts
			(arc
				(start 120.63222 -143.14551)
				(mid 120.3071 -143.14551)
				(end 120.63222 -143.14551)
			)
		)
		(stroke
			(width 0)
			(type solid)
		)
		(fill yes)
		(layer "F.Cu")
		(net "GND")
	)
	(gr_poly
		(pts
			(arc
				(start 121.80443 -167.494204)
				(mid 121.47931 -167.494204)
				(end 121.80443 -167.494204)
			)
		)
		(stroke
			(width 0)
			(type solid)
		)
		(fill yes)
		(layer "F.Cu")
		(net "GND")
	)
	(gr_poly
		(pts
			(arc
				(start 121.918222 -169.841164)
				(mid 121.593102 -169.841164)
				(end 121.918222 -169.841164)
			)
		)
		(stroke
			(width 0)
			(type solid)
		)
		(fill yes)
		(layer "F.Cu")
		(net "GND")
	)
	(gr_poly
		(pts
			(arc
				(start 121.97461 -118.769638)
				(mid 121.64949 -118.769638)
				(end 121.97461 -118.769638)
			)
		)
		(stroke
			(width 0)
			(type solid)
		)
		(fill yes)
		(layer "F.Cu")
		(net "GND")
	)
	(gr_poly
		(pts
			(arc
				(start 122.020076 -117.598952)
				(mid 121.694956 -117.598952)
				(end 122.020076 -117.598952)
			)
		)
		(stroke
			(width 0)
			(type solid)
		)
		(fill yes)
		(layer "F.Cu")
		(net "GND")
	)
	(gr_poly
		(pts
			(arc
				(start 122.09526 -106.567224)
				(mid 121.77014 -106.567224)
				(end 122.09526 -106.567224)
			)
		)
		(stroke
			(width 0)
			(type solid)
		)
		(fill yes)
		(layer "F.Cu")
		(net "GND")
	)
	(gr_poly
		(pts
			(arc
				(start 122.43308 -140.51534)
				(mid 122.10796 -140.51534)
				(end 122.43308 -140.51534)
			)
		)
		(stroke
			(width 0)
			(type solid)
		)
		(fill yes)
		(layer "F.Cu")
		(net "GND")
	)
	(gr_poly
		(pts
			(arc
				(start 122.4407 -145.685002)
				(mid 122.11558 -145.685002)
				(end 122.4407 -145.685002)
			)
		)
		(stroke
			(width 0)
			(type solid)
		)
		(fill yes)
		(layer "F.Cu")
		(net "GND")
	)
	(gr_poly
		(pts
			(arc
				(start 123.007374 -121.825512)
				(mid 122.682254 -121.825512)
				(end 123.007374 -121.825512)
			)
		)
		(stroke
			(width 0)
			(type solid)
		)
		(fill yes)
		(layer "F.Cu")
		(net "GND")
	)
	(gr_poly
		(pts
			(arc
				(start 123.01855 -120.274588)
				(mid 122.69343 -120.274588)
				(end 123.01855 -120.274588)
			)
		)
		(stroke
			(width 0)
			(type solid)
		)
		(fill yes)
		(layer "F.Cu")
		(net "GND")
	)
	(gr_poly
		(pts
			(arc
				(start 123.57862 -150.003002)
				(mid 123.2535 -150.003002)
				(end 123.57862 -150.003002)
			)
		)
		(stroke
			(width 0)
			(type solid)
		)
		(fill yes)
		(layer "F.Cu")
		(net "GND")
	)
	(gr_poly
		(pts
			(arc
				(start 123.76912 -138.096498)
				(mid 123.444 -138.096498)
				(end 123.76912 -138.096498)
			)
		)
		(stroke
			(width 0)
			(type solid)
		)
		(fill yes)
		(layer "F.Cu")
		(net "GND")
	)
	(gr_poly
		(pts
			(arc
				(start 123.77674 -108.253784)
				(mid 123.45162 -108.253784)
				(end 123.77674 -108.253784)
			)
		)
		(stroke
			(width 0)
			(type solid)
		)
		(fill yes)
		(layer "F.Cu")
		(net "GND")
	)
	(gr_poly
		(pts
			(arc
				(start 123.78944 -143.18742)
				(mid 123.46432 -143.18742)
				(end 123.78944 -143.18742)
			)
		)
		(stroke
			(width 0)
			(type solid)
		)
		(fill yes)
		(layer "F.Cu")
		(net "GND")
	)
	(gr_poly
		(pts
			(arc
				(start 124.46508 -150.073106)
				(mid 124.13996 -150.073106)
				(end 124.46508 -150.073106)
			)
		)
		(stroke
			(width 0)
			(type solid)
		)
		(fill yes)
		(layer "F.Cu")
		(net "GND")
	)
	(gr_poly
		(pts
			(arc
				(start 125.92812 -97.983548)
				(mid 125.603 -97.983548)
				(end 125.92812 -97.983548)
			)
		)
		(stroke
			(width 0)
			(type solid)
		)
		(fill yes)
		(layer "F.Cu")
		(net "GND")
	)
	(gr_poly
		(pts
			(arc
				(start 128.406398 -99.182174)
				(mid 128.081278 -99.182174)
				(end 128.406398 -99.182174)
			)
		)
		(stroke
			(width 0)
			(type solid)
		)
		(fill yes)
		(layer "F.Cu")
		(net "GND")
	)
	(gr_poly
		(pts
			(xy 128.440942 -109.701076) (xy 128.440942 -109.089952) (xy 127.562356 -108.211366) (xy 127.331978 -108.211366)
			(xy 127.070104 -107.949492) (xy 127.070104 -106.600752) (xy 127.18796 -106.482896) (xy 127.945134 -106.482896)
			(arc
				(start 127.957326 -106.48061)
				(mid 128.14427 -106.462338)
				(end 128.331214 -106.48061)
			)
			(xy 128.343406 -106.482896) (xy 129.06375 -106.482896) (xy 129.58699 -107.006136) (xy 129.58699 -107.504992)
			(xy 130.199892 -108.117894) (xy 132.085842 -108.117894) (xy 132.443982 -107.759754) (xy 132.443982 -105.363518)
			(xy 132.451094 -105.356406) (xy 131.913884 -104.819196) (xy 126.299214 -104.819196) (xy 126.00559 -105.11282)
			(xy 126.00559 -109.384338) (xy 126.44247 -109.821218) (xy 128.3208 -109.821218)
		)
		(stroke
			(width 0)
			(type solid)
		)
		(fill yes)
		(layer "F.Cu")
		(net "GND")
	)
	(gr_poly
		(pts
			(arc
				(start 128.62052 -125.95352)
				(mid 128.2954 -125.95352)
				(end 128.62052 -125.95352)
			)
		)
		(stroke
			(width 0)
			(type solid)
		)
		(fill yes)
		(layer "F.Cu")
		(net "GND")
	)
	(gr_poly
		(pts
			(arc
				(start 130.08864 -126.04877)
				(mid 129.76352 -126.04877)
				(end 130.08864 -126.04877)
			)
		)
		(stroke
			(width 0)
			(type solid)
		)
		(fill yes)
		(layer "F.Cu")
		(net "GND")
	)
	(gr_poly
		(pts
			(arc
				(start 130.0988 -130.503168)
				(mid 129.77368 -130.503168)
				(end 130.0988 -130.503168)
			)
		)
		(stroke
			(width 0)
			(type solid)
		)
		(fill yes)
		(layer "F.Cu")
		(net "GND")
	)
	(gr_poly
		(pts
			(arc
				(start 132.11302 -126.14783)
				(mid 131.7879 -126.14783)
				(end 132.11302 -126.14783)
			)
		)
		(stroke
			(width 0)
			(type solid)
		)
		(fill yes)
		(layer "F.Cu")
		(net "GND")
	)
	(gr_poly
		(pts
			(arc
				(start 132.81406 -130.477768)
				(mid 132.48894 -130.477768)
				(end 132.81406 -130.477768)
			)
		)
		(stroke
			(width 0)
			(type solid)
		)
		(fill yes)
		(layer "F.Cu")
		(net "GND")
	)
	(gr_poly
		(pts
			(arc
				(start 133.242812 -134.29615)
				(mid 132.917692 -134.29615)
				(end 133.242812 -134.29615)
			)
		)
		(stroke
			(width 0)
			(type solid)
		)
		(fill yes)
		(layer "F.Cu")
		(net "GND")
	)
	(gr_poly
		(pts
			(arc
				(start 133.689852 -126.167896)
				(mid 133.364732 -126.167896)
				(end 133.689852 -126.167896)
			)
		)
		(stroke
			(width 0)
			(type solid)
		)
		(fill yes)
		(layer "F.Cu")
		(net "GND")
	)
	(gr_poly
		(pts
			(arc
				(start 134.7597 -106.547412)
				(mid 134.43458 -106.547412)
				(end 134.7597 -106.547412)
			)
		)
		(stroke
			(width 0)
			(type solid)
		)
		(fill yes)
		(layer "F.Cu")
		(net "GND")
	)
	(gr_poly
		(pts
			(arc
				(start 135.527796 -124.811536)
				(mid 135.202676 -124.811536)
				(end 135.527796 -124.811536)
			)
		)
		(stroke
			(width 0)
			(type solid)
		)
		(fill yes)
		(layer "F.Cu")
		(net "GND")
	)
	(gr_poly
		(pts
			(arc
				(start 135.70712 -120.358408)
				(mid 135.796923 -120.321211)
				(end 135.83412 -120.231408)
			)
			(arc
				(start 135.83412 -114.775742)
				(mid 135.796923 -114.685939)
				(end 135.70712 -114.648742)
			)
			(xy 131.435348 -114.648742) (xy 130.268472 -114.648742) (xy 130.05943 -114.857784) (xy 130.05943 -115.183412)
			(xy 130.05943 -115.183666)
			(arc
				(start 130.05943 -120.231408)
				(mid 130.096627 -120.321211)
				(end 130.18643 -120.358408)
			)
		)
		(stroke
			(width 0)
			(type solid)
		)
		(fill yes)
		(layer "F.Cu")
		(net "GND")
	)
	(gr_poly
		(pts
			(arc
				(start 137.174986 -124.741178)
				(mid 136.849866 -124.741178)
				(end 137.174986 -124.741178)
			)
		)
		(stroke
			(width 0)
			(type solid)
		)
		(fill yes)
		(layer "F.Cu")
		(net "GND")
	)
	(gr_poly
		(pts
			(arc
				(start 138.181334 -113.900712)
				(mid 137.856214 -113.900712)
				(end 138.181334 -113.900712)
			)
		)
		(stroke
			(width 0)
			(type solid)
		)
		(fill yes)
		(layer "F.Cu")
		(net "GND")
	)
	(gr_poly
		(pts
			(arc
				(start 139.32408 -130.998722)
				(mid 138.99896 -130.998722)
				(end 139.32408 -130.998722)
			)
		)
		(stroke
			(width 0)
			(type solid)
		)
		(fill yes)
		(layer "F.Cu")
		(net "GND")
	)
	(gr_poly
		(pts
			(arc
				(start 139.35456 -129.411222)
				(mid 139.02944 -129.411222)
				(end 139.35456 -129.411222)
			)
		)
		(stroke
			(width 0)
			(type solid)
		)
		(fill yes)
		(layer "F.Cu")
		(net "GND")
	)
	(gr_poly
		(pts
			(arc
				(start 141.312138 -98.843084)
				(mid 140.987018 -98.843084)
				(end 141.312138 -98.843084)
			)
		)
		(stroke
			(width 0)
			(type solid)
		)
		(fill yes)
		(layer "F.Cu")
		(net "GND")
	)
	(gr_poly
		(pts
			(arc
				(start 142.6464 -129.578354)
				(mid 142.32128 -129.578354)
				(end 142.6464 -129.578354)
			)
		)
		(stroke
			(width 0)
			(type solid)
		)
		(fill yes)
		(layer "F.Cu")
		(net "GND")
	)
	(gr_poly
		(pts
			(arc
				(start 142.8115 -127.98679)
				(mid 142.48638 -127.98679)
				(end 142.8115 -127.98679)
			)
		)
		(stroke
			(width 0)
			(type solid)
		)
		(fill yes)
		(layer "F.Cu")
		(net "GND")
	)
	(gr_poly
		(pts
			(arc
				(start 144.26184 -105.432352)
				(mid 143.93672 -105.432352)
				(end 144.26184 -105.432352)
			)
		)
		(stroke
			(width 0)
			(type solid)
		)
		(fill yes)
		(layer "F.Cu")
		(net "GND")
	)
	(gr_poly
		(pts
			(arc
				(start 145.40738 -129.390394)
				(mid 145.08226 -129.390394)
				(end 145.40738 -129.390394)
			)
		)
		(stroke
			(width 0)
			(type solid)
		)
		(fill yes)
		(layer "F.Cu")
		(net "GND")
	)
	(gr_poly
		(pts
			(arc
				(start 146.35226 -117.801136)
				(mid 146.02714 -117.801136)
				(end 146.35226 -117.801136)
			)
		)
		(stroke
			(width 0)
			(type solid)
		)
		(fill yes)
		(layer "F.Cu")
		(net "GND")
	)
	(gr_poly
		(pts
			(arc
				(start 146.37766 -119.378984)
				(mid 146.05254 -119.378984)
				(end 146.37766 -119.378984)
			)
		)
		(stroke
			(width 0)
			(type solid)
		)
		(fill yes)
		(layer "F.Cu")
		(net "GND")
	)
	(gr_poly
		(pts
			(arc
				(start 147.38096 -129.255012)
				(mid 147.05584 -129.255012)
				(end 147.38096 -129.255012)
			)
		)
		(stroke
			(width 0)
			(type solid)
		)
		(fill yes)
		(layer "F.Cu")
		(net "GND")
	)
	(gr_poly
		(pts
			(arc
				(start 148.900896 -78.455774)
				(mid 148.575776 -78.455774)
				(end 148.900896 -78.455774)
			)
		)
		(stroke
			(width 0)
			(type solid)
		)
		(fill yes)
		(layer "F.Cu")
		(net "GND")
	)
	(gr_poly
		(pts
			(arc
				(start 149.777704 -139.40155)
				(mid 149.452584 -139.40155)
				(end 149.777704 -139.40155)
			)
		)
		(stroke
			(width 0)
			(type solid)
		)
		(fill yes)
		(layer "F.Cu")
		(net "GND")
	)
	(gr_poly
		(pts
			(arc
				(start 150.175214 -157.148784)
				(mid 149.850094 -157.148784)
				(end 150.175214 -157.148784)
			)
		)
		(stroke
			(width 0)
			(type solid)
		)
		(fill yes)
		(layer "F.Cu")
		(net "GND")
	)
	(gr_poly
		(pts
			(arc
				(start 150.224998 -154.446478)
				(mid 149.899878 -154.446478)
				(end 150.224998 -154.446478)
			)
		)
		(stroke
			(width 0)
			(type solid)
		)
		(fill yes)
		(layer "F.Cu")
		(net "GND")
	)
	(gr_poly
		(pts
			(arc
				(start 150.250652 -151.678132)
				(mid 149.925532 -151.678132)
				(end 150.250652 -151.678132)
			)
		)
		(stroke
			(width 0)
			(type solid)
		)
		(fill yes)
		(layer "F.Cu")
		(net "GND")
	)
	(gr_poly
		(pts
			(arc
				(start 150.282402 -152.497536)
				(mid 149.957282 -152.497536)
				(end 150.282402 -152.497536)
			)
		)
		(stroke
			(width 0)
			(type solid)
		)
		(fill yes)
		(layer "F.Cu")
		(net "GND")
	)
	(gr_poly
		(pts
			(arc
				(start 152.965912 -168.858692)
				(mid 152.640792 -168.858692)
				(end 152.965912 -168.858692)
			)
		)
		(stroke
			(width 0)
			(type solid)
		)
		(fill yes)
		(layer "F.Cu")
		(net "GND")
	)
	(gr_poly
		(pts
			(arc
				(start 153.924508 -154.790902)
				(mid 153.599388 -154.790902)
				(end 153.924508 -154.790902)
			)
		)
		(stroke
			(width 0)
			(type solid)
		)
		(fill yes)
		(layer "F.Cu")
		(net "GND")
	)
	(gr_poly
		(pts
			(arc
				(start 153.978102 -100.05568)
				(mid 153.652982 -100.05568)
				(end 153.978102 -100.05568)
			)
		)
		(stroke
			(width 0)
			(type solid)
		)
		(fill yes)
		(layer "F.Cu")
		(net "GND")
	)
	(gr_poly
		(pts
			(arc
				(start 154.022044 -98.510598)
				(mid 153.696924 -98.510598)
				(end 154.022044 -98.510598)
			)
		)
		(stroke
			(width 0)
			(type solid)
		)
		(fill yes)
		(layer "F.Cu")
		(net "GND")
	)
	(gr_poly
		(pts
			(arc
				(start 154.360118 -143.99641)
				(mid 154.034998 -143.99641)
				(end 154.360118 -143.99641)
			)
		)
		(stroke
			(width 0)
			(type solid)
		)
		(fill yes)
		(layer "F.Cu")
		(net "GND")
	)
	(gr_poly
		(pts
			(arc
				(start 154.803094 -102.47503)
				(mid 154.477974 -102.47503)
				(end 154.803094 -102.47503)
			)
		)
		(stroke
			(width 0)
			(type solid)
		)
		(fill yes)
		(layer "F.Cu")
		(net "GND")
	)
	(gr_poly
		(pts
			(arc
				(start 154.815286 -100.827586)
				(mid 154.490166 -100.827586)
				(end 154.815286 -100.827586)
			)
		)
		(stroke
			(width 0)
			(type solid)
		)
		(fill yes)
		(layer "F.Cu")
		(net "GND")
	)
	(gr_poly
		(pts
			(arc
				(start 154.891232 -140.932154)
				(mid 154.566112 -140.932154)
				(end 154.891232 -140.932154)
			)
		)
		(stroke
			(width 0)
			(type solid)
		)
		(fill yes)
		(layer "F.Cu")
		(net "GND")
	)
	(gr_poly
		(pts
			(arc
				(start 155.418536 -180.29682)
				(mid 155.093416 -180.29682)
				(end 155.418536 -180.29682)
			)
		)
		(stroke
			(width 0)
			(type solid)
		)
		(fill yes)
		(layer "F.Cu")
		(net "GND")
	)
	(gr_poly
		(pts
			(arc
				(start 156.904182 -180.128418)
				(mid 156.579062 -180.128418)
				(end 156.904182 -180.128418)
			)
		)
		(stroke
			(width 0)
			(type solid)
		)
		(fill yes)
		(layer "F.Cu")
		(net "GND")
	)
	(gr_poly
		(pts
			(arc
				(start 157.961076 -181.302152)
				(mid 157.635956 -181.302152)
				(end 157.961076 -181.302152)
			)
		)
		(stroke
			(width 0)
			(type solid)
		)
		(fill yes)
		(layer "F.Cu")
		(net "GND")
	)
	(gr_poly
		(pts
			(arc
				(start 158.748984 -44.730924)
				(mid 158.423864 -44.730924)
				(end 158.748984 -44.730924)
			)
		)
		(stroke
			(width 0)
			(type solid)
		)
		(fill yes)
		(layer "F.Cu")
		(net "GND")
	)
	(gr_poly
		(pts
			(arc
				(start 158.898336 -48.21555)
				(mid 158.573216 -48.21555)
				(end 158.898336 -48.21555)
			)
		)
		(stroke
			(width 0)
			(type solid)
		)
		(fill yes)
		(layer "F.Cu")
		(net "GND")
	)
	(gr_poly
		(pts
			(arc
				(start 160.812734 -48.970438)
				(mid 160.487614 -48.970438)
				(end 160.812734 -48.970438)
			)
		)
		(stroke
			(width 0)
			(type solid)
		)
		(fill yes)
		(layer "F.Cu")
		(net "GND")
	)
	(gr_poly
		(pts
			(arc
				(start 160.813242 -51.331622)
				(mid 160.488122 -51.331622)
				(end 160.813242 -51.331622)
			)
		)
		(stroke
			(width 0)
			(type solid)
		)
		(fill yes)
		(layer "F.Cu")
		(net "GND")
	)
	(gr_poly
		(pts
			(arc
				(start 161.112962 -104.396286)
				(mid 160.787842 -104.396286)
				(end 161.112962 -104.396286)
			)
		)
		(stroke
			(width 0)
			(type solid)
		)
		(fill yes)
		(layer "F.Cu")
		(net "GND")
	)
	(gr_poly
		(pts
			(arc
				(start 163.09848 -109.293406)
				(mid 162.77336 -109.293406)
				(end 163.09848 -109.293406)
			)
		)
		(stroke
			(width 0)
			(type solid)
		)
		(fill yes)
		(layer "F.Cu")
		(net "GND")
	)
	(gr_poly
		(pts
			(arc
				(start 165.282626 -109.293406)
				(mid 164.957506 -109.293406)
				(end 165.282626 -109.293406)
			)
		)
		(stroke
			(width 0)
			(type solid)
		)
		(fill yes)
		(layer "F.Cu")
		(net "GND")
	)
	(gr_poly
		(pts
			(arc
				(start 166.791894 -108.677456)
				(mid 166.466774 -108.677456)
				(end 166.791894 -108.677456)
			)
		)
		(stroke
			(width 0)
			(type solid)
		)
		(fill yes)
		(layer "F.Cu")
		(net "GND")
	)
	(gr_poly
		(pts
			(arc
				(start 167.442388 -56.543956)
				(mid 167.117268 -56.543956)
				(end 167.442388 -56.543956)
			)
		)
		(stroke
			(width 0)
			(type solid)
		)
		(fill yes)
		(layer "F.Cu")
		(net "GND")
	)
	(gr_poly
		(pts
			(arc
				(start 167.447214 -58.36158)
				(mid 167.122094 -58.36158)
				(end 167.447214 -58.36158)
			)
		)
		(stroke
			(width 0)
			(type solid)
		)
		(fill yes)
		(layer "F.Cu")
		(net "GND")
	)
	(gr_poly
		(pts
			(arc
				(start 167.489378 -38.357302)
				(mid 167.164258 -38.357302)
				(end 167.489378 -38.357302)
			)
		)
		(stroke
			(width 0)
			(type solid)
		)
		(fill yes)
		(layer "F.Cu")
		(net "GND")
	)
	(gr_poly
		(pts
			(arc
				(start 167.489886 -36.48202)
				(mid 167.164766 -36.48202)
				(end 167.489886 -36.48202)
			)
		)
		(stroke
			(width 0)
			(type solid)
		)
		(fill yes)
		(layer "F.Cu")
		(net "GND")
	)
	(gr_poly
		(pts
			(arc
				(start 167.538146 -42.06875)
				(mid 167.213026 -42.06875)
				(end 167.538146 -42.06875)
			)
		)
		(stroke
			(width 0)
			(type solid)
		)
		(fill yes)
		(layer "F.Cu")
		(net "GND")
	)
	(gr_poly
		(pts
			(arc
				(start 167.541448 -40.217598)
				(mid 167.216328 -40.217598)
				(end 167.541448 -40.217598)
			)
		)
		(stroke
			(width 0)
			(type solid)
		)
		(fill yes)
		(layer "F.Cu")
		(net "GND")
	)
	(gr_poly
		(pts
			(arc
				(start 168.0972 -59.81319)
				(mid 167.77208 -59.81319)
				(end 168.0972 -59.81319)
			)
		)
		(stroke
			(width 0)
			(type solid)
		)
		(fill yes)
		(layer "F.Cu")
		(net "GND")
	)
	(gr_poly
		(pts
			(arc
				(start 168.10482 -62.50559)
				(mid 167.7797 -62.50559)
				(end 168.10482 -62.50559)
			)
		)
		(stroke
			(width 0)
			(type solid)
		)
		(fill yes)
		(layer "F.Cu")
		(net "GND")
	)
	(gr_poly
		(pts
			(arc
				(start 169.267124 -108.678472)
				(mid 168.942004 -108.678472)
				(end 169.267124 -108.678472)
			)
		)
		(stroke
			(width 0)
			(type solid)
		)
		(fill yes)
		(layer "F.Cu")
		(net "GND")
	)
	(gr_poly
		(pts
			(arc
				(start 170.69816 -169.202354)
				(mid 170.37304 -169.202354)
				(end 170.69816 -169.202354)
			)
		)
		(stroke
			(width 0)
			(type solid)
		)
		(fill yes)
		(layer "F.Cu")
		(net "GND")
	)
	(gr_poly
		(pts
			(arc
				(start 173.2153 -169.334434)
				(mid 172.89018 -169.334434)
				(end 173.2153 -169.334434)
			)
		)
		(stroke
			(width 0)
			(type solid)
		)
		(fill yes)
		(layer "F.Cu")
		(net "GND")
	)
	(gr_poly
		(pts
			(arc
				(start 174.592234 -104.990646)
				(mid 174.267114 -104.990646)
				(end 174.592234 -104.990646)
			)
		)
		(stroke
			(width 0)
			(type solid)
		)
		(fill yes)
		(layer "F.Cu")
		(net "GND")
	)
	(gr_poly
		(pts
			(arc
				(start 174.691294 -103.379016)
				(mid 174.366174 -103.379016)
				(end 174.691294 -103.379016)
			)
		)
		(stroke
			(width 0)
			(type solid)
		)
		(fill yes)
		(layer "F.Cu")
		(net "GND")
	)
	(gr_poly
		(pts
			(arc
				(start 175.388016 -101.127814)
				(mid 175.062896 -101.127814)
				(end 175.388016 -101.127814)
			)
		)
		(stroke
			(width 0)
			(type solid)
		)
		(fill yes)
		(layer "F.Cu")
		(net "GND")
	)
	(gr_poly
		(pts
			(arc
				(start 175.388016 -99.60102)
				(mid 175.062896 -99.60102)
				(end 175.388016 -99.60102)
			)
		)
		(stroke
			(width 0)
			(type solid)
		)
		(fill yes)
		(layer "F.Cu")
		(net "GND")
	)
	(gr_poly
		(pts
			(arc
				(start 176.11344 -170.31716)
				(mid 175.78832 -170.31716)
				(end 176.11344 -170.31716)
			)
		)
		(stroke
			(width 0)
			(type solid)
		)
		(fill yes)
		(layer "F.Cu")
		(net "GND")
	)
	(gr_poly
		(pts
			(arc
				(start 177.66538 -170.345608)
				(mid 177.34026 -170.345608)
				(end 177.66538 -170.345608)
			)
		)
		(stroke
			(width 0)
			(type solid)
		)
		(fill yes)
		(layer "F.Cu")
		(net "GND")
	)
	(gr_poly
		(pts
			(arc
				(start 178.86934 -170.951144)
				(mid 178.54422 -170.951144)
				(end 178.86934 -170.951144)
			)
		)
		(stroke
			(width 0)
			(type solid)
		)
		(fill yes)
		(layer "F.Cu")
		(net "GND")
	)
	(gr_poly
		(pts
			(arc
				(start 179.9082 -170.993816)
				(mid 179.58308 -170.993816)
				(end 179.9082 -170.993816)
			)
		)
		(stroke
			(width 0)
			(type solid)
		)
		(fill yes)
		(layer "F.Cu")
		(net "GND")
	)
	(gr_poly
		(pts
			(arc
				(start 181.4957 -173.05782)
				(mid 181.17058 -173.05782)
				(end 181.4957 -173.05782)
			)
		)
		(stroke
			(width 0)
			(type solid)
		)
		(fill yes)
		(layer "F.Cu")
		(net "GND")
	)
	(gr_poly
		(pts
			(arc
				(start 182.57266 -193.80581)
				(mid 182.24754 -193.80581)
				(end 182.57266 -193.80581)
			)
		)
		(stroke
			(width 0)
			(type solid)
		)
		(fill yes)
		(layer "F.Cu")
		(net "GND")
	)
	(gr_poly
		(pts
			(arc
				(start 182.6641 -173.107604)
				(mid 182.33898 -173.107604)
				(end 182.6641 -173.107604)
			)
		)
		(stroke
			(width 0)
			(type solid)
		)
		(fill yes)
		(layer "F.Cu")
		(net "GND")
	)
	(gr_poly
		(pts
			(arc
				(start 183.32196 -193.777362)
				(mid 182.99684 -193.777362)
				(end 183.32196 -193.777362)
			)
		)
		(stroke
			(width 0)
			(type solid)
		)
		(fill yes)
		(layer "F.Cu")
		(net "GND")
	)
	(gr_poly
		(pts
			(arc
				(start 184.96534 -196.920612)
				(mid 184.64022 -196.920612)
				(end 184.96534 -196.920612)
			)
		)
		(stroke
			(width 0)
			(type solid)
		)
		(fill yes)
		(layer "F.Cu")
		(net "GND")
	)
	(gr_poly
		(pts
			(arc
				(start 185.83402 -196.934836)
				(mid 185.5089 -196.934836)
				(end 185.83402 -196.934836)
			)
		)
		(stroke
			(width 0)
			(type solid)
		)
		(fill yes)
		(layer "F.Cu")
		(net "GND")
	)
	(gr_poly
		(pts
			(xy 33.55086 -187.932822) (xy 33.55086 -186.864752) (xy 33.04286 -186.356752) (xy 33.04286 -183.919368)
			(xy 32.872172 -183.74868) (xy 32.340042 -183.74868) (xy 32.12592 -183.962802) (xy 32.12592 -184.108344)
			(xy 32.150304 -184.108344) (xy 32.150304 -184.361836) (xy 32.150812 -184.361836) (xy 32.150812 -185.200036)
			(xy 32.12592 -185.200036) (xy 32.12592 -185.32729) (xy 31.9659 -185.48731) (xy 31.173674 -185.48731)
			(xy 31.09722 -185.563764)
			(arc
				(start 31.09722 -186.47664)
				(mid 31.134417 -186.566443)
				(end 31.22422 -186.60364)
			)
			(xy 31.8643 -186.60364) (xy 32.33166 -187.071) (xy 32.33166 -187.763912) (xy 32.51581 -187.948062)
			(xy 33.53562 -187.948062)
		)
		(stroke
			(width 0)
			(type solid)
		)
		(fill yes)
		(layer "F.Cu")
		(net "AGND_HSC_NODE1")
	)
	(gr_poly
		(pts
			(xy 34.217102 -132.903214) (xy 34.217102 -130.252216) (xy 34.217102 -129.387092) (xy 34.417508 -129.186686)
			(xy 34.417508 -127.741934) (xy 32.642048 -127.741934) (xy 32.487108 -127.896874) (xy 32.10687 -127.896874)
			(xy 31.49727 -127.896874) (xy 31.26867 -127.896874) (xy 31.01467 -127.896874) (xy 30.791404 -127.896874)
			(xy 30.78607 -127.902208) (xy 30.78607 -127.896874) (xy 30.58287 -127.896874) (xy 30.519878 -127.959866)
			(xy 30.519878 -128.798574) (xy 30.557216 -128.835912) (xy 30.557216 -129.82702) (xy 30.65907 -129.928874)
			(xy 31.44647 -129.928874) (xy 31.654496 -130.1369) (xy 31.654496 -131.786884) (xy 31.989014 -132.121402)
			(xy 32.671004 -132.121402) (xy 32.920432 -132.37083) (xy 32.920432 -133.166104) (xy 33.36163 -133.166104)
			(xy 33.581848 -133.166104) (xy 33.954212 -133.166104)
		)
		(stroke
			(width 0)
			(type solid)
		)
		(fill yes)
		(layer "F.Cu")
		(net "P1V538_BMC_NODE1")
	)
	(gr_poly
		(pts
			(xy 38.975284 -11.158982) (xy 38.975284 -10.890758) (xy 38.949884 -10.865612) (xy 38.949884 -10.547858)
			(xy 38.953948 -10.544048) (xy 38.953948 -10.125964) (xy 38.942264 -10.053828) (xy 38.942264 -9.730232)
			(xy 38.939724 -9.66216)
			(arc
				(start 38.939724 -9.549384)
				(mid 38.902527 -9.459581)
				(end 38.812724 -9.422384)
			)
			(xy 37.235638 -9.422384) (xy 37.19957 -9.458452) (xy 37.19957 -9.702038) (xy 37.217604 -9.720072)
			(xy 37.217604 -10.049764) (xy 37.206936 -10.060432) (xy 37.206936 -10.525252) (xy 37.212524 -10.530586)
			(xy 37.212524 -10.860024) (xy 37.19957 -10.872724) (xy 37.19957 -11.1379) (xy 37.253672 -11.192002)
			(xy 38.94201 -11.192002)
		)
		(stroke
			(width 0)
			(type solid)
		)
		(fill yes)
		(layer "F.Cu")
		(net "GND")
	)
	(gr_poly
		(pts
			(arc
				(start 47.441612 -68.779898)
				(mid 47.106332 -68.779898)
				(end 47.441612 -68.779898)
			)
		)
		(stroke
			(width 0)
			(type solid)
		)
		(fill yes)
		(layer "F.Cu")
		(net "GND")
	)
	(gr_poly
		(pts
			(arc
				(start 54.022752 -59.520582)
				(mid 53.687472 -59.520582)
				(end 54.022752 -59.520582)
			)
		)
		(stroke
			(width 0)
			(type solid)
		)
		(fill yes)
		(layer "F.Cu")
		(net "GND")
	)
	(gr_poly
		(pts
			(arc
				(start 94.827852 -140.390118)
				(mid 94.917655 -140.352921)
				(end 94.954852 -140.263118)
			)
			(xy 94.954852 -138.10615) (xy 94.94012 -138.091672) (xy 94.94012 -137.117582) (xy 94.954852 -137.103104)
			(xy 94.954852 -137.021062) (xy 94.954852 -137.018522) (xy 94.651068 -137.018522) (xy 94.247716 -137.42162)
			(xy 94.247716 -137.487152) (xy 94.391988 -137.63117) (xy 94.391988 -139.109958) (xy 94.175326 -139.326366)
			(xy 94.108524 -139.326366) (xy 93.585538 -139.849352)
			(arc
				(start 93.585538 -140.263118)
				(mid 93.622735 -140.352921)
				(end 93.712538 -140.390118)
			)
		)
		(stroke
			(width 0)
			(type solid)
		)
		(fill yes)
		(layer "F.Cu")
		(net "P1V05_SUS_NODE1_ADJ")
	)
	(gr_poly
		(pts
			(xy 109.785404 -132.444744) (xy 109.785404 -130.62712) (xy 109.777784 -130.6195)
			(arc
				(start 109.777784 -129.777998)
				(mid 109.740587 -129.688195)
				(end 109.650784 -129.650998)
			)
			(arc
				(start 109.399324 -129.650998)
				(mid 109.309521 -129.688195)
				(end 109.272324 -129.777998)
			)
			(xy 109.272324 -129.877566) (xy 109.2581 -129.877566) (xy 109.2581 -130.132074) (xy 109.274864 -130.132074)
			(xy 109.274864 -131.3053) (xy 109.21492 -131.365244) (xy 109.21492 -131.561078) (xy 109.227874 -131.574286)
			(xy 109.227874 -132.641594) (xy 109.309662 -132.723382) (xy 109.506766 -132.723382)
		)
		(stroke
			(width 0)
			(type solid)
		)
		(fill yes)
		(layer "F.Cu")
		(net "VR_PVCCP_NODE1_UGATE1")
	)
	(gr_poly
		(pts
			(xy 45.466254 -8.830818) (xy 45.466254 -8.049514) (xy 46.032928 -7.48284) (xy 48.209962 -7.48284)
			(xy 51.068732 -7.48284) (xy 51.640486 -7.48284) (xy 51.921918 -7.201408) (xy 51.921918 -5.257292)
			(xy 51.718972 -5.054346) (xy 49.158144 -5.054346) (xy 48.500538 -4.39674) (xy 44.807886 -4.39674)
			(xy 43.625008 -4.39674) (xy 42.259758 -4.39674) (xy 41.24071 -4.39674) (xy 41.07942 -4.39674) (xy 40.935402 -4.540758)
			(xy 40.935402 -5.632958) (xy 41.028874 -5.72643) (xy 43.08221 -5.72643) (xy 43.44035 -6.08457) (xy 43.44035 -6.32079)
			(xy 43.44035 -6.42366) (xy 43.44035 -7.992618) (xy 43.381168 -8.0518) (xy 43.3705 -8.062468) (xy 42.74312 -8.062468)
			(xy 42.725086 -8.080502) (xy 42.725086 -8.864092) (xy 42.73677 -8.875776) (xy 45.421296 -8.875776)
		)
		(stroke
			(width 0)
			(type solid)
		)
		(fill yes)
		(layer "F.Cu")
		(net "SW_PV_VDDR_NODE1_VIN_FLT")
	)
	(gr_poly
		(pts
			(xy 48.598328 -12.422378) (xy 48.598328 -9.32815) (xy 48.513746 -9.243568) (xy 47.798736 -9.243568)
			(xy 42.73677 -9.243568) (xy 41.251124 -9.243568) (xy 40.682418 -9.812274) (xy 40.56507 -9.812274)
			(xy 40.557196 -9.820148) (xy 40.31869 -9.820148) (xy 39.214552 -9.820148) (xy 39.196772 -9.837928)
			(xy 39.196772 -9.958578) (xy 39.217092 -9.978898) (xy 40.32631 -9.978898) (xy 40.57269 -9.978898)
			(xy 40.980614 -9.978898) (xy 41.090342 -9.978898) (xy 41.091612 -9.980168) (xy 41.169844 -9.980168)
			(xy 41.846246 -10.65657) (xy 42.429938 -11.240262) (xy 42.590212 -11.240262) (xy 45.671232 -11.240262)
			(xy 45.898054 -11.467084) (xy 45.898054 -11.805158) (xy 45.898054 -12.048236) (xy 45.898054 -12.615672)
			(xy 45.960284 -12.677902) (xy 47.883318 -12.677902) (xy 48.342804 -12.677902)
		)
		(stroke
			(width 0)
			(type solid)
		)
		(fill yes)
		(layer "F.Cu")
		(net "SW_PV_VDDR_NODE1_PH")
	)
	(gr_poly
		(pts
			(xy 111.662972 -139.848336) (xy 111.662972 -138.895328) (xy 111.378492 -138.610848) (xy 110.97514 -138.610848)
			(xy 110.842552 -138.478514) (xy 110.834424 -138.478514) (xy 110.834424 -138.470386) (xy 110.815628 -138.451336)
			(xy 110.815628 -137.353802) (xy 110.928912 -137.240518) (xy 110.928912 -137.039096) (xy 110.812834 -136.923018)
			(xy 110.600236 -136.923018) (xy 110.202472 -137.320782) (xy 110.189772 -137.320782) (xy 110.076742 -137.433812)
			(xy 110.076742 -138.072114) (xy 110.092236 -138.087354) (xy 110.092236 -138.741404) (xy 110.711488 -139.36091)
			(xy 110.711488 -139.433046) (xy 110.782862 -139.504166)
			(arc
				(start 110.782862 -139.741402)
				(mid 110.820059 -139.831205)
				(end 110.909862 -139.868402)
			)
			(xy 111.642906 -139.868402)
		)
		(stroke
			(width 0)
			(type solid)
		)
		(fill yes)
		(layer "F.Cu")
		(net "VR_PVCCP_NODE1_VCC")
	)
	(gr_poly
		(pts
			(xy 126.5174 -34.422588) (xy 126.5174 -33.499806) (xy 126.251462 -33.233868) (xy 125.6157 -33.233868)
			(xy 125.329696 -32.947864)
			(arc
				(start 125.329696 -31.66872)
				(mid 125.292499 -31.578917)
				(end 125.202696 -31.54172)
			)
			(xy 124.395738 -31.54172)
			(arc
				(start 123.860052 -31.006034)
				(mid 123.7703 -30.968969)
				(end 123.680474 -31.006034)
			)
			(xy 123.18492 -31.501588) (xy 123.18492 -31.863538) (xy 123.444 -32.122872) (xy 123.480576 -32.122872)
			(xy 123.480576 -32.159448) (xy 123.54814 -32.226758) (xy 123.54814 -34.584132) (xy 123.571 -34.606992)
			(xy 126.332996 -34.606992)
		)
		(stroke
			(width 0)
			(type solid)
		)
		(fill yes)
		(layer "F.Cu")
		(net "SIO_VCCH")
	)
	(gr_poly
		(pts
			(xy 167.000936 -78.40218) (xy 167.664384 -78.40218) (xy 167.914574 -78.15199) (xy 167.914574 -76.688188)
			(xy 167.914574 -76.500482) (xy 167.914574 -75.236578) (xy 167.87114 -75.193144) (xy 167.11676 -75.193144)
			(xy 165.847014 -76.46289) (xy 165.740588 -76.569316) (xy 165.556438 -76.753466) (xy 164.291264 -76.753466)
			(xy 164.281866 -76.762864) (xy 164.281866 -76.96073) (xy 164.286692 -76.965556) (xy 164.286692 -77.719174)
			(xy 164.286692 -77.902562) (xy 164.346128 -77.961998) (xy 165.282372 -77.961998) (xy 165.446964 -77.961998)
			(xy 165.751764 -78.266798)
			(arc
				(start 165.777926 -78.27645)
				(mid 165.862932 -78.317077)
				(end 165.938962 -78.372716)
			)
			(arc
				(start 165.938962 -78.372716)
				(mid 165.978068 -78.396423)
				(end 166.023036 -78.40472)
			)
			(xy 166.998396 -78.40472)
		)
		(stroke
			(width 0)
			(type solid)
		)
		(fill yes)
		(layer "F.Cu")
		(net "P1V8_NODE1")
	)
	(gr_poly
		(pts
			(xy 32.264604 -107.757468)
			(arc
				(start 32.264604 -107.26928)
				(mid 32.275617 -107.164277)
				(end 32.308038 -107.063794)
			)
			(xy 32.31896 -107.039156) (xy 32.31896 -106.64063) (xy 32.47644 -106.48315) (xy 32.983932 -106.48315)
			(xy 32.995616 -106.471466) (xy 32.995616 -104.91343) (xy 32.607758 -104.525572) (xy 32.607758 -101.594666)
			(xy 32.966152 -101.236272) (xy 33.018222 -101.236272) (xy 33.052004 -101.202236) (xy 34.233104 -101.202236)
			(xy 34.52622 -100.90912) (xy 34.52622 -99.957128) (xy 34.519108 -99.950016) (xy 30.883352 -99.950016)
			(xy 30.42412 -100.409248) (xy 30.42412 -100.894642) (xy 30.947106 -101.417628) (xy 30.947106 -104.688894)
			(xy 30.81528 -104.82072) (xy 29.70403 -104.82072) (xy 29.48178 -105.04297) (xy 29.48178 -107.735878)
			(xy 29.596588 -107.850686) (xy 32.17164 -107.850686)
		)
		(stroke
			(width 0)
			(type solid)
		)
		(fill yes)
		(layer "F.Cu")
		(net "GND")
	)
	(gr_poly
		(pts
			(arc
				(start 47.118016 -157.573726)
				(mid 47.207819 -157.536529)
				(end 47.245016 -157.446726)
			)
			(arc
				(start 47.245016 -152.390348)
				(mid 47.207819 -152.300545)
				(end 47.118016 -152.263348)
			)
			(arc
				(start 42.006012 -152.263348)
				(mid 41.916209 -152.300545)
				(end 41.879012 -152.390348)
			)
			(arc
				(start 41.879012 -157.446726)
				(mid 41.916209 -157.536529)
				(end 42.006012 -157.573726)
			)
		)
		(stroke
			(width 0)
			(type solid)
		)
		(fill yes)
		(layer "F.Cu")
		(net "GND")
	)
	(gr_poly
		(pts
			(arc
				(start 59.384184 -120.862598)
				(mid 59.473987 -120.825401)
				(end 59.511184 -120.735598)
			)
			(arc
				(start 59.511184 -119.16664)
				(mid 59.473987 -119.076837)
				(end 59.384184 -119.03964)
			)
			(arc
				(start 59.0931 -119.03964)
				(mid 59.003297 -119.076837)
				(end 58.9661 -119.16664)
			)
			(arc
				(start 58.9661 -120.735598)
				(mid 59.003297 -120.825401)
				(end 59.0931 -120.862598)
			)
		)
		(stroke
			(width 0)
			(type solid)
		)
		(fill yes)
		(layer "F.Cu")
		(net "P3V3_NODE1")
	)
	(gr_poly
		(pts
			(arc
				(start 148.462746 -81.585816)
				(mid 148.07565 -81.585816)
				(end 148.462746 -81.585816)
			)
		)
		(stroke
			(width 0)
			(type solid)
		)
		(fill yes)
		(layer "F.Cu")
		(net "GND")
	)
	(gr_poly
		(pts
			(arc
				(start 150.555706 -81.11744)
				(mid 150.16861 -81.11744)
				(end 150.555706 -81.11744)
			)
		)
		(stroke
			(width 0)
			(type solid)
		)
		(fill yes)
		(layer "F.Cu")
		(net "GND")
	)
	(gr_poly
		(pts
			(arc
				(start 150.612602 -78.482952)
				(mid 150.225506 -78.482952)
				(end 150.612602 -78.482952)
			)
		)
		(stroke
			(width 0)
			(type solid)
		)
		(fill yes)
		(layer "F.Cu")
		(net "GND")
	)
	(gr_poly
		(pts
			(xy 29.15666 -128.266698) (xy 29.15666 -127.781812) (xy 29.295852 -127.64262) (xy 30.47746 -127.64262)
			(arc
				(start 32.02178 -127.64262)
				(mid 32.111583 -127.605423)
				(end 32.14878 -127.51562)
			)
			(arc
				(start 32.14878 -126.119128)
				(mid 32.111583 -126.029325)
				(end 32.02178 -125.992128)
			)
			(xy 31.44266 -125.992128) (xy 31.402274 -125.951996) (xy 29.903674 -125.951996) (xy 29.8958 -125.943868)
			(xy 29.355796 -125.943868) (xy 28.985718 -125.57379) (xy 27.522678 -125.57379) (xy 26.685748 -126.41072)
			(xy 25.698958 -126.41072) (xy 25.56002 -126.549658) (xy 25.56002 -128.47828) (xy 25.91308 -128.83134)
			(xy 28.592018 -128.83134)
		)
		(stroke
			(width 0)
			(type solid)
		)
		(fill yes)
		(layer "F.Cu")
		(net "GND")
	)
	(gr_poly
		(pts
			(arc
				(start 91.9226 -85.271864)
				(mid 92.012403 -85.234667)
				(end 92.0496 -85.144864)
			)
			(arc
				(start 92.0496 -83.188048)
				(mid 92.012403 -83.098245)
				(end 91.9226 -83.061048)
			)
			(xy 89.199466 -83.061048) (xy 89.014554 -83.24596)
			(arc
				(start 88.82126 -83.24596)
				(mid 88.731457 -83.283157)
				(end 88.69426 -83.37296)
			)
			(arc
				(start 88.69426 -85.144864)
				(mid 88.731457 -85.234667)
				(end 88.82126 -85.271864)
			)
		)
		(stroke
			(width 0)
			(type solid)
		)
		(fill yes)
		(layer "F.Cu")
		(net "GND")
	)
	(gr_poly
		(pts
			(xy 139.491466 -25.411938) (xy 139.491466 -24.26589) (xy 139.714986 -24.04237) (xy 140.121386 -24.04237)
			(xy 140.132816 -24.03094) (xy 143.049498 -24.03094) (xy 143.05534 -24.025098) (xy 143.47952 -24.449278)
			(xy 143.47952 -25.494488) (xy 143.480013 -25.511143) (xy 143.488633 -25.543318) (xy 143.505287 -25.572165)
			(xy 143.528841 -25.595718) (xy 143.55769 -25.61237) (xy 143.589865 -25.620988) (xy 143.60652 -25.621488)
			(xy 144.145254 -25.621488) (xy 144.16024 -25.606502) (xy 144.16024 -19.923506) (xy 143.479012 -19.242278)
			(xy 137.59942 -19.242278) (xy 137.398252 -19.443446) (xy 137.398252 -19.897852) (xy 137.82802 -19.897852)
			(xy 139.631928 -19.897852) (xy 139.631928 -21.70176) (xy 137.82802 -21.70176) (xy 137.82802 -19.897852)
			(xy 137.398252 -19.897852) (xy 137.398252 -25.343612) (xy 137.464546 -25.409906) (xy 138.479022 -25.409906)
			(xy 138.69924 -25.630124) (xy 139.27328 -25.630124)
		)
		(stroke
			(width 0)
			(type solid)
		)
		(fill yes)
		(layer "F.Cu")
		(net "P5V_NODE1")
	)
	(gr_poly
		(pts
			(xy 35.675316 -115.595654) (xy 35.675316 -112.561878) (xy 36.688776 -111.548418) (xy 38.085014 -111.548418)
			(xy 38.6969 -110.936532) (xy 38.6969 -102.209854) (xy 37.94379 -101.456744) (xy 37.63264 -101.456744)
			(xy 33.157414 -101.456744) (xy 32.894778 -101.71938) (xy 32.894778 -103.317802) (xy 32.90697 -103.329994)
			(xy 32.914844 -103.337868) (xy 34.65957 -103.337868) (xy 35.017964 -102.979474) (xy 36.393628 -102.979474)
			(xy 36.487608 -103.073454) (xy 36.487608 -107.145074)
			(arc
				(start 36.493196 -107.163362)
				(mid 36.510169 -107.275884)
				(end 36.493196 -107.388406)
			)
			(xy 36.487608 -107.406694) (xy 36.487608 -107.978956) (xy 35.79114 -108.675424) (xy 33.781492 -108.675424)
			(xy 32.22244 -108.675424) (xy 31.93796 -108.959904) (xy 31.93796 -115.52682) (xy 32.060896 -115.649756)
			(xy 33.426654 -115.649756) (xy 33.545018 -115.76812) (xy 35.50285 -115.76812)
		)
		(stroke
			(width 0)
			(type solid)
		)
		(fill yes)
		(layer "F.Cu")
		(net "P1V5_SUS_NODE1")
	)
	(gr_poly
		(pts
			(xy 56.375808 -117.802406)
			(arc
				(start 56.375808 -117.7417)
				(mid 56.638914 -117.296476)
				(end 57.155842 -117.312186)
			)
			(xy 57.18683 -117.331744) (xy 57.72277 -117.331744)
			(arc
				(start 57.749186 -117.31879)
				(mid 57.790627 -117.300658)
				(end 57.833514 -117.286278)
			)
			(xy 57.865264 -117.277134) (xy 58.029094 -117.113304) (xy 58.029094 -116.885974) (xy 57.926732 -116.783358)
			(xy 54.702456 -116.783358) (xy 54.545484 -116.940584) (xy 54.545484 -117.950234) (xy 54.836568 -118.241318)
			(xy 55.936896 -118.241318)
		)
		(stroke
			(width 0)
			(type solid)
		)
		(fill yes)
		(layer "F.Cu")
		(net "GND")
	)
	(gr_poly
		(pts
			(xy 150.375112 -70.061582) (xy 150.375112 -69.782182) (xy 150.154132 -69.561202) (xy 150.154132 -69.336412)
			(xy 150.005796 -69.18833) (xy 150.005796 -67.922648) (xy 149.960584 -67.877182) (xy 149.051772 -67.877182)
			(xy 149.003512 -67.925442)
			(arc
				(start 149.003512 -68.076572)
				(mid 149.021129 -68.141105)
				(end 149.069044 -68.187824)
			)
			(arc
				(start 149.069044 -68.187824)
				(mid 149.332469 -68.444414)
				(end 149.429216 -68.799202)
			)
			(xy 149.429216 -69.569838)
			(arc
				(start 149.4282 -69.573648)
				(mid 149.427438 -69.640449)
				(end 149.460712 -69.698362)
			)
			(xy 149.948392 -70.186042) (xy 150.250652 -70.186042)
		)
		(stroke
			(width 0)
			(type solid)
		)
		(fill yes)
		(layer "F.Cu")
		(net "SATA_VCONT_NODE1")
	)
	(gr_poly
		(pts
			(xy 184.91962 -59.870848) (xy 184.91962 -58.606944) (xy 184.531 -58.218324)
			(arc
				(start 181.51983 -58.218324)
				(mid 180.74005 -58.385184)
				(end 179.96027 -58.218324)
			)
			(xy 178.492912 -58.218324) (xy 176.77384 -56.499252) (xy 176.77384 -53.277262) (xy 177.638456 -52.412646)
			(xy 177.638456 -50.470054)
			(arc
				(start 177.535078 -50.366422)
				(mid 177.493838 -50.338803)
				(end 177.445162 -50.329084)
			)
			(xy 172.209968 -50.329084) (xy 171.59986 -50.939192) (xy 171.59986 -55.344568) (xy 172.111162 -55.85587)
			(xy 173.279562 -55.85587) (xy 177.6476 -60.223908) (xy 184.56656 -60.223908)
		)
		(stroke
			(width 0)
			(type solid)
		)
		(fill yes)
		(layer "F.Cu")
		(net "USBPWR_P1")
	)
	(gr_poly
		(pts
			(arc
				(start 34.95167 -11.321796)
				(mid 35.000217 -11.312046)
				(end 35.041332 -11.284458)
			)
			(xy 35.5473 -10.77849) (xy 35.567112 -10.758678) (xy 35.860736 -10.758678) (xy 35.86099 -10.758424)
			(xy 36.519866 -10.758424) (xy 36.533582 -10.758678)
			(arc
				(start 36.825428 -10.758678)
				(mid 36.915231 -10.721481)
				(end 36.952428 -10.631678)
			)
			(xy 36.952428 -10.23874) (xy 36.93668 -10.222738) (xy 36.952428 -10.20699)
			(arc
				(start 36.952428 -9.968992)
				(mid 36.915231 -9.879189)
				(end 36.825428 -9.841992)
			)
			(xy 35.585908 -9.841992) (xy 35.320986 -9.57707) (xy 34.751518 -9.57707) (xy 34.627312 -9.701276)
			(xy 34.627312 -11.289284) (xy 34.659824 -11.321796)
		)
		(stroke
			(width 0)
			(type solid)
		)
		(fill yes)
		(layer "F.Cu")
		(net "PV_VDDR_NODE1_V1")
	)
	(gr_poly
		(pts
			(arc
				(start 78.978252 -82.440526)
				(mid 79.18196 -82.38159)
				(end 79.385668 -82.440526)
			)
			(xy 79.416656 -82.460084) (xy 79.65694 -82.460084) (xy 79.89951 -82.217514)
			(arc
				(start 84.090256 -82.217514)
				(mid 84.180059 -82.180317)
				(end 84.217256 -82.090514)
			)
			(arc
				(start 84.217256 -80.934052)
				(mid 84.180059 -80.844249)
				(end 84.090256 -80.807052)
			)
			(xy 78.626208 -80.807052) (xy 78.467204 -80.966056) (xy 78.467204 -81.309464) (xy 78.22438 -81.552288)
			(xy 78.22438 -81.845658) (xy 78.838806 -82.460084) (xy 78.947264 -82.460084)
		)
		(stroke
			(width 0)
			(type solid)
		)
		(fill yes)
		(layer "F.Cu")
		(net "GND")
	)
	(gr_poly
		(pts
			(xy 97.501202 -131.775454)
			(arc
				(start 97.542096 -131.775454)
				(mid 97.631899 -131.738257)
				(end 97.669096 -131.648454)
			)
			(arc
				(start 97.669096 -131.367784)
				(mid 97.629903 -131.276283)
				(end 97.536762 -131.241038)
			)
			(xy 97.516696 -131.241546)
			(arc
				(start 96.719644 -131.241546)
				(mid 96.66234 -131.238075)
				(end 96.605852 -131.22783)
			)
			(arc
				(start 96.605852 -131.22783)
				(mid 96.388877 -131.274998)
				(end 96.291908 -131.474718)
			)
			(xy 96.291908 -131.968748) (xy 96.30156 -131.9784) (xy 97.298256 -131.9784)
		)
		(stroke
			(width 0)
			(type solid)
		)
		(fill yes)
		(layer "F.Cu")
		(net "P5V_STB_NODE1")
	)
	(gr_poly
		(pts
			(arc
				(start 109.06252 -66.143124)
				(mid 109.152323 -66.105927)
				(end 109.18952 -66.016124)
			)
			(xy 109.18952 -65.356232) (xy 109.0041 -65.170812) (xy 106.583988 -65.170812) (xy 106.03484 -65.71996)
			(xy 106.02976 -65.71996) (xy 105.974896 -65.774824) (xy 103.610918 -65.774824) (xy 103.607616 -65.778126)
			(xy 103.607616 -66.01714) (xy 103.624888 -66.034412) (xy 106.125518 -66.034412) (xy 106.19232 -66.10096)
			(xy 106.631994 -66.10096)
			(arc
				(start 106.666284 -66.075052)
				(mid 106.921968 -65.99741)
				(end 107.165902 -66.106548)
			)
			(arc
				(start 107.165902 -66.106548)
				(mid 107.206876 -66.133613)
				(end 107.255056 -66.143124)
			)
		)
		(stroke
			(width 0)
			(type solid)
		)
		(fill yes)
		(layer "F.Cu")
		(net "P1V05_STB_NODE1_XDP_A")
	)
	(gr_poly
		(pts
			(arc
				(start 52.504594 -77.91196)
				(mid 52.608413 -77.832905)
				(end 52.731924 -77.790802)
			)
			(xy 52.772056 -77.783944) (xy 52.832762 -77.723238) (xy 53.505862 -77.723238) (xy 53.715412 -77.513942)
			(xy 53.717698 -77.511402) (xy 53.735986 -77.493368) (xy 53.755798 -77.446378) (xy 53.755798 -77.366368)
			(xy 53.580284 -77.190854) (xy 52.783994 -77.190854)
			(arc
				(start 52.687474 -77.28712)
				(mid 52.61232 -77.346351)
				(end 52.525422 -77.386434)
			)
			(xy 52.496212 -77.396086) (xy 52.39639 -77.495908)
			(arc
				(start 52.386738 -77.525118)
				(mid 52.361296 -77.586256)
				(end 52.326286 -77.642466)
			)
			(arc
				(start 52.326286 -77.642466)
				(mid 52.302156 -77.701976)
				(end 52.310284 -77.765656)
			)
			(arc
				(start 52.337208 -77.832458)
				(mid 52.383963 -77.890273)
				(end 52.455064 -77.91196)
			)
		)
		(stroke
			(width 0)
			(type solid)
		)
		(fill yes)
		(layer "F.Cu")
		(net "P1V8_VCCASFRHPLL_NODE1")
	)
	(gr_poly
		(pts
			(xy 171.15282 -81.317846) (xy 171.15282 -76.52004) (xy 170.748198 -76.115418) (xy 168.745154 -76.115418)
			(xy 168.421304 -76.439268) (xy 168.421304 -78.51775) (xy 168.279826 -78.659228) (xy 167.08628 -78.659228)
			(arc
				(start 166.952676 -78.792832)
				(mid 166.925106 -78.833954)
				(end 166.915338 -78.882494)
			)
			(xy 166.915338 -80.44815) (xy 166.763192 -80.600296) (xy 165.525704 -80.600296) (xy 165.278308 -80.3529)
			(xy 165.278308 -79.953104) (xy 165.278308 -79.264764) (xy 164.80282 -78.789276) (xy 164.18814 -78.789276)
			(xy 164.02177 -78.622906) (xy 164.02177 -75.818492) (xy 164.225224 -75.615038) (xy 164.225224 -74.375264)
			(xy 164.24402 -74.356468) (xy 164.24402 -72.995028) (xy 161.650934 -72.995028) (xy 161.61004 -73.035922)
			(xy 161.61004 -75.57135) (xy 161.949384 -75.910694) (xy 162.298126 -75.910694) (xy 162.32759 -75.940158)
			(xy 162.32759 -79.476854) (xy 162.41268 -79.561944) (xy 162.822636 -79.561944) (xy 163.28644 -80.025748)
			(xy 163.28644 -82.927444) (xy 163.546536 -83.18754) (xy 163.629848 -83.270852) (xy 169.199814 -83.270852)
		)
		(stroke
			(width 0)
			(type solid)
		)
		(fill yes)
		(layer "F.Cu")
		(net "GND")
	)
	(gr_poly
		(pts
			(arc
				(start 121.87174 -173.850808)
				(mid 121.920424 -173.841106)
				(end 121.961656 -173.81347)
			)
			(arc
				(start 121.961656 -173.81347)
				(mid 122.231658 -173.701483)
				(end 122.50166 -173.81347)
			)
			(arc
				(start 122.50166 -173.81347)
				(mid 122.5429 -173.841089)
				(end 122.591576 -173.850808)
			)
			(xy 123.528836 -173.850808) (xy 123.641612 -173.738032) (xy 123.641612 -172.828712)
			(arc
				(start 123.63323 -172.806868)
				(mid 123.609229 -172.722831)
				(end 123.599956 -172.635926)
			)
			(arc
				(start 123.599956 -172.635926)
				(mid 123.523792 -172.459578)
				(end 123.345956 -172.387006)
			)
			(xy 119.963946 -172.387006) (xy 119.888762 -172.46219) (xy 119.888762 -173.194218) (xy 120.545352 -173.850808)
		)
		(stroke
			(width 0)
			(type solid)
		)
		(fill yes)
		(layer "F.Cu")
		(net "P3V3_NODE1")
	)
	(gr_poly
		(pts
			(arc
				(start 46.79442 -167.674544)
				(mid 46.884223 -167.637347)
				(end 46.92142 -167.547544)
			)
			(arc
				(start 46.92142 -167.331136)
				(mid 46.884223 -167.241333)
				(end 46.79442 -167.204136)
			)
			(xy 44.41952 -167.204136) (xy 44.41952 -166.105332)
			(arc
				(start 43.641518 -165.32733)
				(mid 43.551602 -165.290011)
				(end 43.461686 -165.32733)
			)
			(xy 42.683684 -166.105332) (xy 42.683684 -167.204136)
			(arc
				(start 40.31234 -167.204136)
				(mid 40.222537 -167.241333)
				(end 40.18534 -167.331136)
			)
			(arc
				(start 40.18534 -167.547544)
				(mid 40.222537 -167.637347)
				(end 40.31234 -167.674544)
			)
		)
		(stroke
			(width 0)
			(type solid)
		)
		(fill yes)
		(layer "F.Cu")
		(net "GND")
	)
	(gr_poly
		(pts
			(xy 62.346078 -149.942042) (xy 62.346078 -149.518878) (xy 62.335156 -149.518878) (xy 62.335156 -149.503638)
			(arc
				(start 62.30493 -149.467824)
				(mid 62.183046 -149.137624)
				(end 62.30493 -148.807424)
			)
			(arc
				(start 62.30493 -148.807424)
				(mid 62.32743 -148.76885)
				(end 62.335156 -148.724874)
			)
			(arc
				(start 62.335156 -148.534374)
				(mid 62.327397 -148.49041)
				(end 62.30493 -148.451824)
			)
			(arc
				(start 62.30493 -148.451824)
				(mid 62.186984 -148.184773)
				(end 62.235334 -147.896834)
			)
			(xy 62.253368 -147.860004) (xy 62.24016 -147.77974) (xy 62.08522 -147.6248) (xy 60.036456 -147.6248)
			(xy 59.939428 -147.721828) (xy 59.939428 -149.770592) (xy 60.267342 -150.098506) (xy 62.189614 -150.098506)
		)
		(stroke
			(width 0)
			(type solid)
		)
		(fill yes)
		(layer "F.Cu")
		(net "BMC_NODE1_DACAV33")
	)
	(gr_poly
		(pts
			(xy 109.020356 -131.19989) (xy 109.020356 -130.435604) (xy 109.020356 -130.386328) (xy 109.003592 -130.386328)
			(xy 109.003592 -129.623312) (xy 109.017816 -129.623312) (xy 109.017816 -127.945388) (xy 109.0168 -127.944372)
			(xy 109.0168 -127.541528) (xy 109.0168 -127.323088) (xy 109.048042 -127.291846) (xy 109.157516 -127.291846)
			(xy 109.86516 -127.291846) (xy 109.883448 -127.273558) (xy 109.883448 -122.978418) (xy 110.448344 -122.413522)
			(xy 110.454948 -122.413522) (xy 110.723172 -122.145298) (xy 111.538004 -121.330466) (xy 111.538004 -120.459246)
			(xy 111.287052 -120.208294) (xy 110.633764 -120.208294) (xy 109.6137 -120.208294) (xy 109.54893 -120.273064)
			(xy 109.54893 -120.765062) (xy 109.54893 -120.845834) (xy 109.468158 -120.926606) (xy 108.322618 -120.926606)
			(xy 108.309156 -120.913144) (xy 108.309156 -120.812052) (xy 108.309156 -120.180862) (xy 108.261912 -120.133618)
			(xy 107.385358 -120.133618) (xy 107.253278 -120.133618) (xy 106.99623 -120.390666) (xy 106.99623 -127.263906)
			(xy 107.037886 -127.305562) (xy 107.606846 -127.305562) (xy 107.876086 -127.574802) (xy 107.876086 -127.945388)
			(xy 107.876086 -129.772156) (xy 108.578142 -130.474212) (xy 108.592366 -130.474212) (xy 108.592366 -131.137406)
			(xy 108.717334 -131.262374) (xy 108.957872 -131.262374)
		)
		(stroke
			(width 0)
			(type solid)
		)
		(fill yes)
		(layer "F.Cu")
		(net "VR_PVCCP_NODE1_PHASE1")
	)
	(gr_poly
		(pts
			(arc
				(start 33.599882 -185.78449)
				(mid 33.815671 -185.664063)
				(end 33.826958 -185.417206)
			)
			(arc
				(start 33.826958 -185.417206)
				(mid 33.777926 -185.161869)
				(end 33.86836 -184.918096)
			)
			(arc
				(start 33.86836 -184.918096)
				(mid 33.892334 -184.838064)
				(end 33.861502 -184.760362)
			)
			(arc
				(start 33.861502 -184.760362)
				(mid 33.744578 -184.427101)
				(end 33.885632 -184.103264)
			)
			(xy 33.991804 -183.997346) (xy 33.991804 -183.915304) (xy 33.88868 -183.81218) (xy 33.424876 -183.81218)
			(xy 33.332166 -183.90489) (xy 33.332166 -185.725562) (xy 33.391094 -185.78449)
		)
		(stroke
			(width 0)
			(type solid)
		)
		(fill yes)
		(layer "F.Cu")
		(net "P12V_AUX_EN")
	)
	(gr_poly
		(pts
			(xy 87.119206 -82.293968) (xy 87.11946 -82.293968)
			(arc
				(start 87.321136 -82.092292)
				(mid 87.348706 -82.05117)
				(end 87.358474 -82.00263)
			)
			(xy 87.358474 -79.242158) (xy 87.202772 -79.086456) (xy 86.193376 -79.086456) (xy 86.135972 -79.11846)
			(arc
				(start 86.118446 -79.1464)
				(mid 85.924316 -79.303395)
				(end 85.674708 -79.306674)
			)
			(arc
				(start 85.674708 -79.306674)
				(mid 85.576768 -79.333131)
				(end 85.475318 -79.332836)
			)
			(arc
				(start 85.475318 -79.332836)
				(mid 85.384452 -79.425663)
				(end 85.351366 -79.551276)
			)
			(arc
				(start 85.351366 -82.084926)
				(mid 85.361116 -82.133473)
				(end 85.388704 -82.174588)
			)
			(xy 85.508084 -82.293968) (xy 86.405974 -82.293968) (xy 86.436708 -82.29727)
			(arc
				(start 86.468204 -82.300572)
				(mid 86.494087 -82.303843)
				(end 86.519766 -82.308446)
			)
			(xy 86.532466 -82.31124) (xy 87.101934 -82.31124)
		)
		(stroke
			(width 0)
			(type solid)
		)
		(fill yes)
		(layer "F.Cu")
		(net "P1V05_VCCPLLCPU1SIO_NODE1")
	)
	(gr_poly
		(pts
			(xy 120.92686 -175.172116) (xy 120.92686 -174.162466) (xy 120.907302 -174.11573) (xy 120.896888 -174.105316)
			(xy 120.439942 -174.105316) (xy 120.16994 -173.83506)
			(arc
				(start 119.633492 -173.298866)
				(mid 119.533447 -173.116518)
				(end 119.330724 -173.070012)
			)
			(arc
				(start 119.330724 -173.070012)
				(mid 119.071977 -173.038553)
				(end 118.893844 -172.84827)
			)
			(xy 118.878858 -172.813218) (xy 118.815104 -172.771054)
			(arc
				(start 115.915186 -172.771054)
				(mid 115.866639 -172.780804)
				(end 115.825524 -172.808392)
			)
			(xy 115.706906 -172.92701) (xy 114.440716 -172.92701) (xy 113.914428 -173.453298)
			(arc
				(start 113.914428 -175.208946)
				(mid 113.951625 -175.298749)
				(end 114.041428 -175.335946)
			)
			(xy 120.76303 -175.335946)
		)
		(stroke
			(width 0)
			(type solid)
		)
		(fill yes)
		(layer "F.Cu")
		(net "GND")
	)
	(gr_poly
		(pts
			(arc
				(start 153.525982 -55.073042)
				(mid 153.708083 -54.996116)
				(end 153.779982 -54.81193)
			)
			(arc
				(start 153.779982 -54.81193)
				(mid 153.877927 -54.327551)
				(end 154.17927 -53.935884)
			)
			(arc
				(start 154.17927 -53.935884)
				(mid 154.213593 -53.891967)
				(end 154.225752 -53.837586)
			)
			(xy 154.225752 -51.330352) (xy 154.0764 -51.181) (xy 151.356314 -51.181) (xy 150.79218 -51.745134)
			(arc
				(start 145.842482 -51.745134)
				(mid 145.793798 -51.754836)
				(end 145.752566 -51.782472)
			)
			(xy 145.693638 -51.841654) (xy 144.677384 -51.841654) (xy 144.676876 -51.842162) (xy 144.50568 -51.842162)
			(arc
				(start 144.389348 -51.95824)
				(mid 144.361729 -51.99948)
				(end 144.35201 -52.048156)
			)
			(xy 144.35201 -54.869334) (xy 144.555718 -55.073042)
		)
		(stroke
			(width 0)
			(type solid)
		)
		(fill yes)
		(layer "F.Cu")
		(net "SATA_P7")
	)
	(gr_poly
		(pts
			(xy 179.98948 -150.647654) (xy 179.98948 -146.06016) (xy 181.000654 -145.048986) (xy 183.07558 -145.048986)
			(xy 183.3118 -144.812766) (xy 183.3118 -144.15897) (xy 183.368188 -144.102582) (xy 186.219846 -144.102582)
			(xy 186.89574 -143.426688) (xy 186.89574 -140.697712) (xy 186.575446 -140.377418) (xy 179.10302 -140.377418)
			(xy 177.87112 -141.609318) (xy 177.87112 -141.74597) (xy 177.934112 -141.808962) (xy 177.934112 -143.092033)
			(xy 180.079107 -143.092033) (xy 180.079107 -143.028767) (xy 180.087365 -142.966044) (xy 180.10374 -142.904934)
			(xy 180.127952 -142.846486) (xy 180.159586 -142.791697) (xy 180.198102 -142.741507) (xy 180.242839 -142.696774)
			(xy 180.293032 -142.658263) (xy 180.347823 -142.626634) (xy 180.406274 -142.602427) (xy 180.467385 -142.586057)
			(xy 180.530109 -142.577804) (xy 180.561742 -142.577312) (xy 182.03164 -142.577312) (xy 182.03164 -143.543528)
			(xy 180.561742 -143.543528) (xy 180.530109 -143.542996) (xy 180.467385 -143.534743) (xy 180.406274 -143.518373)
			(xy 180.347823 -143.494166) (xy 180.293032 -143.462537) (xy 180.242839 -143.424026) (xy 180.198102 -143.379293)
			(xy 180.159586 -143.329103) (xy 180.127952 -143.274314) (xy 180.10374 -143.215866) (xy 180.087365 -143.154756)
			(xy 180.079107 -143.092033) (xy 177.934112 -143.092033) (xy 177.934112 -150.778464) (xy 178.2318 -151.075898)
			(xy 179.561236 -151.075898)
		)
		(stroke
			(width 0)
			(type solid)
		)
		(fill yes)
		(layer "F.Cu")
		(net "P3V3_NODE1")
	)
	(gr_poly
		(pts
			(xy 106.167428 -116.632736)
			(arc
				(start 108.393484 -116.632736)
				(mid 108.483287 -116.595539)
				(end 108.520484 -116.505736)
			)
			(xy 108.520484 -116.253768)
			(arc
				(start 108.565696 -116.253768)
				(mid 108.610455 -116.245619)
				(end 108.649516 -116.222272)
			)
			(arc
				(start 108.649516 -116.222272)
				(mid 108.901738 -116.126944)
				(end 109.15396 -116.222272)
			)
			(arc
				(start 109.15396 -116.222272)
				(mid 109.192997 -116.245685)
				(end 109.23778 -116.253768)
			)
			(xy 109.282992 -116.253768)
			(arc
				(start 109.282992 -116.505736)
				(mid 109.320189 -116.595539)
				(end 109.409992 -116.632736)
			)
			(xy 113.71326 -116.632736) (xy 113.997486 -116.34851) (xy 113.997486 -104.696006) (xy 113.096548 -103.795068)
			(xy 105.9561 -103.795068) (xy 105.50652 -104.244648) (xy 105.50652 -113.614454) (xy 105.085896 -114.035078)
			(xy 103.85552 -114.035078) (xy 103.65994 -114.230658) (xy 103.65994 -117.60835) (xy 103.85552 -117.80393)
			(xy 104.996234 -117.80393)
		)
		(stroke
			(width 0)
			(type solid)
		)
		(fill yes)
		(layer "F.Cu")
		(net "PV_VCCP_NODE1")
	)
	(gr_poly
		(pts
			(arc
				(start 66.595244 -77.827886)
				(mid 66.77779 -77.750501)
				(end 66.84899 -77.565504)
			)
			(xy 66.848736 -77.555598) (xy 66.848736 -77.42428) (xy 66.8782 -77.39507) (xy 66.8782 -77.221588)
			(arc
				(start 66.858896 -77.1906)
				(mid 66.844575 -77.1652)
				(end 66.832226 -77.138784)
			)
			(arc
				(start 66.832226 -77.138784)
				(mid 66.764068 -77.071265)
				(end 66.668142 -77.070712)
			)
			(arc
				(start 66.668142 -77.070712)
				(mid 66.588567 -77.092857)
				(end 66.50609 -77.097382)
			)
			(arc
				(start 66.50609 -77.097382)
				(mid 66.417599 -77.127161)
				(end 66.373248 -77.209396)
			)
			(arc
				(start 66.373248 -77.209396)
				(mid 66.282764 -77.414894)
				(end 66.092324 -77.533754)
			)
			(xy 66.059558 -77.542644)
			(arc
				(start 65.990978 -77.61097)
				(mid 65.963339 -77.749514)
				(end 66.080894 -77.827886)
			)
		)
		(stroke
			(width 0)
			(type solid)
		)
		(fill yes)
		(layer "F.Cu")
		(net "GND")
	)
	(gr_poly
		(pts
			(arc
				(start 56.616092 -74.275442)
				(mid 56.734588 -74.342371)
				(end 56.8706 -74.338434)
			)
			(arc
				(start 56.966358 -74.242676)
				(mid 56.982564 -74.201798)
				(end 56.983884 -74.15784)
			)
			(xy 56.617108 -73.79081)
			(arc
				(start 56.599836 -73.78192)
				(mid 56.544462 -73.747283)
				(end 56.494934 -73.704704)
			)
			(xy 55.795926 -73.005696)
			(arc
				(start 55.66029 -73.005696)
				(mid 55.574034 -73.044804)
				(end 55.538878 -73.132696)
			)
			(xy 55.538878 -73.166478)
			(arc
				(start 55.555642 -73.195942)
				(mid 55.604788 -73.336314)
				(end 55.6006 -73.484994)
			)
			(arc
				(start 55.6006 -73.484994)
				(mid 55.648746 -73.695031)
				(end 55.840884 -73.792588)
			)
			(arc
				(start 56.000396 -73.792588)
				(mid 56.212008 -73.851985)
				(end 56.361838 -74.012806)
			)
			(xy 56.370982 -74.030332) (xy 56.431688 -74.091292) (xy 56.606186 -74.26579)
		)
		(stroke
			(width 0)
			(type solid)
		)
		(fill yes)
		(layer "F.Cu")
		(net "GND")
	)
	(gr_poly
		(pts
			(arc
				(start 116.429028 -45.628052)
				(mid 116.518831 -45.590855)
				(end 116.556028 -45.501052)
			)
			(xy 116.556028 -44.219622) (xy 116.73459 -44.04106)
			(arc
				(start 118.026434 -44.04106)
				(mid 118.116237 -44.003863)
				(end 118.153434 -43.91406)
			)
			(xy 118.153434 -41.008554) (xy 117.897148 -40.752268) (xy 116.64188 -40.752268) (xy 116.64188 -39.074852)
			(arc
				(start 118.026434 -39.074852)
				(mid 118.116237 -39.037655)
				(end 118.153434 -38.947852)
			)
			(arc
				(start 118.153434 -38.897052)
				(mid 118.116237 -38.807249)
				(end 118.026434 -38.770052)
			)
			(xy 112.89411 -38.770052) (xy 112.819434 -38.844728)
			(arc
				(start 112.819434 -43.882056)
				(mid 112.856631 -43.971859)
				(end 112.946434 -44.009056)
			)
			(xy 114.180366 -44.009056) (xy 114.26063 -44.08932) (xy 114.420396 -44.248832)
			(arc
				(start 114.420396 -45.501052)
				(mid 114.457593 -45.590855)
				(end 114.547396 -45.628052)
			)
		)
		(stroke
			(width 0)
			(type solid)
		)
		(fill yes)
		(layer "F.Cu")
		(net "GND")
	)
	(gr_poly
		(pts
			(arc
				(start 60.922916 -79.346552)
				(mid 61.012742 -79.383796)
				(end 61.102494 -79.346552)
			)
			(arc
				(start 61.129672 -79.319374)
				(mid 61.166811 -79.229622)
				(end 61.129672 -79.139796)
			)
			(arc
				(start 60.895484 -78.905354)
				(mid 60.769559 -78.576232)
				(end 60.930536 -78.262734)
			)
			(arc
				(start 60.930536 -78.262734)
				(mid 60.977981 -78.167905)
				(end 60.936886 -78.070202)
			)
			(arc
				(start 60.936886 -78.070202)
				(mid 60.91779 -78.051417)
				(end 60.900056 -78.03134)
			)
			(arc
				(start 60.900056 -78.03134)
				(mid 60.800285 -77.985093)
				(end 60.701936 -78.034134)
			)
			(arc
				(start 60.701936 -78.034134)
				(mid 60.686859 -78.052268)
				(end 60.670694 -78.06944)
			)
			(xy 60.270644 -78.46949) (xy 60.253118 -78.485746) (xy 60.25007 -78.48854)
			(arc
				(start 60.247276 -78.491334)
				(mid 60.210032 -78.58116)
				(end 60.247276 -78.670912)
			)
		)
		(stroke
			(width 0)
			(type solid)
		)
		(fill yes)
		(layer "F.Cu")
		(net "GND")
	)
	(gr_poly
		(pts
			(arc
				(start 81.6864 -98.334322)
				(mid 81.708051 -98.332467)
				(end 81.729072 -98.326956)
			)
			(xy 82.182462 -98.326956) (xy 82.203036 -98.334322) (xy 82.413856 -98.334322) (xy 82.463894 -98.284284)
			(xy 82.463894 -97.88398) (xy 82.63128 -97.71634) (xy 82.63128 -97.695512) (xy 82.652616 -97.695512)
			(xy 83.360514 -96.98736) (xy 83.360514 -96.275144) (xy 82.890106 -95.804736) (xy 82.890106 -94.960694)
			(xy 82.883756 -94.954344) (xy 82.883756 -92.070428) (xy 82.824574 -92.011246) (xy 80.576928 -92.011246)
			(xy 80.467708 -92.120466) (xy 80.467708 -92.384118) (xy 80.482948 -92.399358)
			(arc
				(start 80.482948 -93.384624)
				(mid 80.47986 -93.440074)
				(end 80.470756 -93.49486)
			)
			(xy 80.467708 -93.508322) (xy 80.467708 -96.108266) (xy 80.530446 -96.179894)
			(arc
				(start 80.57769 -96.186498)
				(mid 80.633382 -96.197371)
				(end 80.687418 -96.214692)
			)
			(arc
				(start 80.687418 -96.214692)
				(mid 80.734944 -96.236056)
				(end 80.779874 -96.262444)
			)
			(xy 80.811878 -96.28378) (xy 80.869028 -96.28378) (xy 80.869028 -96.33585)
			(arc
				(start 80.895444 -96.37014)
				(mid 80.995918 -96.665034)
				(end 80.895444 -96.959928)
			)
			(xy 80.869028 -96.994218) (xy 80.869028 -97.046288)
			(arc
				(start 80.86725 -97.046288)
				(mid 80.818566 -97.05599)
				(end 80.777334 -97.083626)
			)
			(xy 80.68564 -97.175574) (xy 80.68564 -97.869248) (xy 80.605122 -97.949512)
			(arc
				(start 80.59166 -97.962974)
				(mid 80.556352 -98.052205)
				(end 80.593438 -98.140774)
			)
			(xy 80.786986 -98.334322)
		)
		(stroke
			(width 0)
			(type solid)
		)
		(fill yes)
		(layer "F.Cu")
		(net "P3V3_SUS_NODE1")
	)
	(gr_poly
		(pts
			(xy 91.516708 -77.831188) (xy 91.516708 -75.50277) (xy 91.05138 -75.037442) (xy 87.92464 -75.037442)
			(xy 87.809578 -75.152504) (xy 87.809578 -75.512676) (xy 87.914988 -75.618086) (xy 87.914988 -77.598524)
			(xy 88.08974 -77.773276)
			(arc
				(start 89.120218 -77.773276)
				(mid 89.345274 -77.814252)
				(end 89.51214 -77.657706)
			)
			(arc
				(start 89.51214 -77.657706)
				(mid 89.853469 -77.392514)
				(end 90.22334 -77.616304)
			)
			(arc
				(start 90.22334 -77.616304)
				(mid 90.155234 -78.033233)
				(end 89.74455 -78.13167)
			)
			(arc
				(start 89.74455 -78.13167)
				(mid 89.511906 -78.162093)
				(end 89.403428 -78.370176)
			)
			(xy 89.403428 -78.780132) (xy 89.407492 -78.784196) (xy 90.5637 -78.784196)
		)
		(stroke
			(width 0)
			(type solid)
		)
		(fill yes)
		(layer "F.Cu")
		(net "GND")
	)
	(gr_poly
		(pts
			(arc
				(start 53.94452 -73.985374)
				(mid 54.000146 -73.998191)
				(end 54.055772 -73.985374)
			)
			(xy 54.09819 -73.964546) (xy 54.114954 -73.94575) (xy 54.130194 -73.929748) (xy 54.130448 -73.929494)
			(xy 54.530498 -73.529444) (xy 54.542182 -73.518268) (xy 54.548024 -73.512934) (xy 54.551072 -73.510394)
			(arc
				(start 54.553866 -73.5076)
				(mid 54.590931 -73.417848)
				(end 54.553866 -73.328022)
			)
			(xy 54.548278 -73.322434) (xy 54.543452 -73.317608) (xy 54.512718 -73.28662) (xy 54.509162 -73.283064)
			(xy 54.508654 -73.282556)
			(arc
				(start 54.507892 -73.282048)
				(mid 54.41814 -73.244983)
				(end 54.328314 -73.282048)
			)
			(arc
				(start 54.305708 -73.304654)
				(mid 53.987748 -73.431044)
				(end 53.677566 -73.28662)
			)
			(arc
				(start 53.677566 -73.28662)
				(mid 53.585521 -73.244226)
				(end 53.491638 -73.282556)
			)
			(xy 53.47589 -73.29805)
			(arc
				(start 53.455824 -73.315576)
				(mid 53.411632 -73.386803)
				(end 53.421534 -73.470008)
			)
			(xy 53.434742 -73.497186) (xy 53.453538 -73.51395) (xy 53.46954 -73.52919) (xy 53.469794 -73.529444)
			(xy 53.869844 -73.929494) (xy 53.870098 -73.929748) (xy 53.885338 -73.94575) (xy 53.902102 -73.964546)
		)
		(stroke
			(width 0)
			(type solid)
		)
		(fill yes)
		(layer "F.Cu")
		(net "GND")
	)
	(gr_poly
		(pts
			(xy 167.7543 -85.753702) (xy 167.7543 -84.538058) (xy 166.93769 -83.721448) (xy 163.46932 -83.721448)
			(xy 162.97656 -83.228688) (xy 162.97656 -80.108298) (xy 162.86734 -79.999078) (xy 162.69589 -79.827628)
			(xy 162.318954 -79.827628) (xy 162.307524 -79.816452) (xy 162.30727 -79.816452) (xy 162.073336 -79.582264)
			(xy 162.073336 -79.581756) (xy 162.06089 -79.56931) (xy 162.06089 -77.477366) (xy 162.07232 -77.465936)
			(xy 162.07232 -77.258164) (xy 162.058604 -77.244448) (xy 161.070036 -77.244448) (xy 160.973008 -77.244448)
			(xy 160.967674 -77.249782) (xy 160.744662 -77.249782) (xy 160.7439 -77.24902) (xy 160.031684 -77.24902)
			(xy 159.724598 -76.941934) (xy 158.973012 -76.941934) (xy 158.850584 -77.064362) (xy 158.850584 -77.146404)
			(xy 155.162504 -77.146404) (xy 154.38628 -77.922628) (xy 154.38628 -84.478622)
			(arc
				(start 155.144216 -85.236558)
				(mid 155.324153 -85.310941)
				(end 155.50388 -85.23605)
			)
			(arc
				(start 155.50388 -85.23605)
				(mid 156.058394 -85.124375)
				(end 156.373068 -85.594444)
			)
			(arc
				(start 156.373068 -85.686392)
				(mid 156.410265 -85.776195)
				(end 156.500068 -85.813392)
			)
			(xy 163.490656 -85.813392) (xy 164.04844 -86.371176) (xy 167.136826 -86.371176)
		)
		(stroke
			(width 0)
			(type solid)
		)
		(fill yes)
		(layer "F.Cu")
		(net "P1V0_NODE1")
	)
	(gr_poly
		(pts
			(arc
				(start 63.392812 -83.870038)
				(mid 63.421435 -83.863591)
				(end 63.45047 -83.85937)
			)
			(arc
				(start 63.45047 -83.85937)
				(mid 63.470002 -83.857849)
				(end 63.489586 -83.857338)
			)
			(xy 63.819532 -83.857338) (xy 63.961772 -83.715098)
			(arc
				(start 63.961772 -83.679792)
				(mid 63.885039 -83.495114)
				(end 63.939166 -83.302602)
			)
			(xy 63.961772 -83.269836) (xy 63.961772 -82.921856)
			(arc
				(start 63.939166 -82.88909)
				(mid 63.884515 -82.714846)
				(end 63.939166 -82.540602)
			)
			(xy 63.961772 -82.507836) (xy 63.961772 -82.351626) (xy 63.919862 -82.258662)
			(arc
				(start 63.903098 -82.241898)
				(mid 63.822043 -82.127421)
				(end 63.784734 -81.992216)
			)
			(xy 63.780416 -81.947004) (xy 63.494412 -81.661) (xy 63.494412 -81.158588) (xy 63.42634 -81.090516)
			(xy 63.152528 -81.090516) (xy 63.149988 -81.087976) (xy 62.752224 -81.087976) (xy 62.691772 -81.148428)
			(xy 62.691772 -82.038698) (xy 62.693042 -82.039968) (xy 62.693042 -82.725768) (xy 62.81547 -82.850228)
			(arc
				(start 62.859158 -82.855816)
				(mid 62.961454 -82.883418)
				(end 63.052198 -82.938112)
			)
			(arc
				(start 63.052198 -82.938112)
				(mid 63.175268 -83.118686)
				(end 63.178944 -83.337146)
			)
			(xy 63.174372 -83.35391) (xy 63.174372 -83.740498)
			(arc
				(start 63.270892 -83.837018)
				(mid 63.327458 -83.869694)
				(end 63.392812 -83.870038)
			)
		)
		(stroke
			(width 0)
			(type solid)
		)
		(fill yes)
		(layer "F.Cu")
		(net "P3V3_RTC_NODE1")
	)
	(gr_poly
		(pts
			(xy 46.4947 -191.34074) (xy 46.4947 -190.371984) (xy 46.473872 -190.351156) (xy 46.473872 -188.48959)
			(xy 46.081442 -188.09716) (xy 46.081442 -186.765438) (xy 45.988732 -186.672728) (xy 43.274488 -186.672728)
			(xy 43.21429 -186.61253) (xy 43.21429 -185.846974) (xy 42.70756 -185.340244) (xy 38.7096 -185.340244)
			(xy 38.692947 -185.340739) (xy 38.660777 -185.349361) (xy 38.631936 -185.366017) (xy 38.60839 -185.389571)
			(xy 38.591744 -185.418418) (xy 38.583133 -185.450591) (xy 38.5826 -185.467244) (xy 38.5826 -186.031124)
			(xy 38.49116 -186.122564) (xy 36.481258 -186.122564) (xy 35.729926 -185.371232) (xy 35.46602 -185.371232)
			(xy 35.401504 -185.435748) (xy 35.401504 -187.782708) (xy 44.809662 -187.782708) (xy 44.813733 -187.727086)
			(xy 44.825859 -187.672649) (xy 44.845782 -187.620558) (xy 44.873078 -187.571923) (xy 44.907164 -187.52778)
			(xy 44.947313 -187.489071) (xy 44.992671 -187.45662) (xy 45.042271 -187.431119) (xy 45.095055 -187.413112)
			(xy 45.149898 -187.402982) (xy 45.205632 -187.400945) (xy 45.261069 -187.407045) (xy 45.315026 -187.421151)
			(xy 45.366355 -187.442963) (xy 45.413961 -187.472017) (xy 45.456829 -187.507692) (xy 45.494046 -187.549229)
			(xy 45.524819 -187.595742) (xy 45.548491 -187.646239) (xy 45.564559 -187.699646) (xy 45.572679 -187.754822)
			(xy 45.573188 -187.782708) (xy 45.572679 -187.810594) (xy 45.564559 -187.86577) (xy 45.548491 -187.919177)
			(xy 45.524819 -187.969674) (xy 45.494046 -188.016187) (xy 45.456829 -188.057724) (xy 45.413961 -188.093399)
			(xy 45.366355 -188.122453) (xy 45.315026 -188.144265) (xy 45.261069 -188.158371) (xy 45.205632 -188.164471)
			(xy 45.149898 -188.162434) (xy 45.095055 -188.152304) (xy 45.042271 -188.134297) (xy 44.992671 -188.108796)
			(xy 44.947313 -188.076345) (xy 44.907164 -188.037636) (xy 44.873078 -187.993493) (xy 44.845782 -187.944858)
			(xy 44.825859 -187.892767) (xy 44.813733 -187.83833) (xy 44.809662 -187.782708) (xy 35.401504 -187.782708)
			(xy 35.401504 -188.375036) (xy 35.397694 -188.378846) (xy 35.397694 -188.845952) (xy 35.309302 -188.934344)
			(xy 35.309302 -189.464696) (xy 35.317684 -189.48654) (xy 35.328345 -189.515661) (xy 35.343322 -189.575841)
			(xy 35.350866 -189.637396) (xy 35.350866 -189.699412) (xy 35.343321 -189.760966) (xy 35.328343 -189.821146)
			(xy 35.317684 -189.850268) (xy 35.309302 -189.872112) (xy 35.309302 -191.334898) (xy 35.85464 -191.880236)
			(xy 45.482256 -191.880236) (xy 45.955204 -191.880236)
		)
		(stroke
			(width 0)
			(type solid)
		)
		(fill yes)
		(layer "F.Cu")
		(net "P12V_PDB")
	)
	(gr_poly
		(pts
			(arc
				(start 53.111146 -72.334882)
				(mid 53.197768 -72.371663)
				(end 53.285898 -72.338692)
			)
			(xy 53.292248 -72.333104)
			(arc
				(start 53.296566 -72.328024)
				(mid 53.587804 -72.192493)
				(end 53.886608 -72.310498)
			)
			(xy 53.887624 -72.311514) (xy 53.89245 -72.316086) (xy 53.929788 -72.353424) (xy 54.03469 -72.353424)
			(xy 54.114192 -72.273922) (xy 54.219856 -72.168004) (xy 54.3941 -71.99376)
			(arc
				(start 54.477412 -71.99376)
				(mid 54.594779 -71.915278)
				(end 54.567074 -71.776844)
			)
			(arc
				(start 54.494684 -71.704454)
				(mid 54.426643 -71.61605)
				(end 54.383432 -71.513192)
			)
			(xy 54.378606 -71.493634) (xy 54.371494 -71.462646) (xy 54.298342 -71.37781)
			(arc
				(start 54.2671 -71.36638)
				(mid 54.190468 -71.328651)
				(end 54.123844 -71.275194)
			)
			(xy 54.008274 -71.159624) (xy 53.996336 -71.159624) (xy 53.766212 -71.389748) (xy 53.748686 -71.389748)
			(xy 53.570886 -71.567548)
			(arc
				(start 53.561996 -71.58482)
				(mid 53.549826 -71.606676)
				(end 53.536342 -71.627746)
			)
			(arc
				(start 53.536342 -71.627746)
				(mid 53.441748 -71.726076)
				(end 53.319934 -71.787512)
			)
			(xy 53.289962 -71.796656) (xy 53.198014 -71.888858)
			(arc
				(start 53.18887 -71.91883)
				(mid 53.142999 -72.017738)
				(end 53.072538 -72.100948)
			)
			(xy 53.053234 -72.11822)
			(arc
				(start 53.040026 -72.146414)
				(mid 53.02998 -72.222324)
				(end 53.065426 -72.290178)
			)
			(xy 53.070252 -72.295004) (xy 53.072538 -72.297036) (xy 53.087016 -72.311006) (xy 53.087524 -72.311514)
		)
		(stroke
			(width 0)
			(type solid)
		)
		(fill yes)
		(layer "F.Cu")
		(net "GND")
	)
	(gr_poly
		(pts
			(arc
				(start 13.21054 -207.26146)
				(mid 13.300343 -207.224263)
				(end 13.33754 -207.13446)
			)
			(xy 13.33754 -203.100178) (xy 13.709904 -202.728068) (xy 13.709904 -200.784968) (xy 13.97127 -200.523602)
			(arc
				(start 13.979652 -200.488296)
				(mid 14.620712 -200.305706)
				(end 14.438122 -200.946766)
			)
			(xy 14.402816 -200.955148) (xy 14.320012 -201.037952) (xy 14.320012 -202.740768) (xy 14.64564 -203.066396)
			(arc
				(start 14.64564 -207.13446)
				(mid 14.682837 -207.224263)
				(end 14.77264 -207.26146)
			)
			(arc
				(start 15.25524 -207.26146)
				(mid 15.345043 -207.224263)
				(end 15.38224 -207.13446)
			)
			(xy 15.38224 -203.077318) (xy 15.4051 -203.054458) (xy 15.619476 -203.054458) (xy 15.64894 -203.083922)
			(xy 15.64894 -207.179418) (xy 15.72768 -207.258158)
			(arc
				(start 16.24838 -207.258158)
				(mid 16.338183 -207.220961)
				(end 16.37538 -207.131158)
			)
			(xy 16.37538 -202.910694) (xy 16.61414 -202.671934) (xy 16.61414 -201.50328) (xy 16.709644 -201.407776)
			(xy 16.709644 -200.174352) (xy 17.78762 -199.09663) (xy 17.78762 -196.872352) (xy 17.458436 -196.543168)
			(xy 15.13586 -196.543168) (xy 12.958572 -198.720456) (xy 12.958572 -201.616818) (xy 12.657328 -201.918062)
			(xy 12.657328 -203.095352) (xy 12.64412 -203.10856) (xy 12.64412 -207.24495) (xy 12.66063 -207.26146)
		)
		(stroke
			(width 0)
			(type solid)
		)
		(fill yes)
		(layer "F.Cu")
		(net "P12V_PDB")
	)
	(gr_poly
		(pts
			(arc
				(start 62.718696 -99.959922)
				(mid 62.808499 -99.922725)
				(end 62.845696 -99.832922)
			)
			(xy 62.845696 -99.346766) (xy 62.91453 -99.277932) (xy 63.102236 -99.277932) (xy 63.142876 -99.318572)
			(arc
				(start 63.142876 -99.832922)
				(mid 63.180073 -99.922725)
				(end 63.269876 -99.959922)
			)
			(arc
				(start 63.360046 -99.959922)
				(mid 63.449849 -99.922725)
				(end 63.487046 -99.832922)
			)
			(xy 63.487046 -99.437444) (xy 63.558928 -99.365562) (xy 63.752984 -99.365562) (xy 63.790576 -99.403154)
			(arc
				(start 63.790576 -99.832922)
				(mid 63.827773 -99.922725)
				(end 63.917576 -99.959922)
			)
			(xy 64.103504 -99.959922) (xy 64.19723 -99.866196) (xy 64.19723 -98.314002) (xy 64.066166 -98.182938)
			(xy 63.847726 -98.182938)
			(arc
				(start 63.827152 -98.19005)
				(mid 63.667894 -98.217064)
				(end 63.508636 -98.19005)
			)
			(xy 63.488062 -98.182938) (xy 63.102236 -98.182938) (xy 63.020956 -98.101658) (xy 63.020956 -97.770188)
			(xy 62.83452 -97.583752) (xy 62.503304 -97.583752) (xy 62.495176 -97.575878) (xy 62.019688 -97.575878)
			(xy 61.838332 -97.757234)
			(arc
				(start 61.838332 -98.034348)
				(mid 61.853459 -98.09446)
				(end 61.895228 -98.140266)
			)
			(xy 61.926978 -98.161348) (xy 61.984128 -98.161348)
			(arc
				(start 61.984128 -98.216466)
				(mid 62.010226 -98.247308)
				(end 62.033658 -98.28022)
			)
			(xy 62.041024 -98.29165) (xy 62.182502 -98.433128) (xy 62.182502 -98.654362) (xy 62.443868 -98.915474)
			(arc
				(start 62.443868 -99.28479)
				(mid 62.410473 -99.461035)
				(end 62.31509 -99.612958)
			)
			(arc
				(start 62.31509 -99.612958)
				(mid 62.28119 -99.701743)
				(end 62.318392 -99.789234)
			)
			(xy 62.48908 -99.959922)
		)
		(stroke
			(width 0)
			(type solid)
		)
		(fill yes)
		(layer "F.Cu")
		(net "P1V8_SUS_NODE1")
	)
	(gr_poly
		(pts
			(xy 44.045378 -180.589936) (xy 44.045378 -177.102262) (xy 43.866308 -176.923192) (xy 43.866308 -175.922686)
			(xy 43.45686 -175.513238) (xy 43.45686 -174.427642) (xy 42.434002 -173.404784) (xy 42.434002 -170.909488)
			(xy 42.212006 -170.687492) (xy 41.88206 -170.687492) (xy 41.609772 -170.415204) (xy 41.48074 -170.415204)
			(xy 41.48074 -170.286172) (xy 41.02862 -169.834052) (xy 41.02862 -169.022268) (xy 38.83787 -166.831518)
			(xy 35.514026 -166.831518) (xy 35.2044 -167.141144) (xy 35.2044 -168.652698)
			(arc
				(start 36.372292 -169.82059)
				(mid 36.462118 -169.857909)
				(end 36.55187 -169.82059)
			)
			(xy 36.902898 -169.469816)
			(arc
				(start 37.6428 -169.469816)
				(mid 38.151054 -169.97807)
				(end 37.6428 -170.486324)
			)
			(xy 37.32403 -170.486324) (xy 37.221668 -170.58894) (xy 37.221668 -170.687492) (xy 37.156644 -170.752516)
			(xy 37.156644 -173.156626) (xy 37.35197 -173.351952) (xy 37.858446 -173.351952) (xy 38.13429 -173.627796)
			(xy 38.13429 -175.479202) (xy 38.344094 -175.689006) (xy 38.903402 -175.689006) (xy 38.94455 -175.730154)
			(xy 41.050464 -175.730154) (xy 41.34866 -176.02835)
			(arc
				(start 41.34866 -179.462176)
				(mid 41.385857 -179.551979)
				(end 41.47566 -179.589176)
			)
			(xy 43.278806 -179.589176) (xy 43.551602 -179.861972) (xy 43.551602 -180.34381) (xy 43.555158 -180.358288)
			(arc
				(start 43.563032 -180.398674)
				(mid 43.567765 -180.439952)
				(end 43.569128 -180.481478)
			)
			(arc
				(start 43.569128 -180.482494)
				(mid 43.606325 -180.572297)
				(end 43.696128 -180.609494)
			)
			(xy 44.02582 -180.609494)
		)
		(stroke
			(width 0)
			(type solid)
		)
		(fill yes)
		(layer "F.Cu")
		(net "P12V_AUX")
	)
	(gr_poly
		(pts
			(arc
				(start 66.877438 -76.567284)
				(mid 66.945596 -76.634803)
				(end 67.041522 -76.635356)
			)
			(arc
				(start 67.041522 -76.635356)
				(mid 67.060901 -76.62822)
				(end 67.080638 -76.622148)
			)
			(arc
				(start 67.080638 -76.622148)
				(mid 67.229225 -76.509635)
				(end 67.260978 -76.325984)
			)
			(arc
				(start 67.260978 -76.325984)
				(mid 67.262559 -76.205045)
				(end 67.31508 -76.096114)
			)
			(arc
				(start 67.31508 -76.096114)
				(mid 67.369463 -75.931945)
				(end 67.30619 -75.770994)
			)
			(arc
				(start 67.30619 -75.770994)
				(mid 67.249563 -75.677135)
				(end 67.229736 -75.569318)
			)
			(xy 67.229736 -75.43292)
			(arc
				(start 67.308984 -75.353926)
				(mid 67.382879 -75.158601)
				(end 67.285362 -74.973942)
			)
			(arc
				(start 67.277996 -74.9681)
				(mid 67.131521 -74.910982)
				(end 66.979546 -74.951082)
			)
			(arc
				(start 66.979546 -74.951082)
				(mid 66.930219 -74.9778)
				(end 66.877438 -74.996802)
			)
			(arc
				(start 66.877438 -74.996802)
				(mid 66.803834 -75.051975)
				(end 66.78676 -75.142344)
			)
			(arc
				(start 66.78676 -75.142344)
				(mid 66.73119 -75.420728)
				(end 66.498724 -75.583542)
			)
			(xy 66.463418 -75.591924)
			(arc
				(start 66.242692 -75.81265)
				(mid 66.205448 -75.902476)
				(end 66.242692 -75.992228)
			)
			(xy 66.589148 -76.33843)
			(arc
				(start 66.622422 -76.347066)
				(mid 66.775519 -76.427524)
				(end 66.877438 -76.567284)
			)
		)
		(stroke
			(width 0)
			(type solid)
		)
		(fill yes)
		(layer "F.Cu")
		(net "GND")
	)
	(gr_poly
		(pts
			(xy 83.26882 -19.389598) (xy 83.26882 -18.030952) (xy 83.05292 -17.815052) (xy 67.525138 -17.815052)
			(xy 67.23888 -17.528794) (xy 67.23888 -14.155674) (xy 66.34226 -13.259054) (xy 66.34226 -10.22604)
			(xy 66.13398 -10.01776) (xy 65.75298 -10.01776) (xy 65.43548 -9.70026) (xy 65.43548 -8.503666) (xy 64.39916 -7.467346)
			(xy 64.043052 -7.111238) (xy 53.54955 -7.111238) (xy 51.5493 -9.111488) (xy 51.5493 -13.170154) (xy 52.117752 -13.738606)
			(xy 55.201312 -13.738606) (xy 55.721583 -14.258877) (xy 65.022843 -14.258877) (xy 65.026155 -14.20323)
			(xy 65.037527 -14.148656) (xy 65.056716 -14.096317) (xy 65.083316 -14.047326) (xy 65.116759 -14.002726)
			(xy 65.156334 -13.963465) (xy 65.2012 -13.930379) (xy 65.250402 -13.904171) (xy 65.276476 -13.894308)
			(xy 65.258076 -13.873369) (xy 65.226855 -13.827194) (xy 65.202683 -13.776968) (xy 65.186074 -13.723761)
			(xy 65.177383 -13.668703) (xy 65.176793 -13.612967) (xy 65.184317 -13.557737) (xy 65.199795 -13.50419)
			(xy 65.222898 -13.453464) (xy 65.253134 -13.406638) (xy 65.289861 -13.364709) (xy 65.332296 -13.328568)
			(xy 65.379537 -13.298985) (xy 65.430579 -13.276588) (xy 65.484336 -13.261855) (xy 65.539664 -13.255098)
			(xy 65.595387 -13.256462) (xy 65.650319 -13.265918) (xy 65.703291 -13.283263) (xy 65.753176 -13.30813)
			(xy 65.798913 -13.339989) (xy 65.839529 -13.378162) (xy 65.87416 -13.421838) (xy 65.90207 -13.470087)
			(xy 65.922663 -13.521883) (xy 65.935503 -13.576123) (xy 65.940317 -13.631654) (xy 65.937001 -13.687295)
			(xy 65.925626 -13.741861) (xy 65.906434 -13.794193) (xy 65.879834 -13.843176) (xy 65.846392 -13.887768)
			(xy 65.806818 -13.927022) (xy 65.761956 -13.960101) (xy 65.712758 -13.986302) (xy 65.686686 -13.996162)
			(xy 65.705127 -14.017068) (xy 65.736358 -14.063245) (xy 65.760538 -14.113474) (xy 65.777155 -14.166686)
			(xy 65.785854 -14.221749) (xy 65.786451 -14.277492) (xy 65.778932 -14.332728) (xy 65.763459 -14.386284)
			(xy 65.740358 -14.437018) (xy 65.710124 -14.483853) (xy 65.673398 -14.525791) (xy 65.630961 -14.561941)
			(xy 65.583718 -14.591533) (xy 65.532672 -14.613937) (xy 65.47891 -14.628678) (xy 65.423576 -14.635441)
			(xy 65.367846 -14.634082) (xy 65.312907 -14.624631) (xy 65.259927 -14.607289) (xy 65.210034 -14.582424)
			(xy 65.164288 -14.550565) (xy 65.123664 -14.512391) (xy 65.089025 -14.468713) (xy 65.061108 -14.420461)
			(xy 65.040507 -14.368661) (xy 65.027661 -14.314415) (xy 65.022843 -14.258877) (xy 55.721583 -14.258877)
			(xy 56.27624 -14.813534) (xy 64.893444 -14.813534) (xy 64.896492 -14.810232) (xy 64.896492 -14.826234)
			(xy 65.29578 -15.225522) (xy 65.29578 -18.659602) (xy 65.42278 -18.786602) (xy 66.72072 -18.786602)
			(xy 67.424554 -19.490436) (xy 67.52082 -19.586702) (xy 83.071716 -19.586702)
		)
		(stroke
			(width 0)
			(type solid)
		)
		(fill yes)
		(layer "F.Cu")
		(net "PV_VDDR_NODE1")
	)
	(gr_poly
		(pts
			(arc
				(start 71.910194 -73.665842)
				(mid 71.982402 -73.722539)
				(end 72.074024 -73.71588)
			)
			(arc
				(start 72.074024 -73.71588)
				(mid 72.118317 -73.698898)
				(end 72.164702 -73.688956)
			)
			(arc
				(start 72.164702 -73.688956)
				(mid 72.243467 -73.6468)
				(end 72.274938 -73.563226)
			)
			(xy 72.274684 -72.603106) (xy 72.297798 -72.580246)
			(arc
				(start 72.30618 -72.54494)
				(mid 72.352829 -72.431768)
				(end 72.432926 -72.3392)
			)
			(arc
				(start 72.432926 -72.3392)
				(mid 72.4747 -72.272587)
				(end 72.469248 -72.194166)
			)
			(arc
				(start 72.469248 -72.194166)
				(mid 72.447036 -72.078781)
				(end 72.47001 -71.963534)
			)
			(arc
				(start 72.47001 -71.963534)
				(mid 72.477804 -71.792228)
				(end 72.375014 -71.654924)
			)
			(arc
				(start 72.375014 -71.654924)
				(mid 72.250383 -71.486522)
				(end 72.263762 -71.27748)
			)
			(arc
				(start 72.263762 -71.27748)
				(mid 72.272144 -71.203012)
				(end 72.237092 -71.136764)
			)
			(xy 72.12076 -71.020178)
			(arc
				(start 72.12076 -70.825868)
				(mid 72.083563 -70.736065)
				(end 71.99376 -70.698868)
			)
			(xy 71.961502 -70.698868) (xy 71.905114 -70.729348)
			(arc
				(start 71.887588 -70.756272)
				(mid 71.834799 -70.820121)
				(end 71.769478 -70.87108)
			)
			(arc
				(start 71.769478 -70.87108)
				(mid 71.725383 -70.917243)
				(end 71.70928 -70.97903)
			)
			(xy 71.70928 -71.664322)
			(arc
				(start 71.560944 -71.812658)
				(mid 71.543153 -71.829016)
				(end 71.524114 -71.8439)
			)
			(arc
				(start 71.524114 -71.8439)
				(mid 71.471568 -71.94677)
				(end 71.524114 -72.04964)
			)
			(arc
				(start 71.524114 -72.04964)
				(mid 71.616961 -72.158025)
				(end 71.650352 -72.296782)
			)
			(xy 71.650352 -72.988932) (xy 71.76008 -73.09866)
			(arc
				(start 71.76008 -73.453244)
				(mid 71.773352 -73.510021)
				(end 71.810626 -73.554844)
			)
			(arc
				(start 71.810626 -73.554844)
				(mid 71.865898 -73.605422)
				(end 71.910194 -73.665842)
			)
		)
		(stroke
			(width 0)
			(type solid)
		)
		(fill yes)
		(layer "F.Cu")
		(net "GND")
	)
	(gr_poly
		(pts
			(xy 152.966674 -25.921208) (xy 158.87954 -25.921208) (xy 159.59582 -25.204928) (xy 159.59582 -21.019262)
			(xy 158.9786 -20.402042) (xy 148.327872 -20.402042) (xy 147.583652 -21.146262) (xy 147.583652 -21.608343)
			(xy 149.326343 -21.608343) (xy 149.326343 -21.528477) (xy 149.334423 -21.449022) (xy 149.3505 -21.370792)
			(xy 149.374409 -21.29459) (xy 149.405904 -21.221197) (xy 149.444663 -21.151367) (xy 149.490287 -21.085817)
			(xy 149.542309 -21.025218) (xy 149.600194 -20.970194) (xy 149.66335 -20.921308) (xy 149.731127 -20.879062)
			(xy 149.80283 -20.84389) (xy 149.877724 -20.816153) (xy 149.955039 -20.796134) (xy 150.033983 -20.784041)
			(xy 150.113746 -20.779996) (xy 150.193509 -20.784041) (xy 150.272453 -20.796134) (xy 150.349768 -20.816153)
			(xy 150.424662 -20.84389) (xy 150.496365 -20.879062) (xy 150.564142 -20.921308) (xy 150.627298 -20.970194)
			(xy 150.685183 -21.025218) (xy 150.737205 -21.085817) (xy 150.782829 -21.151367) (xy 150.821588 -21.221197)
			(xy 150.853083 -21.29459) (xy 150.876992 -21.370792) (xy 150.893069 -21.449022) (xy 150.901149 -21.528477)
			(xy 150.901654 -21.56841) (xy 150.901149 -21.608343) (xy 155.589475 -21.608343) (xy 155.589475 -21.528477)
			(xy 155.597555 -21.449022) (xy 155.613632 -21.370792) (xy 155.637541 -21.29459) (xy 155.669036 -21.221197)
			(xy 155.707795 -21.151367) (xy 155.753419 -21.085817) (xy 155.805441 -21.025218) (xy 155.863326 -20.970194)
			(xy 155.926482 -20.921308) (xy 155.994259 -20.879062) (xy 156.065962 -20.84389) (xy 156.140856 -20.816153)
			(xy 156.218171 -20.796134) (xy 156.297115 -20.784041) (xy 156.376878 -20.779996) (xy 156.456641 -20.784041)
			(xy 156.535585 -20.796134) (xy 156.6129 -20.816153) (xy 156.687794 -20.84389) (xy 156.759497 -20.879062)
			(xy 156.827274 -20.921308) (xy 156.89043 -20.970194) (xy 156.948315 -21.025218) (xy 157.000337 -21.085817)
			(xy 157.045961 -21.151367) (xy 157.08472 -21.221197) (xy 157.116215 -21.29459) (xy 157.140124 -21.370792)
			(xy 157.156201 -21.449022) (xy 157.164281 -21.528477) (xy 157.164786 -21.56841) (xy 157.164281 -21.608343)
			(xy 157.156201 -21.687798) (xy 157.140124 -21.766028) (xy 157.116215 -21.84223) (xy 157.08472 -21.915623)
			(xy 157.045961 -21.985453) (xy 157.000337 -22.051003) (xy 156.948315 -22.111602) (xy 156.89043 -22.166626)
			(xy 156.827274 -22.215512) (xy 156.759497 -22.257758) (xy 156.687794 -22.29293) (xy 156.6129 -22.320667)
			(xy 156.535585 -22.340686) (xy 156.456641 -22.352779) (xy 156.376878 -22.356825) (xy 156.297115 -22.352779)
			(xy 156.218171 -22.340686) (xy 156.140856 -22.320667) (xy 156.065962 -22.29293) (xy 155.994259 -22.257758)
			(xy 155.926482 -22.215512) (xy 155.863326 -22.166626) (xy 155.805441 -22.111602) (xy 155.753419 -22.051003)
			(xy 155.707795 -21.985453) (xy 155.669036 -21.915623) (xy 155.637541 -21.84223) (xy 155.613632 -21.766028)
			(xy 155.597555 -21.687798) (xy 155.589475 -21.608343) (xy 150.901149 -21.608343) (xy 150.893069 -21.687798)
			(xy 150.876992 -21.766028) (xy 150.853083 -21.84223) (xy 150.821588 -21.915623) (xy 150.782829 -21.985453)
			(xy 150.737205 -22.051003) (xy 150.685183 -22.111602) (xy 150.627298 -22.166626) (xy 150.564142 -22.215512)
			(xy 150.496365 -22.257758) (xy 150.424662 -22.29293) (xy 150.349768 -22.320667) (xy 150.272453 -22.340686)
			(xy 150.193509 -22.352779) (xy 150.113746 -22.356825) (xy 150.033983 -22.352779) (xy 149.955039 -22.340686)
			(xy 149.877724 -22.320667) (xy 149.80283 -22.29293) (xy 149.731127 -22.257758) (xy 149.66335 -22.215512)
			(xy 149.600194 -22.166626) (xy 149.542309 -22.111602) (xy 149.490287 -22.051003) (xy 149.444663 -21.985453)
			(xy 149.405904 -21.915623) (xy 149.374409 -21.84223) (xy 149.3505 -21.766028) (xy 149.334423 -21.687798)
			(xy 149.326343 -21.608343) (xy 147.583652 -21.608343) (xy 147.583652 -23.533862) (xy 147.602702 -23.552912)
			(xy 147.602702 -26.120852) (xy 148.680932 -27.199082) (xy 151.6888 -27.199082)
		)
		(stroke
			(width 0)
			(type solid)
		)
		(fill yes)
		(layer "F.Cu")
		(net "P3V3_NODE1")
	)
	(gr_poly
		(pts
			(xy 34.29127 -151.875998) (xy 34.313988 -151.853961) (xy 34.363952 -151.815107) (xy 34.418353 -151.782757)
			(xy 34.47635 -151.757412) (xy 34.537045 -151.739463) (xy 34.599499 -151.729189) (xy 34.662745 -151.726749)
			(xy 34.725805 -151.73218) (xy 34.756852 -151.73833) (xy 34.772445 -151.741156) (xy 34.804099 -151.739912)
			(xy 34.834469 -151.730902) (xy 34.861682 -151.714685) (xy 34.873184 -151.703786) (xy 35.266376 -151.310594)
			(xy 38.87597 -151.310594) (xy 38.892734 -151.305768) (xy 38.90421 -151.302655) (xy 38.927468 -151.297695)
			(xy 38.939216 -151.295862) (xy 38.953292 -151.293865) (xy 38.981642 -151.291706) (xy 38.995858 -151.291544)
			(xy 40.0177 -151.291544) (xy 40.031917 -151.291689) (xy 40.060268 -151.293849) (xy 40.074342 -151.295862)
			(xy 40.086088 -151.297706) (xy 40.109346 -151.302665) (xy 40.120824 -151.305768) (xy 40.137588 -151.310594)
			(xy 40.44315 -151.310594) (xy 40.453056 -151.300688) (xy 40.453056 -151.123142) (xy 40.206422 -150.876508)
			(xy 40.206422 -150.257256) (xy 40.203628 -150.254716) (xy 40.203628 -149.456648) (xy 39.15664 -148.40966)
			(xy 39.15664 -147.748244) (xy 38.995096 -147.5867) (xy 28.346908 -147.5867) (xy 27.704542 -146.94408)
			(xy 27.704542 -145.308574) (xy 27.703996 -145.291926) (xy 27.695374 -145.259765) (xy 27.678725 -145.23093)
			(xy 27.655183 -145.207384) (xy 27.62635 -145.190732) (xy 27.59419 -145.182106) (xy 27.577542 -145.181574)
			(xy 26.293572 -145.181574) (xy 26.194512 -145.280634) (xy 26.194512 -147.261834) (xy 25.82545 -147.630896)
			(xy 24.34844 -147.630896) (xy 24.16556 -147.813776) (xy 24.16556 -148.36775) (xy 36.671502 -148.36775)
			(xy 36.675573 -148.312128) (xy 36.687699 -148.257691) (xy 36.707622 -148.2056) (xy 36.734918 -148.156965)
			(xy 36.769004 -148.112822) (xy 36.809153 -148.074113) (xy 36.854511 -148.041662) (xy 36.904111 -148.016161)
			(xy 36.956895 -147.998154) (xy 37.011738 -147.988024) (xy 37.067472 -147.985987) (xy 37.122909 -147.992087)
			(xy 37.176866 -148.006193) (xy 37.228195 -148.028005) (xy 37.275801 -148.057059) (xy 37.318669 -148.092734)
			(xy 37.355886 -148.134271) (xy 37.386659 -148.180784) (xy 37.410331 -148.231281) (xy 37.426399 -148.284688)
			(xy 37.434519 -148.339864) (xy 37.435028 -148.36775) (xy 37.434519 -148.395636) (xy 37.426399 -148.450812)
			(xy 37.410331 -148.504219) (xy 37.386659 -148.554716) (xy 37.355886 -148.601229) (xy 37.318669 -148.642766)
			(xy 37.275801 -148.678441) (xy 37.228195 -148.707495) (xy 37.176866 -148.729307) (xy 37.122909 -148.743413)
			(xy 37.067472 -148.749513) (xy 37.011738 -148.747476) (xy 36.956895 -148.737346) (xy 36.904111 -148.719339)
			(xy 36.854511 -148.693838) (xy 36.809153 -148.661387) (xy 36.769004 -148.622678) (xy 36.734918 -148.578535)
			(xy 36.707622 -148.5299) (xy 36.687699 -148.477809) (xy 36.675573 -148.423372) (xy 36.671502 -148.36775)
			(xy 24.16556 -148.36775) (xy 24.16556 -149.975316) (xy 38.200582 -149.975316) (xy 38.204653 -149.919694)
			(xy 38.216779 -149.865257) (xy 38.236702 -149.813166) (xy 38.263998 -149.764531) (xy 38.298084 -149.720388)
			(xy 38.338233 -149.681679) (xy 38.383591 -149.649228) (xy 38.433191 -149.623727) (xy 38.485975 -149.60572)
			(xy 38.540818 -149.59559) (xy 38.596552 -149.593553) (xy 38.651989 -149.599653) (xy 38.705946 -149.613759)
			(xy 38.757275 -149.635571) (xy 38.804881 -149.664625) (xy 38.847749 -149.7003) (xy 38.884966 -149.741837)
			(xy 38.915739 -149.78835) (xy 38.939411 -149.838847) (xy 38.955479 -149.892254) (xy 38.963599 -149.94743)
			(xy 38.964108 -149.975316) (xy 38.963599 -150.003202) (xy 38.955479 -150.058378) (xy 38.939411 -150.111785)
			(xy 38.915739 -150.162282) (xy 38.884966 -150.208795) (xy 38.847749 -150.250332) (xy 38.804881 -150.286007)
			(xy 38.757275 -150.315061) (xy 38.705946 -150.336873) (xy 38.651989 -150.350979) (xy 38.596552 -150.357079)
			(xy 38.540818 -150.355042) (xy 38.485975 -150.344912) (xy 38.433191 -150.326905) (xy 38.383591 -150.301404)
			(xy 38.338233 -150.268953) (xy 38.298084 -150.230244) (xy 38.263998 -150.186101) (xy 38.236702 -150.137466)
			(xy 38.216779 -150.085375) (xy 38.204653 -150.030938) (xy 38.200582 -149.975316) (xy 24.16556 -149.975316)
			(xy 24.16556 -150.99284) (xy 24.89962 -151.7269) (xy 28.379166 -151.7269) (xy 28.607766 -151.9555)
			(xy 34.211514 -151.9555)
		)
		(stroke
			(width 0)
			(type solid)
		)
		(fill yes)
		(layer "F.Cu")
		(net "LAN1_CTRL_P1V9")
	)
	(gr_poly
		(pts
			(xy 192.10274 -39.49573) (xy 192.10274 -30.574234) (xy 191.66332 -30.134814) (xy 180.626258 -30.134814)
			(xy 176.85512 -33.905952) (xy 176.85512 -36.46297) (xy 178.834042 -36.46297) (xy 178.838039 -36.339594)
			(xy 178.850014 -36.216736) (xy 178.869917 -36.094911) (xy 178.897663 -35.97463) (xy 178.933137 -35.856396)
			(xy 178.97619 -35.740707) (xy 179.026641 -35.628048) (xy 179.084278 -35.51889) (xy 179.148861 -35.413692)
			(xy 179.220118 -35.312895) (xy 179.297749 -35.216922) (xy 179.381431 -35.126175) (xy 179.47081 -35.041036)
			(xy 179.565514 -34.96186) (xy 179.665143 -34.888981) (xy 179.769282 -34.822703) (xy 179.877492 -34.763305)
			(xy 179.98932 -34.711037) (xy 180.104296 -34.666116) (xy 180.22194 -34.628732) (xy 180.341756 -34.599042)
			(xy 180.463243 -34.577169) (xy 180.585891 -34.563206) (xy 180.709186 -34.557212) (xy 180.83261 -34.559211)
			(xy 180.955646 -34.569195) (xy 181.077777 -34.587122) (xy 181.198492 -34.612917) (xy 181.317285 -34.646472)
			(xy 181.433656 -34.687645) (xy 181.547118 -34.736265) (xy 181.657194 -34.792128) (xy 181.763424 -34.854999)
			(xy 181.865362 -34.924614) (xy 181.962579 -35.000681) (xy 182.054669 -35.082882) (xy 182.141245 -35.170871)
			(xy 182.221944 -35.26428) (xy 182.296427 -35.362717) (xy 182.364382 -35.465768) (xy 182.425524 -35.573002)
			(xy 182.479597 -35.683969) (xy 182.526373 -35.798203) (xy 182.565657 -35.915226) (xy 182.597284 -36.034546)
			(xy 182.621121 -36.155663) (xy 182.637068 -36.278068) (xy 182.645058 -36.40125) (xy 182.645558 -36.46297)
			(xy 184.523642 -36.46297) (xy 184.527639 -36.339594) (xy 184.539614 -36.216736) (xy 184.559517 -36.094911)
			(xy 184.587263 -35.97463) (xy 184.622737 -35.856396) (xy 184.66579 -35.740707) (xy 184.716241 -35.628048)
			(xy 184.773878 -35.51889) (xy 184.838461 -35.413692) (xy 184.909718 -35.312895) (xy 184.987349 -35.216922)
			(xy 185.071031 -35.126175) (xy 185.16041 -35.041036) (xy 185.255114 -34.96186) (xy 185.354743 -34.888981)
			(xy 185.458882 -34.822703) (xy 185.567092 -34.763305) (xy 185.67892 -34.711037) (xy 185.793896 -34.666116)
			(xy 185.91154 -34.628732) (xy 186.031356 -34.599042) (xy 186.152843 -34.577169) (xy 186.275491 -34.563206)
			(xy 186.398786 -34.557212) (xy 186.52221 -34.559211) (xy 186.645246 -34.569195) (xy 186.767377 -34.587122)
			(xy 186.888092 -34.612917) (xy 187.006885 -34.646472) (xy 187.123256 -34.687645) (xy 187.236718 -34.736265)
			(xy 187.346794 -34.792128) (xy 187.453024 -34.854999) (xy 187.554962 -34.924614) (xy 187.652179 -35.000681)
			(xy 187.744269 -35.082882) (xy 187.830845 -35.170871) (xy 187.911544 -35.26428) (xy 187.986027 -35.362717)
			(xy 188.053982 -35.465768) (xy 188.115124 -35.573002) (xy 188.169197 -35.683969) (xy 188.215973 -35.798203)
			(xy 188.255257 -35.915226) (xy 188.286884 -36.034546) (xy 188.310721 -36.155663) (xy 188.326668 -36.278068)
			(xy 188.334658 -36.40125) (xy 188.335158 -36.46297) (xy 188.334658 -36.52469) (xy 188.326668 -36.647872)
			(xy 188.310721 -36.770277) (xy 188.286884 -36.891394) (xy 188.255257 -37.010714) (xy 188.215973 -37.127737)
			(xy 188.169197 -37.241971) (xy 188.115124 -37.352938) (xy 188.053982 -37.460172) (xy 187.986027 -37.563223)
			(xy 187.911544 -37.66166) (xy 187.830845 -37.755069) (xy 187.744269 -37.843058) (xy 187.652179 -37.925259)
			(xy 187.554962 -38.001326) (xy 187.453024 -38.070941) (xy 187.346794 -38.133812) (xy 187.236718 -38.189675)
			(xy 187.123256 -38.238295) (xy 187.006885 -38.279468) (xy 186.888092 -38.313023) (xy 186.767377 -38.338818)
			(xy 186.645246 -38.356745) (xy 186.52221 -38.366729) (xy 186.398786 -38.368728) (xy 186.275491 -38.362734)
			(xy 186.152843 -38.348771) (xy 186.031356 -38.326898) (xy 185.91154 -38.297208) (xy 185.793896 -38.259824)
			(xy 185.67892 -38.214903) (xy 185.567092 -38.162635) (xy 185.458882 -38.103237) (xy 185.354743 -38.036959)
			(xy 185.255114 -37.96408) (xy 185.16041 -37.884904) (xy 185.071031 -37.799765) (xy 184.987349 -37.709018)
			(xy 184.909718 -37.613045) (xy 184.838461 -37.512248) (xy 184.773878 -37.40705) (xy 184.716241 -37.297892)
			(xy 184.66579 -37.185233) (xy 184.622737 -37.069544) (xy 184.587263 -36.95131) (xy 184.559517 -36.831029)
			(xy 184.539614 -36.709204) (xy 184.527639 -36.586346) (xy 184.523642 -36.46297) (xy 182.645558 -36.46297)
			(xy 182.645058 -36.52469) (xy 182.637068 -36.647872) (xy 182.621121 -36.770277) (xy 182.597284 -36.891394)
			(xy 182.565657 -37.010714) (xy 182.526373 -37.127737) (xy 182.479597 -37.241971) (xy 182.425524 -37.352938)
			(xy 182.364382 -37.460172) (xy 182.296427 -37.563223) (xy 182.221944 -37.66166) (xy 182.141245 -37.755069)
			(xy 182.054669 -37.843058) (xy 181.962579 -37.925259) (xy 181.865362 -38.001326) (xy 181.763424 -38.070941)
			(xy 181.657194 -38.133812) (xy 181.547118 -38.189675) (xy 181.433656 -38.238295) (xy 181.317285 -38.279468)
			(xy 181.198492 -38.313023) (xy 181.077777 -38.338818) (xy 180.955646 -38.356745) (xy 180.83261 -38.366729)
			(xy 180.709186 -38.368728) (xy 180.585891 -38.362734) (xy 180.463243 -38.348771) (xy 180.341756 -38.326898)
			(xy 180.22194 -38.297208) (xy 180.104296 -38.259824) (xy 179.98932 -38.214903) (xy 179.877492 -38.162635)
			(xy 179.769282 -38.103237) (xy 179.665143 -38.036959) (xy 179.565514 -37.96408) (xy 179.47081 -37.884904)
			(xy 179.381431 -37.799765) (xy 179.297749 -37.709018) (xy 179.220118 -37.613045) (xy 179.148861 -37.512248)
			(xy 179.084278 -37.40705) (xy 179.026641 -37.297892) (xy 178.97619 -37.185233) (xy 178.933137 -37.069544)
			(xy 178.897663 -36.95131) (xy 178.869917 -36.831029) (xy 178.850014 -36.709204) (xy 178.838039 -36.586346)
			(xy 178.834042 -36.46297) (xy 176.85512 -36.46297) (xy 176.85512 -39.303452) (xy 176.855647 -39.320092)
			(xy 176.864326 -39.352222) (xy 176.881026 -39.381011) (xy 176.892458 -39.393114) (xy 177.62982 -40.130476)
			(xy 191.467994 -40.130476)
		)
		(stroke
			(width 0)
			(type solid)
		)
		(fill yes)
		(layer "F.Cu")
		(net "USBPWR_P0")
	)
	(gr_poly
		(pts
			(xy 13.83792 -95.216726) (xy 13.83792 -79.836772) (xy 13.196824 -79.195676) (xy 13.184697 -79.184274)
			(xy 13.155916 -79.167578) (xy 13.123797 -79.158887) (xy 13.107162 -79.158338) (xy 2.878074 -79.158338)
			(xy 1.840484 -80.195928) (xy 1.840484 -81.774992) (xy 10.396718 -81.774992) (xy 10.396718 -81.68112)
			(xy 10.404679 -81.587586) (xy 10.420543 -81.495064) (xy 10.444197 -81.404221) (xy 10.475469 -81.315712)
			(xy 10.514135 -81.230173) (xy 10.559916 -81.148221) (xy 10.612482 -81.070447) (xy 10.671455 -80.997412)
			(xy 10.736408 -80.92964) (xy 10.806875 -80.867621) (xy 10.882348 -80.811802) (xy 10.962283 -80.762584)
			(xy 11.046104 -80.720322) (xy 11.133207 -80.685322) (xy 11.222964 -80.657834) (xy 11.314729 -80.638057)
			(xy 11.407841 -80.626134) (xy 11.501628 -80.62215) (xy 11.595415 -80.626134) (xy 11.688527 -80.638057)
			(xy 11.780292 -80.657834) (xy 11.870049 -80.685322) (xy 11.957152 -80.720322) (xy 12.040973 -80.762584)
			(xy 12.120908 -80.811802) (xy 12.196381 -80.867621) (xy 12.266848 -80.92964) (xy 12.331801 -80.997412)
			(xy 12.390774 -81.070447) (xy 12.44334 -81.148221) (xy 12.489121 -81.230173) (xy 12.527787 -81.315712)
			(xy 12.559059 -81.404221) (xy 12.582713 -81.495064) (xy 12.598577 -81.587586) (xy 12.606538 -81.68112)
			(xy 12.607036 -81.728056) (xy 12.606538 -81.774992) (xy 12.598577 -81.868526) (xy 12.582713 -81.961048)
			(xy 12.559059 -82.051891) (xy 12.527787 -82.1404) (xy 12.489121 -82.225939) (xy 12.44334 -82.307891)
			(xy 12.390774 -82.385665) (xy 12.331801 -82.4587) (xy 12.266848 -82.526472) (xy 12.196381 -82.588491)
			(xy 12.120908 -82.64431) (xy 12.040973 -82.693528) (xy 11.957152 -82.73579) (xy 11.870049 -82.77079)
			(xy 11.780292 -82.798278) (xy 11.688527 -82.818055) (xy 11.595415 -82.829978) (xy 11.501628 -82.833963)
			(xy 11.407841 -82.829978) (xy 11.314729 -82.818055) (xy 11.222964 -82.798278) (xy 11.133207 -82.77079)
			(xy 11.046104 -82.73579) (xy 10.962283 -82.693528) (xy 10.882348 -82.64431) (xy 10.806875 -82.588491)
			(xy 10.736408 -82.526472) (xy 10.671455 -82.4587) (xy 10.612482 -82.385665) (xy 10.559916 -82.307891)
			(xy 10.514135 -82.225939) (xy 10.475469 -82.1404) (xy 10.444197 -82.051891) (xy 10.420543 -81.961048)
			(xy 10.404679 -81.868526) (xy 10.396718 -81.774992) (xy 1.840484 -81.774992) (xy 1.840484 -84.822792)
			(xy 10.39622 -84.822792) (xy 12.607036 -84.822792) (xy 12.607036 -87.033608) (xy 10.39622 -87.033608)
			(xy 10.39622 -84.822792) (xy 1.840484 -84.822792) (xy 1.840484 -90.697241) (xy 4.534904 -90.697241)
			(xy 4.534904 -90.573415) (xy 4.542837 -90.449844) (xy 4.558672 -90.327036) (xy 4.582342 -90.205494)
			(xy 4.613751 -90.085718) (xy 4.652769 -89.968201) (xy 4.699237 -89.853425) (xy 4.752963 -89.741862)
			(xy 4.813726 -89.633971) (xy 4.881277 -89.530194) (xy 4.955339 -89.430959) (xy 5.035606 -89.336672)
			(xy 5.121749 -89.247722) (xy 5.213414 -89.164474) (xy 5.310225 -89.087271) (xy 5.411783 -89.016428)
			(xy 5.517671 -88.952238) (xy 5.627455 -88.894964) (xy 5.740682 -88.844841) (xy 5.856889 -88.802076)
			(xy 5.975596 -88.766845) (xy 6.096317 -88.739291) (xy 6.218555 -88.719528) (xy 6.341808 -88.707638)
			(xy 6.46557 -88.70367) (xy 6.589332 -88.707638) (xy 6.712585 -88.719528) (xy 6.834823 -88.739291)
			(xy 6.955544 -88.766845) (xy 7.074251 -88.802076) (xy 7.190458 -88.844841) (xy 7.303685 -88.894964)
			(xy 7.413469 -88.952238) (xy 7.519357 -89.016428) (xy 7.620915 -89.087271) (xy 7.717726 -89.164474)
			(xy 7.809391 -89.247722) (xy 7.895534 -89.336672) (xy 7.975801 -89.430959) (xy 8.049863 -89.530194)
			(xy 8.117414 -89.633971) (xy 8.178177 -89.741862) (xy 8.231903 -89.853425) (xy 8.278371 -89.968201)
			(xy 8.317389 -90.085718) (xy 8.348798 -90.205494) (xy 8.372468 -90.327036) (xy 8.388303 -90.449844)
			(xy 8.396236 -90.573415) (xy 8.396732 -90.635328) (xy 8.396236 -90.697241) (xy 8.388303 -90.820812)
			(xy 8.372468 -90.94362) (xy 8.348798 -91.065162) (xy 8.317389 -91.184938) (xy 8.278371 -91.302455)
			(xy 8.231903 -91.417231) (xy 8.178177 -91.528794) (xy 8.177831 -91.529408) (xy 12.125958 -91.529408)
			(xy 12.130029 -91.473786) (xy 12.142155 -91.419349) (xy 12.162078 -91.367258) (xy 12.189374 -91.318623)
			(xy 12.22346 -91.27448) (xy 12.263609 -91.235771) (xy 12.308967 -91.20332) (xy 12.358567 -91.177819)
			(xy 12.411351 -91.159812) (xy 12.466194 -91.149682) (xy 12.521928 -91.147645) (xy 12.577365 -91.153745)
			(xy 12.631322 -91.167851) (xy 12.682651 -91.189663) (xy 12.730257 -91.218717) (xy 12.773125 -91.254392)
			(xy 12.810342 -91.295929) (xy 12.841115 -91.342442) (xy 12.864787 -91.392939) (xy 12.880855 -91.446346)
			(xy 12.888975 -91.501522) (xy 12.889484 -91.529408) (xy 12.888975 -91.557294) (xy 12.880855 -91.61247)
			(xy 12.864787 -91.665877) (xy 12.841115 -91.716374) (xy 12.810342 -91.762887) (xy 12.773125 -91.804424)
			(xy 12.730257 -91.840099) (xy 12.682651 -91.869153) (xy 12.631322 -91.890965) (xy 12.577365 -91.905071)
			(xy 12.521928 -91.911171) (xy 12.466194 -91.909134) (xy 12.411351 -91.899004) (xy 12.358567 -91.880997)
			(xy 12.308967 -91.855496) (xy 12.263609 -91.823045) (xy 12.22346 -91.784336) (xy 12.189374 -91.740193)
			(xy 12.162078 -91.691558) (xy 12.142155 -91.639467) (xy 12.130029 -91.58503) (xy 12.125958 -91.529408)
			(xy 8.177831 -91.529408) (xy 8.117414 -91.636685) (xy 8.049863 -91.740462) (xy 7.975801 -91.839697)
			(xy 7.895534 -91.933984) (xy 7.809391 -92.022934) (xy 7.717726 -92.106182) (xy 7.620915 -92.183385)
			(xy 7.519357 -92.254228) (xy 7.413469 -92.318418) (xy 7.303685 -92.375692) (xy 7.190458 -92.425815)
			(xy 7.074251 -92.46858) (xy 6.955544 -92.503811) (xy 6.834823 -92.531365) (xy 6.712585 -92.551128)
			(xy 6.589332 -92.563018) (xy 6.46557 -92.566987) (xy 6.341808 -92.563018) (xy 6.218555 -92.551128)
			(xy 6.096317 -92.531365) (xy 5.975596 -92.503811) (xy 5.856889 -92.46858) (xy 5.740682 -92.425815)
			(xy 5.627455 -92.375692) (xy 5.517671 -92.318418) (xy 5.411783 -92.254228) (xy 5.310225 -92.183385)
			(xy 5.213414 -92.106182) (xy 5.121749 -92.022934) (xy 5.035606 -91.933984) (xy 4.955339 -91.839697)
			(xy 4.881277 -91.740462) (xy 4.813726 -91.636685) (xy 4.752963 -91.528794) (xy 4.699237 -91.417231)
			(xy 4.652769 -91.302455) (xy 4.613751 -91.184938) (xy 4.582342 -91.065162) (xy 4.558672 -90.94362)
			(xy 4.542837 -90.820812) (xy 4.534904 -90.697241) (xy 1.840484 -90.697241) (xy 1.840484 -95.52813)
			(xy 2.60858 -96.296226) (xy 12.75842 -96.296226)
		)
		(stroke
			(width 0)
			(type solid)
		)
		(fill yes)
		(layer "F.Cu")
		(net "P12V_DBG")
	)
	(gr_poly
		(pts
			(xy 75.151742 -89.323164) (xy 75.153774 -89.320878) (xy 75.17638 -89.298272) (xy 75.178666 -89.29624)
			(xy 75.24369 -89.231216) (xy 75.24369 -86.487762) (xy 75.243164 -86.471121) (xy 75.234489 -86.438988)
			(xy 75.217792 -86.410196) (xy 75.206352 -86.3981) (xy 74.9681 -86.159848) (xy 74.803254 -86.159848)
			(xy 74.78268 -86.13902) (xy 74.770512 -86.127536) (xy 74.741549 -86.110805) (xy 74.709235 -86.102168)
			(xy 74.69251 -86.101682) (xy 74.630788 -86.101682) (xy 74.608436 -86.07933) (xy 74.606658 -86.07933)
			(xy 74.049382 -85.522054) (xy 73.007982 -85.522054) (xy 73.00468 -85.519006) (xy 72.969882 -85.484208)
			(xy 72.87133 -85.385402) (xy 72.69988 -85.214206) (xy 72.543162 -85.214206) (xy 72.516642 -85.213612)
			(xy 72.464406 -85.204413) (xy 72.439276 -85.195918) (xy 72.418194 -85.188298) (xy 71.835772 -85.188298)
			(xy 71.251572 -85.772498) (xy 71.149718 -85.772498) (xy 71.116444 -85.805772) (xy 70.975728 -85.805772)
			(xy 70.955507 -85.806203) (xy 70.915242 -85.802385) (xy 70.895464 -85.798152) (xy 70.869776 -85.791622)
			(xy 70.820982 -85.770938) (xy 70.798436 -85.757004) (xy 70.776874 -85.742448) (xy 70.738597 -85.707221)
			(xy 70.706843 -85.666017) (xy 70.682531 -85.620028) (xy 70.673976 -85.59546) (xy 70.664578 -85.566504)
			(xy 70.387972 -85.289898) (xy 69.981572 -85.289898) (xy 69.32168 -85.94979) (xy 69.32168 -86.230206)
			(xy 69.330824 -86.23935) (xy 69.35687 -86.251326) (xy 69.405337 -86.281938) (xy 69.427344 -86.30031)
			(xy 69.463158 -86.331298) (xy 69.531738 -86.331298) (xy 70.06294 -86.8625) (xy 70.589406 -86.8625)
			(xy 70.593578 -86.812173) (xy 70.605977 -86.76322) (xy 70.626267 -86.716975) (xy 70.653893 -86.674703)
			(xy 70.688102 -86.637555) (xy 70.72796 -86.606546) (xy 70.772379 -86.582521) (xy 70.820147 -86.566138)
			(xy 70.86996 -86.557842) (xy 70.89521 -86.557358) (xy 70.951598 -86.557358) (xy 70.966872 -86.556873)
			(xy 70.996531 -86.549549) (xy 71.023603 -86.535391) (xy 71.046538 -86.515209) (xy 71.064024 -86.490159)
			(xy 71.069962 -86.476078) (xy 71.080137 -86.450958) (xy 71.106592 -86.403657) (xy 71.139472 -86.360572)
			(xy 71.178115 -86.322572) (xy 71.221745 -86.29042) (xy 71.269483 -86.264762) (xy 71.320371 -86.246114)
			(xy 71.373385 -86.234852) (xy 71.427459 -86.231202) (xy 71.454518 -86.232746) (xy 71.476541 -86.233933)
			(xy 71.52043 -86.229619) (xy 71.562913 -86.217789) (xy 71.602715 -86.198799) (xy 71.638638 -86.17322)
			(xy 71.669603 -86.141819) (xy 71.694679 -86.105543) (xy 71.713111 -86.06548) (xy 71.719186 -86.044278)
			(xy 71.726049 -86.020171) (xy 71.746589 -85.974454) (xy 71.774321 -85.932705) (xy 71.8085 -85.896048)
			(xy 71.848209 -85.865466) (xy 71.89238 -85.841783) (xy 71.939827 -85.825633) (xy 71.989274 -85.817451)
			(xy 72.014334 -85.816948) (xy 72.359774 -85.816948) (xy 72.390762 -85.797644) (xy 72.413824 -85.783921)
			(xy 72.462963 -85.762354) (xy 72.514639 -85.747882) (xy 72.567832 -85.740792) (xy 72.621494 -85.741223)
			(xy 72.674567 -85.749167) (xy 72.726004 -85.764467) (xy 72.77479 -85.786822) (xy 72.819964 -85.81579)
			(xy 72.840596 -85.83295) (xy 72.858274 -85.847492) (xy 72.897758 -85.870642) (xy 72.940746 -85.886357)
			(xy 72.985852 -85.894129) (xy 73.031621 -85.893707) (xy 73.076576 -85.885106) (xy 73.119268 -85.868603)
			(xy 73.139046 -85.85708) (xy 73.160529 -85.844479) (xy 73.206651 -85.825693) (xy 73.255213 -85.814646)
			(xy 73.304923 -85.811633) (xy 73.354463 -85.816732) (xy 73.402517 -85.82981) (xy 73.44781 -85.850518)
			(xy 73.489138 -85.878307) (xy 73.525404 -85.912439) (xy 73.555646 -85.952007) (xy 73.57906 -85.995961)
			(xy 73.595025 -86.043135) (xy 73.603117 -86.092275) (xy 73.603612 -86.117176) (xy 73.603612 -86.275418)
			(xy 73.604093 -86.291276) (xy 73.611943 -86.322007) (xy 73.62713 -86.349852) (xy 73.648716 -86.373092)
			(xy 73.661778 -86.382098) (xy 73.684693 -86.397512) (xy 73.726239 -86.433893) (xy 73.762105 -86.475885)
			(xy 73.79154 -86.52261) (xy 73.81393 -86.573092) (xy 73.828806 -86.626275) (xy 73.835857 -86.681047)
			(xy 73.834935 -86.736263) (xy 73.826061 -86.790769) (xy 73.80942 -86.843426) (xy 73.785359 -86.893133)
			(xy 73.754381 -86.93885) (xy 73.717134 -86.979622) (xy 73.674397 -87.014597) (xy 73.627064 -87.043044)
			(xy 73.576122 -87.064367) (xy 73.522639 -87.078121) (xy 73.46773 -87.084019) (xy 73.412546 -87.081937)
			(xy 73.358238 -87.071919) (xy 73.305943 -87.054174) (xy 73.256753 -87.029073) (xy 73.211697 -86.997141)
			(xy 73.171717 -86.959045) (xy 73.137648 -86.915582) (xy 73.110203 -86.867661) (xy 73.089956 -86.816283)
			(xy 73.083166 -86.789514) (xy 73.074784 -86.754208) (xy 72.993504 -86.672928) (xy 72.993504 -86.549992)
			(xy 72.992964 -86.533344) (xy 72.984344 -86.501182) (xy 72.967695 -86.472346) (xy 72.94415 -86.448802)
			(xy 72.915314 -86.432154) (xy 72.883152 -86.423536) (xy 72.866504 -86.422992) (xy 72.829166 -86.422992)
			(xy 72.79767 -86.443058) (xy 72.774842 -86.45718) (xy 72.726057 -86.479573) (xy 72.674613 -86.494901)
			(xy 72.621528 -86.502861) (xy 72.567851 -86.503297) (xy 72.514644 -86.496199) (xy 72.462958 -86.481707)
			(xy 72.413816 -86.46011) (xy 72.390762 -86.44636) (xy 72.359774 -86.427056) (xy 72.014334 -86.427056)
			(xy 71.999376 -86.42688) (xy 71.969605 -86.423949) (xy 71.954898 -86.421214) (xy 71.940008 -86.418665)
			(xy 71.909831 -86.419948) (xy 71.880801 -86.428287) (xy 71.854545 -86.443215) (xy 71.832532 -86.463897)
			(xy 71.815998 -86.489173) (xy 71.805867 -86.517627) (xy 71.802707 -86.547666) (xy 71.804276 -86.562692)
			(xy 71.807481 -86.590625) (xy 71.806635 -86.646843) (xy 71.797552 -86.702328) (xy 71.780428 -86.75588)
			(xy 71.755633 -86.806341) (xy 71.723704 -86.852619) (xy 71.685332 -86.893713) (xy 71.641347 -86.928733)
			(xy 71.5927 -86.956922) (xy 71.540445 -86.97767) (xy 71.513192 -86.984586) (xy 71.477886 -86.992968)
			(xy 71.303134 -87.16772) (xy 70.89521 -87.16772) (xy 70.86996 -87.167158) (xy 70.820147 -87.158862)
			(xy 70.772379 -87.142479) (xy 70.72796 -87.118454) (xy 70.688102 -87.087445) (xy 70.653893 -87.050297)
			(xy 70.626267 -87.008025) (xy 70.605977 -86.96178) (xy 70.593578 -86.912827) (xy 70.589406 -86.8625)
			(xy 70.06294 -86.8625) (xy 70.139814 -86.939374) (xy 70.139814 -86.964774) (xy 70.201028 -87.001858)
			(xy 70.224662 -87.016787) (xy 70.267692 -87.052469) (xy 70.305056 -87.094047) (xy 70.335954 -87.140632)
			(xy 70.359726 -87.191225) (xy 70.375862 -87.244745) (xy 70.384017 -87.300047) (xy 70.384018 -87.355947)
			(xy 70.375863 -87.411249) (xy 70.359728 -87.464769) (xy 70.335957 -87.515363) (xy 70.305059 -87.561948)
			(xy 70.267696 -87.603526) (xy 70.224667 -87.639209) (xy 70.201028 -87.65413) (xy 70.172326 -87.671402)
			(xy 70.139814 -87.729314) (xy 70.139814 -87.920576) (xy 70.140277 -87.937306) (xy 70.148899 -87.969633)
			(xy 70.165635 -87.998604) (xy 70.177152 -88.010746) (xy 70.227952 -88.061292) (xy 70.227952 -88.774524)
			(xy 70.227952 -89.673684) (xy 70.416166 -89.861898) (xy 74.613008 -89.861898)
		)
		(stroke
			(width 0)
			(type solid)
		)
		(fill yes)
		(layer "F.Cu")
		(net "GND")
	)
	(gr_poly
		(pts
			(xy 105.000044 -90.79611) (xy 104.899914 -90.796611) (xy 104.699814 -90.804623) (xy 104.500195 -90.820635)
			(xy 104.301376 -90.844621) (xy 104.103677 -90.876542) (xy 103.907412 -90.916347) (xy 103.712898 -90.963973)
			(xy 103.520444 -91.019344) (xy 103.330361 -91.08237) (xy 103.142951 -91.15295) (xy 102.958515 -91.230973)
			(xy 102.777348 -91.316312) (xy 102.599741 -91.408831) (xy 102.425977 -91.508382) (xy 102.256336 -91.614806)
			(xy 102.091088 -91.727932) (xy 101.930499 -91.847578) (xy 101.774826 -91.973554) (xy 101.624317 -92.105658)
			(xy 101.479215 -92.243677) (xy 101.339751 -92.387392) (xy 101.206148 -92.536571) (xy 101.078621 -92.690976)
			(xy 100.957373 -92.85036) (xy 100.8426 -93.014468) (xy 100.734485 -93.183036) (xy 100.6332 -93.355794)
			(xy 100.538908 -93.532467) (xy 100.451761 -93.712771) (xy 100.371897 -93.896417) (xy 100.299445 -94.083112)
			(xy 100.23452 -94.272555) (xy 100.177227 -94.464445) (xy 100.127657 -94.658473) (xy 100.08589 -94.85433)
			(xy 100.051993 -95.0517) (xy 100.026019 -95.250269) (xy 100.008011 -95.449718) (xy 99.997997 -95.649727)
			(xy 99.99685 -95.764319) (xy 102.485192 -95.764319) (xy 102.491234 -95.622098) (xy 102.505312 -95.480447)
			(xy 102.527381 -95.339819) (xy 102.557371 -95.200665) (xy 102.595186 -95.06343) (xy 102.640704 -94.928555)
			(xy 102.69378 -94.796471) (xy 102.754243 -94.667601) (xy 102.8219 -94.542358) (xy 102.896535 -94.421144)
			(xy 102.977908 -94.304346) (xy 103.065758 -94.192339) (xy 103.159805 -94.085481) (xy 103.259746 -93.984116)
			(xy 103.365262 -93.888567) (xy 103.476015 -93.79914) (xy 103.591649 -93.716122) (xy 103.711796 -93.63978)
			(xy 103.836068 -93.570357) (xy 103.96407 -93.508076) (xy 104.09539 -93.453136) (xy 104.229607 -93.405714)
			(xy 104.366293 -93.365961) (xy 104.505009 -93.334005) (xy 104.64531 -93.309948) (xy 104.786748 -93.293867)
			(xy 104.928869 -93.285814) (xy 105.000044 -93.28531) (xy 105.071219 -93.285814) (xy 105.21334 -93.293867)
			(xy 105.354778 -93.309948) (xy 105.495079 -93.334005) (xy 105.633795 -93.365961) (xy 105.770481 -93.405714)
			(xy 105.904698 -93.453136) (xy 106.036018 -93.508076) (xy 106.16402 -93.570357) (xy 106.288292 -93.63978)
			(xy 106.408439 -93.716122) (xy 106.524073 -93.79914) (xy 106.634826 -93.888567) (xy 106.740342 -93.984116)
			(xy 106.840283 -94.085481) (xy 106.93433 -94.192339) (xy 107.02218 -94.304346) (xy 107.103553 -94.421144)
			(xy 107.178188 -94.542358) (xy 107.245845 -94.667601) (xy 107.306308 -94.796471) (xy 107.359384 -94.928555)
			(xy 107.404902 -95.06343) (xy 107.442717 -95.200665) (xy 107.472707 -95.339819) (xy 107.494776 -95.480447)
			(xy 107.508854 -95.622098) (xy 107.514896 -95.764319) (xy 107.512881 -95.906654) (xy 107.502818 -96.048647)
			(xy 107.484737 -96.189843) (xy 107.458697 -96.32979) (xy 107.424781 -96.46804) (xy 107.383098 -96.604149)
			(xy 107.333781 -96.737683) (xy 107.276989 -96.868212) (xy 107.212902 -96.995319) (xy 107.141728 -97.118597)
			(xy 107.063693 -97.237651) (xy 106.979047 -97.352099) (xy 106.888063 -97.461575) (xy 106.79103 -97.565729)
			(xy 106.68826 -97.664226) (xy 106.580082 -97.75675) (xy 106.466843 -97.843007) (xy 106.348906 -97.922719)
			(xy 106.226647 -97.995631) (xy 106.10046 -98.061509) (xy 105.970747 -98.120143) (xy 105.837925 -98.171344)
			(xy 105.702419 -98.214949) (xy 105.564663 -98.250818) (xy 105.425099 -98.278836) (xy 105.284172 -98.298913)
			(xy 105.142336 -98.310985) (xy 105.000044 -98.315014) (xy 104.857752 -98.310985) (xy 104.715916 -98.298913)
			(xy 104.574989 -98.278836) (xy 104.435425 -98.250818) (xy 104.297669 -98.214949) (xy 104.162163 -98.171344)
			(xy 104.029341 -98.120143) (xy 103.899628 -98.061509) (xy 103.773441 -97.995631) (xy 103.651182 -97.922719)
			(xy 103.533245 -97.843007) (xy 103.420006 -97.75675) (xy 103.311828 -97.664226) (xy 103.209058 -97.565729)
			(xy 103.112025 -97.461575) (xy 103.021041 -97.352099) (xy 102.936395 -97.237651) (xy 102.85836 -97.118597)
			(xy 102.787186 -96.995319) (xy 102.723099 -96.868212) (xy 102.666307 -96.737683) (xy 102.61699 -96.604149)
			(xy 102.575307 -96.46804) (xy 102.541391 -96.32979) (xy 102.515351 -96.189843) (xy 102.49727 -96.048647)
			(xy 102.487207 -95.906654) (xy 102.485192 -95.764319) (xy 99.99685 -95.764319) (xy 99.995993 -95.849978)
			(xy 100.002003 -96.050148) (xy 100.016017 -96.249917) (xy 100.038013 -96.448965) (xy 100.067954 -96.646975)
			(xy 100.105794 -96.843627) (xy 100.151472 -97.038609) (xy 100.204914 -97.231606) (xy 100.266035 -97.422311)
			(xy 100.334737 -97.610418) (xy 100.41091 -97.795625) (xy 100.494433 -97.977637) (xy 100.58517 -98.156161)
			(xy 100.682978 -98.330912) (xy 100.787699 -98.501609) (xy 100.899166 -98.66798) (xy 101.0172 -98.829758)
			(xy 101.141612 -98.986684) (xy 101.272203 -99.138507) (xy 101.408764 -99.284983) (xy 101.551076 -99.425878)
			(xy 101.698911 -99.560967) (xy 101.852033 -99.690032) (xy 102.010195 -99.812868) (xy 102.173146 -99.929278)
			(xy 102.340624 -100.039074) (xy 102.512361 -100.142082) (xy 102.688081 -100.238137) (xy 102.867504 -100.327084)
			(xy 103.050342 -100.408781) (xy 103.236303 -100.483097) (xy 103.425087 -100.549914) (xy 103.616394 -100.609124)
			(xy 103.809917 -100.660633) (xy 104.005345 -100.704357) (xy 104.202367 -100.740228) (xy 104.400666 -100.768187)
			(xy 104.599924 -100.78819) (xy 104.799824 -100.800204) (xy 105.000044 -100.804211) (xy 105.200264 -100.800204)
			(xy 105.400164 -100.78819) (xy 105.599422 -100.768187) (xy 105.797721 -100.740228) (xy 105.994743 -100.704357)
			(xy 106.190171 -100.660633) (xy 106.383694 -100.609124) (xy 106.575001 -100.549914) (xy 106.763785 -100.483097)
			(xy 106.949746 -100.408781) (xy 107.132584 -100.327084) (xy 107.312007 -100.238137) (xy 107.487727 -100.142082)
			(xy 107.659464 -100.039074) (xy 107.826942 -99.929278) (xy 107.989893 -99.812868) (xy 108.148055 -99.690032)
			(xy 108.301177 -99.560967) (xy 108.449012 -99.425878) (xy 108.591324 -99.284983) (xy 108.727885 -99.138507)
			(xy 108.858476 -98.986684) (xy 108.982888 -98.829758) (xy 109.100922 -98.66798) (xy 109.212389 -98.501609)
			(xy 109.31711 -98.330912) (xy 109.414918 -98.156161) (xy 109.505655 -97.977637) (xy 109.589178 -97.795625)
			(xy 109.665351 -97.610418) (xy 109.734053 -97.422311) (xy 109.795174 -97.231606) (xy 109.848616 -97.038609)
			(xy 109.894294 -96.843627) (xy 109.932134 -96.646975) (xy 109.962075 -96.448965) (xy 109.984071 -96.249917)
			(xy 109.998085 -96.050148) (xy 110.004095 -95.849978) (xy 110.002091 -95.649727) (xy 109.992077 -95.449718)
			(xy 109.974069 -95.250269) (xy 109.948095 -95.0517) (xy 109.914198 -94.85433) (xy 109.872431 -94.658473)
			(xy 109.822861 -94.464445) (xy 109.765568 -94.272555) (xy 109.700643 -94.083112) (xy 109.628191 -93.896417)
			(xy 109.548327 -93.712771) (xy 109.46118 -93.532467) (xy 109.366888 -93.355794) (xy 109.265603 -93.183036)
			(xy 109.157488 -93.014468) (xy 109.042715 -92.85036) (xy 108.921467 -92.690976) (xy 108.79394 -92.536571)
			(xy 108.660337 -92.387392) (xy 108.520873 -92.243677) (xy 108.375771 -92.105658) (xy 108.225262 -91.973554)
			(xy 108.069589 -91.847578) (xy 107.909 -91.727932) (xy 107.743752 -91.614806) (xy 107.574111 -91.508382)
			(xy 107.400347 -91.408831) (xy 107.22274 -91.316312) (xy 107.041573 -91.230973) (xy 106.857137 -91.15295)
			(xy 106.669727 -91.08237) (xy 106.479644 -91.019344) (xy 106.28719 -90.963973) (xy 106.092676 -90.916347)
			(xy 105.896411 -90.876542) (xy 105.698712 -90.844621) (xy 105.499893 -90.820635) (xy 105.300274 -90.804623)
			(xy 105.100174 -90.796611)
		)
		(stroke
			(width 0)
			(type solid)
		)
		(fill yes)
		(layer "F.Cu")
		(net "GND")
	)
	(gr_poly
		(pts
			(xy 71.897494 -77.772006)
			(arc
				(start 71.907146 -77.728318)
				(mid 71.914742 -77.700467)
				(end 71.924926 -77.673454)
			)
			(arc
				(start 71.924926 -77.673454)
				(mid 71.936201 -77.504079)
				(end 71.838312 -77.365352)
			)
			(arc
				(start 71.838312 -77.365352)
				(mid 71.713749 -77.064025)
				(end 71.932546 -76.8223)
			)
			(xy 71.96455 -76.813156) (xy 72.116696 -76.66101) (xy 72.116696 -76.212192) (xy 72.26173 -76.067412)
			(xy 72.27951 -76.00315)
			(arc
				(start 72.271636 -75.970638)
				(mid 72.266108 -75.942399)
				(end 72.263508 -75.913742)
			)
			(arc
				(start 72.263508 -75.913742)
				(mid 72.194896 -75.749596)
				(end 72.035416 -75.670664)
			)
			(arc
				(start 72.035416 -75.670664)
				(mid 71.799399 -75.300819)
				(end 72.21347 -75.155806)
			)
			(arc
				(start 72.21347 -75.155806)
				(mid 72.402796 -75.18933)
				(end 72.56145 -75.080622)
			)
			(xy 72.579484 -75.056492) (xy 72.610726 -75.018392) (xy 72.606154 -74.920856) (xy 72.345804 -74.66076)
			(xy 72.345804 -74.563986) (xy 71.989188 -74.20737)
			(arc
				(start 71.973948 -74.190606)
				(mid 71.892792 -74.147333)
				(end 71.803768 -74.170286)
			)
			(arc
				(start 71.803768 -74.170286)
				(mid 71.447434 -74.217076)
				(end 71.210424 -73.94702)
			)
			(xy 71.202042 -73.911714) (xy 71.149464 -73.85939) (xy 71.149464 -73.351644) (xy 71.044054 -73.24598)
			(xy 70.978268 -73.228454) (xy 70.945248 -73.237344) (xy 70.932294 -73.240646) (xy 70.896988 -73.249028)
			(xy 70.50278 -73.643236)
			(arc
				(start 70.493636 -73.673208)
				(mid 70.468193 -73.732297)
				(end 70.430898 -73.784714)
			)
			(arc
				(start 70.430898 -73.784714)
				(mid 70.36763 -73.945665)
				(end 70.422008 -74.109834)
			)
			(arc
				(start 70.422008 -74.109834)
				(mid 70.453986 -74.405199)
				(end 70.202298 -74.56297)
			)
			(arc
				(start 70.202298 -74.56297)
				(mid 70.11266 -74.600257)
				(end 70.075552 -74.68997)
			)
			(xy 70.075552 -74.883518) (xy 69.878702 -75.080114)
			(arc
				(start 69.87032 -75.11542)
				(mid 69.865348 -75.134358)
				(end 69.859398 -75.153012)
			)
			(arc
				(start 69.859398 -75.153012)
				(mid 69.863477 -75.246159)
				(end 69.93001 -75.311508)
			)
			(arc
				(start 69.93001 -75.311508)
				(mid 69.978421 -75.337861)
				(end 70.020688 -75.37323)
			)
			(arc
				(start 70.020688 -75.37323)
				(mid 70.202044 -75.449328)
				(end 70.3834 -75.37323)
			)
			(arc
				(start 70.3834 -75.37323)
				(mid 70.767932 -75.359259)
				(end 70.803008 -75.742546)
			)
			(arc
				(start 70.803008 -75.742546)
				(mid 70.748625 -75.906715)
				(end 70.811898 -76.067666)
			)
			(arc
				(start 70.811898 -76.067666)
				(mid 70.839882 -76.10462)
				(end 70.861936 -76.14539)
			)
			(arc
				(start 70.861936 -76.14539)
				(mid 70.976196 -76.22083)
				(end 71.092568 -76.148692)
			)
			(arc
				(start 71.092568 -76.148692)
				(mid 71.533956 -76.062913)
				(end 71.487538 -76.510134)
			)
			(arc
				(start 71.487538 -76.510134)
				(mid 71.372073 -76.66072)
				(end 71.393304 -76.849224)
			)
			(arc
				(start 71.393304 -76.849224)
				(mid 71.379176 -77.235476)
				(end 71.03491 -77.411072)
			)
			(arc
				(start 71.03491 -77.411072)
				(mid 70.982299 -77.419194)
				(end 70.937628 -77.448156)
			)
			(arc
				(start 70.774814 -77.61097)
				(mid 70.747127 -77.749397)
				(end 70.864476 -77.827886)
			)
			(xy 71.827898 -77.827886)
		)
		(stroke
			(width 0)
			(type solid)
		)
		(fill yes)
		(layer "F.Cu")
		(net "GND")
	)
	(gr_poly
		(pts
			(xy 109.300772 -30.281118) (xy 109.31743 -30.280627) (xy 109.349612 -30.272011) (xy 109.378468 -30.255358)
			(xy 109.40203 -30.231805) (xy 109.418693 -30.202955) (xy 109.427321 -30.170776) (xy 109.427772 -30.154118)
			(xy 109.427772 -29.50591) (xy 109.845348 -29.08808) (xy 115.235482 -29.08808) (xy 115.252137 -29.087588)
			(xy 115.284314 -29.078969) (xy 115.313162 -29.062315) (xy 115.336716 -29.038761) (xy 115.35337 -29.009912)
			(xy 115.361988 -28.977735) (xy 115.362482 -28.96108) (xy 115.362482 -25.692354) (xy 115.488212 -25.566624)
			(xy 115.488212 -24.889968) (xy 115.289584 -24.69134) (xy 115.162584 -24.69134) (xy 114.802666 -25.051512)
			(xy 114.783022 -25.070511) (xy 114.739271 -25.10326) (xy 114.691293 -25.129426) (xy 114.640069 -25.148471)
			(xy 114.586651 -25.160006) (xy 114.532132 -25.163795) (xy 114.477632 -25.159759) (xy 114.424267 -25.147981)
			(xy 114.37313 -25.128703) (xy 114.325271 -25.102319) (xy 114.28167 -25.069372) (xy 114.262154 -25.050242)
			(xy 114.2619 -25.050242) (xy 114.2619 -25.049988) (xy 114.249768 -25.038527) (xy 114.220889 -25.021818)
			(xy 114.188666 -25.013167) (xy 114.155302 -25.013167) (xy 114.123079 -25.021818) (xy 114.0942 -25.038527)
			(xy 114.082068 -25.049988) (xy 113.732056 -25.4) (xy 113.732056 -26.309828) (xy 112.664748 -26.309828)
			(xy 112.664748 -25.480264) (xy 112.664201 -25.463617) (xy 112.655578 -25.431457) (xy 112.638928 -25.402624)
			(xy 112.615386 -25.379079) (xy 112.586554 -25.362427) (xy 112.554395 -25.353801) (xy 112.537748 -25.353264)
			(xy 111.272828 -25.353264) (xy 110.62208 -24.702516) (xy 110.62208 -24.664162) (xy 107.94238 -21.984462)
			(xy 107.94238 -17.537176) (xy 107.121706 -16.716502) (xy 103.742998 -16.716502) (xy 103.142542 -17.316958)
			(xy 103.142542 -18.747232) (xy 104.863392 -18.747232) (xy 104.863392 -17.781016) (xy 105.23728 -17.781016)
			(xy 105.254806 -17.77619) (xy 105.282608 -17.768505) (xy 105.339456 -17.758736) (xy 105.397046 -17.755465)
			(xy 105.454636 -17.758736) (xy 105.511484 -17.768505) (xy 105.539286 -17.77619) (xy 105.556812 -17.781016)
			(xy 105.9307 -17.781016) (xy 105.9307 -18.747232) (xy 105.9053 -18.747232) (xy 105.9053 -19.123914)
			(xy 105.904799 -19.155859) (xy 105.896791 -19.219245) (xy 105.880902 -19.281128) (xy 105.857383 -19.340532)
			(xy 105.826603 -19.396519) (xy 105.78905 -19.448208) (xy 105.745314 -19.494782) (xy 105.696086 -19.535507)
			(xy 105.642141 -19.569741) (xy 105.584332 -19.596944) (xy 105.523569 -19.616687) (xy 105.46081 -19.628659)
			(xy 105.397046 -19.632671) (xy 105.333282 -19.628659) (xy 105.270523 -19.616687) (xy 105.20976 -19.596944)
			(xy 105.151951 -19.569741) (xy 105.098006 -19.535507) (xy 105.048778 -19.494782) (xy 105.005042 -19.448208)
			(xy 104.967489 -19.396519) (xy 104.936709 -19.340532) (xy 104.91319 -19.281128) (xy 104.897301 -19.219245)
			(xy 104.889293 -19.155859) (xy 104.888792 -19.123914) (xy 104.888792 -18.747232) (xy 104.863392 -18.747232)
			(xy 103.142542 -18.747232) (xy 103.142542 -20.738592) (xy 103.154226 -20.763738) (xy 103.167141 -20.793058)
			(xy 103.185356 -20.854482) (xy 103.194557 -20.917886) (xy 103.19512 -20.94992) (xy 103.19512 -22.530308)
			(xy 103.194544 -22.562341) (xy 103.185329 -22.62574) (xy 103.167135 -22.687168) (xy 103.154226 -22.71649)
			(xy 103.142542 -22.741636) (xy 103.142542 -23.63724) (xy 103.157782 -23.665434) (xy 103.164549 -23.678175)
			(xy 103.176376 -23.70449) (xy 103.181404 -23.718012) (xy 103.187359 -23.73315) (xy 103.205722 -23.759989)
			(xy 103.230272 -23.781316) (xy 103.259416 -23.795744) (xy 103.29126 -23.802337) (xy 103.323737 -23.800668)
			(xy 103.339392 -23.796244) (xy 103.361849 -23.789466) (xy 103.407954 -23.780807) (xy 103.43134 -23.778972)
			(xy 103.447229 -23.77749) (xy 103.477582 -23.767672) (xy 103.504545 -23.750623) (xy 103.526427 -23.72741)
			(xy 103.541858 -23.69949) (xy 103.549871 -23.668611) (xy 103.549962 -23.63671) (xy 103.542126 -23.605787)
			(xy 103.534972 -23.59152) (xy 103.521693 -23.566141) (xy 103.501443 -23.51256) (xy 103.488718 -23.456713)
			(xy 103.483757 -23.399649) (xy 103.486652 -23.342443) (xy 103.497349 -23.286172) (xy 103.515648 -23.231895)
			(xy 103.541203 -23.180633) (xy 103.573534 -23.133351) (xy 103.612032 -23.090939) (xy 103.655973 -23.054195)
			(xy 103.704529 -23.023811) (xy 103.756787 -23.000359) (xy 103.811763 -22.98428) (xy 103.868422 -22.975877)
			(xy 103.925699 -22.975308) (xy 103.982514 -22.982583) (xy 104.037798 -22.997566) (xy 104.090512 -23.019975)
			(xy 104.139662 -23.049388) (xy 104.184325 -23.085251) (xy 104.223658 -23.126889) (xy 104.256923 -23.173519)
			(xy 104.283492 -23.224263) (xy 104.302866 -23.278166) (xy 104.314679 -23.334214) (xy 104.318711 -23.391351)
			(xy 104.314885 -23.448502) (xy 104.303272 -23.504591) (xy 104.284092 -23.558564) (xy 104.257705 -23.609403)
			(xy 104.224608 -23.656152) (xy 104.185424 -23.697931) (xy 104.140891 -23.733954) (xy 104.091846 -23.763543)
			(xy 104.039213 -23.786141) (xy 104.01173 -23.794212) (xy 103.988993 -23.80102) (xy 103.946368 -23.821883)
			(xy 103.908352 -23.850288) (xy 103.876262 -23.885252) (xy 103.851214 -23.925559) (xy 103.834075 -23.969813)
			(xy 103.825441 -24.016478) (xy 103.82561 -24.063934) (xy 103.829612 -24.087328) (xy 103.834209 -24.113501)
			(xy 103.836967 -24.166568) (xy 103.83233 -24.219504) (xy 103.820389 -24.271284) (xy 103.801375 -24.320905)
			(xy 103.775656 -24.367405) (xy 103.74373 -24.409884) (xy 103.706216 -24.44752) (xy 103.66384 -24.479583)
			(xy 103.617423 -24.505452) (xy 103.567864 -24.524627) (xy 103.542084 -24.531066) (xy 103.506778 -24.539448)
			(xy 103.353616 -24.69261) (xy 103.353616 -25.094499) (xy 104.408977 -25.094499) (xy 104.408977 -25.005477)
			(xy 104.416957 -24.916813) (xy 104.432853 -24.829222) (xy 104.456536 -24.743407) (xy 104.487816 -24.660062)
			(xy 104.526442 -24.579856) (xy 104.572101 -24.503435) (xy 104.624427 -24.431414) (xy 104.682998 -24.364374)
			(xy 104.747343 -24.302854) (xy 104.816943 -24.24735) (xy 104.891239 -24.198308) (xy 104.969631 -24.156123)
			(xy 105.05149 -24.121135) (xy 105.136155 -24.093626) (xy 105.222945 -24.073816) (xy 105.311161 -24.061866)
			(xy 105.400094 -24.057873) (xy 105.489027 -24.061866) (xy 105.577243 -24.073816) (xy 105.664033 -24.093626)
			(xy 105.748698 -24.121135) (xy 105.830557 -24.156123) (xy 105.908949 -24.198308) (xy 105.983245 -24.24735)
			(xy 106.052845 -24.302854) (xy 106.11719 -24.364374) (xy 106.175761 -24.431414) (xy 106.228087 -24.503435)
			(xy 106.273746 -24.579856) (xy 106.312372 -24.660062) (xy 106.343652 -24.743407) (xy 106.367335 -24.829222)
			(xy 106.383231 -24.916813) (xy 106.391211 -25.005477) (xy 106.39171 -25.049988) (xy 106.391211 -25.094499)
			(xy 106.383231 -25.183163) (xy 106.367335 -25.270754) (xy 106.343652 -25.356569) (xy 106.312372 -25.439914)
			(xy 106.273746 -25.52012) (xy 106.228087 -25.596541) (xy 106.175761 -25.668562) (xy 106.11719 -25.735602)
			(xy 106.052845 -25.797122) (xy 105.983245 -25.852626) (xy 105.908949 -25.901668) (xy 105.830557 -25.943853)
			(xy 105.748698 -25.978841) (xy 105.664033 -26.00635) (xy 105.577243 -26.02616) (xy 105.489027 -26.03811)
			(xy 105.400094 -26.042104) (xy 105.311161 -26.03811) (xy 105.222945 -26.02616) (xy 105.136155 -26.00635)
			(xy 105.05149 -25.978841) (xy 104.969631 -25.943853) (xy 104.891239 -25.901668) (xy 104.816943 -25.852626)
			(xy 104.747343 -25.797122) (xy 104.682998 -25.735602) (xy 104.624427 -25.668562) (xy 104.572101 -25.596541)
			(xy 104.526442 -25.52012) (xy 104.487816 -25.439914) (xy 104.456536 -25.356569) (xy 104.432853 -25.270754)
			(xy 104.416957 -25.183163) (xy 104.408977 -25.094499) (xy 103.353616 -25.094499) (xy 103.353616 -27.880564)
			(xy 103.47452 -28.001468) (xy 103.47452 -30.128464) (xy 103.589836 -30.24378) (xy 103.601967 -30.255172)
			(xy 103.630751 -30.271847) (xy 103.662867 -30.280519) (xy 103.679498 -30.281118)
		)
		(stroke
			(width 0)
			(type solid)
		)
		(fill yes)
		(layer "F.Cu")
		(net "PV_VTT_DDR_NODE1")
	)
	(gr_poly
		(pts
			(xy 91.09837 -79.86014) (xy 92.627196 -79.86014) (xy 92.688664 -79.921862) (xy 95.393764 -79.921862)
			(xy 95.98406 -79.331566) (xy 95.98406 -77.87894) (xy 95.79864 -77.69352) (xy 95.79864 -74.504042)
			(xy 94.695518 -73.40092) (xy 86.68766 -73.40092) (xy 86.041738 -74.046842) (xy 86.728552 -74.046842)
			(xy 86.732623 -73.99122) (xy 86.744749 -73.936783) (xy 86.764672 -73.884692) (xy 86.791968 -73.836057)
			(xy 86.826054 -73.791914) (xy 86.866203 -73.753205) (xy 86.911561 -73.720754) (xy 86.961161 -73.695253)
			(xy 87.013945 -73.677246) (xy 87.068788 -73.667116) (xy 87.124522 -73.665079) (xy 87.179959 -73.671179)
			(xy 87.233916 -73.685285) (xy 87.285245 -73.707097) (xy 87.332851 -73.736151) (xy 87.375719 -73.771826)
			(xy 87.412936 -73.813363) (xy 87.443709 -73.859876) (xy 87.467381 -73.910373) (xy 87.483449 -73.96378)
			(xy 87.491569 -74.018956) (xy 87.492078 -74.046842) (xy 87.491569 -74.074728) (xy 87.483449 -74.129904)
			(xy 87.467381 -74.183311) (xy 87.443709 -74.233808) (xy 87.412936 -74.280321) (xy 87.375719 -74.321858)
			(xy 87.332851 -74.357533) (xy 87.285245 -74.386587) (xy 87.233916 -74.408399) (xy 87.179959 -74.422505)
			(xy 87.124522 -74.428605) (xy 87.068788 -74.426568) (xy 87.013945 -74.416438) (xy 86.961161 -74.398431)
			(xy 86.911561 -74.37293) (xy 86.866203 -74.340479) (xy 86.826054 -74.30177) (xy 86.791968 -74.257627)
			(xy 86.764672 -74.208992) (xy 86.744749 -74.156901) (xy 86.732623 -74.102464) (xy 86.728552 -74.046842)
			(xy 86.041738 -74.046842) (xy 85.891878 -74.196702) (xy 83.54822 -74.196702) (xy 83.093306 -74.651616)
			(xy 82.789268 -74.651616) (xy 82.789268 -74.680064) (xy 82.02676 -74.680064) (xy 82.02676 -74.651616)
			(xy 81.794604 -74.651616) (xy 81.756504 -74.689716) (xy 81.629504 -74.689716) (xy 80.993488 -74.689716)
			(xy 80.955388 -74.651616) (xy 80.145636 -74.651616) (xy 80.128979 -74.652106) (xy 80.096798 -74.660722)
			(xy 80.067945 -74.677374) (xy 80.044387 -74.700929) (xy 80.027729 -74.72978) (xy 80.019109 -74.761959)
			(xy 80.018636 -74.778616) (xy 80.018636 -75.393804) (xy 80.11033 -75.485498) (xy 80.898238 -75.485498)
			(xy 81.100168 -75.687428) (xy 84.169504 -75.687428) (xy 84.201119 -75.687945) (xy 84.263808 -75.696199)
			(xy 84.324884 -75.712564) (xy 84.3833 -75.736762) (xy 84.438059 -75.768377) (xy 84.488223 -75.80687)
			(xy 84.532933 -75.85158) (xy 84.571425 -75.901744) (xy 84.60304 -75.956503) (xy 84.627237 -76.01492)
			(xy 84.643602 -76.075996) (xy 84.651855 -76.138685) (xy 84.651855 -76.201915) (xy 84.643602 -76.264604)
			(xy 84.627237 -76.32568) (xy 84.60304 -76.384097) (xy 84.571425 -76.438856) (xy 84.532933 -76.48902)
			(xy 84.488223 -76.53373) (xy 84.438059 -76.572223) (xy 84.3833 -76.603838) (xy 84.324884 -76.628036)
			(xy 84.263808 -76.644401) (xy 84.201119 -76.652655) (xy 84.169504 -76.653136) (xy 81.26476 -76.653136)
			(xy 81.26476 -76.65847) (xy 81.099914 -76.823316) (xy 80.0735 -76.823316) (xy 80.018636 -76.87818)
			(xy 80.018636 -78.69047) (xy 80.05699 -78.728824) (xy 83.568794 -78.728824) (xy 83.884516 -78.413102)
			(xy 85.053932 -78.413102) (xy 85.315044 -78.15199) (xy 85.315044 -75.411076) (xy 85.454998 -75.271122)
			(xy 87.310976 -75.271122) (xy 87.919052 -74.6633) (xy 91.547188 -74.6633) (xy 91.849956 -74.966068)
			(xy 91.849956 -77.007657) (xy 92.891921 -77.007657) (xy 92.896765 -76.952398) (xy 92.909561 -76.898424)
			(xy 92.930038 -76.846871) (xy 92.957765 -76.798828) (xy 92.992157 -76.755306) (xy 93.03249 -76.717224)
			(xy 93.077913 -76.685385) (xy 93.127467 -76.660459) (xy 93.180109 -76.642972) (xy 93.207332 -76.637642)
			(xy 93.230933 -76.632894) (xy 93.27592 -76.615774) (xy 93.316879 -76.590492) (xy 93.352347 -76.557951)
			(xy 93.381055 -76.519315) (xy 93.401976 -76.475965) (xy 93.414362 -76.429453) (xy 93.416628 -76.405486)
			(xy 93.41908 -76.378384) (xy 93.43062 -76.325207) (xy 93.449599 -76.27421) (xy 93.475632 -76.226426)
			(xy 93.50819 -76.182826) (xy 93.546612 -76.144295) (xy 93.59012 -76.111614) (xy 93.63783 -76.085447)
			(xy 93.688774 -76.066324) (xy 93.741918 -76.054635) (xy 93.796184 -76.050614) (xy 93.850471 -76.054346)
			(xy 93.903677 -76.065753) (xy 93.954722 -76.084604) (xy 94.00257 -76.110518) (xy 94.046251 -76.142967)
			(xy 94.084878 -76.181293) (xy 94.117668 -76.224719) (xy 94.143954 -76.272363) (xy 94.163204 -76.323259)
			(xy 94.175026 -76.376374) (xy 94.179182 -76.43063) (xy 94.177866 -76.45781) (xy 94.176881 -76.479382)
			(xy 94.181321 -76.522332) (xy 94.192961 -76.563913) (xy 94.211466 -76.602925) (xy 94.236303 -76.638245)
			(xy 94.266757 -76.668856) (xy 94.30195 -76.693874) (xy 94.340867 -76.712579) (xy 94.361508 -76.718922)
			(xy 94.388534 -76.727231) (xy 94.440013 -76.75061) (xy 94.487479 -76.781328) (xy 94.529893 -76.818713)
			(xy 94.566327 -76.861948) (xy 94.595982 -76.910085) (xy 94.61821 -76.96207) (xy 94.632525 -77.016767)
			(xy 94.638612 -77.072977) (xy 94.636338 -77.12947) (xy 94.625754 -77.185009) (xy 94.607091 -77.238379)
			(xy 94.580757 -77.28841) (xy 94.54733 -77.334009) (xy 94.50754 -77.374176) (xy 94.485206 -77.391514)
			(xy 94.471831 -77.402264) (xy 94.450791 -77.42935) (xy 94.437722 -77.46106) (xy 94.433569 -77.495106)
			(xy 94.43863 -77.529028) (xy 94.445074 -77.54493) (xy 94.455933 -77.570376) (xy 94.470986 -77.623612)
			(xy 94.478195 -77.678464) (xy 94.477408 -77.733783) (xy 94.468641 -77.788408) (xy 94.452079 -77.841194)
			(xy 94.428068 -77.891036) (xy 94.397113 -77.936889) (xy 94.35986 -77.977791) (xy 94.317093 -78.012886)
			(xy 94.269706 -78.041437) (xy 94.218692 -78.062847) (xy 94.165122 -78.076667) (xy 94.110118 -78.082607)
			(xy 94.054833 -78.080542) (xy 94.000425 -78.070516) (xy 93.948035 -78.052739) (xy 93.898761 -78.027584)
			(xy 93.853636 -77.995577) (xy 93.813605 -77.95739) (xy 93.779507 -77.913823) (xy 93.752058 -77.865789)
			(xy 93.731832 -77.814295) (xy 93.719253 -77.760421) (xy 93.714585 -77.705294) (xy 93.717926 -77.650071)
			(xy 93.729206 -77.595909) (xy 93.748188 -77.543944) (xy 93.774475 -77.495264) (xy 93.807515 -77.45089)
			(xy 93.846617 -77.411751) (xy 93.868494 -77.394816) (xy 93.881921 -77.384125) (xy 93.902959 -77.357022)
			(xy 93.916019 -77.325295) (xy 93.920159 -77.291236) (xy 93.91508 -77.257304) (xy 93.908626 -77.2414)
			(xy 93.899394 -77.219911) (xy 93.885638 -77.175208) (xy 93.881194 -77.152246) (xy 93.878052 -77.137306)
			(xy 93.865689 -77.109401) (xy 93.847046 -77.085236) (xy 93.823191 -77.066198) (xy 93.795494 -77.053378)
			(xy 93.765542 -77.047511) (xy 93.735055 -77.048935) (xy 93.705781 -77.057567) (xy 93.679399 -77.072913)
			(xy 93.657422 -77.094091) (xy 93.641111 -77.119888) (xy 93.63583 -77.134212) (xy 93.626491 -77.160334)
			(xy 93.601481 -77.209846) (xy 93.569564 -77.255214) (xy 93.531413 -77.295482) (xy 93.487833 -77.3298)
			(xy 93.439742 -77.357445) (xy 93.388155 -77.377835) (xy 93.334159 -77.390538) (xy 93.278892 -77.395288)
			(xy 93.22352 -77.391984) (xy 93.16921 -77.380696) (xy 93.117108 -77.361662) (xy 93.068311 -77.335283)
			(xy 93.023849 -77.302115) (xy 92.984659 -77.262858) (xy 92.951567 -77.21834) (xy 92.925272 -77.169498)
			(xy 92.906326 -77.117363) (xy 92.895131 -77.063034) (xy 92.891921 -77.007657) (xy 91.849956 -77.007657)
			(xy 91.849956 -77.812138) (xy 91.771216 -77.891132) (xy 91.771216 -77.936598) (xy 90.66911 -79.038704)
			(xy 89.302082 -79.038704) (xy 89.14892 -78.885542) (xy 89.14892 -78.675992) (xy 89.14892 -78.164944)
			(xy 89.01176 -78.027784) (xy 88.0364 -78.027784) (xy 88.020703 -78.028889) (xy 87.990542 -78.037829)
			(xy 87.963496 -78.053897) (xy 87.94122 -78.076109) (xy 87.925075 -78.103109) (xy 87.916049 -78.133244)
			(xy 87.914988 -78.148942) (xy 87.914988 -78.33995) (xy 87.599012 -78.655926) (xy 87.599012 -79.123032)
			(xy 87.612728 -79.136748) (xy 87.612728 -79.814674) (xy 87.613965 -79.830813) (xy 87.623549 -79.861719)
			(xy 87.640584 -79.88923) (xy 87.66398 -79.911583) (xy 87.692239 -79.927347) (xy 87.72355 -79.935512)
			(xy 87.739728 -79.936086) (xy 89.380822 -79.936086) (xy 89.505536 -80.0608) (xy 89.625678 -80.0608)
			(xy 89.64168 -80.077056) (xy 90.881454 -80.077056)
		)
		(stroke
			(width 0)
			(type solid)
		)
		(fill yes)
		(layer "F.Cu")
		(net "P1V05_NODE1")
	)
	(gr_poly
		(pts
			(arc
				(start 68.881244 -77.827886)
				(mid 69.06379 -77.750501)
				(end 69.13499 -77.565504)
			)
			(arc
				(start 69.13499 -77.565504)
				(mid 69.156116 -77.443334)
				(end 69.224144 -77.339698)
			)
			(xy 69.296788 -77.267308) (xy 69.314314 -77.201014)
			(arc
				(start 69.30517 -77.167994)
				(mid 69.319371 -76.92385)
				(end 69.478906 -76.73848)
			)
			(arc
				(start 69.478906 -76.73848)
				(mid 69.594172 -76.588607)
				(end 69.573902 -76.40066)
			)
			(arc
				(start 69.573902 -76.40066)
				(mid 69.54297 -76.23774)
				(end 69.609716 -76.085954)
			)
			(arc
				(start 69.609716 -76.085954)
				(mid 69.671992 -75.91933)
				(end 69.609716 -75.752706)
			)
			(arc
				(start 69.609716 -75.752706)
				(mid 69.554418 -75.65447)
				(end 69.542406 -75.542394)
			)
			(arc
				(start 69.542406 -75.542394)
				(mid 69.516794 -75.452628)
				(end 69.436742 -75.404726)
			)
			(arc
				(start 69.436742 -75.404726)
				(mid 69.140031 -75.157649)
				(end 69.210936 -74.778108)
			)
			(arc
				(start 69.210936 -74.778108)
				(mid 69.273124 -74.61817)
				(end 69.219318 -74.455274)
			)
			(arc
				(start 69.219318 -74.455274)
				(mid 69.162775 -74.24435)
				(end 69.274944 -74.057002)
			)
			(xy 69.283072 -74.05116)
			(arc
				(start 69.28993 -74.044048)
				(mid 69.327069 -73.954296)
				(end 69.28993 -73.86447)
			)
			(arc
				(start 69.224144 -73.798938)
				(mid 69.142518 -73.514453)
				(end 69.340476 -73.294494)
			)
			(arc
				(start 69.340476 -73.294494)
				(mid 69.425731 -73.173241)
				(end 69.337936 -73.053702)
			)
			(arc
				(start 69.337936 -73.053702)
				(mid 69.279663 -73.029369)
				(end 69.226176 -72.99579)
			)
			(arc
				(start 69.226176 -72.99579)
				(mid 69.073776 -72.94499)
				(end 68.921376 -72.99579)
			)
			(arc
				(start 68.921376 -72.99579)
				(mid 68.562413 -73.048918)
				(end 68.321428 -72.777604)
			)
			(xy 68.313046 -72.742298) (xy 68.103496 -72.532748)
			(arc
				(start 68.099432 -72.529446)
				(mid 68.081042 -72.512398)
				(end 68.064126 -72.493886)
			)
			(arc
				(start 68.064126 -72.493886)
				(mid 68.020544 -72.46082)
				(end 67.967098 -72.449182)
			)
			(xy 67.91452 -72.449182) (xy 67.840352 -72.52335) (xy 67.840352 -72.85228)
			(arc
				(start 67.851782 -72.877426)
				(mid 67.87984 -72.965131)
				(end 67.886072 -73.057004)
			)
			(arc
				(start 67.886072 -73.057004)
				(mid 67.92362 -73.203982)
				(end 68.038218 -73.303384)
			)
			(arc
				(start 68.038218 -73.303384)
				(mid 68.088059 -73.330881)
				(end 68.131944 -73.367138)
			)
			(xy 68.325746 -73.561194)
			(arc
				(start 68.367148 -73.56729)
				(mid 68.655409 -73.79208)
				(end 68.612766 -74.155046)
			)
			(arc
				(start 68.612766 -74.155046)
				(mid 68.56411 -74.300354)
				(end 68.60794 -74.447146)
			)
			(arc
				(start 68.60794 -74.447146)
				(mid 68.649536 -74.79488)
				(end 68.390008 -75.030076)
			)
			(arc
				(start 68.390008 -75.030076)
				(mid 68.3189 -75.079719)
				(end 68.296282 -75.163426)
			)
			(arc
				(start 68.297552 -75.186032)
				(mid 68.322559 -75.258476)
				(end 68.384674 -75.30338)
			)
			(arc
				(start 68.384674 -75.30338)
				(mid 68.565139 -75.488526)
				(end 68.517008 -75.742546)
			)
			(arc
				(start 68.517008 -75.742546)
				(mid 68.462625 -75.906715)
				(end 68.525898 -76.067666)
			)
			(arc
				(start 68.525898 -76.067666)
				(mid 68.582525 -76.161525)
				(end 68.602352 -76.269342)
			)
			(xy 68.602352 -76.519278) (xy 68.628768 -76.572618)
			(arc
				(start 68.652644 -76.590652)
				(mid 68.788952 -77.001144)
				(end 68.45427 -77.275182)
			)
			(arc
				(start 68.45427 -77.275182)
				(mid 68.28854 -77.356274)
				(end 68.221352 -77.528166)
			)
			(xy 68.221352 -77.555598)
			(arc
				(start 68.221098 -77.565504)
				(mid 68.292381 -77.750421)
				(end 68.474844 -77.827886)
			)
		)
		(stroke
			(width 0)
			(type solid)
		)
		(fill yes)
		(layer "F.Cu")
		(net "GND")
	)
	(gr_poly
		(pts
			(xy 58.794396 -80.55483)
			(arc
				(start 58.803032 -80.514444)
				(mid 58.813377 -80.476003)
				(end 58.827416 -80.438752)
			)
			(arc
				(start 58.827416 -80.438752)
				(mid 58.865983 -80.369192)
				(end 58.917332 -80.30845)
			)
			(arc
				(start 58.917332 -80.30845)
				(mid 58.95583 -80.214563)
				(end 58.913268 -80.122522)
			)
			(xy 58.895234 -80.105504)
			(arc
				(start 58.095134 -79.305404)
				(mid 58.001121 -79.164389)
				(end 57.968642 -78.998064)
			)
			(arc
				(start 57.968642 -78.998064)
				(mid 57.992255 -78.858702)
				(end 58.059574 -78.734412)
			)
			(arc
				(start 58.059574 -78.734412)
				(mid 58.113112 -78.586944)
				(end 58.069734 -78.436216)
			)
			(arc
				(start 58.069734 -78.436216)
				(mid 58.047464 -78.401443)
				(end 58.02884 -78.364588)
			)
			(arc
				(start 58.02884 -78.364588)
				(mid 58.00271 -78.283997)
				(end 57.993788 -78.199742)
			)
			(xy 57.993788 -77.972158) (xy 58.062114 -77.903832) (xy 58.37301 -77.59319) (xy 58.378852 -77.587094)
			(xy 58.379868 -77.586332) (xy 58.492136 -77.474064) (xy 59.050174 -77.474064) (xy 59.46394 -77.88783)
			(xy 59.567064 -77.9907) (xy 59.671966 -77.9907)
			(arc
				(start 59.694064 -77.968602)
				(mid 59.711009 -77.94779)
				(end 59.72937 -77.928216)
			)
			(arc
				(start 60.117228 -77.540104)
				(mid 60.148712 -77.509362)
				(end 60.183522 -77.482446)
			)
			(xy 60.209176 -77.456792) (xy 60.20943 -77.351636)
			(arc
				(start 60.141104 -77.283564)
				(mid 60.109926 -77.251483)
				(end 60.082684 -77.216)
			)
			(xy 60.056014 -77.18933) (xy 59.950858 -77.189076)
			(arc
				(start 59.870594 -77.26934)
				(mid 59.6155 -77.380792)
				(end 59.352688 -77.289152)
			)
			(arc
				(start 59.352688 -77.289152)
				(mid 59.290806 -77.221634)
				(end 59.24677 -77.141324)
			)
			(xy 59.23534 -77.112622) (xy 59.137042 -77.028294)
			(arc
				(start 59.106054 -77.021182)
				(mid 59.059704 -77.007985)
				(end 59.015122 -76.989686)
			)
			(arc
				(start 59.015122 -76.989686)
				(mid 58.95158 -76.952499)
				(end 58.895234 -76.905104)
			)
			(xy 58.095134 -76.105004)
			(arc
				(start 58.078116 -76.08697)
				(mid 57.986071 -76.044576)
				(end 57.892188 -76.082906)
			)
			(arc
				(start 57.892188 -76.082906)
				(mid 57.60347 -76.206098)
				(end 57.313068 -76.08697)
			)
			(arc
				(start 56.512968 -75.28687)
				(mid 56.476417 -75.2451)
				(end 56.445912 -75.198732)
			)
			(xy 56.4388 -75.185524) (xy 56.429656 -75.167998) (xy 56.121046 -74.859388)
			(arc
				(start 55.904892 -74.643234)
				(mid 55.86377 -74.615664)
				(end 55.81523 -74.605896)
			)
			(arc
				(start 55.66283 -74.605896)
				(mid 55.573027 -74.643093)
				(end 55.53583 -74.732896)
			)
			(xy 55.53583 -74.766932)
			(arc
				(start 55.552848 -74.796396)
				(mid 55.601731 -75.065144)
				(end 55.469536 -75.304142)
			)
			(arc
				(start 55.469536 -75.304142)
				(mid 55.427069 -75.388067)
				(end 55.454042 -75.478132)
			)
			(arc
				(start 55.454042 -75.478132)
				(mid 55.472416 -75.493481)
				(end 55.489856 -75.509882)
			)
			(arc
				(start 55.531004 -75.55103)
				(mid 55.62092 -75.588349)
				(end 55.710836 -75.55103)
			)
			(xy 55.711852 -75.550014)
			(arc
				(start 55.714646 -75.546966)
				(mid 55.790214 -75.48129)
				(end 55.880254 -75.437492)
			)
			(arc
				(start 55.880254 -75.437492)
				(mid 56.088251 -75.428331)
				(end 56.270144 -75.529694)
			)
			(arc
				(start 57.070244 -76.329794)
				(mid 57.070244 -76.86929)
				(end 56.530748 -76.86929)
			)
			(xy 56.068468 -76.40701) (xy 55.96382 -76.40701)
			(arc
				(start 55.93334 -76.43749)
				(mid 55.902699 -76.475248)
				(end 55.867808 -76.509118)
			)
			(arc
				(start 55.84698 -76.555346)
				(mid 55.837883 -76.630244)
				(end 55.872888 -76.697078)
			)
			(arc
				(start 55.887874 -76.712064)
				(mid 55.955998 -76.802473)
				(end 55.996586 -76.908152)
			)
			(arc
				(start 55.996586 -76.908152)
				(mid 56.030533 -76.969455)
				(end 56.091836 -77.003402)
			)
			(arc
				(start 56.091836 -77.003402)
				(mid 56.197529 -77.043965)
				(end 56.287924 -77.112114)
			)
			(xy 56.687974 -77.512164) (xy 56.702198 -77.526896) (xy 56.705246 -77.530198) (xy 56.707532 -77.532738)
			(arc
				(start 56.709818 -77.535024)
				(mid 56.799644 -77.572343)
				(end 56.88965 -77.535278)
			)
			(xy 56.947562 -77.477366)
			(arc
				(start 57.313068 -77.112114)
				(mid 57.888124 -77.112114)
				(end 57.888124 -77.68717)
			)
			(xy 57.088024 -78.48727)
			(arc
				(start 57.08396 -78.491334)
				(mid 57.045462 -78.585221)
				(end 57.088024 -78.677262)
			)
			(xy 57.106058 -78.69428)
			(arc
				(start 57.906158 -79.49438)
				(mid 58.03258 -79.81117)
				(end 57.889902 -80.120998)
			)
			(xy 57.885076 -80.125316)
			(arc
				(start 57.87898 -80.13192)
				(mid 57.845849 -80.218955)
				(end 57.881012 -80.305148)
			)
			(xy 57.883806 -80.307942)
			(arc
				(start 57.888124 -80.312514)
				(mid 57.942854 -80.380488)
				(end 57.98185 -80.458564)
			)
			(arc
				(start 57.98185 -80.458564)
				(mid 57.991116 -80.486206)
				(end 57.99836 -80.514444)
			)
			(xy 58.006996 -80.55483) (xy 58.130694 -80.665066) (xy 58.670698 -80.665066)
		)
		(stroke
			(width 0)
			(type solid)
		)
		(fill yes)
		(layer "F.Cu")
		(net "GND")
	)
	(gr_poly
		(pts
			(xy 19.000216 -182.799736) (xy 19.000706 -182.909332) (xy 19.008702 -183.128379) (xy 19.024693 -183.346988)
			(xy 19.048658 -183.564866) (xy 19.080564 -183.781724) (xy 19.12037 -183.997272) (xy 19.168021 -184.211223)
			(xy 19.223455 -184.42329) (xy 19.286597 -184.633191) (xy 19.357363 -184.840646) (xy 19.435659 -185.045378)
			(xy 19.52138 -185.247114) (xy 19.614411 -185.445585) (xy 19.71463 -185.640525) (xy 19.821901 -185.831675)
			(xy 19.936082 -186.018779) (xy 20.057021 -186.201589) (xy 20.184555 -186.379859) (xy 20.318516 -186.553353)
			(xy 20.458724 -186.721838) (xy 20.604991 -186.88509) (xy 20.757124 -187.042891) (xy 20.914918 -187.19503)
			(xy 21.078164 -187.341304) (xy 21.246643 -187.481519) (xy 21.420131 -187.615487) (xy 21.598396 -187.743029)
			(xy 21.7812 -187.863976) (xy 21.9683 -187.978165) (xy 22.159445 -188.085444) (xy 22.354381 -188.185671)
			(xy 22.552848 -188.278711) (xy 22.75458 -188.36444) (xy 22.959309 -188.442745) (xy 23.166761 -188.51352)
			(xy 23.376659 -188.57667) (xy 23.588724 -188.632113) (xy 23.802673 -188.679773) (xy 24.018219 -188.719588)
			(xy 24.235076 -188.751504) (xy 24.452953 -188.775478) (xy 24.671561 -188.791478) (xy 24.890608 -188.799484)
			(xy 25.1098 -188.799484) (xy 25.328847 -188.791478) (xy 25.547455 -188.775478) (xy 25.765332 -188.751504)
			(xy 25.982189 -188.719588) (xy 26.197735 -188.679773) (xy 26.411684 -188.632113) (xy 26.623749 -188.57667)
			(xy 26.833647 -188.51352) (xy 27.041099 -188.442745) (xy 27.245828 -188.36444) (xy 27.44756 -188.278711)
			(xy 27.646027 -188.185671) (xy 27.840963 -188.085444) (xy 28.032108 -187.978165) (xy 28.219208 -187.863976)
			(xy 28.402012 -187.743029) (xy 28.580277 -187.615487) (xy 28.753765 -187.481519) (xy 28.922244 -187.341304)
			(xy 29.08549 -187.19503) (xy 29.243284 -187.042891) (xy 29.395417 -186.88509) (xy 29.541684 -186.721838)
			(xy 29.681892 -186.553353) (xy 29.815853 -186.379859) (xy 29.943387 -186.201589) (xy 30.064326 -186.018779)
			(xy 30.178507 -185.831675) (xy 30.285778 -185.640525) (xy 30.385997 -185.445585) (xy 30.479028 -185.247114)
			(xy 30.564749 -185.045378) (xy 30.643045 -184.840646) (xy 30.713811 -184.633191) (xy 30.776953 -184.42329)
			(xy 30.832387 -184.211223) (xy 30.880038 -183.997272) (xy 30.919844 -183.781724) (xy 30.95175 -183.564866)
			(xy 30.975715 -183.346988) (xy 30.991706 -183.128379) (xy 30.999702 -182.909332) (xy 31.000192 -182.799736)
			(xy 30.999938 -177.749962) (xy 30.998539 -177.640959) (xy 30.988802 -177.423155) (xy 30.971159 -177.205849)
			(xy 30.945633 -176.989327) (xy 30.912258 -176.773876) (xy 30.871079 -176.559779) (xy 30.822148 -176.347319)
			(xy 30.765532 -176.136777) (xy 30.701305 -175.928431) (xy 30.629551 -175.722556) (xy 30.550365 -175.519423)
			(xy 30.463852 -175.319301) (xy 30.370126 -175.122454) (xy 30.269311 -174.929142) (xy 30.16154 -174.73962)
			(xy 30.046955 -174.554138) (xy 29.925707 -174.372941) (xy 29.797957 -174.196268) (xy 29.663873 -174.024353)
			(xy 29.523632 -173.857423) (xy 29.37742 -173.695697) (xy 29.225428 -173.53939) (xy 29.067859 -173.388708)
			(xy 28.90492 -173.243849) (xy 28.736826 -173.105005) (xy 28.563798 -172.972359) (xy 28.386067 -172.846087)
			(xy 28.203865 -172.726355) (xy 28.017434 -172.613321) (xy 27.827019 -172.507134) (xy 27.632873 -172.407934)
			(xy 27.435251 -172.315854) (xy 27.234415 -172.231013) (xy 27.030629 -172.153524) (xy 26.824162 -172.083489)
			(xy 26.615288 -172.021002) (xy 26.404281 -171.966143) (xy 26.191421 -171.918986) (xy 25.976988 -171.879594)
			(xy 25.761265 -171.848017) (xy 25.544538 -171.824298) (xy 25.327092 -171.808467) (xy 25.109215 -171.800547)
			(xy 24.891193 -171.800547) (xy 24.673316 -171.808467) (xy 24.45587 -171.824298) (xy 24.239143 -171.848017)
			(xy 24.02342 -171.879594) (xy 23.808987 -171.918986) (xy 23.596127 -171.966143) (xy 23.38512 -172.021002)
			(xy 23.176246 -172.083489) (xy 22.969779 -172.153524) (xy 22.765993 -172.231013) (xy 22.565157 -172.315854)
			(xy 22.367535 -172.407934) (xy 22.173389 -172.507134) (xy 21.982974 -172.613321) (xy 21.796543 -172.726355)
			(xy 21.614341 -172.846087) (xy 21.43661 -172.972359) (xy 21.263582 -173.105005) (xy 21.095488 -173.243849)
			(xy 20.932549 -173.388708) (xy 20.77498 -173.53939) (xy 20.622988 -173.695697) (xy 20.476776 -173.857423)
			(xy 20.336535 -174.024353) (xy 20.202451 -174.196268) (xy 20.074701 -174.372941) (xy 19.953453 -174.554138)
			(xy 19.838868 -174.73962) (xy 19.731097 -174.929142) (xy 19.630282 -175.122454) (xy 19.536556 -175.319301)
			(xy 19.450043 -175.519423) (xy 19.370857 -175.722556) (xy 19.299103 -175.928431) (xy 19.234876 -176.136777)
			(xy 19.17826 -176.347319) (xy 19.129329 -176.559779) (xy 19.08815 -176.773876) (xy 19.054775 -176.989327)
			(xy 19.029249 -177.205849) (xy 19.011606 -177.423155) (xy 19.001869 -177.640959) (xy 19.000504 -177.747317)
			(xy 20.989385 -177.747317) (xy 20.9957 -177.568929) (xy 21.009946 -177.390997) (xy 21.032093 -177.213876)
			(xy 21.062099 -177.037915) (xy 21.099904 -176.863464) (xy 21.145432 -176.690867) (xy 21.198594 -176.520467)
			(xy 21.259285 -176.3526) (xy 21.327384 -176.1876) (xy 21.402756 -176.025793) (xy 21.485252 -175.8675)
			(xy 21.57471 -175.713033) (xy 21.67095 -175.5627) (xy 21.773784 -175.416797) (xy 21.883008 -175.275613)
			(xy 21.998404 -175.139429) (xy 22.119745 -175.008513) (xy 22.24679 -174.883126) (xy 22.379288 -174.763515)
			(xy 22.516976 -174.649917) (xy 22.659582 -174.542558) (xy 22.806823 -174.441649) (xy 22.958408 -174.347391)
			(xy 23.114036 -174.25997) (xy 23.273399 -174.17956) (xy 23.436182 -174.106319) (xy 23.602062 -174.040393)
			(xy 23.770711 -173.981913) (xy 23.941795 -173.930993) (xy 24.114975 -173.887736) (xy 24.289908 -173.852226)
			(xy 24.466247 -173.824534) (xy 24.643644 -173.804714) (xy 24.821748 -173.792807) (xy 25.000204 -173.788835)
			(xy 25.17866 -173.792807) (xy 25.356764 -173.804714) (xy 25.534161 -173.824534) (xy 25.7105 -173.852226)
			(xy 25.885433 -173.887736) (xy 26.058613 -173.930993) (xy 26.229697 -173.981913) (xy 26.398346 -174.040393)
			(xy 26.564226 -174.106319) (xy 26.727009 -174.17956) (xy 26.886372 -174.25997) (xy 27.042 -174.347391)
			(xy 27.193585 -174.441649) (xy 27.340826 -174.542558) (xy 27.483432 -174.649917) (xy 27.62112 -174.763515)
			(xy 27.753618 -174.883126) (xy 27.880663 -175.008513) (xy 28.002004 -175.139429) (xy 28.1174 -175.275613)
			(xy 28.226624 -175.416797) (xy 28.329458 -175.5627) (xy 28.425698 -175.713033) (xy 28.515156 -175.8675)
			(xy 28.597652 -176.025793) (xy 28.673024 -176.1876) (xy 28.741123 -176.3526) (xy 28.801814 -176.520467)
			(xy 28.854976 -176.690867) (xy 28.900504 -176.863464) (xy 28.938309 -177.037915) (xy 28.968315 -177.213876)
			(xy 28.990462 -177.390997) (xy 29.004708 -177.568929) (xy 29.011023 -177.747317) (xy 29.009395 -177.925811)
			(xy 28.999828 -178.104055) (xy 28.982341 -178.281697) (xy 28.956967 -178.458385) (xy 28.923758 -178.633769)
			(xy 28.882778 -178.807502) (xy 28.83411 -178.97924) (xy 28.77785 -179.148643) (xy 28.714108 -179.315374)
			(xy 28.643012 -179.479105) (xy 28.564701 -179.639511) (xy 28.479332 -179.796274) (xy 28.387073 -179.949083)
			(xy 28.288107 -180.097637) (xy 28.18263 -180.241641) (xy 28.07085 -180.380809) (xy 27.95299 -180.514866)
			(xy 27.829282 -180.643547) (xy 27.699971 -180.766597) (xy 27.565314 -180.883772) (xy 27.495754 -180.939694)
			(xy 27.471441 -180.959638) (xy 27.427607 -181.004729) (xy 27.389918 -181.055068) (xy 27.358994 -181.109824)
			(xy 27.335348 -181.168094) (xy 27.319368 -181.228915) (xy 27.311321 -181.291283) (xy 27.310842 -181.322726)
			(xy 27.310842 -182.79999) (xy 27.310335 -182.868477) (xy 27.30222 -183.00521) (xy 27.28602 -183.141223)
			(xy 27.26179 -183.276037) (xy 27.229617 -183.409178) (xy 27.189613 -183.54018) (xy 27.141919 -183.668582)
			(xy 27.086701 -183.793933) (xy 27.024155 -183.915793) (xy 26.954499 -184.033733) (xy 26.877979 -184.14734)
			(xy 26.794864 -184.256215) (xy 26.705444 -184.359974) (xy 26.610035 -184.458254) (xy 26.508971 -184.550709)
			(xy 26.402607 -184.637014) (xy 26.291318 -184.716867) (xy 26.175493 -184.789987) (xy 26.055541 -184.856117)
			(xy 25.931881 -184.915025) (xy 25.804949 -184.966503) (xy 25.67519 -185.010372) (xy 25.54306 -185.046476)
			(xy 25.409023 -185.07469) (xy 25.273551 -185.094914) (xy 25.137118 -185.107077) (xy 25.000204 -185.111136)
			(xy 24.86329 -185.107077) (xy 24.726857 -185.094914) (xy 24.591385 -185.07469) (xy 24.457348 -185.046476)
			(xy 24.325218 -185.010372) (xy 24.195459 -184.966503) (xy 24.068527 -184.915025) (xy 23.944867 -184.856117)
			(xy 23.824915 -184.789987) (xy 23.70909 -184.716867) (xy 23.597801 -184.637014) (xy 23.491437 -184.550709)
			(xy 23.390373 -184.458254) (xy 23.294964 -184.359974) (xy 23.205544 -184.256215) (xy 23.122429 -184.14734)
			(xy 23.045909 -184.033733) (xy 22.976253 -183.915793) (xy 22.913707 -183.793933) (xy 22.858489 -183.668582)
			(xy 22.810795 -183.54018) (xy 22.770791 -183.409178) (xy 22.738618 -183.276037) (xy 22.714388 -183.141223)
			(xy 22.698188 -183.00521) (xy 22.690073 -182.868477) (xy 22.689566 -182.79999) (xy 22.689566 -181.322726)
			(xy 22.689088 -181.291287) (xy 22.680995 -181.228931) (xy 22.66499 -181.168123) (xy 22.641336 -181.109863)
			(xy 22.610422 -181.055108) (xy 22.572757 -181.004759) (xy 22.528959 -180.959643) (xy 22.504654 -180.939694)
			(xy 22.435094 -180.883772) (xy 22.300437 -180.766597) (xy 22.171126 -180.643547) (xy 22.047418 -180.514866)
			(xy 21.929558 -180.380809) (xy 21.817778 -180.241641) (xy 21.712301 -180.097637) (xy 21.613335 -179.949083)
			(xy 21.521076 -179.796274) (xy 21.435707 -179.639511) (xy 21.357396 -179.479105) (xy 21.2863 -179.315374)
			(xy 21.222558 -179.148643) (xy 21.166298 -178.97924) (xy 21.11763 -178.807502) (xy 21.07665 -178.633769)
			(xy 21.043441 -178.458385) (xy 21.018067 -178.281697) (xy 21.00058 -178.104055) (xy 20.991013 -177.925811)
			(xy 20.989385 -177.747317) (xy 19.000504 -177.747317) (xy 19.00047 -177.749962)
		)
		(stroke
			(width 0)
			(type solid)
		)
		(fill yes)
		(layer "F.Cu")
		(net "GND")
	)
	(gr_poly
		(pts
			(xy 19.000216 -26.799794) (xy 19.000706 -26.90939) (xy 19.008702 -27.128437) (xy 19.024693 -27.347046)
			(xy 19.048658 -27.564924) (xy 19.080564 -27.781782) (xy 19.12037 -27.99733) (xy 19.168021 -28.211281)
			(xy 19.223455 -28.423348) (xy 19.286597 -28.633249) (xy 19.357363 -28.840704) (xy 19.435659 -29.045436)
			(xy 19.52138 -29.247172) (xy 19.614411 -29.445643) (xy 19.71463 -29.640583) (xy 19.821901 -29.831733)
			(xy 19.936082 -30.018837) (xy 20.057021 -30.201647) (xy 20.184555 -30.379917) (xy 20.318516 -30.553411)
			(xy 20.458724 -30.721896) (xy 20.604991 -30.885148) (xy 20.757124 -31.042949) (xy 20.914918 -31.195088)
			(xy 21.078164 -31.341362) (xy 21.246643 -31.481577) (xy 21.420131 -31.615545) (xy 21.598396 -31.743087)
			(xy 21.7812 -31.864034) (xy 21.9683 -31.978223) (xy 22.159445 -32.085502) (xy 22.354381 -32.185729)
			(xy 22.552848 -32.278769) (xy 22.75458 -32.364498) (xy 22.959309 -32.442803) (xy 23.166761 -32.513578)
			(xy 23.376659 -32.576728) (xy 23.588724 -32.632171) (xy 23.802673 -32.679831) (xy 24.018219 -32.719646)
			(xy 24.235076 -32.751562) (xy 24.452953 -32.775536) (xy 24.671561 -32.791536) (xy 24.890608 -32.799542)
			(xy 25.1098 -32.799542) (xy 25.328847 -32.791536) (xy 25.547455 -32.775536) (xy 25.765332 -32.751562)
			(xy 25.982189 -32.719646) (xy 26.197735 -32.679831) (xy 26.411684 -32.632171) (xy 26.623749 -32.576728)
			(xy 26.833647 -32.513578) (xy 27.041099 -32.442803) (xy 27.245828 -32.364498) (xy 27.44756 -32.278769)
			(xy 27.646027 -32.185729) (xy 27.840963 -32.085502) (xy 28.032108 -31.978223) (xy 28.219208 -31.864034)
			(xy 28.402012 -31.743087) (xy 28.580277 -31.615545) (xy 28.753765 -31.481577) (xy 28.922244 -31.341362)
			(xy 29.08549 -31.195088) (xy 29.243284 -31.042949) (xy 29.395417 -30.885148) (xy 29.541684 -30.721896)
			(xy 29.681892 -30.553411) (xy 29.815853 -30.379917) (xy 29.943387 -30.201647) (xy 30.064326 -30.018837)
			(xy 30.178507 -29.831733) (xy 30.285778 -29.640583) (xy 30.385997 -29.445643) (xy 30.479028 -29.247172)
			(xy 30.564749 -29.045436) (xy 30.643045 -28.840704) (xy 30.713811 -28.633249) (xy 30.776953 -28.423348)
			(xy 30.832387 -28.211281) (xy 30.880038 -27.99733) (xy 30.919844 -27.781782) (xy 30.95175 -27.564924)
			(xy 30.975715 -27.347046) (xy 30.991706 -27.128437) (xy 30.999702 -26.90939) (xy 31.000192 -26.799794)
			(xy 30.999938 -21.75002) (xy 30.998539 -21.641017) (xy 30.988802 -21.423213) (xy 30.971159 -21.205907)
			(xy 30.945633 -20.989385) (xy 30.912258 -20.773934) (xy 30.871079 -20.559837) (xy 30.822148 -20.347377)
			(xy 30.765532 -20.136835) (xy 30.701305 -19.928489) (xy 30.629551 -19.722614) (xy 30.550365 -19.519481)
			(xy 30.463852 -19.319359) (xy 30.370126 -19.122512) (xy 30.269311 -18.9292) (xy 30.16154 -18.739678)
			(xy 30.046955 -18.554196) (xy 29.925707 -18.372999) (xy 29.797957 -18.196326) (xy 29.663873 -18.024411)
			(xy 29.523632 -17.857481) (xy 29.37742 -17.695755) (xy 29.225428 -17.539448) (xy 29.067859 -17.388766)
			(xy 28.90492 -17.243907) (xy 28.736826 -17.105063) (xy 28.563798 -16.972417) (xy 28.386067 -16.846145)
			(xy 28.203865 -16.726413) (xy 28.017434 -16.613379) (xy 27.827019 -16.507192) (xy 27.632873 -16.407992)
			(xy 27.435251 -16.315912) (xy 27.234415 -16.231071) (xy 27.030629 -16.153582) (xy 26.824162 -16.083547)
			(xy 26.615288 -16.02106) (xy 26.404281 -15.966201) (xy 26.191421 -15.919044) (xy 25.976988 -15.879652)
			(xy 25.761265 -15.848075) (xy 25.544538 -15.824356) (xy 25.327092 -15.808525) (xy 25.109215 -15.800605)
			(xy 24.891193 -15.800605) (xy 24.673316 -15.808525) (xy 24.45587 -15.824356) (xy 24.239143 -15.848075)
			(xy 24.02342 -15.879652) (xy 23.808987 -15.919044) (xy 23.596127 -15.966201) (xy 23.38512 -16.02106)
			(xy 23.176246 -16.083547) (xy 22.969779 -16.153582) (xy 22.765993 -16.231071) (xy 22.565157 -16.315912)
			(xy 22.367535 -16.407992) (xy 22.173389 -16.507192) (xy 21.982974 -16.613379) (xy 21.796543 -16.726413)
			(xy 21.614341 -16.846145) (xy 21.43661 -16.972417) (xy 21.263582 -17.105063) (xy 21.095488 -17.243907)
			(xy 20.932549 -17.388766) (xy 20.77498 -17.539448) (xy 20.622988 -17.695755) (xy 20.476776 -17.857481)
			(xy 20.336535 -18.024411) (xy 20.202451 -18.196326) (xy 20.074701 -18.372999) (xy 19.953453 -18.554196)
			(xy 19.838868 -18.739678) (xy 19.731097 -18.9292) (xy 19.630282 -19.122512) (xy 19.536556 -19.319359)
			(xy 19.450043 -19.519481) (xy 19.370857 -19.722614) (xy 19.299103 -19.928489) (xy 19.234876 -20.136835)
			(xy 19.17826 -20.347377) (xy 19.129329 -20.559837) (xy 19.08815 -20.773934) (xy 19.054775 -20.989385)
			(xy 19.029249 -21.205907) (xy 19.011606 -21.423213) (xy 19.001869 -21.641017) (xy 19.000504 -21.747375)
			(xy 20.989385 -21.747375) (xy 20.9957 -21.568987) (xy 21.009946 -21.391055) (xy 21.032093 -21.213934)
			(xy 21.062099 -21.037973) (xy 21.099904 -20.863522) (xy 21.145432 -20.690925) (xy 21.198594 -20.520525)
			(xy 21.259285 -20.352658) (xy 21.327384 -20.187658) (xy 21.402756 -20.025851) (xy 21.485252 -19.867558)
			(xy 21.57471 -19.713091) (xy 21.67095 -19.562758) (xy 21.773784 -19.416855) (xy 21.883008 -19.275671)
			(xy 21.998404 -19.139487) (xy 22.119745 -19.008571) (xy 22.24679 -18.883184) (xy 22.379288 -18.763573)
			(xy 22.516976 -18.649975) (xy 22.659582 -18.542616) (xy 22.806823 -18.441707) (xy 22.958408 -18.347449)
			(xy 23.114036 -18.260028) (xy 23.273399 -18.179618) (xy 23.436182 -18.106377) (xy 23.602062 -18.040451)
			(xy 23.770711 -17.981971) (xy 23.941795 -17.931051) (xy 24.114975 -17.887794) (xy 24.289908 -17.852284)
			(xy 24.466247 -17.824592) (xy 24.643644 -17.804772) (xy 24.821748 -17.792865) (xy 25.000204 -17.788893)
			(xy 25.17866 -17.792865) (xy 25.356764 -17.804772) (xy 25.534161 -17.824592) (xy 25.7105 -17.852284)
			(xy 25.885433 -17.887794) (xy 26.058613 -17.931051) (xy 26.229697 -17.981971) (xy 26.398346 -18.040451)
			(xy 26.564226 -18.106377) (xy 26.727009 -18.179618) (xy 26.886372 -18.260028) (xy 27.042 -18.347449)
			(xy 27.193585 -18.441707) (xy 27.340826 -18.542616) (xy 27.483432 -18.649975) (xy 27.62112 -18.763573)
			(xy 27.753618 -18.883184) (xy 27.880663 -19.008571) (xy 28.002004 -19.139487) (xy 28.1174 -19.275671)
			(xy 28.226624 -19.416855) (xy 28.329458 -19.562758) (xy 28.425698 -19.713091) (xy 28.515156 -19.867558)
			(xy 28.597652 -20.025851) (xy 28.673024 -20.187658) (xy 28.741123 -20.352658) (xy 28.801814 -20.520525)
			(xy 28.854976 -20.690925) (xy 28.900504 -20.863522) (xy 28.938309 -21.037973) (xy 28.968315 -21.213934)
			(xy 28.990462 -21.391055) (xy 29.004708 -21.568987) (xy 29.011023 -21.747375) (xy 29.009395 -21.925869)
			(xy 28.999828 -22.104113) (xy 28.982341 -22.281755) (xy 28.956967 -22.458443) (xy 28.923758 -22.633827)
			(xy 28.882778 -22.80756) (xy 28.83411 -22.979298) (xy 28.77785 -23.148701) (xy 28.714108 -23.315432)
			(xy 28.643012 -23.479163) (xy 28.564701 -23.639569) (xy 28.479332 -23.796332) (xy 28.387073 -23.949141)
			(xy 28.288107 -24.097695) (xy 28.18263 -24.241699) (xy 28.07085 -24.380867) (xy 27.95299 -24.514924)
			(xy 27.829282 -24.643605) (xy 27.699971 -24.766655) (xy 27.565314 -24.88383) (xy 27.495754 -24.939752)
			(xy 27.471461 -24.95972) (xy 27.427626 -25.004806) (xy 27.389935 -25.055141) (xy 27.359009 -25.109894)
			(xy 27.335359 -25.16816) (xy 27.319376 -25.228977) (xy 27.311323 -25.291342) (xy 27.310842 -25.322784)
			(xy 27.310842 -26.800048) (xy 27.310335 -26.868535) (xy 27.30222 -27.005268) (xy 27.28602 -27.141281)
			(xy 27.26179 -27.276095) (xy 27.229617 -27.409236) (xy 27.189613 -27.540238) (xy 27.141919 -27.66864)
			(xy 27.086701 -27.793991) (xy 27.024155 -27.915851) (xy 26.954499 -28.033791) (xy 26.877979 -28.147398)
			(xy 26.794864 -28.256273) (xy 26.705444 -28.360032) (xy 26.610035 -28.458312) (xy 26.508971 -28.550767)
			(xy 26.402607 -28.637072) (xy 26.291318 -28.716925) (xy 26.175493 -28.790045) (xy 26.055541 -28.856175)
			(xy 25.931881 -28.915083) (xy 25.804949 -28.966561) (xy 25.67519 -29.01043) (xy 25.54306 -29.046534)
			(xy 25.409023 -29.074748) (xy 25.273551 -29.094972) (xy 25.137118 -29.107135) (xy 25.000204 -29.111194)
			(xy 24.86329 -29.107135) (xy 24.726857 -29.094972) (xy 24.591385 -29.074748) (xy 24.457348 -29.046534)
			(xy 24.325218 -29.01043) (xy 24.195459 -28.966561) (xy 24.068527 -28.915083) (xy 23.944867 -28.856175)
			(xy 23.824915 -28.790045) (xy 23.70909 -28.716925) (xy 23.597801 -28.637072) (xy 23.491437 -28.550767)
			(xy 23.390373 -28.458312) (xy 23.294964 -28.360032) (xy 23.205544 -28.256273) (xy 23.122429 -28.147398)
			(xy 23.045909 -28.033791) (xy 22.976253 -27.915851) (xy 22.913707 -27.793991) (xy 22.858489 -27.66864)
			(xy 22.810795 -27.540238) (xy 22.770791 -27.409236) (xy 22.738618 -27.276095) (xy 22.714388 -27.141281)
			(xy 22.698188 -27.005268) (xy 22.690073 -26.868535) (xy 22.689566 -26.800048) (xy 22.689566 -25.322784)
			(xy 22.689046 -25.291346) (xy 22.68096 -25.228992) (xy 22.664962 -25.168185) (xy 22.641316 -25.109925)
			(xy 22.610408 -25.05517) (xy 22.572749 -25.00482) (xy 22.528956 -24.959702) (xy 22.504654 -24.939752)
			(xy 22.435094 -24.88383) (xy 22.300437 -24.766655) (xy 22.171126 -24.643605) (xy 22.047418 -24.514924)
			(xy 21.929558 -24.380867) (xy 21.817778 -24.241699) (xy 21.712301 -24.097695) (xy 21.613335 -23.949141)
			(xy 21.521076 -23.796332) (xy 21.435707 -23.639569) (xy 21.357396 -23.479163) (xy 21.2863 -23.315432)
			(xy 21.222558 -23.148701) (xy 21.166298 -22.979298) (xy 21.11763 -22.80756) (xy 21.07665 -22.633827)
			(xy 21.043441 -22.458443) (xy 21.018067 -22.281755) (xy 21.00058 -22.104113) (xy 20.991013 -21.925869)
			(xy 20.989385 -21.747375) (xy 19.000504 -21.747375) (xy 19.00047 -21.75002)
		)
		(stroke
			(width 0)
			(type solid)
		)
		(fill yes)
		(layer "F.Cu")
		(net "GND")
	)
	(gr_poly
		(pts
			(xy 169.00017 -182.749952) (xy 169.00067 -182.859545) (xy 169.008676 -183.078586) (xy 169.024675 -183.297187)
			(xy 169.048648 -183.515059) (xy 169.080562 -183.73191) (xy 169.120374 -183.94745) (xy 169.168032 -184.161393)
			(xy 169.223471 -184.373452) (xy 169.286619 -184.583346) (xy 169.35739 -184.790792) (xy 169.43569 -184.995516)
			(xy 169.521415 -185.197244) (xy 169.61445 -185.395706) (xy 169.714671 -185.590638) (xy 169.821945 -185.781779)
			(xy 169.936128 -185.968875) (xy 170.057068 -186.151676) (xy 170.184604 -186.329938) (xy 170.318565 -186.503424)
			(xy 170.458773 -186.671901) (xy 170.60504 -186.835145) (xy 170.757172 -186.992938) (xy 170.914965 -187.14507)
			(xy 171.078209 -187.291337) (xy 171.246686 -187.431545) (xy 171.420172 -187.565506) (xy 171.598434 -187.693042)
			(xy 171.781235 -187.813982) (xy 171.968331 -187.928165) (xy 172.159472 -188.035439) (xy 172.354404 -188.13566)
			(xy 172.552866 -188.228695) (xy 172.754594 -188.31442) (xy 172.959318 -188.39272) (xy 173.166764 -188.463491)
			(xy 173.376658 -188.526639) (xy 173.588717 -188.582078) (xy 173.80266 -188.629736) (xy 174.0182 -188.669548)
			(xy 174.235051 -188.701462) (xy 174.452923 -188.725435) (xy 174.671524 -188.741434) (xy 174.890565 -188.74944)
			(xy 175.109751 -188.74944) (xy 175.328792 -188.741434) (xy 175.547393 -188.725435) (xy 175.765265 -188.701462)
			(xy 175.982116 -188.669548) (xy 176.197656 -188.629736) (xy 176.411599 -188.582078) (xy 176.623658 -188.526639)
			(xy 176.833552 -188.463491) (xy 177.040998 -188.39272) (xy 177.245722 -188.31442) (xy 177.44745 -188.228695)
			(xy 177.645912 -188.13566) (xy 177.840844 -188.035439) (xy 178.031985 -187.928165) (xy 178.219081 -187.813982)
			(xy 178.401882 -187.693042) (xy 178.580144 -187.565506) (xy 178.75363 -187.431545) (xy 178.922107 -187.291337)
			(xy 179.085351 -187.14507) (xy 179.243144 -186.992938) (xy 179.395276 -186.835145) (xy 179.541543 -186.671901)
			(xy 179.681751 -186.503424) (xy 179.815712 -186.329938) (xy 179.943248 -186.151676) (xy 180.064188 -185.968875)
			(xy 180.178371 -185.781779) (xy 180.285645 -185.590638) (xy 180.385866 -185.395706) (xy 180.478901 -185.197244)
			(xy 180.564626 -184.995516) (xy 180.642926 -184.790792) (xy 180.713697 -184.583346) (xy 180.776845 -184.373452)
			(xy 180.832284 -184.161393) (xy 180.879942 -183.94745) (xy 180.919754 -183.73191) (xy 180.951668 -183.515059)
			(xy 180.975641 -183.297187) (xy 180.99164 -183.078586) (xy 180.999646 -182.859545) (xy 181.000146 -182.749952)
			(xy 181.000146 -177.749962) (xy 180.999646 -177.640369) (xy 180.99164 -177.421328) (xy 180.975641 -177.202727)
			(xy 180.951668 -176.984855) (xy 180.919754 -176.768004) (xy 180.879942 -176.552464) (xy 180.832284 -176.338521)
			(xy 180.776845 -176.126462) (xy 180.713697 -175.916568) (xy 180.642926 -175.709122) (xy 180.564626 -175.504398)
			(xy 180.478901 -175.30267) (xy 180.385866 -175.104208) (xy 180.285645 -174.909276) (xy 180.178371 -174.718135)
			(xy 180.064188 -174.531039) (xy 179.943248 -174.348238) (xy 179.815712 -174.169976) (xy 179.681751 -173.99649)
			(xy 179.541543 -173.828013) (xy 179.395276 -173.664769) (xy 179.243144 -173.506976) (xy 179.085351 -173.354844)
			(xy 178.922107 -173.208577) (xy 178.75363 -173.068369) (xy 178.580144 -172.934408) (xy 178.401882 -172.806872)
			(xy 178.219081 -172.685932) (xy 178.031985 -172.571749) (xy 177.840844 -172.464475) (xy 177.645912 -172.364254)
			(xy 177.44745 -172.271219) (xy 177.245722 -172.185494) (xy 177.040998 -172.107194) (xy 176.833552 -172.036423)
			(xy 176.623658 -171.973275) (xy 176.411599 -171.917836) (xy 176.197656 -171.870178) (xy 175.982116 -171.830366)
			(xy 175.765265 -171.798452) (xy 175.547393 -171.774479) (xy 175.328792 -171.75848) (xy 175.109751 -171.750474)
			(xy 174.890565 -171.750474) (xy 174.671524 -171.75848) (xy 174.452923 -171.774479) (xy 174.235051 -171.798452)
			(xy 174.0182 -171.830366) (xy 173.80266 -171.870178) (xy 173.588717 -171.917836) (xy 173.376658 -171.973275)
			(xy 173.166764 -172.036423) (xy 172.959318 -172.107194) (xy 172.754594 -172.185494) (xy 172.552866 -172.271219)
			(xy 172.354404 -172.364254) (xy 172.159472 -172.464475) (xy 171.968331 -172.571749) (xy 171.781235 -172.685932)
			(xy 171.598434 -172.806872) (xy 171.420172 -172.934408) (xy 171.246686 -173.068369) (xy 171.078209 -173.208577)
			(xy 170.914965 -173.354844) (xy 170.757172 -173.506976) (xy 170.60504 -173.664769) (xy 170.458773 -173.828013)
			(xy 170.318565 -173.99649) (xy 170.184604 -174.169976) (xy 170.057068 -174.348238) (xy 169.936128 -174.531039)
			(xy 169.821945 -174.718135) (xy 169.714671 -174.909276) (xy 169.61445 -175.104208) (xy 169.521415 -175.30267)
			(xy 169.43569 -175.504398) (xy 169.35739 -175.709122) (xy 169.286619 -175.916568) (xy 169.223471 -176.126462)
			(xy 169.168032 -176.338521) (xy 169.120374 -176.552464) (xy 169.080562 -176.768004) (xy 169.048648 -176.984855)
			(xy 169.024675 -177.202727) (xy 169.008676 -177.421328) (xy 169.00067 -177.640369) (xy 169.000224 -177.738164)
			(xy 170.98885 -177.738164) (xy 170.993402 -177.558564) (xy 171.005992 -177.379348) (xy 171.026595 -177.200876)
			(xy 171.055168 -177.023506) (xy 171.091656 -176.847593) (xy 171.135984 -176.67349) (xy 171.188064 -176.501547)
			(xy 171.247792 -176.332108) (xy 171.315046 -176.165514) (xy 171.389694 -176.002099) (xy 171.471584 -175.84219)
			(xy 171.560552 -175.686108) (xy 171.656421 -175.534168) (xy 171.758997 -175.386672) (xy 171.868075 -175.243918)
			(xy 171.983436 -175.106191) (xy 172.104849 -174.973769) (xy 172.232069 -174.846916) (xy 172.364843 -174.725887)
			(xy 172.502903 -174.610925) (xy 172.645972 -174.502261) (xy 172.793764 -174.400112) (xy 172.945981 -174.304683)
			(xy 173.102319 -174.216167) (xy 173.262464 -174.13474) (xy 173.426095 -174.060566) (xy 173.592883 -173.993794)
			(xy 173.762494 -173.934557) (xy 173.934587 -173.882975) (xy 174.108817 -173.839151) (xy 174.284835 -173.803172)
			(xy 174.462288 -173.775112) (xy 174.640819 -173.755026) (xy 174.820071 -173.742955) (xy 174.999683 -173.738923)
			(xy 175.179295 -173.742937) (xy 175.358548 -173.754991) (xy 175.537081 -173.775059) (xy 175.714536 -173.803102)
			(xy 175.890558 -173.839063) (xy 176.064792 -173.88287) (xy 176.236891 -173.934435) (xy 176.406507 -173.993655)
			(xy 176.573302 -174.060411) (xy 176.73694 -174.134569) (xy 176.897093 -174.21598) (xy 177.05344 -174.304481)
			(xy 177.205667 -174.399895) (xy 177.353469 -174.502029) (xy 177.496549 -174.610679) (xy 177.63462 -174.725628)
			(xy 177.767405 -174.846643) (xy 177.894638 -174.973484) (xy 178.016064 -175.105895) (xy 178.131439 -175.24361)
			(xy 178.240531 -175.386353) (xy 178.343121 -175.533839) (xy 178.439005 -175.68577) (xy 178.527989 -175.841843)
			(xy 178.609894 -176.001743) (xy 178.684558 -176.165151) (xy 178.751829 -176.331739) (xy 178.811573 -176.501171)
			(xy 178.86367 -176.67311) (xy 178.908015 -176.847208) (xy 178.94452 -177.023118) (xy 178.973111 -177.200485)
			(xy 178.993731 -177.378955) (xy 179.006339 -177.55817) (xy 179.010909 -177.737769) (xy 179.007432 -177.917393)
			(xy 178.995915 -178.096681) (xy 178.976381 -178.275273) (xy 178.948869 -178.452812) (xy 178.913435 -178.62894)
			(xy 178.870149 -178.803305) (xy 178.8191 -178.975557) (xy 178.760387 -179.14535) (xy 178.694131 -179.312343)
			(xy 178.620463 -179.476203) (xy 178.539532 -179.636599) (xy 178.451499 -179.79321) (xy 178.356541 -179.945721)
			(xy 178.25485 -180.093828) (xy 178.146628 -180.237233) (xy 178.032094 -180.375647) (xy 177.911476 -180.508794)
			(xy 177.785016 -180.636406) (xy 177.65297 -180.758228) (xy 177.584608 -180.816504) (xy 177.561635 -180.8365)
			(xy 177.520284 -180.881217) (xy 177.484805 -180.930722) (xy 177.455747 -180.98425) (xy 177.433561 -181.040971)
			(xy 177.418589 -181.100008) (xy 177.411064 -181.160447) (xy 177.410618 -181.1909) (xy 177.410618 -182.749952)
			(xy 177.410126 -182.818799) (xy 177.402265 -182.956269) (xy 177.386569 -183.093066) (xy 177.36309 -183.228744)
			(xy 177.331902 -183.36286) (xy 177.293109 -183.494977) (xy 177.246837 -183.624664) (xy 177.193237 -183.751497)
			(xy 177.132483 -183.875064) (xy 177.064774 -183.994961) (xy 176.990331 -184.110797) (xy 176.909396 -184.222194)
			(xy 176.822234 -184.328789) (xy 176.729128 -184.430235) (xy 176.630383 -184.526199) (xy 176.52632 -184.61637)
			(xy 176.41728 -184.700453) (xy 176.303617 -184.778173) (xy 176.185702 -184.849279) (xy 176.063921 -184.913536)
			(xy 175.938669 -184.970736) (xy 175.810357 -185.020693) (xy 175.679402 -185.063243) (xy 175.546231 -185.098247)
			(xy 175.411279 -185.125592) (xy 175.274986 -185.145188) (xy 175.137796 -185.156971) (xy 175.000158 -185.160904)
			(xy 174.86252 -185.156971) (xy 174.72533 -185.145188) (xy 174.589037 -185.125592) (xy 174.454085 -185.098247)
			(xy 174.320914 -185.063243) (xy 174.189959 -185.020693) (xy 174.061647 -184.970736) (xy 173.936395 -184.913536)
			(xy 173.814614 -184.849279) (xy 173.696699 -184.778173) (xy 173.583036 -184.700453) (xy 173.473996 -184.61637)
			(xy 173.369933 -184.526199) (xy 173.271188 -184.430235) (xy 173.178082 -184.328789) (xy 173.09092 -184.222194)
			(xy 173.009985 -184.110797) (xy 172.935542 -183.994961) (xy 172.867833 -183.875064) (xy 172.807079 -183.751497)
			(xy 172.753479 -183.624664) (xy 172.707207 -183.494977) (xy 172.668414 -183.36286) (xy 172.637226 -183.228744)
			(xy 172.613747 -183.093066) (xy 172.598051 -182.956269) (xy 172.59019 -182.818799) (xy 172.589698 -182.749952)
			(xy 172.589698 -181.1909) (xy 172.589235 -181.160458) (xy 172.581636 -181.100048) (xy 172.566606 -181.041047)
			(xy 172.544377 -180.984365) (xy 172.515291 -180.930876) (xy 172.479797 -180.881406) (xy 172.438444 -180.836719)
			(xy 172.415454 -180.816758) (xy 172.347086 -180.758489) (xy 172.215028 -180.63668) (xy 172.088556 -180.509081)
			(xy 171.967925 -180.375946) (xy 171.853377 -180.237542) (xy 171.745141 -180.094149) (xy 171.643435 -179.946052)
			(xy 171.548462 -179.793549) (xy 171.460414 -179.636947) (xy 171.379467 -179.476559) (xy 171.305783 -179.312707)
			(xy 171.23951 -179.14572) (xy 171.180781 -178.975933) (xy 171.129714 -178.803686) (xy 171.086412 -178.629325)
			(xy 171.05096 -178.4532) (xy 171.023431 -178.275664) (xy 171.00388 -178.097074) (xy 170.992345 -177.917787)
			(xy 170.98885 -177.738164) (xy 169.000224 -177.738164) (xy 169.00017 -177.749962)
		)
		(stroke
			(width 0)
			(type solid)
		)
		(fill yes)
		(layer "F.Cu")
		(net "GND")
	)
	(gr_poly
		(pts
			(xy 169.00017 -26.75001) (xy 169.00067 -26.859603) (xy 169.008676 -27.078644) (xy 169.024675 -27.297245)
			(xy 169.048648 -27.515117) (xy 169.080562 -27.731968) (xy 169.120374 -27.947508) (xy 169.168032 -28.161451)
			(xy 169.223471 -28.37351) (xy 169.286619 -28.583404) (xy 169.35739 -28.79085) (xy 169.43569 -28.995574)
			(xy 169.521415 -29.197302) (xy 169.61445 -29.395764) (xy 169.714671 -29.590696) (xy 169.821945 -29.781837)
			(xy 169.936128 -29.968933) (xy 170.057068 -30.151734) (xy 170.184604 -30.329996) (xy 170.318565 -30.503482)
			(xy 170.458773 -30.671959) (xy 170.60504 -30.835203) (xy 170.757172 -30.992996) (xy 170.914965 -31.145128)
			(xy 171.078209 -31.291395) (xy 171.246686 -31.431603) (xy 171.420172 -31.565564) (xy 171.598434 -31.6931)
			(xy 171.781235 -31.81404) (xy 171.968331 -31.928223) (xy 172.159472 -32.035497) (xy 172.354404 -32.135718)
			(xy 172.552866 -32.228753) (xy 172.754594 -32.314478) (xy 172.959318 -32.392778) (xy 173.166764 -32.463549)
			(xy 173.376658 -32.526697) (xy 173.588717 -32.582136) (xy 173.80266 -32.629794) (xy 174.0182 -32.669606)
			(xy 174.235051 -32.70152) (xy 174.452923 -32.725493) (xy 174.671524 -32.741492) (xy 174.890565 -32.749498)
			(xy 175.109751 -32.749498) (xy 175.328792 -32.741492) (xy 175.547393 -32.725493) (xy 175.765265 -32.70152)
			(xy 175.982116 -32.669606) (xy 176.197656 -32.629794) (xy 176.411599 -32.582136) (xy 176.623658 -32.526697)
			(xy 176.833552 -32.463549) (xy 177.040998 -32.392778) (xy 177.245722 -32.314478) (xy 177.44745 -32.228753)
			(xy 177.645912 -32.135718) (xy 177.840844 -32.035497) (xy 178.031985 -31.928223) (xy 178.219081 -31.81404)
			(xy 178.401882 -31.6931) (xy 178.580144 -31.565564) (xy 178.75363 -31.431603) (xy 178.922107 -31.291395)
			(xy 179.085351 -31.145128) (xy 179.243144 -30.992996) (xy 179.395276 -30.835203) (xy 179.541543 -30.671959)
			(xy 179.681751 -30.503482) (xy 179.815712 -30.329996) (xy 179.943248 -30.151734) (xy 180.064188 -29.968933)
			(xy 180.178371 -29.781837) (xy 180.285645 -29.590696) (xy 180.385866 -29.395764) (xy 180.478901 -29.197302)
			(xy 180.564626 -28.995574) (xy 180.642926 -28.79085) (xy 180.713697 -28.583404) (xy 180.776845 -28.37351)
			(xy 180.832284 -28.161451) (xy 180.879942 -27.947508) (xy 180.919754 -27.731968) (xy 180.951668 -27.515117)
			(xy 180.975641 -27.297245) (xy 180.99164 -27.078644) (xy 180.999646 -26.859603) (xy 181.000146 -26.75001)
			(xy 181.000146 -21.75002) (xy 180.999646 -21.640427) (xy 180.99164 -21.421386) (xy 180.975641 -21.202785)
			(xy 180.951668 -20.984913) (xy 180.919754 -20.768062) (xy 180.879942 -20.552522) (xy 180.832284 -20.338579)
			(xy 180.776845 -20.12652) (xy 180.713697 -19.916626) (xy 180.642926 -19.70918) (xy 180.564626 -19.504456)
			(xy 180.478901 -19.302728) (xy 180.385866 -19.104266) (xy 180.285645 -18.909334) (xy 180.178371 -18.718193)
			(xy 180.064188 -18.531097) (xy 179.943248 -18.348296) (xy 179.815712 -18.170034) (xy 179.681751 -17.996548)
			(xy 179.541543 -17.828071) (xy 179.395276 -17.664827) (xy 179.243144 -17.507034) (xy 179.085351 -17.354902)
			(xy 178.922107 -17.208635) (xy 178.75363 -17.068427) (xy 178.580144 -16.934466) (xy 178.401882 -16.80693)
			(xy 178.219081 -16.68599) (xy 178.031985 -16.571807) (xy 177.840844 -16.464533) (xy 177.645912 -16.364312)
			(xy 177.44745 -16.271277) (xy 177.245722 -16.185552) (xy 177.040998 -16.107252) (xy 176.833552 -16.036481)
			(xy 176.623658 -15.973333) (xy 176.411599 -15.917894) (xy 176.197656 -15.870236) (xy 175.982116 -15.830424)
			(xy 175.765265 -15.79851) (xy 175.547393 -15.774537) (xy 175.328792 -15.758538) (xy 175.109751 -15.750532)
			(xy 174.890565 -15.750532) (xy 174.671524 -15.758538) (xy 174.452923 -15.774537) (xy 174.235051 -15.79851)
			(xy 174.0182 -15.830424) (xy 173.80266 -15.870236) (xy 173.588717 -15.917894) (xy 173.376658 -15.973333)
			(xy 173.166764 -16.036481) (xy 172.959318 -16.107252) (xy 172.754594 -16.185552) (xy 172.552866 -16.271277)
			(xy 172.354404 -16.364312) (xy 172.159472 -16.464533) (xy 171.968331 -16.571807) (xy 171.781235 -16.68599)
			(xy 171.598434 -16.80693) (xy 171.420172 -16.934466) (xy 171.246686 -17.068427) (xy 171.078209 -17.208635)
			(xy 170.914965 -17.354902) (xy 170.757172 -17.507034) (xy 170.60504 -17.664827) (xy 170.458773 -17.828071)
			(xy 170.318565 -17.996548) (xy 170.184604 -18.170034) (xy 170.057068 -18.348296) (xy 169.936128 -18.531097)
			(xy 169.821945 -18.718193) (xy 169.714671 -18.909334) (xy 169.61445 -19.104266) (xy 169.521415 -19.302728)
			(xy 169.43569 -19.504456) (xy 169.35739 -19.70918) (xy 169.286619 -19.916626) (xy 169.223471 -20.12652)
			(xy 169.168032 -20.338579) (xy 169.120374 -20.552522) (xy 169.080562 -20.768062) (xy 169.048648 -20.984913)
			(xy 169.024675 -21.202785) (xy 169.008676 -21.421386) (xy 169.00067 -21.640427) (xy 169.000224 -21.738223)
			(xy 170.988852 -21.738223) (xy 170.993404 -21.558623) (xy 171.005994 -21.379408) (xy 171.026596 -21.200936)
			(xy 171.05517 -21.023565) (xy 171.091658 -20.847652) (xy 171.135986 -20.673549) (xy 171.188066 -20.501606)
			(xy 171.247793 -20.332168) (xy 171.315048 -20.165574) (xy 171.389695 -20.002159) (xy 171.471585 -19.84225)
			(xy 171.560554 -19.686169) (xy 171.656422 -19.534228) (xy 171.758998 -19.386733) (xy 171.868076 -19.243979)
			(xy 171.983437 -19.106252) (xy 172.10485 -18.97383) (xy 172.232071 -18.846977) (xy 172.364844 -18.725948)
			(xy 172.502904 -18.610986) (xy 172.645973 -18.502322) (xy 172.793765 -18.400173) (xy 172.945982 -18.304744)
			(xy 173.10232 -18.216228) (xy 173.262465 -18.134801) (xy 173.426096 -18.060627) (xy 173.592884 -17.993855)
			(xy 173.762495 -17.934618) (xy 173.934588 -17.883036) (xy 174.108818 -17.839212) (xy 174.284836 -17.803234)
			(xy 174.462288 -17.775174) (xy 174.640819 -17.755088) (xy 174.820071 -17.743017) (xy 174.999683 -17.738984)
			(xy 175.179295 -17.742999) (xy 175.358548 -17.755052) (xy 175.537081 -17.775121) (xy 175.714536 -17.803163)
			(xy 175.890557 -17.839124) (xy 176.064792 -17.882931) (xy 176.23689 -17.934497) (xy 176.406507 -17.993717)
			(xy 176.573301 -18.060472) (xy 176.736939 -18.13463) (xy 176.897092 -18.216041) (xy 177.053439 -18.304542)
			(xy 177.205666 -18.399956) (xy 177.353467 -18.50209) (xy 177.496547 -18.61074) (xy 177.634618 -18.725689)
			(xy 177.767404 -18.846704) (xy 177.894637 -18.973545) (xy 178.016063 -19.105955) (xy 178.131437 -19.24367)
			(xy 178.240529 -19.386414) (xy 178.34312 -19.533899) (xy 178.439003 -19.68583) (xy 178.527987 -19.841903)
			(xy 178.609893 -20.001803) (xy 178.684556 -20.165211) (xy 178.751827 -20.331799) (xy 178.811571 -20.501231)
			(xy 178.863668 -20.673169) (xy 178.908014 -20.847268) (xy 178.944519 -21.023177) (xy 178.97311 -21.200545)
			(xy 178.99373 -21.379015) (xy 179.006337 -21.558229) (xy 179.010907 -21.737828) (xy 179.00743 -21.917452)
			(xy 178.995913 -22.09674) (xy 178.976379 -22.275332) (xy 178.948868 -22.45287) (xy 178.913434 -22.628999)
			(xy 178.870148 -22.803364) (xy 178.819098 -22.975615) (xy 178.760386 -23.145408) (xy 178.69413 -23.312402)
			(xy 178.620462 -23.476261) (xy 178.539531 -23.636657) (xy 178.451498 -23.793268) (xy 178.356541 -23.94578)
			(xy 178.254849 -24.093886) (xy 178.146628 -24.237291) (xy 178.032093 -24.375705) (xy 177.911475 -24.508852)
			(xy 177.785016 -24.636464) (xy 177.65297 -24.758286) (xy 177.584608 -24.816562) (xy 177.561607 -24.836527)
			(xy 177.520257 -24.88125) (xy 177.484781 -24.93076) (xy 177.455727 -24.984293) (xy 177.433545 -25.041019)
			(xy 177.418579 -25.10006) (xy 177.41106 -25.160503) (xy 177.410618 -25.190958) (xy 177.410618 -26.75001)
			(xy 177.410126 -26.818857) (xy 177.402265 -26.956327) (xy 177.386569 -27.093124) (xy 177.36309 -27.228802)
			(xy 177.331902 -27.362918) (xy 177.293109 -27.495035) (xy 177.246837 -27.624722) (xy 177.193237 -27.751555)
			(xy 177.132483 -27.875122) (xy 177.064774 -27.995019) (xy 176.990331 -28.110855) (xy 176.909396 -28.222252)
			(xy 176.822234 -28.328847) (xy 176.729128 -28.430293) (xy 176.630383 -28.526257) (xy 176.52632 -28.616428)
			(xy 176.41728 -28.700511) (xy 176.303617 -28.778231) (xy 176.185702 -28.849337) (xy 176.063921 -28.913594)
			(xy 175.938669 -28.970794) (xy 175.810357 -29.020751) (xy 175.679402 -29.063301) (xy 175.546231 -29.098305)
			(xy 175.411279 -29.12565) (xy 175.274986 -29.145246) (xy 175.137796 -29.157029) (xy 175.000158 -29.160962)
			(xy 174.86252 -29.157029) (xy 174.72533 -29.145246) (xy 174.589037 -29.12565) (xy 174.454085 -29.098305)
			(xy 174.320914 -29.063301) (xy 174.189959 -29.020751) (xy 174.061647 -28.970794) (xy 173.936395 -28.913594)
			(xy 173.814614 -28.849337) (xy 173.696699 -28.778231) (xy 173.583036 -28.700511) (xy 173.473996 -28.616428)
			(xy 173.369933 -28.526257) (xy 173.271188 -28.430293) (xy 173.178082 -28.328847) (xy 173.09092 -28.222252)
			(xy 173.009985 -28.110855) (xy 172.935542 -27.995019) (xy 172.867833 -27.875122) (xy 172.807079 -27.751555)
			(xy 172.753479 -27.624722) (xy 172.707207 -27.495035) (xy 172.668414 -27.362918) (xy 172.637226 -27.228802)
			(xy 172.613747 -27.093124) (xy 172.598051 -26.956327) (xy 172.59019 -26.818857) (xy 172.589698 -26.75001)
			(xy 172.589698 -25.190958) (xy 172.589194 -25.160517) (xy 172.581603 -25.100109) (xy 172.56658 -25.041109)
			(xy 172.544357 -24.984427) (xy 172.515277 -24.930937) (xy 172.479789 -24.881467) (xy 172.438441 -24.836778)
			(xy 172.415454 -24.816816) (xy 172.347086 -24.758547) (xy 172.215028 -24.636738) (xy 172.088556 -24.509139)
			(xy 171.967925 -24.376004) (xy 171.853377 -24.237601) (xy 171.745141 -24.094207) (xy 171.643435 -23.94611)
			(xy 171.548463 -23.793607) (xy 171.460415 -23.637005) (xy 171.379468 -23.476617) (xy 171.305784 -23.312765)
			(xy 171.239511 -23.145778) (xy 171.180782 -22.975991) (xy 171.129715 -22.803744) (xy 171.086413 -22.629384)
			(xy 171.050962 -22.453259) (xy 171.023432 -22.275723) (xy 171.003881 -22.097133) (xy 170.992346 -21.917846)
			(xy 170.988852 -21.738223) (xy 169.000224 -21.738223) (xy 169.00017 -21.75002)
		)
		(stroke
			(width 0)
			(type solid)
		)
		(fill yes)
		(layer "F.Cu")
		(net "GND")
	)
	(gr_poly
		(pts
			(xy 56.128666 -83.61299) (xy 56.476646 -83.61299) (xy 56.56326 -83.526376) (xy 56.56326 -81.650332)
			(xy 56.758078 -81.455514) (xy 56.938164 -81.455514) (xy 56.996838 -81.39684) (xy 56.996838 -80.651604)
			(xy 56.994044 -80.648556) (xy 56.994044 -80.595724) (xy 56.814212 -80.415892) (xy 56.814212 -80.329786)
			(xy 56.808878 -80.312006) (xy 56.800922 -80.283173) (xy 56.792674 -80.223935) (xy 56.793344 -80.164129)
			(xy 56.802915 -80.105091) (xy 56.821176 -80.048137) (xy 56.847718 -79.994539) (xy 56.881949 -79.945494)
			(xy 56.902096 -79.923386) (xy 56.909208 -79.91602) (xy 56.909462 -79.915766) (xy 56.917844 -79.907384)
			(xy 56.932068 -79.886048) (xy 56.941125 -79.871177) (xy 56.951675 -79.838011) (xy 56.95289 -79.803228)
			(xy 56.944678 -79.769407) (xy 56.92765 -79.739053) (xy 56.915812 -79.726282) (xy 56.494934 -79.305404)
			(xy 56.474293 -79.284069) (xy 56.438459 -79.236742) (xy 56.409444 -79.184953) (xy 56.387796 -79.129678)
			(xy 56.38038 -79.100934) (xy 56.373565 -79.070306) (xy 56.367824 -79.007825) (xy 56.371185 -78.945172)
			(xy 56.383576 -78.883664) (xy 56.404738 -78.824596) (xy 56.418988 -78.796642) (xy 56.427899 -78.780346)
			(xy 56.448121 -78.749188) (xy 56.459374 -78.734412) (xy 56.472937 -78.716145) (xy 56.494024 -78.675836)
			(xy 56.507604 -78.632418) (xy 56.513243 -78.587277) (xy 56.510762 -78.541853) (xy 56.50024 -78.497594)
			(xy 56.482012 -78.455914) (xy 56.469788 -78.436724) (xy 56.461248 -78.424591) (xy 56.445742 -78.399291)
			(xy 56.4388 -78.386178) (xy 56.429656 -78.368398) (xy 56.23179 -78.170278) (xy 56.214264 -78.161388)
			(xy 56.186516 -78.146384) (xy 56.135616 -78.109127) (xy 56.112918 -78.08722) (xy 56.10987 -78.084426)
			(xy 56.109362 -78.083918) (xy 56.107584 -78.08214) (xy 56.095764 -78.070996) (xy 56.067757 -78.054555)
			(xy 56.036507 -78.045718) (xy 56.004038 -78.045058) (xy 55.972455 -78.052617) (xy 55.943803 -78.067906)
			(xy 55.931562 -78.078584) (xy 55.925974 -78.083918) (xy 55.92191 -78.08849) (xy 55.903842 -78.108002)
			(xy 55.863724 -78.142911) (xy 55.819624 -78.172631) (xy 55.772209 -78.196712) (xy 55.722197 -78.21479)
			(xy 55.696358 -78.221078) (xy 55.660544 -78.227682) (xy 55.632188 -78.23121) (xy 55.575047 -78.23165)
			(xy 55.518347 -78.22455) (xy 55.463078 -78.210036) (xy 55.410206 -78.18836) (xy 55.360654 -78.159901)
			(xy 55.315287 -78.125157) (xy 55.294784 -78.105254) (xy 54.894734 -77.705204) (xy 54.874865 -77.684674)
			(xy 54.840149 -77.639298) (xy 54.811711 -77.589746) (xy 54.790046 -77.53688) (xy 54.775531 -77.481622)
			(xy 54.768418 -77.424934) (xy 54.768833 -77.367803) (xy 54.772306 -77.339444) (xy 54.77891 -77.30363)
			(xy 54.785213 -77.277795) (xy 54.803293 -77.227784) (xy 54.82737 -77.180367) (xy 54.857078 -77.13626)
			(xy 54.891971 -77.096129) (xy 54.911498 -77.078078) (xy 54.91607 -77.074014) (xy 54.921404 -77.068426)
			(xy 54.932033 -77.056156) (xy 54.947281 -77.027508) (xy 54.954817 -76.995942) (xy 54.954156 -76.963496)
			(xy 54.94534 -76.932263) (xy 54.928939 -76.90426) (xy 54.917848 -76.892404) (xy 54.912006 -76.886562)
			(xy 54.908958 -76.88326) (xy 54.888604 -76.861572) (xy 54.85376 -76.813371) (xy 54.826299 -76.760614)
			(xy 54.806803 -76.704424) (xy 54.795688 -76.645995) (xy 54.793896 -76.616306) (xy 54.793642 -76.609956)
			(xy 54.793408 -76.578447) (xy 54.801495 -76.51596) (xy 54.819127 -76.455469) (xy 54.845881 -76.398423)
			(xy 54.862984 -76.371958) (xy 54.874388 -76.35551) (xy 54.899962 -76.324718) (xy 54.914038 -76.31049)
			(xy 54.931056 -76.293726) (xy 54.953662 -76.24318) (xy 54.959438 -76.229096) (xy 54.964858 -76.19915)
			(xy 54.96302 -76.168773) (xy 54.954029 -76.139699) (xy 54.938399 -76.113588) (xy 54.928008 -76.102464)
			(xy 54.925976 -76.100432) (xy 54.912768 -76.08697) (xy 54.893532 -76.06707) (xy 54.860069 -76.022984)
			(xy 54.832893 -75.974768) (xy 54.812507 -75.923312) (xy 54.799287 -75.869567) (xy 54.793477 -75.814526)
			(xy 54.795184 -75.759205) (xy 54.804378 -75.704627) (xy 54.820888 -75.6518) (xy 54.844409 -75.601699)
			(xy 54.874507 -75.555251) (xy 54.910625 -75.513313) (xy 54.931056 -75.494642) (xy 54.942324 -75.484125)
			(xy 54.959863 -75.458788) (xy 54.970813 -75.429984) (xy 54.974534 -75.399395) (xy 54.97081 -75.368805)
			(xy 54.959858 -75.340002) (xy 54.942317 -75.314667) (xy 54.931056 -75.304142) (xy 54.912768 -75.28687)
			(xy 54.512718 -74.88682) (xy 54.491151 -74.864445) (xy 54.454379 -74.814349) (xy 54.42566 -74.759239)
			(xy 54.405664 -74.700401) (xy 54.399688 -74.669904) (xy 54.396755 -74.65561) (xy 54.385289 -74.628785)
			(xy 54.368029 -74.605266) (xy 54.345876 -74.586284) (xy 54.31999 -74.572832) (xy 54.305962 -74.568812)
			(xy 54.279517 -74.561581) (xy 54.228877 -74.540579) (xy 54.18176 -74.51255) (xy 54.160166 -74.49566)
			(xy 54.143077 -74.482351) (xy 54.105306 -74.461152) (xy 54.064487 -74.446668) (xy 54.021802 -74.439319)
			(xy 53.97849 -74.439319) (xy 53.935805 -74.446668) (xy 53.894986 -74.461152) (xy 53.857215 -74.482351)
			(xy 53.840126 -74.49566) (xy 53.818075 -74.512877) (xy 53.769917 -74.541344) (xy 53.718117 -74.562474)
			(xy 53.663788 -74.575813) (xy 53.608092 -74.581075) (xy 53.552226 -74.578147) (xy 53.497386 -74.567093)
			(xy 53.444748 -74.548148) (xy 53.395441 -74.52172) (xy 53.350522 -74.488374) (xy 53.330348 -74.46899)
			(xy 53.307742 -74.446384) (xy 53.297836 -74.436224) (xy 53.289962 -74.42835) (xy 53.27779 -74.416948)
			(xy 53.248918 -74.400279) (xy 53.216715 -74.39165) (xy 53.183377 -74.39165) (xy 53.151174 -74.400279)
			(xy 53.122302 -74.416948) (xy 53.11013 -74.42835) (xy 53.102256 -74.436224) (xy 53.09235 -74.446384)
			(xy 53.069744 -74.46899) (xy 53.05806 -74.480166) (xy 53.051202 -74.486262) (xy 53.038768 -74.498211)
			(xy 53.020244 -74.527283) (xy 53.01019 -74.560256) (xy 53.00934 -74.594716) (xy 53.017756 -74.628145)
			(xy 53.034824 -74.658094) (xy 53.04663 -74.670666) (xy 53.051964 -74.676) (xy 53.05679 -74.680826)
			(xy 53.087524 -74.711814) (xy 53.107398 -74.732383) (xy 53.141768 -74.778098) (xy 53.169399 -74.828175)
			(xy 53.189746 -74.881628) (xy 53.202408 -74.937404) (xy 53.207135 -74.994402) (xy 53.203835 -75.051502)
			(xy 53.192573 -75.107576) (xy 53.173569 -75.161522) (xy 53.1472 -75.212275) (xy 53.130958 -75.235816)
			(xy 53.120565 -75.250067) (xy 53.097675 -75.276904) (xy 53.085238 -75.28941) (xy 53.069008 -75.306101)
			(xy 53.042315 -75.344239) (xy 53.023015 -75.3866) (xy 53.011753 -75.431768) (xy 53.008906 -75.478232)
			(xy 53.014569 -75.524437) (xy 53.028553 -75.568837) (xy 53.03901 -75.589638) (xy 53.047578 -75.599597)
			(xy 53.063221 -75.620705) (xy 53.070252 -75.631802) (xy 53.078126 -75.644502) (xy 53.105304 -75.67168)
			(xy 53.105304 -75.709272) (xy 53.10886 -75.724004) (xy 53.114058 -75.747155) (xy 53.118333 -75.794408)
			(xy 53.115541 -75.841772) (xy 53.105743 -75.888196) (xy 53.089157 -75.932648) (xy 53.066151 -75.974144)
			(xy 53.037235 -76.011761) (xy 53.020468 -76.02855) (xy 53.013059 -76.048422) (xy 53.004217 -76.089898)
			(xy 53.00239 -76.132267) (xy 53.007629 -76.17435) (xy 53.019788 -76.214978) (xy 53.03853 -76.25302)
			(xy 53.063332 -76.287419) (xy 53.078126 -76.302616) (xy 53.098291 -76.322187) (xy 53.1336 -76.365903)
			(xy 53.148484 -76.389738) (xy 53.161411 -76.41201) (xy 53.182161 -76.459143) (xy 53.196796 -76.508518)
			(xy 53.205081 -76.559345) (xy 53.206396 -76.585064) (xy 53.206861 -76.601476) (xy 53.205466 -76.634283)
			(xy 53.203602 -76.650596) (xy 53.201157 -76.673835) (xy 53.203786 -76.720485) (xy 53.214898 -76.765867)
			(xy 53.23412 -76.808453) (xy 53.260803 -76.846808) (xy 53.294048 -76.879638) (xy 53.332735 -76.905838)
			(xy 53.375559 -76.924524) (xy 53.421077 -76.935066) (xy 53.444394 -76.9366) (xy 53.685694 -76.9366)
			(xy 53.735224 -76.9366) (xy 54.010052 -77.211428) (xy 54.010052 -77.260958) (xy 54.010052 -77.284834)
			(xy 54.010562 -77.301578) (xy 54.019281 -77.333911) (xy 54.036109 -77.362864) (xy 54.059887 -77.386444)
			(xy 54.088981 -77.403028) (xy 54.105048 -77.40777) (xy 54.105302 -77.40777) (xy 54.106064 -77.408024)
			(xy 54.131976 -77.41528) (xy 54.181765 -77.435694) (xy 54.228427 -77.462493) (xy 54.271149 -77.49521)
			(xy 54.290468 -77.513942) (xy 54.797452 -78.020672) (xy 54.807104 -78.030324) (xy 54.807104 -78.199742)
			(xy 54.806606 -78.228575) (xy 54.798471 -78.285664) (xy 54.782355 -78.341031) (xy 54.758582 -78.393569)
			(xy 54.727628 -78.442222) (xy 54.690114 -78.486017) (xy 54.646791 -78.524075) (xy 54.598528 -78.555634)
			(xy 54.546292 -78.580061) (xy 54.49113 -78.596867) (xy 54.434147 -78.605715) (xy 54.376486 -78.606427)
			(xy 54.319302 -78.598989) (xy 54.263742 -78.58355) (xy 54.210918 -78.56042) (xy 54.161891 -78.530063)
			(xy 54.117641 -78.493086) (xy 54.097936 -78.47203) (xy 54.095396 -78.469236) (xy 54.092856 -78.466442)
			(xy 54.080684 -78.45504) (xy 54.051812 -78.438371) (xy 54.019609 -78.429742) (xy 53.986271 -78.429742)
			(xy 53.954068 -78.438371) (xy 53.925196 -78.45504) (xy 53.913024 -78.466442) (xy 53.77307 -78.606396)
			(xy 53.600096 -78.606396) (xy 53.561488 -78.604618) (xy 53.5432 -78.602586) (xy 53.529992 -78.600554)
			(xy 53.519324 -78.598776) (xy 53.334666 -78.598776) (xy 53.318029 -78.599322) (xy 53.285888 -78.607936)
			(xy 53.257068 -78.624568) (xy 53.23353 -78.648087) (xy 53.216875 -78.676894) (xy 53.208235 -78.709027)
			(xy 53.2082 -78.742302) (xy 53.21677 -78.774454) (xy 53.233364 -78.803296) (xy 53.24475 -78.815438)
			(xy 53.24602 -78.816708) (xy 53.24729 -78.817978) (xy 53.418645 -78.989496) (xy 54.818693 -78.989496)
			(xy 54.824319 -78.933702) (xy 54.838059 -78.879335) (xy 54.859615 -78.827567) (xy 54.888523 -78.779515)
			(xy 54.924158 -78.736217) (xy 54.965752 -78.698606) (xy 55.012407 -78.667495) (xy 55.063116 -78.643554)
			(xy 55.116786 -78.627301) (xy 55.172258 -78.619085) (xy 55.200296 -78.618588) (xy 55.36565 -78.618588)
			(xy 55.882286 -79.13497) (xy 55.90121 -79.154582) (xy 55.93387 -79.19821) (xy 55.959989 -79.246043)
			(xy 55.979034 -79.297105) (xy 55.990618 -79.350358) (xy 55.994506 -79.404718) (xy 55.990618 -79.459078)
			(xy 55.979034 -79.512331) (xy 55.959989 -79.563393) (xy 55.93387 -79.611226) (xy 55.90121 -79.654854)
			(xy 55.862674 -79.69339) (xy 55.819046 -79.72605) (xy 55.771213 -79.752169) (xy 55.720151 -79.771214)
			(xy 55.666898 -79.782798) (xy 55.612538 -79.786686) (xy 55.558178 -79.782798) (xy 55.504925 -79.771214)
			(xy 55.453863 -79.752169) (xy 55.40603 -79.72605) (xy 55.362402 -79.69339) (xy 55.34279 -79.674466)
			(xy 54.979062 -79.310738) (xy 54.97195 -79.30515) (xy 54.94984 -79.287898) (xy 54.910337 -79.248097)
			(xy 54.87709 -79.202939) (xy 54.850817 -79.153398) (xy 54.832086 -79.100542) (xy 54.8213 -79.045512)
			(xy 54.818693 -78.989496) (xy 53.418645 -78.989496) (xy 53.514498 -79.08544) (xy 53.535615 -79.107291)
			(xy 53.572332 -79.155709) (xy 53.602115 -79.208677) (xy 53.624407 -79.265206) (xy 53.638794 -79.324244)
			(xy 53.645008 -79.384692) (xy 53.642934 -79.445422) (xy 53.632609 -79.505305) (xy 53.614226 -79.563223)
			(xy 53.588128 -79.6181) (xy 53.554801 -79.668911) (xy 53.514865 -79.714711) (xy 53.469065 -79.754647)
			(xy 53.418254 -79.787974) (xy 53.363377 -79.814072) (xy 53.305459 -79.832455) (xy 53.245576 -79.84278)
			(xy 53.184846 -79.844854) (xy 53.124398 -79.83864) (xy 53.06536 -79.824253) (xy 53.008831 -79.801961)
			(xy 52.955863 -79.772178) (xy 52.907445 -79.735461) (xy 52.885594 -79.714344) (xy 52.485544 -79.314294)
			(xy 52.468272 -79.29626) (xy 52.456436 -79.283834) (xy 52.427607 -79.265244) (xy 52.394867 -79.255006)
			(xy 52.360583 -79.25386) (xy 52.327232 -79.261888) (xy 52.297226 -79.278511) (xy 52.28463 -79.290164)
			(xy 52.277264 -79.29753) (xy 52.274978 -79.299562) (xy 52.272184 -79.302102) (xy 52.269644 -79.304388)
			(xy 52.249324 -79.324708) (xy 52.237882 -79.336825) (xy 52.221201 -79.365663) (xy 52.212565 -79.39784)
			(xy 52.212565 -79.431156) (xy 52.2212 -79.463333) (xy 52.23788 -79.492172) (xy 52.249324 -79.504286)
			(xy 52.388008 -79.64297) (xy 52.388008 -79.749142) (xy 52.442872 -79.81823) (xy 52.486306 -79.82839)
			(xy 52.512908 -79.835056) (xy 52.564 -79.854984) (xy 52.611712 -79.882021) (xy 52.65506 -79.915612)
			(xy 52.693153 -79.955064) (xy 52.725204 -79.999564) (xy 52.750552 -80.048194) (xy 52.768677 -80.099953)
			(xy 52.779203 -80.153774) (xy 52.781915 -80.208547) (xy 52.776756 -80.263144) (xy 52.763832 -80.31644)
			(xy 52.74341 -80.367336) (xy 52.715911 -80.414784) (xy 52.681902 -80.457805) (xy 52.642083 -80.495513)
			(xy 52.61991 -80.51165) (xy 52.61102 -80.518) (xy 52.144168 -80.984852) (xy 51.22799 -80.984852)
			(xy 51.11242 -81.100422) (xy 51.11242 -81.198212) (xy 51.112892 -81.214408) (xy 51.121024 -81.245761)
			(xy 51.136788 -81.274058) (xy 51.159167 -81.297474) (xy 51.18672 -81.314504) (xy 51.217672 -81.324048)
			(xy 51.233832 -81.325212) (xy 51.483514 -81.325212) (xy 51.726846 -81.568544) (xy 52.13731 -81.568544)
			(xy 52.15509 -81.56321) (xy 52.183636 -81.55521) (xy 52.242289 -81.546605) (xy 52.301571 -81.546605)
			(xy 52.360224 -81.55521) (xy 52.38877 -81.56321) (xy 52.414932 -81.571084) (xy 52.415186 -81.571338)
			(xy 52.436776 -81.58099) (xy 52.466963 -81.595109) (xy 52.52267 -81.631676) (xy 52.571694 -81.676811)
			(xy 52.592732 -81.702656) (xy 52.596288 -81.707482) (xy 52.602892 -81.716118) (xy 52.932838 -82.046318)
			(xy 52.95335 -82.067555) (xy 52.988652 -82.11488) (xy 53.01675 -82.166807) (xy 53.037056 -82.222247)
			(xy 53.043582 -82.251042) (xy 53.065771 -82.269336) (xy 53.104928 -82.311452) (xy 53.137333 -82.358958)
			(xy 53.150262 -82.384646) (xy 53.15966 -82.40395) (xy 53.568854 -82.813144) (xy 53.60797 -82.820256)
			(xy 53.628253 -82.824354) (xy 53.667407 -82.837738) (xy 53.685948 -82.846926) (xy 53.71338 -82.860896)
			(xy 54.103016 -82.860896) (xy 54.130194 -82.846926) (xy 54.150105 -82.837161) (xy 54.192246 -82.823352)
			(xy 54.236037 -82.81636) (xy 54.280383 -82.81636) (xy 54.324174 -82.823352) (xy 54.366315 -82.837161)
			(xy 54.386226 -82.846926) (xy 54.431184 -82.87004) (xy 55.21452 -83.653376) (xy 56.08828 -83.653376)
		)
		(stroke
			(width 0)
			(type solid)
		)
		(fill yes)
		(layer "F.Cu")
		(net "GND")
	)
	(gr_poly
		(pts
			(xy 72.9361 -81.367122)
			(arc
				(start 72.954388 -81.345278)
				(mid 73.076683 -81.248081)
				(end 73.227692 -81.208118)
			)
			(xy 73.227946 -81.208118) (xy 73.307956 -81.203292) (xy 74.052176 -81.203292) (xy 74.05624 -81.207356)
			(xy 74.152252 -81.207356) (xy 74.184256 -81.23936) (xy 74.33564 -81.390998) (xy 74.700892 -81.390998)
			(arc
				(start 74.736198 -81.361534)
				(mid 74.9808 -81.272763)
				(end 75.225402 -81.361534)
			)
			(xy 75.260708 -81.390998) (xy 75.811126 -81.390998) (xy 75.82408 -81.37779)
			(arc
				(start 77.986636 -81.37779)
				(mid 78.035183 -81.36804)
				(end 78.076298 -81.340452)
			)
			(xy 78.212696 -81.204054) (xy 78.212696 -80.860646) (xy 78.520798 -80.552544)
			(arc
				(start 84.081112 -80.552544)
				(mid 84.170915 -80.515347)
				(end 84.208112 -80.425544)
			)
			(xy 84.208112 -79.657956) (xy 84.15147 -79.601314) (xy 84.111084 -79.561182) (xy 84.111084 -79.408274)
			(xy 83.786218 -79.083408) (xy 78.853792 -79.083408) (xy 78.283308 -79.653892) (xy 76.592684 -79.653892)
			(xy 76.472796 -79.77378) (xy 76.098146 -79.77378) (xy 76.005436 -79.681324) (xy 74.27214 -79.681324)
			(xy 74.150982 -79.777082)
			(arc
				(start 74.139044 -79.81315)
				(mid 73.990954 -80.014682)
				(end 73.752964 -80.091534)
			)
			(xy 73.016618 -80.091534) (xy 72.806052 -80.301846)
			(arc
				(start 72.072754 -80.301846)
				(mid 72.046428 -80.301553)
				(end 72.020176 -80.29956)
			)
			(xy 72.004682 -80.297782)
			(arc
				(start 71.983346 -80.293972)
				(mid 71.822891 -80.314259)
				(end 71.707248 -80.427322)
			)
			(arc
				(start 71.707248 -80.427322)
				(mid 71.249678 -80.637475)
				(end 70.938136 -80.241902)
			)
			(xy 70.938136 -79.7179)
			(arc
				(start 70.676516 -79.456026)
				(mid 70.622369 -79.389099)
				(end 70.583552 -79.312262)
			)
			(arc
				(start 70.582536 -79.309722)
				(mid 70.563556 -79.240239)
				(end 70.557136 -79.168498)
			)
			(arc
				(start 70.557136 -79.148432)
				(mid 70.531179 -79.071494)
				(end 70.463918 -79.026004)
			)
			(arc
				(start 70.463918 -79.026004)
				(mid 70.413804 -79.008321)
				(end 70.366636 -78.98384)
			)
			(arc
				(start 70.366636 -78.98384)
				(mid 70.350225 -78.973335)
				(end 70.334378 -78.961996)
			)
			(arc
				(start 70.334378 -78.961996)
				(mid 70.186373 -78.915465)
				(end 70.038976 -78.963774)
			)
			(arc
				(start 70.038976 -78.963774)
				(mid 69.972448 -79.004502)
				(end 69.899022 -79.03083)
			)
			(xy 69.859906 -79.040482) (xy 69.75348 -79.163672) (xy 69.75348 -79.45628) (xy 69.465952 -79.743808)
			(arc
				(start 69.465952 -80.241902)
				(mid 69.059044 -80.64881)
				(end 68.652136 -80.241902)
			)
			(arc
				(start 68.652136 -79.541878)
				(mid 68.680962 -79.391706)
				(end 68.763134 -79.262732)
			)
			(arc
				(start 68.763134 -79.262732)
				(mid 68.831868 -79.104358)
				(end 68.783454 -78.938628)
			)
			(arc
				(start 68.783454 -78.938628)
				(mid 68.71495 -78.891161)
				(end 68.631816 -78.896464)
			)
			(xy 68.585588 -78.915768)
			(arc
				(start 68.569332 -78.930754)
				(mid 68.53727 -78.95709)
				(end 68.50253 -78.979776)
			)
			(arc
				(start 68.50253 -78.979776)
				(mid 68.481895 -78.990834)
				(end 68.46062 -79.000604)
			)
			(arc
				(start 68.46062 -79.000604)
				(mid 68.262943 -79.027699)
				(end 68.078604 -78.951328)
			)
			(arc
				(start 68.078604 -78.951328)
				(mid 67.930776 -78.903869)
				(end 67.782948 -78.951328)
			)
			(arc
				(start 67.782948 -78.951328)
				(mid 67.519029 -79.029626)
				(end 67.271138 -78.909926)
			)
			(arc
				(start 67.271138 -78.909926)
				(mid 67.153606 -78.909366)
				(end 67.04838 -78.961742)
			)
			(arc
				(start 67.04838 -78.961742)
				(mid 67.028646 -78.977225)
				(end 67.007994 -78.99146)
			)
			(xy 66.996564 -78.998826)
			(arc
				(start 66.986912 -79.008478)
				(mid 66.949668 -79.098304)
				(end 66.986912 -79.188056)
			)
			(xy 67.009772 -79.210916) (xy 67.017138 -79.216504) (xy 67.02171 -79.22006) (xy 67.022218 -79.220314)
			(arc
				(start 67.044316 -79.238602)
				(mid 67.14449 -79.375768)
				(end 67.179952 -79.541878)
			)
			(arc
				(start 67.179952 -80.241902)
				(mid 66.773044 -80.64881)
				(end 66.366136 -80.241902)
			)
			(xy 66.366136 -79.7179)
			(arc
				(start 66.104516 -79.456026)
				(mid 66.029236 -79.352258)
				(end 65.989962 -79.23022)
			)
			(xy 65.986152 -79.196438)
			(arc
				(start 65.98539 -79.179674)
				(mid 65.947048 -79.091983)
				(end 65.85839 -79.055976)
			)
			(xy 65.855342 -79.055976) (xy 65.724532 -78.92542) (xy 65.61963 -78.92542)
			(arc
				(start 65.582292 -78.962504)
				(mid 65.48263 -79.035551)
				(end 65.36563 -79.07528)
			)
			(xy 65.31991 -79.083408) (xy 65.260728 -79.15402) (xy 65.260728 -79.189326) (xy 65.0367 -79.4131)
			(xy 64.525906 -79.4131) (xy 63.17996 -78.067408) (xy 63.081916 -78.062582)
			(arc
				(start 63.04407 -78.093824)
				(mid 62.974772 -78.139434)
				(end 62.897258 -78.169008)
			)
			(xy 62.863984 -78.177644) (xy 62.667134 -78.374494) (xy 62.660784 -78.383384) (xy 62.65164 -78.39583)
			(arc
				(start 62.636146 -78.414118)
				(mid 62.603039 -78.50259)
				(end 62.64021 -78.589378)
			)
			(xy 62.846204 -78.795372)
			(arc
				(start 62.846204 -78.999842)
				(mid 62.821667 -79.145569)
				(end 62.7507 -79.275178)
			)
			(arc
				(start 62.7507 -79.275178)
				(mid 62.696562 -79.422526)
				(end 62.73927 -79.573628)
			)
			(arc
				(start 62.73927 -79.573628)
				(mid 62.762493 -79.612837)
				(end 62.78118 -79.6544)
			)
			(xy 62.78118 -79.654654)
			(arc
				(start 62.795404 -79.691484)
				(mid 62.832606 -79.74303)
				(end 62.890146 -79.76997)
			)
			(arc
				(start 62.890146 -79.76997)
				(mid 63.011497 -79.812628)
				(end 63.114936 -79.889096)
			)
			(xy 63.259208 -80.033114) (xy 63.259208 -80.046576) (xy 63.540386 -80.328008)
			(arc
				(start 63.647066 -80.328008)
				(mid 63.692192 -80.319624)
				(end 63.731394 -80.29575)
			)
			(arc
				(start 63.731394 -80.29575)
				(mid 64.0528 -80.196492)
				(end 64.338962 -80.37322)
			)
			(xy 64.346074 -80.383634) (xy 64.382904 -80.42021) (xy 64.382904 -80.457548)
			(arc
				(start 64.389 -80.476344)
				(mid 64.395667 -80.499661)
				(end 64.400938 -80.523334)
			)
			(arc
				(start 64.400938 -80.523334)
				(mid 64.406434 -80.561514)
				(end 64.408304 -80.600042)
			)
			(arc
				(start 64.408304 -80.654144)
				(mid 64.500463 -80.849908)
				(end 64.710056 -80.903572)
			)
			(arc
				(start 64.710056 -80.903572)
				(mid 64.96283 -80.926515)
				(end 65.152778 -81.094834)
			)
			(arc
				(start 65.169796 -81.127346)
				(mid 65.237321 -81.191307)
				(end 65.330324 -81.192116)
			)
			(arc
				(start 65.330324 -81.192116)
				(mid 65.377718 -81.1771)
				(end 65.42659 -81.167986)
			)
			(arc
				(start 65.42659 -81.167986)
				(mid 65.457525 -81.165405)
				(end 65.488566 -81.165192)
			)
			(arc
				(start 65.520316 -81.167478)
				(mid 65.544442 -81.170818)
				(end 65.568322 -81.175606)
			)
			(xy 65.574926 -81.17713)
			(arc
				(start 65.587626 -81.178908)
				(mid 65.645999 -81.173865)
				(end 65.69583 -81.143094)
			)
			(xy 65.925192 -80.913732) (xy 66.63055 -80.913732) (xy 66.939668 -81.22285)
			(arc
				(start 67.154044 -81.22285)
				(mid 67.173642 -81.223496)
				(end 67.19316 -81.22539)
			)
			(arc
				(start 67.19316 -81.22539)
				(mid 67.278275 -81.249371)
				(end 67.352926 -81.296764)
			)
			(xy 67.38874 -81.327498) (xy 67.681348 -81.327498)
			(arc
				(start 67.717162 -81.296764)
				(mid 67.916044 -81.22304)
				(end 68.114926 -81.296764)
			)
			(xy 68.15074 -81.327498)
			(arc
				(start 68.28663 -81.327498)
				(mid 68.335451 -81.317845)
				(end 68.3768 -81.29016)
			)
			(arc
				(start 68.408296 -81.25841)
				(mid 68.692064 -81.146934)
				(end 68.966842 -81.278984)
			)
			(xy 68.96989 -81.28254) (xy 69.014848 -81.327498) (xy 69.205348 -81.327498)
			(arc
				(start 69.241162 -81.296764)
				(mid 69.440044 -81.22304)
				(end 69.638926 -81.296764)
			)
			(xy 69.67474 -81.327498) (xy 69.967348 -81.327498)
			(arc
				(start 70.003162 -81.296764)
				(mid 70.077826 -81.249402)
				(end 70.162928 -81.22539)
			)
			(arc
				(start 70.162928 -81.22539)
				(mid 70.182445 -81.223487)
				(end 70.202044 -81.22285)
			)
			(xy 70.69201 -81.22285)
			(arc
				(start 70.725284 -81.19872)
				(mid 70.838537 -81.141101)
				(end 70.964044 -81.12125)
			)
			(xy 71.464678 -81.12125) (xy 71.659496 -81.316068)
			(arc
				(start 71.742808 -81.316068)
				(mid 72.023049 -81.212307)
				(end 72.29856 -81.328006)
			)
			(xy 72.31507 -81.344262) (xy 72.41413 -81.387696) (xy 72.458834 -81.374234) (xy 72.477884 -81.3689)
			(xy 72.479154 -81.368646)
			(arc
				(start 72.48652 -81.366868)
				(mid 72.596394 -81.359033)
				(end 72.703944 -81.38287)
			)
			(xy 72.725788 -81.390998) (xy 72.885046 -81.390998)
		)
		(stroke
			(width 0)
			(type solid)
		)
		(fill yes)
		(layer "F.Cu")
		(net "PV_VCCP_NODE1")
	)
	(gr_poly
		(pts
			(xy 116.493036 -102.726744) (xy 117.73789 -102.726744) (xy 117.759693 -102.726302) (xy 117.802661 -102.718872)
			(xy 117.843729 -102.704211) (xy 117.881688 -102.68275) (xy 117.915423 -102.65512) (xy 117.943943 -102.622134)
			(xy 117.966409 -102.58476) (xy 117.98216 -102.544098) (xy 117.990733 -102.501344) (xy 117.991878 -102.457753)
			(xy 117.985558 -102.414607) (xy 117.97919 -102.39375) (xy 117.971555 -102.368949) (xy 117.962291 -102.317891)
			(xy 117.960034 -102.266049) (xy 117.964826 -102.214379) (xy 117.976579 -102.163836) (xy 117.995076 -102.115353)
			(xy 118.019974 -102.069825) (xy 118.050815 -102.028093) (xy 118.068598 -102.009194) (xy 118.079802 -101.99692)
			(xy 118.096061 -101.967952) (xy 118.104306 -101.935772) (xy 118.103982 -101.902554) (xy 118.09511 -101.870541)
			(xy 118.078289 -101.841895) (xy 118.06682 -101.82987) (xy 118.047696 -101.810418) (xy 118.014641 -101.767026)
			(xy 117.988102 -101.719368) (xy 117.968621 -101.668417) (xy 117.956594 -101.615211) (xy 117.952268 -101.560834)
			(xy 117.95573 -101.506395) (xy 117.96691 -101.453005) (xy 117.98558 -101.40175) (xy 118.011358 -101.353677)
			(xy 118.043721 -101.309766) (xy 118.082007 -101.270911) (xy 118.125436 -101.237904) (xy 118.173124 -101.211419)
			(xy 118.224097 -101.191996) (xy 118.277317 -101.18003) (xy 118.331699 -101.175765) (xy 118.386133 -101.179289)
			(xy 118.439511 -101.190529) (xy 118.490744 -101.209256) (xy 118.538788 -101.235089) (xy 118.582663 -101.267501)
			(xy 118.621475 -101.305832) (xy 118.654432 -101.349298) (xy 118.680863 -101.397016) (xy 118.700229 -101.448011)
			(xy 118.706646 -101.474524) (xy 118.710641 -101.4902) (xy 118.725409 -101.51897) (xy 118.746949 -101.543093)
			(xy 118.77387 -101.561012) (xy 118.804437 -101.571572) (xy 118.836679 -101.574092) (xy 118.852696 -101.571806)
			(xy 118.881626 -101.56717) (xy 118.94018 -101.565101) (xy 118.998447 -101.571256) (xy 119.055276 -101.585513)
			(xy 119.109547 -101.607592) (xy 119.16019 -101.637058) (xy 119.206205 -101.673327) (xy 119.246684 -101.715687)
			(xy 119.264176 -101.739192) (xy 119.2774 -101.756839) (xy 119.308882 -101.78771) (xy 119.345223 -101.812682)
			(xy 119.385329 -101.831005) (xy 119.427996 -101.842127) (xy 119.471943 -101.845716) (xy 119.515849 -101.841664)
			(xy 119.558396 -101.830091) (xy 119.598307 -101.811346) (xy 119.634381 -101.785992) (xy 119.650256 -101.770688)
			(xy 124.291852 -97.129092) (xy 131.62788 -97.129092) (xy 135.25246 -93.504512) (xy 135.25246 -87.094568)
			(xy 135.251967 -87.071559) (xy 135.243686 -87.026294) (xy 135.227384 -86.983261) (xy 135.203593 -86.943872)
			(xy 135.173094 -86.909414) (xy 135.136885 -86.881016) (xy 135.09615 -86.859609) (xy 135.052225 -86.845893)
			(xy 135.029448 -86.8426) (xy 135.001439 -86.838646) (xy 134.946929 -86.823542) (xy 134.895248 -86.800554)
			(xy 134.847527 -86.770186) (xy 134.804815 -86.733104) (xy 134.768047 -86.690121) (xy 134.738029 -86.642179)
			(xy 134.715421 -86.59033) (xy 134.700718 -86.535711) (xy 134.694241 -86.479519) (xy 134.696134 -86.422987)
			(xy 134.706355 -86.367354) (xy 134.724679 -86.313841) (xy 134.750705 -86.26362) (xy 134.766812 -86.240366)
			(xy 134.780061 -86.221133) (xy 134.800042 -86.178925) (xy 134.811973 -86.133777) (xy 134.815455 -86.087209)
			(xy 134.810369 -86.040788) (xy 134.796886 -85.996079) (xy 134.775461 -85.954586) (xy 134.746815 -85.917706)
			(xy 134.729728 -85.901784) (xy 134.721955 -85.894839) (xy 134.707088 -85.880226) (xy 134.70001 -85.872574)
			(xy 134.684815 -85.856471) (xy 134.649893 -85.829263) (xy 134.610786 -85.808516) (xy 134.568675 -85.794858)
			(xy 134.524836 -85.788704) (xy 134.480592 -85.790237) (xy 134.437284 -85.799414) (xy 134.39622 -85.815955)
			(xy 134.358643 -85.83936) (xy 134.32569 -85.868922) (xy 134.311644 -85.886036) (xy 134.294626 -85.906102)
			(xy 134.280481 -85.922467) (xy 134.257404 -85.959051) (xy 134.240854 -85.999013) (xy 134.231306 -86.0412)
			(xy 134.229038 -86.084394) (xy 134.234114 -86.127349) (xy 134.246389 -86.168825) (xy 134.265507 -86.207624)
			(xy 134.277862 -86.22538) (xy 134.293761 -86.248095) (xy 134.319527 -86.297186) (xy 134.337916 -86.349491)
			(xy 134.348539 -86.403906) (xy 134.351174 -86.459286) (xy 134.345764 -86.514464) (xy 134.332423 -86.568278)
			(xy 134.311434 -86.619594) (xy 134.283237 -86.667331) (xy 134.248426 -86.710483) (xy 134.207736 -86.748142)
			(xy 134.162023 -86.779514) (xy 134.11225 -86.803938) (xy 134.059466 -86.8209) (xy 134.004782 -86.830042)
			(xy 133.949351 -86.831173) (xy 133.89434 -86.824267) (xy 133.840908 -86.809471) (xy 133.790181 -86.787096)
			(xy 133.743227 -86.757613) (xy 133.701036 -86.721644) (xy 133.664495 -86.679947) (xy 133.634376 -86.633399)
			(xy 133.611312 -86.582981) (xy 133.595789 -86.529756) (xy 133.588135 -86.474844) (xy 133.588509 -86.419403)
			(xy 133.596906 -86.3646) (xy 133.613147 -86.311589) (xy 133.636891 -86.261488) (xy 133.667637 -86.215352)
			(xy 133.685788 -86.194392) (xy 133.699932 -86.178026) (xy 133.723006 -86.141442) (xy 133.739555 -86.101481)
			(xy 133.749101 -86.059294) (xy 133.751368 -86.016101) (xy 133.746291 -85.973147) (xy 133.734017 -85.931673)
			(xy 133.7149 -85.892874) (xy 133.702552 -85.875114) (xy 133.686705 -85.852513) (xy 133.660992 -85.803669)
			(xy 133.642586 -85.75163) (xy 133.631872 -85.697482) (xy 133.629073 -85.642355) (xy 133.634248 -85.5874)
			(xy 133.647289 -85.533764) (xy 133.667924 -85.482568) (xy 133.695721 -85.43488) (xy 133.730101 -85.391695)
			(xy 133.770345 -85.353916) (xy 133.815613 -85.322331) (xy 133.864961 -85.2976) (xy 133.917358 -85.280239)
			(xy 133.97171 -85.27061) (xy 134.026882 -85.268914) (xy 134.081723 -85.275188) (xy 134.135087 -85.289299)
			(xy 134.18586 -85.310953) (xy 134.232983 -85.339699) (xy 134.275471 -85.374935) (xy 134.294372 -85.395054)
			(xy 134.309565 -85.411162) (xy 134.344484 -85.438381) (xy 134.383593 -85.459137) (xy 134.425706 -85.472802)
			(xy 134.469551 -85.478961) (xy 134.513799 -85.477428) (xy 134.557112 -85.468251) (xy 134.59818 -85.451706)
			(xy 134.635759 -85.428295) (xy 134.668712 -85.398725) (xy 134.682738 -85.381592) (xy 134.70143 -85.358622)
			(xy 134.744698 -85.31819) (xy 134.793691 -85.284926) (xy 134.847234 -85.259627) (xy 134.904041 -85.2429)
			(xy 134.96275 -85.235146) (xy 134.992364 -85.235288) (xy 135.014881 -85.235348) (xy 135.059378 -85.228487)
			(xy 135.101969 -85.213891) (xy 135.141321 -85.192018) (xy 135.176203 -85.163552) (xy 135.205523 -85.129384)
			(xy 135.228362 -85.090584) (xy 135.244006 -85.048367) (xy 135.251965 -85.004053) (xy 135.25246 -84.981542)
			(xy 135.25246 -78.533752) (xy 134.41934 -77.700632) (xy 118.494048 -77.700632) (xy 118.494048 -79.237332)
			(xy 118.24081 -79.49057) (xy 117.88267 -79.49057) (xy 117.629432 -79.237332) (xy 117.629432 -77.75321)
			(xy 117.576854 -77.700632) (xy 116.814346 -77.700632) (xy 114.736118 -79.77886) (xy 122.752102 -79.77886)
			(xy 122.756173 -79.723238) (xy 122.768299 -79.668801) (xy 122.788222 -79.61671) (xy 122.815518 -79.568075)
			(xy 122.849604 -79.523932) (xy 122.889753 -79.485223) (xy 122.935111 -79.452772) (xy 122.984711 -79.427271)
			(xy 123.037495 -79.409264) (xy 123.092338 -79.399134) (xy 123.148072 -79.397097) (xy 123.203509 -79.403197)
			(xy 123.257466 -79.417303) (xy 123.308795 -79.439115) (xy 123.356401 -79.468169) (xy 123.399269 -79.503844)
			(xy 123.436486 -79.545381) (xy 123.467259 -79.591894) (xy 123.490931 -79.642391) (xy 123.506999 -79.695798)
			(xy 123.515119 -79.750974) (xy 123.515628 -79.77886) (xy 123.515119 -79.806746) (xy 123.506999 -79.861922)
			(xy 123.490931 -79.915329) (xy 123.467259 -79.965826) (xy 123.436486 -80.012339) (xy 123.399269 -80.053876)
			(xy 123.356401 -80.089551) (xy 123.308795 -80.118605) (xy 123.257466 -80.140417) (xy 123.203509 -80.154523)
			(xy 123.148072 -80.160623) (xy 123.092338 -80.158586) (xy 123.037495 -80.148456) (xy 122.984711 -80.130449)
			(xy 122.935111 -80.104948) (xy 122.889753 -80.072497) (xy 122.849604 -80.033788) (xy 122.815518 -79.989645)
			(xy 122.788222 -79.94101) (xy 122.768299 -79.888919) (xy 122.756173 -79.834482) (xy 122.752102 -79.77886)
			(xy 114.736118 -79.77886) (xy 114.318796 -80.196182) (xy 125.309882 -80.196182) (xy 125.313953 -80.14056)
			(xy 125.326079 -80.086123) (xy 125.346002 -80.034032) (xy 125.373298 -79.985397) (xy 125.407384 -79.941254)
			(xy 125.447533 -79.902545) (xy 125.492891 -79.870094) (xy 125.542491 -79.844593) (xy 125.595275 -79.826586)
			(xy 125.650118 -79.816456) (xy 125.705852 -79.814419) (xy 125.761289 -79.820519) (xy 125.815246 -79.834625)
			(xy 125.866575 -79.856437) (xy 125.914181 -79.885491) (xy 125.957049 -79.921166) (xy 125.994266 -79.962703)
			(xy 126.025039 -80.009216) (xy 126.048711 -80.059713) (xy 126.064779 -80.11312) (xy 126.072899 -80.168296)
			(xy 126.073408 -80.196182) (xy 126.072899 -80.224068) (xy 126.064779 -80.279244) (xy 126.048711 -80.332651)
			(xy 126.025039 -80.383148) (xy 125.994266 -80.429661) (xy 125.957049 -80.471198) (xy 125.914181 -80.506873)
			(xy 125.866575 -80.535927) (xy 125.815246 -80.557739) (xy 125.761289 -80.571845) (xy 125.705852 -80.577945)
			(xy 125.650118 -80.575908) (xy 125.595275 -80.565778) (xy 125.542491 -80.547771) (xy 125.492891 -80.52227)
			(xy 125.447533 -80.489819) (xy 125.407384 -80.45111) (xy 125.373298 -80.406967) (xy 125.346002 -80.358332)
			(xy 125.326079 -80.306241) (xy 125.313953 -80.251804) (xy 125.309882 -80.196182) (xy 114.318796 -80.196182)
			(xy 113.02746 -81.487518) (xy 113.02746 -84.523344) (xy 119.021097 -84.523344) (xy 119.027197 -84.467907)
			(xy 119.041303 -84.41395) (xy 119.063115 -84.362621) (xy 119.092169 -84.315015) (xy 119.127844 -84.272147)
			(xy 119.169381 -84.23493) (xy 119.215894 -84.204157) (xy 119.266391 -84.180485) (xy 119.319798 -84.164417)
			(xy 119.374974 -84.156297) (xy 119.40286 -84.155788) (xy 119.430746 -84.156297) (xy 119.485922 -84.164417)
			(xy 119.539329 -84.180485) (xy 119.589826 -84.204157) (xy 119.636339 -84.23493) (xy 119.677876 -84.272147)
			(xy 119.713551 -84.315015) (xy 119.742605 -84.362621) (xy 119.764417 -84.41395) (xy 119.778523 -84.467907)
			(xy 119.784623 -84.523344) (xy 119.782586 -84.579078) (xy 119.772456 -84.633921) (xy 119.754449 -84.686705)
			(xy 119.728948 -84.736305) (xy 119.696497 -84.781663) (xy 119.663455 -84.815934) (xy 121.748802 -84.815934)
			(xy 121.752873 -84.760312) (xy 121.764999 -84.705875) (xy 121.784922 -84.653784) (xy 121.812218 -84.605149)
			(xy 121.846304 -84.561006) (xy 121.886453 -84.522297) (xy 121.931811 -84.489846) (xy 121.981411 -84.464345)
			(xy 122.034195 -84.446338) (xy 122.089038 -84.436208) (xy 122.144772 -84.434171) (xy 122.200209 -84.440271)
			(xy 122.254166 -84.454377) (xy 122.305495 -84.476189) (xy 122.353101 -84.505243) (xy 122.395969 -84.540918)
			(xy 122.433186 -84.582455) (xy 122.463959 -84.628968) (xy 122.487631 -84.679465) (xy 122.503699 -84.732872)
			(xy 122.511819 -84.788048) (xy 122.512328 -84.815934) (xy 122.511819 -84.84382) (xy 122.503699 -84.898996)
			(xy 122.487631 -84.952403) (xy 122.463959 -85.0029) (xy 122.433186 -85.049413) (xy 122.395969 -85.09095)
			(xy 122.353101 -85.126625) (xy 122.305495 -85.155679) (xy 122.254166 -85.177491) (xy 122.200209 -85.191597)
			(xy 122.144772 -85.197697) (xy 122.089038 -85.19566) (xy 122.034195 -85.18553) (xy 121.981411 -85.167523)
			(xy 121.931811 -85.142022) (xy 121.886453 -85.109571) (xy 121.846304 -85.070862) (xy 121.812218 -85.026719)
			(xy 121.784922 -84.978084) (xy 121.764999 -84.925993) (xy 121.752873 -84.871556) (xy 121.748802 -84.815934)
			(xy 119.663455 -84.815934) (xy 119.657788 -84.821812) (xy 119.613645 -84.855898) (xy 119.56501 -84.883194)
			(xy 119.512919 -84.903117) (xy 119.458482 -84.915243) (xy 119.40286 -84.919314) (xy 119.347238 -84.915243)
			(xy 119.292801 -84.903117) (xy 119.24071 -84.883194) (xy 119.192075 -84.855898) (xy 119.147932 -84.821812)
			(xy 119.109223 -84.781663) (xy 119.076772 -84.736305) (xy 119.051271 -84.686705) (xy 119.033264 -84.633921)
			(xy 119.023134 -84.579078) (xy 119.021097 -84.523344) (xy 113.02746 -84.523344) (xy 113.02746 -86.109302)
			(xy 120.316242 -86.109302) (xy 120.320313 -86.05368) (xy 120.332439 -85.999243) (xy 120.352362 -85.947152)
			(xy 120.379658 -85.898517) (xy 120.413744 -85.854374) (xy 120.453893 -85.815665) (xy 120.499251 -85.783214)
			(xy 120.548851 -85.757713) (xy 120.601635 -85.739706) (xy 120.656478 -85.729576) (xy 120.712212 -85.727539)
			(xy 120.767649 -85.733639) (xy 120.821606 -85.747745) (xy 120.872935 -85.769557) (xy 120.920541 -85.798611)
			(xy 120.963409 -85.834286) (xy 120.980419 -85.85327) (xy 128.939542 -85.85327) (xy 128.943613 -85.797648)
			(xy 128.955739 -85.743211) (xy 128.975662 -85.69112) (xy 129.002958 -85.642485) (xy 129.037044 -85.598342)
			(xy 129.077193 -85.559633) (xy 129.122551 -85.527182) (xy 129.172151 -85.501681) (xy 129.224935 -85.483674)
			(xy 129.279778 -85.473544) (xy 129.335512 -85.471507) (xy 129.390949 -85.477607) (xy 129.444906 -85.491713)
			(xy 129.496235 -85.513525) (xy 129.543841 -85.542579) (xy 129.586709 -85.578254) (xy 129.623926 -85.619791)
			(xy 129.654699 -85.666304) (xy 129.658281 -85.673946) (xy 131.827522 -85.673946) (xy 131.831593 -85.618324)
			(xy 131.843719 -85.563887) (xy 131.863642 -85.511796) (xy 131.890938 -85.463161) (xy 131.925024 -85.419018)
			(xy 131.965173 -85.380309) (xy 132.010531 -85.347858) (xy 132.060131 -85.322357) (xy 132.112915 -85.30435)
			(xy 132.167758 -85.29422) (xy 132.223492 -85.292183) (xy 132.278929 -85.298283) (xy 132.332886 -85.312389)
			(xy 132.384215 -85.334201) (xy 132.431821 -85.363255) (xy 132.474689 -85.39893) (xy 132.511906 -85.440467)
			(xy 132.542679 -85.48698) (xy 132.566351 -85.537477) (xy 132.582419 -85.590884) (xy 132.590539 -85.64606)
			(xy 132.591048 -85.673946) (xy 132.590539 -85.701832) (xy 132.582419 -85.757008) (xy 132.566351 -85.810415)
			(xy 132.542679 -85.860912) (xy 132.511906 -85.907425) (xy 132.474689 -85.948962) (xy 132.431821 -85.984637)
			(xy 132.384215 -86.013691) (xy 132.332886 -86.035503) (xy 132.278929 -86.049609) (xy 132.223492 -86.055709)
			(xy 132.167758 -86.053672) (xy 132.112915 -86.043542) (xy 132.060131 -86.025535) (xy 132.010531 -86.000034)
			(xy 131.965173 -85.967583) (xy 131.925024 -85.928874) (xy 131.890938 -85.884731) (xy 131.863642 -85.836096)
			(xy 131.843719 -85.784005) (xy 131.831593 -85.729568) (xy 131.827522 -85.673946) (xy 129.658281 -85.673946)
			(xy 129.678371 -85.716801) (xy 129.694439 -85.770208) (xy 129.702559 -85.825384) (xy 129.703068 -85.85327)
			(xy 129.702559 -85.881156) (xy 129.694439 -85.936332) (xy 129.678371 -85.989739) (xy 129.654699 -86.040236)
			(xy 129.623926 -86.086749) (xy 129.586709 -86.128286) (xy 129.543841 -86.163961) (xy 129.496235 -86.193015)
			(xy 129.444906 -86.214827) (xy 129.390949 -86.228933) (xy 129.335512 -86.235033) (xy 129.279778 -86.232996)
			(xy 129.224935 -86.222866) (xy 129.172151 -86.204859) (xy 129.122551 -86.179358) (xy 129.077193 -86.146907)
			(xy 129.037044 -86.108198) (xy 129.002958 -86.064055) (xy 128.975662 -86.01542) (xy 128.955739 -85.963329)
			(xy 128.943613 -85.908892) (xy 128.939542 -85.85327) (xy 120.980419 -85.85327) (xy 121.000626 -85.875823)
			(xy 121.031399 -85.922336) (xy 121.055071 -85.972833) (xy 121.071139 -86.02624) (xy 121.079259 -86.081416)
			(xy 121.079768 -86.109302) (xy 121.079259 -86.137188) (xy 121.071139 -86.192364) (xy 121.055071 -86.245771)
			(xy 121.031399 -86.296268) (xy 121.000626 -86.342781) (xy 120.963409 -86.384318) (xy 120.920541 -86.419993)
			(xy 120.872935 -86.449047) (xy 120.821606 -86.470859) (xy 120.767649 -86.484965) (xy 120.712212 -86.491065)
			(xy 120.656478 -86.489028) (xy 120.601635 -86.478898) (xy 120.548851 -86.460891) (xy 120.499251 -86.43539)
			(xy 120.453893 -86.402939) (xy 120.413744 -86.36423) (xy 120.379658 -86.320087) (xy 120.352362 -86.271452)
			(xy 120.332439 -86.219361) (xy 120.320313 -86.164924) (xy 120.316242 -86.109302) (xy 113.02746 -86.109302)
			(xy 113.02746 -86.570566) (xy 130.275582 -86.570566) (xy 130.279653 -86.514944) (xy 130.291779 -86.460507)
			(xy 130.311702 -86.408416) (xy 130.338998 -86.359781) (xy 130.373084 -86.315638) (xy 130.413233 -86.276929)
			(xy 130.458591 -86.244478) (xy 130.508191 -86.218977) (xy 130.560975 -86.20097) (xy 130.615818 -86.19084)
			(xy 130.671552 -86.188803) (xy 130.726989 -86.194903) (xy 130.780946 -86.209009) (xy 130.832275 -86.230821)
			(xy 130.879881 -86.259875) (xy 130.922749 -86.29555) (xy 130.959966 -86.337087) (xy 130.990739 -86.3836)
			(xy 131.014411 -86.434097) (xy 131.030479 -86.487504) (xy 131.038599 -86.54268) (xy 131.039108 -86.570566)
			(xy 131.038599 -86.598452) (xy 131.030479 -86.653628) (xy 131.014411 -86.707035) (xy 130.990739 -86.757532)
			(xy 130.959966 -86.804045) (xy 130.922749 -86.845582) (xy 130.879881 -86.881257) (xy 130.832275 -86.910311)
			(xy 130.780946 -86.932123) (xy 130.726989 -86.946229) (xy 130.671552 -86.952329) (xy 130.615818 -86.950292)
			(xy 130.560975 -86.940162) (xy 130.508191 -86.922155) (xy 130.458591 -86.896654) (xy 130.413233 -86.864203)
			(xy 130.373084 -86.825494) (xy 130.338998 -86.781351) (xy 130.311702 -86.732716) (xy 130.291779 -86.680625)
			(xy 130.279653 -86.626188) (xy 130.275582 -86.570566) (xy 113.02746 -86.570566) (xy 113.02746 -91.55296)
			(xy 128.013202 -91.55296) (xy 128.013202 -91.468264) (xy 128.021253 -91.38395) (xy 128.037282 -91.300784)
			(xy 128.061143 -91.219517) (xy 128.092622 -91.140887) (xy 128.131433 -91.065606) (xy 128.177223 -90.994354)
			(xy 128.229579 -90.927778) (xy 128.288027 -90.86648) (xy 128.352037 -90.811015) (xy 128.421029 -90.761886)
			(xy 128.494379 -90.719537) (xy 128.571422 -90.684353) (xy 128.651461 -90.656651) (xy 128.73377 -90.636683)
			(xy 128.817605 -90.62463) (xy 128.902206 -90.6206) (xy 128.986807 -90.62463) (xy 129.070642 -90.636683)
			(xy 129.152951 -90.656651) (xy 129.23299 -90.684353) (xy 129.310033 -90.719537) (xy 129.383383 -90.761886)
			(xy 129.452375 -90.811015) (xy 129.516385 -90.86648) (xy 129.574833 -90.927778) (xy 129.627189 -90.994354)
			(xy 129.672979 -91.065606) (xy 129.71179 -91.140887) (xy 129.743269 -91.219517) (xy 129.76713 -91.300784)
			(xy 129.783159 -91.38395) (xy 129.79121 -91.468264) (xy 129.791714 -91.510612) (xy 129.79121 -91.55296)
			(xy 129.783159 -91.637274) (xy 129.76713 -91.72044) (xy 129.743269 -91.801707) (xy 129.71179 -91.880337)
			(xy 129.672979 -91.955618) (xy 129.627189 -92.02687) (xy 129.574833 -92.093446) (xy 129.516385 -92.154744)
			(xy 129.452375 -92.210209) (xy 129.383383 -92.259338) (xy 129.310033 -92.301687) (xy 129.23299 -92.336871)
			(xy 129.152951 -92.364573) (xy 129.070642 -92.384541) (xy 128.986807 -92.396594) (xy 128.902206 -92.400625)
			(xy 128.817605 -92.396594) (xy 128.73377 -92.384541) (xy 128.651461 -92.364573) (xy 128.571422 -92.336871)
			(xy 128.494379 -92.301687) (xy 128.421029 -92.259338) (xy 128.352037 -92.210209) (xy 128.288027 -92.154744)
			(xy 128.229579 -92.093446) (xy 128.177223 -92.02687) (xy 128.131433 -91.955618) (xy 128.092622 -91.880337)
			(xy 128.061143 -91.801707) (xy 128.037282 -91.72044) (xy 128.021253 -91.637274) (xy 128.013202 -91.55296)
			(xy 113.02746 -91.55296) (xy 113.02746 -99.67468) (xy 110.98784 -101.7143) (xy 110.98784 -102.855268)
			(xy 110.988331 -102.871924) (xy 110.996947 -102.904101) (xy 111.013601 -102.93295) (xy 111.037156 -102.956504)
			(xy 111.066006 -102.973156) (xy 111.098184 -102.98177) (xy 111.11484 -102.982268) (xy 116.237258 -102.982268)
		)
		(stroke
			(width 0)
			(type solid)
		)
		(fill yes)
		(layer "F.Cu")
		(net "P1V8_NODE1")
	)
	(gr_poly
		(pts
			(xy 129.50444 -150.27275) (xy 129.527883 -150.272201) (xy 129.573971 -150.263584) (xy 129.6177 -150.246668)
			(xy 129.657589 -150.222026) (xy 129.692287 -150.190492) (xy 129.720619 -150.153134) (xy 129.741627 -150.111216)
			(xy 129.754597 -150.06616) (xy 129.757424 -150.04288) (xy 129.759759 -150.01634) (xy 129.770849 -149.964231)
			(xy 129.789066 -149.914166) (xy 129.814055 -149.867114) (xy 129.829306 -149.845268) (xy 129.846484 -149.822548)
			(xy 129.886458 -149.781978) (xy 129.932016 -149.747797) (xy 129.982148 -149.720765) (xy 130.03574 -149.701482)
			(xy 130.091602 -149.690376) (xy 130.148494 -149.687694) (xy 130.205153 -149.693495) (xy 130.260322 -149.70765)
			(xy 130.312774 -149.729845) (xy 130.361347 -149.759588) (xy 130.383534 -149.77745) (xy 130.40218 -149.792395)
			(xy 130.443867 -149.815744) (xy 130.489181 -149.830893) (xy 130.536529 -149.83731) (xy 130.584241 -149.834769)
			(xy 130.630639 -149.823358) (xy 130.674087 -149.80348) (xy 130.693922 -149.79015) (xy 130.716071 -149.774978)
			(xy 130.763766 -149.750333) (xy 130.814446 -149.73262) (xy 130.867109 -149.722188) (xy 130.920715 -149.719244)
			(xy 130.974203 -149.723847) (xy 131.026518 -149.735904) (xy 131.076625 -149.755179) (xy 131.100322 -149.767798)
			(xy 131.12261 -149.780675) (xy 131.163826 -149.811511) (xy 131.200524 -149.847606) (xy 131.232038 -149.888306)
			(xy 131.257798 -149.932871) (xy 131.267962 -149.95652) (xy 131.26974 -149.960838) (xy 131.269994 -149.9616)
			(xy 131.281424 -149.989032) (xy 131.281424 -149.994112) (xy 131.285234 -150.009352) (xy 131.28804 -150.020971)
			(xy 131.292358 -150.044484) (xy 131.29387 -150.056342) (xy 131.297696 -150.078619) (xy 131.312176 -150.121432)
			(xy 131.333999 -150.161009) (xy 131.362478 -150.196103) (xy 131.396715 -150.225606) (xy 131.43563 -150.24859)
			(xy 131.477996 -150.264328) (xy 131.522478 -150.272326) (xy 131.545076 -150.27275) (xy 133.267704 -150.27275)
			(xy 133.284356 -150.272255) (xy 133.316525 -150.263632) (xy 133.345364 -150.246976) (xy 133.368909 -150.223421)
			(xy 133.385553 -150.194574) (xy 133.394162 -150.162402) (xy 133.394704 -150.14575) (xy 133.394704 -150.082504)
			(xy 133.658356 -149.818852) (xy 133.668008 -149.795738) (xy 133.679016 -149.770608) (xy 133.707189 -149.723532)
			(xy 133.741815 -149.680977) (xy 133.782181 -149.643822) (xy 133.827454 -149.612834) (xy 133.876699 -149.588651)
			(xy 133.928901 -149.571774) (xy 133.982982 -149.562548) (xy 134.037827 -149.561167) (xy 134.092304 -149.567656)
			(xy 134.145289 -149.581884) (xy 134.19569 -149.603556) (xy 134.242466 -149.632225) (xy 134.284651 -149.6673)
			(xy 134.321377 -149.708057) (xy 134.351885 -149.753655) (xy 134.375545 -149.803153) (xy 134.39187 -149.85553)
			(xy 134.400522 -149.909706) (xy 134.401323 -149.964563) (xy 134.398258 -149.991826) (xy 134.396266 -150.01544)
			(xy 134.400054 -150.062672) (xy 134.412534 -150.108383) (xy 134.433273 -150.150988) (xy 134.461551 -150.189008)
			(xy 134.496389 -150.221127) (xy 134.536577 -150.246229) (xy 134.580723 -150.263445) (xy 134.627295 -150.272178)
			(xy 134.650988 -150.27275) (xy 134.867904 -150.27275) (xy 134.884556 -150.272255) (xy 134.916725 -150.263632)
			(xy 134.945564 -150.246976) (xy 134.969109 -150.223421) (xy 134.985753 -150.194574) (xy 134.994362 -150.162402)
			(xy 134.994904 -150.14575) (xy 134.994904 -149.980904) (xy 135.007858 -149.967696) (xy 135.010906 -149.91969)
			(xy 135.010906 -149.919436) (xy 135.013069 -149.891718) (xy 135.024415 -149.837294) (xy 135.043548 -149.785095)
			(xy 135.07006 -149.73623) (xy 135.086344 -149.713696) (xy 135.103401 -149.691767) (xy 135.14281 -149.652608)
			(xy 135.18748 -149.619579) (xy 135.236469 -149.593377) (xy 135.288739 -149.574556) (xy 135.343186 -149.563515)
			(xy 135.398659 -149.560486) (xy 135.453984 -149.565533) (xy 135.507993 -149.57855) (xy 135.559543 -149.599262)
			(xy 135.607545 -149.627231) (xy 135.650983 -149.661865) (xy 135.688939 -149.702433) (xy 135.720611 -149.748075)
			(xy 135.745329 -149.797829) (xy 135.762571 -149.850641) (xy 135.771972 -149.905395) (xy 135.77316 -149.933152)
			(xy 135.773338 -149.9594) (xy 135.767359 -150.011547) (xy 135.75428 -150.06238) (xy 135.744712 -150.086822)
			(xy 135.744458 -150.08733) (xy 135.73506 -150.110698) (xy 135.73506 -150.14575) (xy 135.735549 -150.162411)
			(xy 135.744161 -150.1946) (xy 135.760811 -150.223464) (xy 135.784364 -150.247034) (xy 135.813216 -150.263705)
			(xy 135.845399 -150.27234) (xy 135.86206 -150.27275) (xy 136.8679 -150.27275) (xy 136.884552 -150.272255)
			(xy 136.916722 -150.263633) (xy 136.945562 -150.246977) (xy 136.969108 -150.223422) (xy 136.985752 -150.194575)
			(xy 136.994362 -150.162403) (xy 136.9949 -150.14575) (xy 136.9949 -150.06955) (xy 136.985248 -150.046182)
			(xy 136.97517 -150.02036) (xy 136.961737 -149.966582) (xy 136.956229 -149.911426) (xy 136.958761 -149.856054)
			(xy 136.969282 -149.801632) (xy 136.987569 -149.749305) (xy 137.013236 -149.700176) (xy 137.045745 -149.655279)
			(xy 137.084409 -149.61556) (xy 137.128414 -149.581856) (xy 137.176835 -149.554876) (xy 137.22865 -149.535187)
			(xy 137.28277 -149.523206) (xy 137.338054 -149.519184) (xy 137.393338 -149.523206) (xy 137.447458 -149.535187)
			(xy 137.499273 -149.554876) (xy 137.547694 -149.581856) (xy 137.591699 -149.61556) (xy 137.630363 -149.655279)
			(xy 137.662872 -149.700176) (xy 137.688539 -149.749305) (xy 137.706826 -149.801632) (xy 137.717347 -149.856054)
			(xy 137.719879 -149.911426) (xy 137.714371 -149.966582) (xy 137.700938 -150.02036) (xy 137.69086 -150.046182)
			(xy 137.681208 -150.06955) (xy 137.681208 -150.14575) (xy 137.681697 -150.162409) (xy 137.690309 -150.194593)
			(xy 137.706961 -150.223451) (xy 137.730516 -150.247013) (xy 137.759368 -150.263674) (xy 137.791549 -150.272298)
			(xy 137.808208 -150.27275) (xy 138.467592 -150.27275) (xy 138.484245 -150.272256) (xy 138.516416 -150.263636)
			(xy 138.545259 -150.24698) (xy 138.568806 -150.223425) (xy 138.585452 -150.194577) (xy 138.594062 -150.162403)
			(xy 138.594592 -150.14575) (xy 138.594592 -150.06955) (xy 138.585194 -150.046182) (xy 138.58494 -150.045928)
			(xy 138.574906 -150.020108) (xy 138.561555 -149.966346) (xy 138.55612 -149.911219) (xy 138.558715 -149.855886)
			(xy 138.569286 -149.80151) (xy 138.58761 -149.749234) (xy 138.613301 -149.700158) (xy 138.645821 -149.655313)
			(xy 138.684484 -149.615643) (xy 138.728478 -149.581982) (xy 138.776877 -149.555038) (xy 138.828665 -149.535377)
			(xy 138.882752 -149.523412) (xy 138.938 -149.519396) (xy 138.993248 -149.523412) (xy 139.047335 -149.535377)
			(xy 139.099123 -149.555038) (xy 139.147522 -149.581982) (xy 139.191516 -149.615643) (xy 139.230179 -149.655313)
			(xy 139.262699 -149.700158) (xy 139.28839 -149.749234) (xy 139.306714 -149.80151) (xy 139.317285 -149.855886)
			(xy 139.31988 -149.911219) (xy 139.314445 -149.966346) (xy 139.301094 -150.020108) (xy 139.29106 -150.045928)
			(xy 139.290806 -150.046182) (xy 139.281408 -150.06955) (xy 139.281408 -150.14575) (xy 139.281897 -150.162409)
			(xy 139.290509 -150.194593) (xy 139.307161 -150.223451) (xy 139.330716 -150.247013) (xy 139.359568 -150.263674)
			(xy 139.391749 -150.272298) (xy 139.408408 -150.27275) (xy 139.684252 -150.27275) (xy 139.977114 -149.979888)
			(xy 139.992744 -149.963569) (xy 140.018545 -149.926479) (xy 140.03738 -149.885409) (xy 140.048653 -149.841656)
			(xy 140.05201 -149.796599) (xy 140.047344 -149.751658) (xy 140.034802 -149.708251) (xy 140.014781 -149.667747)
			(xy 139.987912 -149.631423) (xy 139.955041 -149.600424) (xy 139.917205 -149.575728) (xy 139.875598 -149.558114)
			(xy 139.85367 -149.55266) (xy 139.827454 -149.546225) (xy 139.777027 -149.526966) (xy 139.729818 -149.500792)
			(xy 139.686769 -149.468226) (xy 139.64874 -149.429917) (xy 139.61649 -149.386631) (xy 139.590662 -149.339231)
			(xy 139.571774 -149.288664) (xy 139.5602 -149.23594) (xy 139.556174 -149.182111) (xy 139.557506 -149.15515)
			(xy 139.559712 -149.12878) (xy 139.570491 -149.076972) (xy 139.588336 -149.027154) (xy 139.612902 -148.980285)
			(xy 139.643718 -148.937266) (xy 139.68019 -148.898925) (xy 139.721616 -148.866) (xy 139.7672 -148.839124)
			(xy 139.79144 -148.828506) (xy 139.814554 -148.818854) (xy 140.00099 -148.632164) (xy 140.19784 -148.632164)
			(xy 140.213991 -148.631008) (xy 140.24495 -148.621549) (xy 140.272519 -148.604583) (xy 140.294913 -148.581209)
			(xy 140.310683 -148.552939) (xy 140.318808 -148.521604) (xy 140.319252 -148.505418) (xy 140.319252 -145.851626)
			(xy 140.318748 -145.828522) (xy 140.3104 -145.783073) (xy 140.293975 -145.739882) (xy 140.270014 -145.700371)
			(xy 140.239306 -145.665841) (xy 140.202862 -145.637431) (xy 140.161884 -145.616077) (xy 140.117721 -145.60248)
			(xy 140.071827 -145.59709) (xy 140.048742 -145.598134) (xy 140.02121 -145.600132) (xy 139.966091 -145.597126)
			(xy 139.911981 -145.586207) (xy 139.860009 -145.567603) (xy 139.811262 -145.541702) (xy 139.766757 -145.509046)
			(xy 139.727423 -145.470317) (xy 139.694082 -145.426322) (xy 139.66743 -145.377982) (xy 139.648023 -145.326305)
			(xy 139.636268 -145.27237) (xy 139.632408 -145.217305) (xy 139.636526 -145.162258) (xy 139.648534 -145.108379)
			(xy 139.668183 -145.056793) (xy 139.695061 -145.008578) (xy 139.728608 -144.964741) (xy 139.748006 -144.9451)
			(xy 139.762993 -144.929353) (xy 139.787897 -144.893724) (xy 139.806368 -144.854374) (xy 139.817866 -144.812453)
			(xy 139.822056 -144.769186) (xy 139.818815 -144.725838) (xy 139.808238 -144.683675) (xy 139.790634 -144.64393)
			(xy 139.778994 -144.625568) (xy 139.763248 -144.602446) (xy 139.737972 -144.552541) (xy 139.720258 -144.499479)
			(xy 139.710486 -144.444399) (xy 139.708864 -144.388482) (xy 139.715429 -144.332928) (xy 139.730038 -144.278929)
			(xy 139.752379 -144.227643) (xy 139.766802 -144.203674) (xy 139.781228 -144.18138) (xy 139.81528 -144.140635)
			(xy 139.854651 -144.105003) (xy 139.898581 -144.075173) (xy 139.946221 -144.051718) (xy 139.996653 -144.035094)
			(xy 140.048901 -144.02562) (xy 140.075412 -144.024096) (xy 140.096988 -144.022793) (xy 140.139257 -144.013772)
			(xy 140.179391 -143.997729) (xy 140.21623 -143.975125) (xy 140.248713 -143.946613) (xy 140.275903 -143.913015)
			(xy 140.297015 -143.8753) (xy 140.31144 -143.834557) (xy 140.318763 -143.791961) (xy 140.319252 -143.77035)
			(xy 140.319252 -143.045942) (xy 140.318762 -143.029286) (xy 140.310147 -142.997107) (xy 140.293494 -142.968257)
			(xy 140.269939 -142.944702) (xy 140.241087 -142.92805) (xy 140.208908 -142.919437) (xy 140.192252 -142.918942)
			(xy 140.167614 -142.918942) (xy 140.153136 -142.922244) (xy 140.124227 -142.928518) (xy 140.065252 -142.933098)
			(xy 140.006277 -142.928518) (xy 139.977368 -142.922244) (xy 139.96289 -142.918942) (xy 139.947396 -142.918942)
			(xy 139.940538 -142.91183) (xy 139.914034 -142.90213) (xy 139.863991 -142.876035) (xy 139.818338 -142.842854)
			(xy 139.77807 -142.80331) (xy 139.744066 -142.758266) (xy 139.717069 -142.708704) (xy 139.697666 -142.655707)
			(xy 139.686281 -142.600429) (xy 139.683163 -142.544078) (xy 139.688379 -142.487882) (xy 139.701816 -142.433067)
			(xy 139.723181 -142.380829) (xy 139.752007 -142.332308) (xy 139.787666 -142.288563) (xy 139.82938 -142.250547)
			(xy 139.876238 -142.219091) (xy 139.927219 -142.194879) (xy 139.98121 -142.178442) (xy 140.037033 -142.170136)
			(xy 140.065252 -142.169642) (xy 140.087438 -142.169191) (xy 140.131138 -142.161494) (xy 140.172838 -142.146325)
			(xy 140.21127 -142.124146) (xy 140.245266 -142.09563) (xy 140.273794 -142.061643) (xy 140.295987 -142.023219)
			(xy 140.311171 -141.981525) (xy 140.318883 -141.937828) (xy 140.319252 -141.915642) (xy 140.319252 -140.645642)
			(xy 140.318762 -140.629465) (xy 140.310603 -140.598156) (xy 140.294827 -140.569909) (xy 140.272449 -140.546542)
			(xy 140.244909 -140.52956) (xy 140.213982 -140.520058) (xy 140.19784 -140.518896) (xy 140.0937 -140.518896)
			(xy 139.916154 -140.341096) (xy 139.89304 -140.331444) (xy 139.867451 -140.320245) (xy 139.819585 -140.291458)
			(xy 139.776426 -140.256001) (xy 139.738899 -140.21463) (xy 139.707804 -140.168229) (xy 139.683807 -140.117791)
			(xy 139.667421 -140.064393) (xy 139.658994 -140.009177) (xy 139.658709 -139.953322) (xy 139.666569 -139.898022)
			(xy 139.682409 -139.844459) (xy 139.705889 -139.793778) (xy 139.736507 -139.747062) (xy 139.773609 -139.705309)
			(xy 139.794742 -139.687046) (xy 139.811714 -139.671713) (xy 139.840378 -139.636075) (xy 139.862203 -139.595884)
			(xy 139.876484 -139.552435) (xy 139.882759 -139.507133) (xy 139.880826 -139.461439) (xy 139.870748 -139.416828)
			(xy 139.852849 -139.374741) (xy 139.827708 -139.336536) (xy 139.796137 -139.303447) (xy 139.777978 -139.289536)
			(xy 139.755268 -139.273258) (xy 139.714416 -139.23514) (xy 139.679561 -139.191471) (xy 139.651447 -139.143186)
			(xy 139.630677 -139.091316) (xy 139.617693 -139.036972) (xy 139.612775 -138.981315) (xy 139.616026 -138.925536)
			(xy 139.627378 -138.870828) (xy 139.646588 -138.81836) (xy 139.673244 -138.769256) (xy 139.706778 -138.724564)
			(xy 139.746471 -138.68524) (xy 139.791475 -138.652127) (xy 139.840827 -138.625931) (xy 139.893472 -138.607213)
			(xy 139.948284 -138.596374) (xy 140.004091 -138.593645) (xy 140.0597 -138.599084) (xy 140.11392 -138.612576)
			(xy 140.139928 -138.622786) (xy 140.163296 -138.632184) (xy 140.19784 -138.632184) (xy 140.213992 -138.631028)
			(xy 140.244953 -138.621569) (xy 140.272524 -138.604604) (xy 140.294922 -138.58123) (xy 140.310696 -138.552961)
			(xy 140.318826 -138.521625) (xy 140.319252 -138.505438) (xy 140.319252 -137.142474) (xy 140.318762 -137.126586)
			(xy 140.310907 -137.095796) (xy 140.295691 -137.067899) (xy 140.274057 -137.044625) (xy 140.247344 -137.027415)
			(xy 140.217209 -137.017336) (xy 140.201396 -137.015728) (xy 140.191998 -137.015728) (xy 140.175256 -137.016236)
			(xy 140.142926 -137.024956) (xy 140.113984 -137.041795) (xy 140.101828 -137.05332) (xy 140.064744 -137.090658)
			(xy 138.957304 -137.090658) (xy 138.940536 -137.091168) (xy 138.90816 -137.099908) (xy 138.879182 -137.116785)
			(xy 138.855604 -137.140633) (xy 138.839057 -137.169801) (xy 138.834368 -137.185908) (xy 138.826871 -137.212875)
			(xy 138.805062 -137.264422) (xy 138.775954 -137.312229) (xy 138.740173 -137.35527) (xy 138.698487 -137.39262)
			(xy 138.651791 -137.423477) (xy 138.601087 -137.44718) (xy 138.547463 -137.46322) (xy 138.492071 -137.471251)
			(xy 138.4361 -137.471102) (xy 138.380752 -137.462776) (xy 138.327215 -137.446451) (xy 138.276637 -137.422479)
			(xy 138.230106 -137.391373) (xy 138.188619 -137.353801) (xy 138.153068 -137.310571) (xy 138.124216 -137.26261)
			(xy 138.113008 -137.236962) (xy 138.103356 -137.213848) (xy 138.041126 -137.151618) (xy 138.028955 -137.140265)
			(xy 138.000116 -137.123676) (xy 137.967972 -137.115091) (xy 137.934702 -137.115091) (xy 137.902558 -137.123676)
			(xy 137.873719 -137.140265) (xy 137.861548 -137.151618) (xy 137.841736 -137.17143) (xy 137.832084 -137.197592)
			(xy 137.822313 -137.222592) (xy 137.796757 -137.269793) (xy 137.764837 -137.312946) (xy 137.727183 -137.351197)
			(xy 137.684538 -137.383792) (xy 137.637744 -137.410087) (xy 137.587727 -137.429562) (xy 137.535473 -137.441833)
			(xy 137.482015 -137.446658) (xy 137.428408 -137.44394) (xy 137.375712 -137.433735) (xy 137.324967 -137.416242)
			(xy 137.277176 -137.391809) (xy 137.233281 -137.360917) (xy 137.194151 -137.324177) (xy 137.160558 -137.282313)
			(xy 137.133165 -137.236154) (xy 137.122408 -137.211562) (xy 137.112756 -137.188448) (xy 137.014966 -137.090658)
			(xy 136.308338 -137.090658) (xy 136.159748 -137.239248) (xy 136.150096 -137.262362) (xy 136.139289 -137.28707)
			(xy 136.11173 -137.333426) (xy 136.077916 -137.375436) (xy 136.038521 -137.412264) (xy 135.99433 -137.443175)
			(xy 135.946226 -137.467553) (xy 135.895167 -137.48491) (xy 135.842172 -137.494901) (xy 135.788298 -137.497327)
			(xy 135.73462 -137.49214) (xy 135.682207 -137.479442) (xy 135.632106 -137.459487) (xy 135.585316 -137.432673)
			(xy 135.542771 -137.399535) (xy 135.505317 -137.360733) (xy 135.473704 -137.317042) (xy 135.44856 -137.269334)
			(xy 135.430389 -137.218559) (xy 135.424418 -137.192258) (xy 135.420406 -137.175285) (xy 135.404462 -137.144279)
			(xy 135.380722 -137.118745) (xy 135.350958 -137.100589) (xy 135.317391 -137.091165) (xy 135.299958 -137.090658)
			(xy 135.258302 -137.090658) (xy 135.242874 -137.091081) (xy 135.212921 -137.098483) (xy 135.18563 -137.112877)
			(xy 135.162605 -137.133417) (xy 135.145202 -137.158895) (xy 135.13943 -137.173208) (xy 135.129276 -137.198933)
			(xy 135.102612 -137.247386) (xy 135.069231 -137.29148) (xy 135.029831 -137.330291) (xy 134.98524 -137.363005)
			(xy 134.936392 -137.388936) (xy 134.88431 -137.407541) (xy 134.830088 -137.418429) (xy 134.774862 -137.421372)
			(xy 134.71979 -137.416309) (xy 134.666026 -137.403346) (xy 134.614698 -137.382754) (xy 134.590536 -137.369296)
			(xy 134.575203 -137.361015) (xy 134.541472 -137.352319) (xy 134.506646 -137.353075) (xy 134.473323 -137.363227)
			(xy 134.443991 -137.382016) (xy 134.43204 -137.394696) (xy 134.413828 -137.414468) (xy 134.372806 -137.449205)
			(xy 134.327313 -137.477838) (xy 134.278249 -137.499797) (xy 134.226587 -137.514648) (xy 134.173351 -137.522096)
			(xy 134.119597 -137.521994) (xy 134.06639 -137.514343) (xy 134.014785 -137.499295) (xy 133.965805 -137.477149)
			(xy 133.920421 -137.448343) (xy 133.899656 -137.431272) (xy 133.886781 -137.421013) (xy 133.857086 -137.406831)
			(xy 133.824752 -137.400714) (xy 133.791929 -137.40307) (xy 133.760799 -137.413743) (xy 133.733435 -137.432021)
			(xy 133.72211 -137.443972) (xy 133.703506 -137.464356) (xy 133.661444 -137.500081) (xy 133.614671 -137.529371)
			(xy 133.564166 -137.551613) (xy 133.510982 -137.566344) (xy 133.45623 -137.573256) (xy 133.401054 -137.572204)
			(xy 133.346605 -137.563211) (xy 133.294021 -137.546465) (xy 133.2444 -137.522314) (xy 133.198777 -137.491264)
			(xy 133.158106 -137.453962) (xy 133.123236 -137.411188) (xy 133.094895 -137.363835) (xy 133.083808 -137.338562)
			(xy 133.074156 -137.315448) (xy 132.994908 -137.2362) (xy 132.994908 -137.217658) (xy 132.99436 -137.201013)
			(xy 132.985735 -137.168859) (xy 132.969084 -137.140032) (xy 132.945541 -137.116495) (xy 132.916709 -137.099852)
			(xy 132.884553 -137.091236) (xy 132.867908 -137.090658) (xy 132.441188 -137.090658) (xy 132.418161 -137.091167)
			(xy 132.372863 -137.099481) (xy 132.329803 -137.115816) (xy 132.290389 -137.139639) (xy 132.25591 -137.17017)
			(xy 132.227492 -137.206412) (xy 132.206066 -137.247178) (xy 132.192331 -137.291137) (xy 132.188966 -137.313924)
			(xy 132.185397 -137.339892) (xy 132.172045 -137.390579) (xy 132.151864 -137.438955) (xy 132.138928 -137.461752)
			(xy 132.131541 -137.475167) (xy 132.122725 -137.504486) (xy 132.121168 -137.535063) (xy 132.126959 -137.565126)
			(xy 132.139764 -137.592935) (xy 132.15884 -137.616881) (xy 132.170678 -137.626598) (xy 132.192022 -137.64371)
			(xy 132.230059 -137.683027) (xy 132.262091 -137.727373) (xy 132.287459 -137.77584) (xy 132.305645 -137.827434)
			(xy 132.316274 -137.881096) (xy 132.31913 -137.935727) (xy 132.314153 -137.990205) (xy 132.301445 -138.043413)
			(xy 132.281268 -138.094261) (xy 132.254034 -138.141705) (xy 132.220303 -138.184773) (xy 132.180766 -138.222581)
			(xy 132.136234 -138.254354) (xy 132.08762 -138.27944) (xy 132.035921 -138.297325) (xy 131.982198 -138.307642)
			(xy 131.927552 -138.31018) (xy 131.873104 -138.304886) (xy 131.81997 -138.291869) (xy 131.76924 -138.271396)
			(xy 131.721955 -138.243887) (xy 131.679085 -138.209906) (xy 131.641507 -138.17015) (xy 131.609994 -138.125433)
			(xy 131.585191 -138.076674) (xy 131.567607 -138.024873) (xy 131.557602 -137.97109) (xy 131.555383 -137.91643)
			(xy 131.560993 -137.862014) (xy 131.574319 -137.808957) (xy 131.595087 -137.758347) (xy 131.608576 -137.734548)
			(xy 131.615963 -137.721132) (xy 131.624778 -137.691813) (xy 131.626336 -137.661237) (xy 131.620544 -137.631174)
			(xy 131.60774 -137.603365) (xy 131.588664 -137.579418) (xy 131.576826 -137.569702) (xy 131.553278 -137.550759)
			(xy 131.511906 -137.506709) (xy 131.477998 -137.456687) (xy 131.452401 -137.401944) (xy 131.435756 -137.34385)
			(xy 131.431538 -137.313924) (xy 131.428258 -137.29112) (xy 131.414538 -137.247143) (xy 131.393113 -137.206361)
			(xy 131.364686 -137.17011) (xy 131.330189 -137.139579) (xy 131.290752 -137.115769) (xy 131.247668 -137.09946)
			(xy 131.20235 -137.091186) (xy 131.179316 -137.090658) (xy 130.89636 -137.090658) (xy 130.879713 -137.091206)
			(xy 130.847555 -137.09983) (xy 130.818723 -137.11648) (xy 130.795181 -137.140022) (xy 130.77853 -137.168853)
			(xy 130.769906 -137.201011) (xy 130.76936 -137.217658) (xy 130.76936 -137.37717) (xy 130.77825 -137.399776)
			(xy 130.788431 -137.426821) (xy 130.80144 -137.483123) (xy 130.805805 -137.540743) (xy 130.801427 -137.598362)
			(xy 130.788406 -137.654661) (xy 130.77825 -137.681716) (xy 130.76936 -137.704322) (xy 130.76936 -137.828782)
			(xy 130.57632 -138.021822) (xy 128.888744 -138.021822) (xy 128.872361 -138.022289) (xy 128.840659 -138.030564)
			(xy 128.812118 -138.046655) (xy 128.788628 -138.069496) (xy 128.779778 -138.08329) (xy 128.779778 -138.083798)
			(xy 128.765274 -138.107087) (xy 128.730632 -138.149631) (xy 128.690254 -138.186775) (xy 128.644973 -138.217755)
			(xy 128.595723 -138.24193) (xy 128.543518 -138.258804) (xy 128.489435 -138.268028) (xy 128.462024 -138.269218)
			(xy 128.437927 -138.270355) (xy 128.390787 -138.280575) (xy 128.346424 -138.299511) (xy 128.306435 -138.326482)
			(xy 128.272256 -138.360518) (xy 128.245119 -138.400395) (xy 128.225998 -138.444679) (xy 128.220216 -138.4681)
			(xy 128.21311 -138.497497) (xy 128.190871 -138.553737) (xy 128.160035 -138.605761) (xy 128.121374 -138.652267)
			(xy 128.075857 -138.692087) (xy 128.050544 -138.708638) (xy 128.038352 -138.716258) (xy 127.847852 -138.907012)
			(xy 127.847852 -139.134088) (xy 127.893004 -139.1793) (xy 138.152884 -139.1793) (xy 138.156955 -139.123678)
			(xy 138.169081 -139.069241) (xy 138.189004 -139.01715) (xy 138.2163 -138.968515) (xy 138.250386 -138.924372)
			(xy 138.290535 -138.885663) (xy 138.335893 -138.853212) (xy 138.385493 -138.827711) (xy 138.438277 -138.809704)
			(xy 138.49312 -138.799574) (xy 138.548854 -138.797537) (xy 138.604291 -138.803637) (xy 138.658248 -138.817743)
			(xy 138.709577 -138.839555) (xy 138.757183 -138.868609) (xy 138.800051 -138.904284) (xy 138.837268 -138.945821)
			(xy 138.868041 -138.992334) (xy 138.891713 -139.042831) (xy 138.907781 -139.096238) (xy 138.915901 -139.151414)
			(xy 138.91641 -139.1793) (xy 138.915901 -139.207186) (xy 138.907781 -139.262362) (xy 138.891713 -139.315769)
			(xy 138.868041 -139.366266) (xy 138.837268 -139.412779) (xy 138.800051 -139.454316) (xy 138.757183 -139.489991)
			(xy 138.709577 -139.519045) (xy 138.658248 -139.540857) (xy 138.604291 -139.554963) (xy 138.548854 -139.561063)
			(xy 138.49312 -139.559026) (xy 138.438277 -139.548896) (xy 138.385493 -139.530889) (xy 138.335893 -139.505388)
			(xy 138.290535 -139.472937) (xy 138.250386 -139.434228) (xy 138.2163 -139.390085) (xy 138.189004 -139.34145)
			(xy 138.169081 -139.289359) (xy 138.156955 -139.234922) (xy 138.152884 -139.1793) (xy 127.893004 -139.1793)
			(xy 128.038352 -139.324842) (xy 128.050544 -139.332462) (xy 128.0738 -139.347642) (xy 128.116067 -139.383666)
			(xy 128.152662 -139.42544) (xy 128.18281 -139.47208) (xy 128.205873 -139.5226) (xy 128.221365 -139.575931)
			(xy 128.228957 -139.630945) (xy 128.228489 -139.686479) (xy 128.21997 -139.741357) (xy 128.203581 -139.794419)
			(xy 128.179668 -139.844543) (xy 128.148738 -139.890668) (xy 128.111444 -139.931818) (xy 128.068576 -139.967124)
			(xy 128.02104 -139.995838) (xy 127.969841 -140.017353) (xy 127.943102 -140.024866) (xy 127.926971 -140.029563)
			(xy 127.897771 -140.046156) (xy 127.873908 -140.06979) (xy 127.857033 -140.098828) (xy 127.848315 -140.131263)
			(xy 127.847852 -140.148056) (xy 127.847852 -140.49375) (xy 127.40005 -140.941552) (xy 127.389531 -140.952768)
			(xy 127.373665 -140.979095) (xy 127.364535 -141.008447) (xy 127.362669 -141.03913) (xy 127.364998 -141.054328)
			(xy 127.368808 -141.075156) (xy 127.371602 -141.0843) (xy 127.37211 -141.08557) (xy 127.380608 -141.113142)
			(xy 127.390156 -141.170041) (xy 127.391036 -141.227729) (xy 127.383228 -141.284892) (xy 127.366909 -141.34023)
			(xy 127.342451 -141.392484) (xy 127.326898 -141.416786) (xy 127.310953 -141.439777) (xy 127.293613 -141.45895)
			(xy 130.132834 -141.45895) (xy 130.136905 -141.403328) (xy 130.149031 -141.348891) (xy 130.168954 -141.2968)
			(xy 130.19625 -141.248165) (xy 130.230336 -141.204022) (xy 130.270485 -141.165313) (xy 130.315843 -141.132862)
			(xy 130.365443 -141.107361) (xy 130.418227 -141.089354) (xy 130.47307 -141.079224) (xy 130.528804 -141.077187)
			(xy 130.584241 -141.083287) (xy 130.638198 -141.097393) (xy 130.689527 -141.119205) (xy 130.737133 -141.148259)
			(xy 130.780001 -141.183934) (xy 130.817218 -141.225471) (xy 130.847991 -141.271984) (xy 130.871663 -141.322481)
			(xy 130.887731 -141.375888) (xy 130.895851 -141.431064) (xy 130.89636 -141.45895) (xy 130.895851 -141.486836)
			(xy 130.887731 -141.542012) (xy 130.871663 -141.595419) (xy 130.847991 -141.645916) (xy 130.817218 -141.692429)
			(xy 130.780001 -141.733966) (xy 130.737133 -141.769641) (xy 130.689527 -141.798695) (xy 130.638198 -141.820507)
			(xy 130.584241 -141.834613) (xy 130.528804 -141.840713) (xy 130.47307 -141.838676) (xy 130.418227 -141.828546)
			(xy 130.365443 -141.810539) (xy 130.315843 -141.785038) (xy 130.270485 -141.752587) (xy 130.230336 -141.713878)
			(xy 130.19625 -141.669735) (xy 130.168954 -141.6211) (xy 130.149031 -141.569009) (xy 130.136905 -141.514572)
			(xy 130.132834 -141.45895) (xy 127.293613 -141.45895) (xy 127.273424 -141.481273) (xy 127.230246 -141.516854)
			(xy 127.182342 -141.54576) (xy 127.156718 -141.556994) (xy 127.13335 -141.566646) (xy 127.08636 -141.61389)
			(xy 126.981204 -141.719046) (xy 126.96952 -141.719046) (xy 126.895352 -141.793214) (xy 126.895352 -142.499842)
			(xy 126.8959 -142.516489) (xy 126.904524 -142.548647) (xy 126.921174 -142.577479) (xy 126.944716 -142.601022)
			(xy 126.973547 -142.617674) (xy 127.005705 -142.626299) (xy 127.022352 -142.626842) (xy 127.027178 -142.626842)
			(xy 127.04317 -142.62669) (xy 127.075089 -142.628721) (xy 127.090932 -142.630906) (xy 127.10033 -142.632176)
			(xy 127.144526 -142.632176) (xy 127.15875 -142.646654) (xy 127.182372 -142.65656) (xy 127.205629 -142.666755)
			(xy 127.24945 -142.692412) (xy 127.289482 -142.723654) (xy 127.325018 -142.759928) (xy 127.35543 -142.800593)
			(xy 127.380181 -142.844932) (xy 127.38989 -142.868396) (xy 127.400067 -142.895613) (xy 127.41299 -142.952262)
			(xy 127.417167 -143.010216) (xy 127.4125 -143.068133) (xy 127.399098 -143.124671) (xy 127.377271 -143.17852)
			(xy 127.347525 -143.228433) (xy 127.329438 -143.251174) (xy 127.314928 -143.269571) (xy 127.292208 -143.310543)
			(xy 127.277388 -143.354987) (xy 127.270968 -143.401394) (xy 127.273168 -143.448192) (xy 127.283912 -143.493793)
			(xy 127.302836 -143.53665) (xy 127.329299 -143.575311) (xy 127.34544 -143.592296) (xy 127.365797 -143.611889)
			(xy 127.401084 -143.656013) (xy 127.429477 -143.704859) (xy 127.450356 -143.757359) (xy 127.463264 -143.812364)
			(xy 127.467918 -143.86867) (xy 127.464216 -143.925048) (xy 127.452241 -143.980263) (xy 127.432252 -144.033108)
			(xy 127.404689 -144.082427) (xy 127.387858 -144.105122) (xy 127.375131 -144.123748) (xy 127.355773 -144.16449)
			(xy 127.343913 -144.20801) (xy 127.339922 -144.252941) (xy 127.343927 -144.29787) (xy 127.355802 -144.341386)
			(xy 127.375173 -144.382122) (xy 127.387858 -144.400778) (xy 127.404167 -144.422662) (xy 127.431027 -144.470171)
			(xy 127.450845 -144.521023) (xy 127.463216 -144.574179) (xy 127.467889 -144.628556) (xy 127.464767 -144.683043)
			(xy 127.453915 -144.73653) (xy 127.435554 -144.787926) (xy 127.410059 -144.836182) (xy 127.377949 -144.880313)
			(xy 127.33988 -144.91942) (xy 127.296628 -144.952705) (xy 127.249075 -144.979489) (xy 127.198192 -144.999225)
			(xy 127.145016 -145.011512) (xy 127.117856 -145.014188) (xy 127.095119 -145.017531) (xy 127.05129 -145.031339)
			(xy 127.010656 -145.0528) (xy 126.974542 -145.081214) (xy 126.944123 -145.115657) (xy 126.943584 -145.11655)
			(xy 129.243834 -145.11655) (xy 129.247905 -145.060928) (xy 129.260031 -145.006491) (xy 129.279954 -144.9544)
			(xy 129.30725 -144.905765) (xy 129.341336 -144.861622) (xy 129.381485 -144.822913) (xy 129.426843 -144.790462)
			(xy 129.476443 -144.764961) (xy 129.529227 -144.746954) (xy 129.58407 -144.736824) (xy 129.639804 -144.734787)
			(xy 129.695241 -144.740887) (xy 129.749198 -144.754993) (xy 129.800527 -144.776805) (xy 129.848133 -144.805859)
			(xy 129.891001 -144.841534) (xy 129.928218 -144.883071) (xy 129.958991 -144.929584) (xy 129.982663 -144.980081)
			(xy 129.998731 -145.033488) (xy 130.006851 -145.088664) (xy 130.00736 -145.11655) (xy 130.006851 -145.144436)
			(xy 129.998731 -145.199612) (xy 129.982663 -145.253019) (xy 129.958991 -145.303516) (xy 129.928218 -145.350029)
			(xy 129.891001 -145.391566) (xy 129.848133 -145.427241) (xy 129.800527 -145.456295) (xy 129.749198 -145.478107)
			(xy 129.695241 -145.492213) (xy 129.639804 -145.498313) (xy 129.58407 -145.496276) (xy 129.529227 -145.486146)
			(xy 129.476443 -145.468139) (xy 129.426843 -145.442638) (xy 129.381485 -145.410187) (xy 129.341336 -145.371478)
			(xy 129.30725 -145.327335) (xy 129.279954 -145.2787) (xy 129.260031 -145.226609) (xy 129.247905 -145.172172)
			(xy 129.243834 -145.11655) (xy 126.943584 -145.11655) (xy 126.920389 -145.155006) (xy 126.904115 -145.19798)
			(xy 126.89583 -145.24318) (xy 126.895352 -145.266156) (xy 126.895352 -145.396712) (xy 126.895881 -145.420413)
			(xy 126.904669 -145.466994) (xy 126.92194 -145.511139) (xy 126.947094 -145.551318) (xy 126.979259 -145.586137)
			(xy 127.017321 -145.614392) (xy 127.059961 -145.635101) (xy 127.105701 -145.647548) (xy 127.129286 -145.64995)
			(xy 127.156915 -145.65175) (xy 127.21126 -145.66233) (xy 127.263504 -145.680658) (xy 127.312549 -145.706347)
			(xy 127.357363 -145.738858) (xy 127.397006 -145.777508) (xy 127.430644 -145.821483) (xy 127.457569 -145.869861)
			(xy 127.477216 -145.921623) (xy 127.489171 -145.975682) (xy 127.493184 -146.030902) (xy 127.489171 -146.086122)
			(xy 127.477214 -146.140181) (xy 127.457567 -146.191943) (xy 127.430641 -146.24032) (xy 127.397003 -146.284296)
			(xy 127.35736 -146.322945) (xy 127.312545 -146.355455) (xy 127.263499 -146.381144) (xy 127.211255 -146.399471)
			(xy 127.15691 -146.410051) (xy 127.129286 -146.41195) (xy 127.105698 -146.414345) (xy 127.059952 -146.426781)
			(xy 127.017305 -146.447485) (xy 126.979238 -146.475738) (xy 126.94707 -146.510561) (xy 126.921919 -146.550746)
			(xy 126.904656 -146.594897) (xy 126.895881 -146.641485) (xy 126.895352 -146.665188) (xy 126.895352 -148.217636)
			(xy 127.09017 -148.412454) (xy 127.113284 -148.422106) (xy 127.137983 -148.432917) (xy 127.18432 -148.460478)
			(xy 127.226318 -148.494286) (xy 127.263139 -148.533668) (xy 127.294051 -148.577841) (xy 127.318439 -148.625924)
			(xy 127.335816 -148.676961) (xy 127.345838 -148.729936) (xy 127.348304 -148.783794) (xy 127.343166 -148.837464)
			(xy 127.330525 -148.889875) (xy 127.321056 -148.91512) (xy 127.313266 -148.93598) (xy 127.304289 -148.97959)
			(xy 127.30305 -149.024098) (xy 127.309586 -149.06814) (xy 127.323698 -149.11037) (xy 127.344953 -149.149493)
			(xy 127.372702 -149.184314) (xy 127.389128 -149.199346) (xy 127.409998 -149.218463) (xy 127.446422 -149.261779)
			(xy 127.476053 -149.309998) (xy 127.49824 -149.362063) (xy 127.512498 -149.416833) (xy 127.518514 -149.473107)
			(xy 127.516157 -149.529654) (xy 127.505478 -149.585232) (xy 127.49657 -149.612096) (xy 127.494792 -149.617176)
			(xy 127.48969 -149.633033) (xy 127.487062 -149.66623) (xy 127.493126 -149.698974) (xy 127.499872 -149.714204)
			(xy 127.51943 -149.754844) (xy 127.51943 -150.14575) (xy 127.519919 -150.162408) (xy 127.528532 -150.19459)
			(xy 127.545184 -150.223445) (xy 127.568739 -150.247004) (xy 127.597592 -150.26366) (xy 127.629772 -150.272279)
			(xy 127.64643 -150.27275)
		)
		(stroke
			(width 0)
			(type solid)
		)
		(fill yes)
		(layer "F.Cu")
		(net "P1V0_NODE1")
	)
	(gr_poly
		(pts
			(xy 81.57972 -141.584172) (xy 81.57972 -140.23975) (xy 81.606898 -140.212572) (xy 82.161888 -140.212572)
			(xy 82.165952 -140.208762) (xy 83.054952 -140.208762) (xy 83.283552 -140.208762) (xy 83.512152 -140.208762)
			(xy 83.516724 -140.20419) (xy 83.521296 -140.208762) (xy 83.791552 -140.208762) (xy 84.052918 -140.208762)
			(xy 84.052918 -138.869928) (xy 83.76793 -138.58494) (xy 83.76793 -137.08126) (xy 83.669632 -136.982962)
			(xy 83.232752 -136.982962) (xy 82.927952 -136.678162) (xy 82.927952 -136.144762) (xy 82.826352 -136.043162)
			(xy 82.343752 -136.043162) (xy 81.86674 -135.56615) (xy 81.86674 -135.559292) (xy 81.184496 -134.877048)
			(xy 80.628744 -134.877048) (xy 80.205072 -134.453376) (xy 80.205072 -133.531864) (xy 80.2386 -133.498336)
			(xy 80.2386 -131.02463) (xy 77.77226 -128.55829) (xy 77.49032 -128.55829) (xy 77.444346 -128.604264)
			(xy 77.444346 -128.595882) (xy 75.414632 -128.595882) (xy 74.995532 -129.014982) (xy 74.38263 -129.014982)
			(xy 74.369302 -129.034755) (xy 74.337167 -129.069982) (xy 74.299646 -129.099406) (xy 74.257774 -129.122214)
			(xy 74.212703 -129.137778) (xy 74.165679 -129.145669) (xy 74.117997 -129.145669) (xy 74.070973 -129.137778)
			(xy 74.025902 -129.122214) (xy 73.98403 -129.099406) (xy 73.946509 -129.069982) (xy 73.914374 -129.034755)
			(xy 73.901046 -129.014982) (xy 73.58253 -129.014982) (xy 73.569202 -129.034755) (xy 73.537067 -129.069982)
			(xy 73.499546 -129.099406) (xy 73.457674 -129.122214) (xy 73.412603 -129.137778) (xy 73.365579 -129.145669)
			(xy 73.317897 -129.145669) (xy 73.270873 -129.137778) (xy 73.225802 -129.122214) (xy 73.18393 -129.099406)
			(xy 73.146409 -129.069982) (xy 73.114274 -129.034755) (xy 73.100946 -129.014982) (xy 72.841612 -129.014982)
			(xy 72.625204 -129.23139) (xy 72.615474 -129.241747) (xy 72.601636 -129.266553) (xy 72.595138 -129.294204)
			(xy 72.596479 -129.322578) (xy 72.605555 -129.349494) (xy 72.621671 -129.372884) (xy 72.643588 -129.390954)
			(xy 72.656446 -129.396998) (xy 72.678462 -129.407155) (xy 72.719003 -129.433741) (xy 72.754491 -129.466772)
			(xy 72.783914 -129.505304) (xy 72.806431 -129.548239) (xy 72.8214 -129.594352) (xy 72.828395 -129.642326)
			(xy 72.827974 -129.659634) (xy 73.054735 -129.659634) (xy 73.058649 -129.612395) (xy 73.070286 -129.566444)
			(xy 73.089326 -129.523036) (xy 73.115252 -129.483353) (xy 73.147356 -129.448479) (xy 73.184762 -129.419365)
			(xy 73.22645 -129.396804) (xy 73.271283 -129.381413) (xy 73.318037 -129.373611) (xy 73.341738 -129.373122)
			(xy 73.365439 -129.373611) (xy 73.412193 -129.381413) (xy 73.457026 -129.396804) (xy 73.498714 -129.419365)
			(xy 73.53612 -129.448479) (xy 73.568224 -129.483353) (xy 73.59415 -129.523036) (xy 73.61319 -129.566444)
			(xy 73.624827 -129.612395) (xy 73.628741 -129.659634) (xy 73.854835 -129.659634) (xy 73.858749 -129.612395)
			(xy 73.870386 -129.566444) (xy 73.889426 -129.523036) (xy 73.915352 -129.483353) (xy 73.947456 -129.448479)
			(xy 73.984862 -129.419365) (xy 74.02655 -129.396804) (xy 74.071383 -129.381413) (xy 74.118137 -129.373611)
			(xy 74.141838 -129.373122) (xy 74.165539 -129.373611) (xy 74.212293 -129.381413) (xy 74.257126 -129.396804)
			(xy 74.298814 -129.419365) (xy 74.33622 -129.448479) (xy 74.368324 -129.483353) (xy 74.39425 -129.523036)
			(xy 74.41329 -129.566444) (xy 74.424927 -129.612395) (xy 74.428841 -129.659634) (xy 74.424927 -129.706873)
			(xy 74.41329 -129.752824) (xy 74.39425 -129.796232) (xy 74.368324 -129.835915) (xy 74.33622 -129.870789)
			(xy 74.298814 -129.899903) (xy 74.257126 -129.922464) (xy 74.212293 -129.937855) (xy 74.165539 -129.945657)
			(xy 74.118137 -129.945657) (xy 74.071383 -129.937855) (xy 74.02655 -129.922464) (xy 73.984862 -129.899903)
			(xy 73.947456 -129.870789) (xy 73.915352 -129.835915) (xy 73.889426 -129.796232) (xy 73.870386 -129.752824)
			(xy 73.858749 -129.706873) (xy 73.854835 -129.659634) (xy 73.628741 -129.659634) (xy 73.624827 -129.706873)
			(xy 73.61319 -129.752824) (xy 73.59415 -129.796232) (xy 73.568224 -129.835915) (xy 73.53612 -129.870789)
			(xy 73.498714 -129.899903) (xy 73.457026 -129.922464) (xy 73.412193 -129.937855) (xy 73.365439 -129.945657)
			(xy 73.318037 -129.945657) (xy 73.271283 -129.937855) (xy 73.22645 -129.922464) (xy 73.184762 -129.899903)
			(xy 73.147356 -129.870789) (xy 73.115252 -129.835915) (xy 73.089326 -129.796232) (xy 73.070286 -129.752824)
			(xy 73.058649 -129.706873) (xy 73.054735 -129.659634) (xy 72.827974 -129.659634) (xy 72.827215 -129.690792)
			(xy 72.817895 -129.738369) (xy 72.8007 -129.783699) (xy 72.77612 -129.825487) (xy 72.744858 -129.862543)
			(xy 72.707805 -129.893808) (xy 72.666018 -129.91839) (xy 72.62069 -129.935589) (xy 72.573114 -129.944913)
			(xy 72.524647 -129.946096) (xy 72.476673 -129.939105) (xy 72.430559 -129.924139) (xy 72.387623 -129.901625)
			(xy 72.349088 -129.872206) (xy 72.316055 -129.83672) (xy 72.289465 -129.796181) (xy 72.279256 -129.774188)
			(xy 72.273173 -129.761345) (xy 72.255134 -129.739401) (xy 72.231756 -129.723264) (xy 72.204842 -129.714179)
			(xy 72.176467 -129.712846) (xy 72.14882 -129.719367) (xy 72.124032 -129.733241) (xy 72.113648 -129.742946)
			(xy 71.825104 -130.03149) (xy 71.815402 -130.041832) (xy 71.80161 -130.066596) (xy 71.795144 -130.094194)
			(xy 71.796502 -130.122508) (xy 71.805578 -130.149361) (xy 71.821676 -130.172692) (xy 71.84356 -130.190708)
			(xy 71.856346 -130.196844) (xy 71.87829 -130.206955) (xy 71.918711 -130.233417) (xy 71.954119 -130.266285)
			(xy 71.983511 -130.304627) (xy 72.006054 -130.347358) (xy 72.021107 -130.393265) (xy 72.028245 -130.441047)
			(xy 72.027871 -130.45948) (xy 72.254889 -130.45948) (xy 72.258803 -130.412241) (xy 72.27044 -130.36629)
			(xy 72.28948 -130.322882) (xy 72.315406 -130.283199) (xy 72.34751 -130.248325) (xy 72.384916 -130.219211)
			(xy 72.426604 -130.19665) (xy 72.471437 -130.181259) (xy 72.518191 -130.173457) (xy 72.541892 -130.172968)
			(xy 72.565593 -130.173457) (xy 72.612347 -130.181259) (xy 72.65718 -130.19665) (xy 72.698868 -130.219211)
			(xy 72.736274 -130.248325) (xy 72.768378 -130.283199) (xy 72.794304 -130.322882) (xy 72.813344 -130.36629)
			(xy 72.824981 -130.412241) (xy 72.828895 -130.45948) (xy 73.054735 -130.45948) (xy 73.058649 -130.412241)
			(xy 73.070286 -130.36629) (xy 73.089326 -130.322882) (xy 73.115252 -130.283199) (xy 73.147356 -130.248325)
			(xy 73.184762 -130.219211) (xy 73.22645 -130.19665) (xy 73.271283 -130.181259) (xy 73.318037 -130.173457)
			(xy 73.341738 -130.172968) (xy 73.365439 -130.173457) (xy 73.412193 -130.181259) (xy 73.457026 -130.19665)
			(xy 73.498714 -130.219211) (xy 73.53612 -130.248325) (xy 73.568224 -130.283199) (xy 73.59415 -130.322882)
			(xy 73.61319 -130.36629) (xy 73.624827 -130.412241) (xy 73.628741 -130.45948) (xy 73.854835 -130.45948)
			(xy 73.858749 -130.412241) (xy 73.870386 -130.36629) (xy 73.889426 -130.322882) (xy 73.915352 -130.283199)
			(xy 73.947456 -130.248325) (xy 73.984862 -130.219211) (xy 74.02655 -130.19665) (xy 74.071383 -130.181259)
			(xy 74.118137 -130.173457) (xy 74.141838 -130.172968) (xy 74.165539 -130.173457) (xy 74.212293 -130.181259)
			(xy 74.257126 -130.19665) (xy 74.298814 -130.219211) (xy 74.33622 -130.248325) (xy 74.368324 -130.283199)
			(xy 74.39425 -130.322882) (xy 74.41329 -130.36629) (xy 74.424927 -130.412241) (xy 74.428841 -130.45948)
			(xy 74.424927 -130.506719) (xy 74.41329 -130.55267) (xy 74.39425 -130.596078) (xy 74.368324 -130.635761)
			(xy 74.347042 -130.658879) (xy 75.033885 -130.658879) (xy 75.039988 -130.603405) (xy 75.054104 -130.549412)
			(xy 75.075931 -130.498049) (xy 75.105004 -130.450411) (xy 75.140703 -130.407515) (xy 75.182267 -130.370273)
			(xy 75.228811 -130.339479) (xy 75.279342 -130.315791) (xy 75.332784 -130.299713) (xy 75.387998 -130.291587)
			(xy 75.415902 -130.291078) (xy 75.443806 -130.291587) (xy 75.49902 -130.299713) (xy 75.552462 -130.315791)
			(xy 75.602993 -130.339479) (xy 75.649537 -130.370273) (xy 75.691101 -130.407515) (xy 75.7268 -130.450411)
			(xy 75.755873 -130.498049) (xy 75.775018 -130.543101) (xy 76.171552 -130.543101) (xy 76.171552 -130.486095)
			(xy 76.179665 -130.429669) (xy 76.195726 -130.374972) (xy 76.219407 -130.323117) (xy 76.250227 -130.275161)
			(xy 76.287558 -130.232078) (xy 76.330641 -130.194747) (xy 76.378597 -130.163927) (xy 76.430452 -130.140246)
			(xy 76.485149 -130.124185) (xy 76.541575 -130.116072) (xy 76.598581 -130.116072) (xy 76.655007 -130.124185)
			(xy 76.709704 -130.140246) (xy 76.761559 -130.163927) (xy 76.809515 -130.194747) (xy 76.852598 -130.232078)
			(xy 76.889929 -130.275161) (xy 76.920749 -130.323117) (xy 76.94443 -130.374972) (xy 76.960491 -130.429669)
			(xy 76.968604 -130.486095) (xy 76.968604 -130.543101) (xy 76.960491 -130.599527) (xy 76.94443 -130.654224)
			(xy 76.920749 -130.706079) (xy 76.889929 -130.754035) (xy 76.852598 -130.797118) (xy 76.809515 -130.834449)
			(xy 76.761559 -130.865269) (xy 76.709704 -130.88895) (xy 76.655007 -130.905011) (xy 76.598581 -130.913124)
			(xy 76.570078 -130.913632) (xy 76.541575 -130.913124) (xy 76.485149 -130.905011) (xy 76.430452 -130.88895)
			(xy 76.378597 -130.865269) (xy 76.330641 -130.834449) (xy 76.287558 -130.797118) (xy 76.250227 -130.754035)
			(xy 76.219407 -130.706079) (xy 76.195726 -130.654224) (xy 76.179665 -130.599527) (xy 76.171552 -130.543101)
			(xy 75.775018 -130.543101) (xy 75.7777 -130.549412) (xy 75.791816 -130.603405) (xy 75.797919 -130.658879)
			(xy 75.795881 -130.71465) (xy 75.785744 -130.769529) (xy 75.767725 -130.822349) (xy 75.742207 -130.871981)
			(xy 75.709735 -130.917369) (xy 75.671 -130.957546) (xy 75.626828 -130.991654) (xy 75.57816 -131.018968)
			(xy 75.526034 -131.038904) (xy 75.471561 -131.051039) (xy 75.415902 -131.055113) (xy 75.360243 -131.051039)
			(xy 75.30577 -131.038904) (xy 75.253644 -131.018968) (xy 75.204976 -130.991654) (xy 75.160804 -130.957546)
			(xy 75.122069 -130.917369) (xy 75.089597 -130.871981) (xy 75.064079 -130.822349) (xy 75.04606 -130.769529)
			(xy 75.035923 -130.71465) (xy 75.033885 -130.658879) (xy 74.347042 -130.658879) (xy 74.33622 -130.670635)
			(xy 74.298814 -130.699749) (xy 74.257126 -130.72231) (xy 74.212293 -130.737701) (xy 74.165539 -130.745503)
			(xy 74.118137 -130.745503) (xy 74.071383 -130.737701) (xy 74.02655 -130.72231) (xy 73.984862 -130.699749)
			(xy 73.947456 -130.670635) (xy 73.915352 -130.635761) (xy 73.889426 -130.596078) (xy 73.870386 -130.55267)
			(xy 73.858749 -130.506719) (xy 73.854835 -130.45948) (xy 73.628741 -130.45948) (xy 73.624827 -130.506719)
			(xy 73.61319 -130.55267) (xy 73.59415 -130.596078) (xy 73.568224 -130.635761) (xy 73.53612 -130.670635)
			(xy 73.498714 -130.699749) (xy 73.457026 -130.72231) (xy 73.412193 -130.737701) (xy 73.365439 -130.745503)
			(xy 73.318037 -130.745503) (xy 73.271283 -130.737701) (xy 73.22645 -130.72231) (xy 73.184762 -130.699749)
			(xy 73.147356 -130.670635) (xy 73.115252 -130.635761) (xy 73.089326 -130.596078) (xy 73.070286 -130.55267)
			(xy 73.058649 -130.506719) (xy 73.054735 -130.45948) (xy 72.828895 -130.45948) (xy 72.824981 -130.506719)
			(xy 72.813344 -130.55267) (xy 72.794304 -130.596078) (xy 72.768378 -130.635761) (xy 72.736274 -130.670635)
			(xy 72.698868 -130.699749) (xy 72.65718 -130.72231) (xy 72.612347 -130.737701) (xy 72.565593 -130.745503)
			(xy 72.518191 -130.745503) (xy 72.471437 -130.737701) (xy 72.426604 -130.72231) (xy 72.384916 -130.699749)
			(xy 72.34751 -130.670635) (xy 72.315406 -130.635761) (xy 72.28948 -130.596078) (xy 72.27044 -130.55267)
			(xy 72.258803 -130.506719) (xy 72.254889 -130.45948) (xy 72.027871 -130.45948) (xy 72.027266 -130.489349)
			(xy 72.018196 -130.536802) (xy 72.001293 -130.582061) (xy 71.977037 -130.623842) (xy 71.946114 -130.660962)
			(xy 71.909402 -130.692367) (xy 71.867941 -130.717168) (xy 71.822907 -130.734661) (xy 71.775577 -130.74435)
			(xy 71.727291 -130.745961) (xy 71.67942 -130.739448) (xy 71.656194 -130.732784) (xy 71.648828 -130.730498)
			(xy 71.278242 -130.730498) (xy 71.266875 -130.744325) (xy 71.242204 -130.770265) (xy 71.228966 -130.782314)
			(xy 71.228966 -131.25958) (xy 71.454789 -131.25958) (xy 71.458703 -131.212341) (xy 71.47034 -131.16639)
			(xy 71.48938 -131.122982) (xy 71.515306 -131.083299) (xy 71.54741 -131.048425) (xy 71.584816 -131.019311)
			(xy 71.626504 -130.99675) (xy 71.671337 -130.981359) (xy 71.718091 -130.973557) (xy 71.741792 -130.973068)
			(xy 71.765493 -130.973557) (xy 71.812247 -130.981359) (xy 71.85708 -130.99675) (xy 71.898768 -131.019311)
			(xy 71.936174 -131.048425) (xy 71.968278 -131.083299) (xy 71.994204 -131.122982) (xy 72.013244 -131.16639)
			(xy 72.024881 -131.212341) (xy 72.028795 -131.25958) (xy 72.254889 -131.25958) (xy 72.258803 -131.212341)
			(xy 72.27044 -131.16639) (xy 72.28948 -131.122982) (xy 72.315406 -131.083299) (xy 72.34751 -131.048425)
			(xy 72.384916 -131.019311) (xy 72.426604 -130.99675) (xy 72.471437 -130.981359) (xy 72.518191 -130.973557)
			(xy 72.541892 -130.973068) (xy 72.565593 -130.973557) (xy 72.612347 -130.981359) (xy 72.65718 -130.99675)
			(xy 72.698868 -131.019311) (xy 72.736274 -131.048425) (xy 72.768378 -131.083299) (xy 72.794304 -131.122982)
			(xy 72.813344 -131.16639) (xy 72.824981 -131.212341) (xy 72.828895 -131.25958) (xy 73.054735 -131.25958)
			(xy 73.058649 -131.212341) (xy 73.070286 -131.16639) (xy 73.089326 -131.122982) (xy 73.115252 -131.083299)
			(xy 73.147356 -131.048425) (xy 73.184762 -131.019311) (xy 73.22645 -130.99675) (xy 73.271283 -130.981359)
			(xy 73.318037 -130.973557) (xy 73.341738 -130.973068) (xy 73.365439 -130.973557) (xy 73.412193 -130.981359)
			(xy 73.457026 -130.99675) (xy 73.498714 -131.019311) (xy 73.53612 -131.048425) (xy 73.568224 -131.083299)
			(xy 73.59415 -131.122982) (xy 73.61319 -131.16639) (xy 73.624827 -131.212341) (xy 73.628741 -131.25958)
			(xy 73.854835 -131.25958) (xy 73.858749 -131.212341) (xy 73.870386 -131.16639) (xy 73.889426 -131.122982)
			(xy 73.915352 -131.083299) (xy 73.947456 -131.048425) (xy 73.984862 -131.019311) (xy 74.02655 -130.99675)
			(xy 74.071383 -130.981359) (xy 74.118137 -130.973557) (xy 74.141838 -130.973068) (xy 74.165539 -130.973557)
			(xy 74.212293 -130.981359) (xy 74.257126 -130.99675) (xy 74.298814 -131.019311) (xy 74.33622 -131.048425)
			(xy 74.368324 -131.083299) (xy 74.39425 -131.122982) (xy 74.41329 -131.16639) (xy 74.424927 -131.212341)
			(xy 74.428841 -131.25958) (xy 74.424927 -131.306819) (xy 74.41329 -131.35277) (xy 74.39425 -131.396178)
			(xy 74.368324 -131.435861) (xy 74.33622 -131.470735) (xy 74.298814 -131.499849) (xy 74.257126 -131.52241)
			(xy 74.212293 -131.537801) (xy 74.165539 -131.545603) (xy 74.118137 -131.545603) (xy 74.071383 -131.537801)
			(xy 74.02655 -131.52241) (xy 73.984862 -131.499849) (xy 73.947456 -131.470735) (xy 73.915352 -131.435861)
			(xy 73.889426 -131.396178) (xy 73.870386 -131.35277) (xy 73.858749 -131.306819) (xy 73.854835 -131.25958)
			(xy 73.628741 -131.25958) (xy 73.624827 -131.306819) (xy 73.61319 -131.35277) (xy 73.59415 -131.396178)
			(xy 73.568224 -131.435861) (xy 73.53612 -131.470735) (xy 73.498714 -131.499849) (xy 73.457026 -131.52241)
			(xy 73.412193 -131.537801) (xy 73.365439 -131.545603) (xy 73.318037 -131.545603) (xy 73.271283 -131.537801)
			(xy 73.22645 -131.52241) (xy 73.184762 -131.499849) (xy 73.147356 -131.470735) (xy 73.115252 -131.435861)
			(xy 73.089326 -131.396178) (xy 73.070286 -131.35277) (xy 73.058649 -131.306819) (xy 73.054735 -131.25958)
			(xy 72.828895 -131.25958) (xy 72.824981 -131.306819) (xy 72.813344 -131.35277) (xy 72.794304 -131.396178)
			(xy 72.768378 -131.435861) (xy 72.736274 -131.470735) (xy 72.698868 -131.499849) (xy 72.65718 -131.52241)
			(xy 72.612347 -131.537801) (xy 72.565593 -131.545603) (xy 72.518191 -131.545603) (xy 72.471437 -131.537801)
			(xy 72.426604 -131.52241) (xy 72.384916 -131.499849) (xy 72.34751 -131.470735) (xy 72.315406 -131.435861)
			(xy 72.28948 -131.396178) (xy 72.27044 -131.35277) (xy 72.258803 -131.306819) (xy 72.254889 -131.25958)
			(xy 72.028795 -131.25958) (xy 72.024881 -131.306819) (xy 72.013244 -131.35277) (xy 71.994204 -131.396178)
			(xy 71.968278 -131.435861) (xy 71.936174 -131.470735) (xy 71.898768 -131.499849) (xy 71.85708 -131.52241)
			(xy 71.812247 -131.537801) (xy 71.765493 -131.545603) (xy 71.718091 -131.545603) (xy 71.671337 -131.537801)
			(xy 71.626504 -131.52241) (xy 71.584816 -131.499849) (xy 71.54741 -131.470735) (xy 71.515306 -131.435861)
			(xy 71.48938 -131.396178) (xy 71.47034 -131.35277) (xy 71.458703 -131.306819) (xy 71.454789 -131.25958)
			(xy 71.228966 -131.25958) (xy 71.228476 -131.283344) (xy 71.220653 -131.330222) (xy 71.205221 -131.375174)
			(xy 71.1826 -131.416973) (xy 71.153409 -131.454479) (xy 71.118442 -131.486668) (xy 71.078654 -131.512663)
			(xy 71.03513 -131.531755) (xy 70.989057 -131.543422) (xy 70.941692 -131.547347) (xy 70.894327 -131.543422)
			(xy 70.848254 -131.531755) (xy 70.80473 -131.512663) (xy 70.764942 -131.486668) (xy 70.729975 -131.454479)
			(xy 70.700784 -131.416973) (xy 70.678163 -131.375174) (xy 70.662731 -131.330222) (xy 70.654908 -131.283344)
			(xy 70.654418 -131.25958) (xy 70.654418 -130.782314) (xy 70.63613 -130.765042) (xy 70.534276 -130.663442)
			(xy 69.144896 -130.663442) (xy 68.973954 -130.834384) (xy 68.950487 -130.860608) (xy 68.898194 -130.907701)
			(xy 68.840518 -130.948022) (xy 68.778329 -130.980961) (xy 68.712569 -131.006021) (xy 68.644231 -131.022821)
			(xy 68.574348 -131.031109) (xy 68.503976 -131.03076) (xy 68.434178 -131.021778) (xy 68.36601 -131.004299)
			(xy 68.300502 -130.978588) (xy 68.238644 -130.945032) (xy 68.209668 -130.925062) (xy 67.693286 -130.925062)
			(xy 67.667886 -130.899662) (xy 67.633596 -130.891026) (xy 67.608958 -130.884168) (xy 67.588803 -130.877567)
			(xy 67.549747 -130.861027) (xy 67.53098 -130.851148) (xy 67.504808 -130.836545) (xy 67.456287 -130.801365)
			(xy 67.412935 -130.759982) (xy 67.375539 -130.713148) (xy 67.344777 -130.661713) (xy 67.321207 -130.606609)
			(xy 67.305258 -130.548837) (xy 67.297218 -130.489446) (xy 67.296792 -130.45948) (xy 67.296792 -130.273298)
			(xy 67.43065 -130.13944) (xy 67.467734 -130.10261) (xy 67.468496 -129.99847) (xy 67.43192 -129.960878)
			(xy 67.420763 -129.949192) (xy 67.400039 -129.924402) (xy 67.390518 -129.911348) (xy 67.381382 -129.899306)
			(xy 67.358513 -129.879553) (xy 67.33163 -129.865753) (xy 67.30225 -129.858684) (xy 67.28714 -129.858262)
			(xy 67.18681 -129.858262) (xy 67.150488 -129.891028) (xy 67.131265 -129.907694) (xy 67.088462 -129.935188)
			(xy 67.041761 -129.955365) (xy 66.992404 -129.967689) (xy 66.9417 -129.971834) (xy 66.890996 -129.967689)
			(xy 66.841639 -129.955365) (xy 66.794938 -129.935188) (xy 66.752135 -129.907694) (xy 66.732912 -129.891028)
			(xy 66.69659 -129.858262) (xy 66.386964 -129.858262) (xy 66.350642 -129.891028) (xy 66.342374 -129.898358)
			(xy 66.324958 -129.911959) (xy 66.315844 -129.918206) (xy 66.305684 -129.925064) (xy 65.789048 -130.4417)
			(xy 65.785746 -130.489452) (xy 65.783345 -130.518257) (xy 65.772027 -130.574939) (xy 65.753461 -130.629677)
			(xy 65.727959 -130.681549) (xy 65.695953 -130.72968) (xy 65.657981 -130.773259) (xy 65.614683 -130.811552)
			(xy 65.56679 -130.843912) (xy 65.541144 -130.857244) (xy 65.51537 -130.869675) (xy 65.461351 -130.888556)
			(xy 65.405356 -130.900351) (xy 65.348311 -130.904864) (xy 65.291159 -130.902021) (xy 65.234843 -130.89187)
			(xy 65.180295 -130.874577) (xy 65.128416 -130.850429) (xy 65.080064 -130.819825) (xy 65.057782 -130.801872)
			(xy 65.022476 -130.772662) (xy 64.861186 -130.772662) (xy 64.82588 -130.801872) (xy 64.801236 -130.821616)
			(xy 64.747437 -130.854678) (xy 64.689504 -130.8798) (xy 64.628601 -130.896478) (xy 64.565951 -130.904376)
			(xy 64.502814 -130.903336) (xy 64.47155 -130.8989) (xy 64.442153 -130.893729) (xy 64.384994 -130.876537)
			(xy 64.330649 -130.851853) (xy 64.280094 -130.820121) (xy 64.23424 -130.78191) (xy 64.21374 -130.760216)
			(xy 64.211962 -130.758184) (xy 63.826644 -130.372612) (xy 63.80668 -130.35203) (xy 63.771661 -130.306626)
			(xy 63.742755 -130.257105) (xy 63.720443 -130.204284) (xy 63.712344 -130.176778) (xy 63.706535 -130.154748)
			(xy 63.698905 -130.109828) (xy 63.697104 -130.087116) (xy 63.694818 -130.053842) (xy 63.628016 -129.951734)
			(xy 63.598298 -129.93624) (xy 63.574422 -129.922524) (xy 63.558125 -129.911818) (xy 63.528061 -129.886984)
			(xy 63.514478 -129.872994) (xy 63.49619 -129.85369) (xy 63.448184 -129.832862) (xy 63.261494 -129.832862)
			(xy 63.170816 -129.872232) (xy 63.154814 -129.887218) (xy 63.135411 -129.904664) (xy 63.091922 -129.933488)
			(xy 63.044241 -129.954672) (xy 62.9937 -129.967623) (xy 62.941708 -129.971981) (xy 62.889716 -129.967623)
			(xy 62.839175 -129.954672) (xy 62.791494 -129.933488) (xy 62.748005 -129.904664) (xy 62.728602 -129.887218)
			(xy 62.7126 -129.872232) (xy 62.621922 -129.832862) (xy 62.461648 -129.832862) (xy 62.37097 -129.872232)
			(xy 62.354968 -129.887218) (xy 62.335565 -129.904664) (xy 62.292076 -129.933488) (xy 62.244395 -129.954672)
			(xy 62.193854 -129.967623) (xy 62.141862 -129.971981) (xy 62.08987 -129.967623) (xy 62.039329 -129.954672)
			(xy 61.991648 -129.933488) (xy 61.948159 -129.904664) (xy 61.928756 -129.887218) (xy 61.912754 -129.872232)
			(xy 61.822076 -129.832862) (xy 61.724286 -129.832862) (xy 61.394086 -130.163062) (xy 61.394086 -131.204462)
			(xy 61.539891 -131.350267) (xy 62.002669 -131.350267) (xy 62.008772 -131.294793) (xy 62.022888 -131.2408)
			(xy 62.044715 -131.189437) (xy 62.073788 -131.141799) (xy 62.109487 -131.098903) (xy 62.151051 -131.061661)
			(xy 62.197595 -131.030867) (xy 62.248126 -131.007179) (xy 62.301568 -130.991101) (xy 62.356782 -130.982975)
			(xy 62.384686 -130.982466) (xy 62.41259 -130.982975) (xy 62.467804 -130.991101) (xy 62.521246 -131.007179)
			(xy 62.571777 -131.030867) (xy 62.618321 -131.061661) (xy 62.659885 -131.098903) (xy 62.695584 -131.141799)
			(xy 62.724657 -131.189437) (xy 62.746484 -131.2408) (xy 62.7606 -131.294793) (xy 62.766703 -131.350267)
			(xy 62.764665 -131.406038) (xy 62.754528 -131.460917) (xy 62.736509 -131.513737) (xy 62.710991 -131.563369)
			(xy 62.678519 -131.608757) (xy 62.639784 -131.648934) (xy 62.595612 -131.683042) (xy 62.546944 -131.710356)
			(xy 62.494818 -131.730292) (xy 62.440345 -131.742427) (xy 62.384686 -131.746501) (xy 62.329027 -131.742427)
			(xy 62.274554 -131.730292) (xy 62.222428 -131.710356) (xy 62.17376 -131.683042) (xy 62.129588 -131.648934)
			(xy 62.090853 -131.608757) (xy 62.058381 -131.563369) (xy 62.032863 -131.513737) (xy 62.014844 -131.460917)
			(xy 62.004707 -131.406038) (xy 62.002669 -131.350267) (xy 61.539891 -131.350267) (xy 61.698886 -131.509262)
			(xy 61.698886 -131.786884) (xy 61.78677 -131.874768) (xy 61.78677 -132.059426) (xy 61.786214 -132.090433)
			(xy 61.777579 -132.151845) (xy 61.76052 -132.211468) (xy 61.748416 -132.24002) (xy 61.737494 -132.264658)
			(xy 61.737494 -132.625592) (xy 61.786516 -132.674868) (xy 61.786516 -132.859526) (xy 61.785993 -132.890317)
			(xy 61.7775 -132.95131) (xy 61.76068 -133.010551) (xy 61.735855 -133.066907) (xy 61.703498 -133.119303)
			(xy 61.664226 -133.166738) (xy 61.618791 -133.208307) (xy 61.568059 -133.243216) (xy 61.513 -133.270798)
			(xy 61.484002 -133.281166) (xy 61.455808 -133.290564) (xy 60.954158 -133.792214) (xy 60.944506 -133.817106)
			(xy 60.933561 -133.843717) (xy 60.905633 -133.894026) (xy 60.87128 -133.940187) (xy 60.851542 -133.961124)
			(xy 60.840472 -133.973207) (xy 60.824331 -134.001713) (xy 60.815981 -134.033391) (xy 60.815474 -134.04977)
			(xy 60.815474 -134.128256) (xy 60.818254 -134.149514) (xy 60.830021 -134.190737) (xy 60.848548 -134.229395)
			(xy 60.873308 -134.264391) (xy 60.888118 -134.279894) (xy 61.430662 -134.822438) (xy 61.462412 -134.831328)
			(xy 61.489644 -134.839464) (xy 61.541945 -134.861713) (xy 61.590987 -134.890442) (xy 61.635971 -134.925182)
			(xy 61.676164 -134.965368) (xy 61.710913 -135.010345) (xy 61.73965 -135.059382) (xy 61.761909 -135.111679)
			(xy 61.770006 -135.138922) (xy 61.778896 -135.170672) (xy 61.902086 -135.293862) (xy 61.902086 -135.661447)
			(xy 62.768478 -135.661447) (xy 62.772341 -135.591948) (xy 62.784614 -135.523432) (xy 62.805115 -135.456914)
			(xy 62.833541 -135.393377) (xy 62.869471 -135.333761) (xy 62.912373 -135.278948) (xy 62.936628 -135.253984)
			(xy 62.967362 -135.222996) (xy 62.967362 -134.493762) (xy 62.936628 -134.462774) (xy 62.913725 -134.439288)
			(xy 62.87294 -134.387902) (xy 62.838301 -134.332189) (xy 62.810261 -134.272879) (xy 62.78919 -134.210751)
			(xy 62.775363 -134.146621) (xy 62.768962 -134.08133) (xy 62.770071 -134.015736) (xy 62.778676 -133.950699)
			(xy 62.794664 -133.887073) (xy 62.805818 -133.856222) (xy 62.80912 -133.847586) (xy 62.80912 -133.469126)
			(xy 62.805818 -133.46049) (xy 62.793912 -133.427481) (xy 62.777342 -133.359292) (xy 62.769235 -133.289588)
			(xy 62.769713 -133.219416) (xy 62.77877 -133.149829) (xy 62.796269 -133.081872) (xy 62.821948 -133.016566)
			(xy 62.855421 -132.95489) (xy 62.896185 -132.89777) (xy 62.943629 -132.846065) (xy 62.997041 -132.800551)
			(xy 63.026036 -132.780786) (xy 63.030354 -132.777992) (xy 63.508128 -132.300218) (xy 63.741808 -132.300218)
			(xy 63.752984 -132.300472) (xy 63.774828 -132.300726) (xy 63.775336 -132.300218) (xy 64.532256 -132.300218)
			(xy 64.533272 -132.299202) (xy 65.107058 -132.299202) (xy 65.108074 -132.300218) (xy 65.889886 -132.300218)
			(xy 66.13652 -132.053838) (xy 66.159786 -132.031199) (xy 66.210596 -131.990788) (xy 66.265653 -131.956388)
			(xy 66.32425 -131.928441) (xy 66.385633 -131.907304) (xy 66.449014 -131.89325) (xy 66.513578 -131.88646)
			(xy 66.578496 -131.887021) (xy 66.642934 -131.894925) (xy 66.706063 -131.910071) (xy 66.736722 -131.920742)
			(xy 66.745104 -131.92379) (xy 67.136772 -131.92379) (xy 67.145154 -131.920742) (xy 67.174954 -131.910289)
			(xy 67.23631 -131.895324) (xy 67.298941 -131.887212) (xy 67.362085 -131.886053) (xy 67.424973 -131.89186)
			(xy 67.486837 -131.904563) (xy 67.51701 -131.913884) (xy 67.52463 -131.916424) (xy 67.957192 -131.916424)
			(xy 67.964812 -131.913884) (xy 67.997857 -131.903728) (xy 68.065713 -131.890508) (xy 68.134668 -131.88556)
			(xy 68.203717 -131.888958) (xy 68.271853 -131.900651) (xy 68.338084 -131.920469) (xy 68.401444 -131.948123)
			(xy 68.46101 -131.98321) (xy 68.515914 -132.02522) (xy 68.550916 -132.059426) (xy 70.654689 -132.059426)
			(xy 70.658603 -132.012187) (xy 70.67024 -131.966236) (xy 70.68928 -131.922828) (xy 70.715206 -131.883145)
			(xy 70.74731 -131.848271) (xy 70.784716 -131.819157) (xy 70.826404 -131.796596) (xy 70.871237 -131.781205)
			(xy 70.917991 -131.773403) (xy 70.941692 -131.772914) (xy 70.965393 -131.773403) (xy 71.012147 -131.781205)
			(xy 71.05698 -131.796596) (xy 71.098668 -131.819157) (xy 71.136074 -131.848271) (xy 71.168178 -131.883145)
			(xy 71.194104 -131.922828) (xy 71.213144 -131.966236) (xy 71.224781 -132.012187) (xy 71.228695 -132.059426)
			(xy 71.454789 -132.059426) (xy 71.458703 -132.012187) (xy 71.47034 -131.966236) (xy 71.48938 -131.922828)
			(xy 71.515306 -131.883145) (xy 71.54741 -131.848271) (xy 71.584816 -131.819157) (xy 71.626504 -131.796596)
			(xy 71.671337 -131.781205) (xy 71.718091 -131.773403) (xy 71.741792 -131.772914) (xy 71.765493 -131.773403)
			(xy 71.812247 -131.781205) (xy 71.85708 -131.796596) (xy 71.898768 -131.819157) (xy 71.936174 -131.848271)
			(xy 71.968278 -131.883145) (xy 71.994204 -131.922828) (xy 72.013244 -131.966236) (xy 72.024881 -132.012187)
			(xy 72.028795 -132.059426) (xy 72.254889 -132.059426) (xy 72.258803 -132.012187) (xy 72.27044 -131.966236)
			(xy 72.28948 -131.922828) (xy 72.315406 -131.883145) (xy 72.34751 -131.848271) (xy 72.384916 -131.819157)
			(xy 72.426604 -131.796596) (xy 72.471437 -131.781205) (xy 72.518191 -131.773403) (xy 72.541892 -131.772914)
			(xy 72.565593 -131.773403) (xy 72.612347 -131.781205) (xy 72.65718 -131.796596) (xy 72.698868 -131.819157)
			(xy 72.736274 -131.848271) (xy 72.768378 -131.883145) (xy 72.794304 -131.922828) (xy 72.813344 -131.966236)
			(xy 72.824981 -132.012187) (xy 72.828895 -132.059426) (xy 73.054735 -132.059426) (xy 73.058649 -132.012187)
			(xy 73.070286 -131.966236) (xy 73.089326 -131.922828) (xy 73.115252 -131.883145) (xy 73.147356 -131.848271)
			(xy 73.184762 -131.819157) (xy 73.22645 -131.796596) (xy 73.271283 -131.781205) (xy 73.318037 -131.773403)
			(xy 73.341738 -131.772914) (xy 73.365439 -131.773403) (xy 73.412193 -131.781205) (xy 73.457026 -131.796596)
			(xy 73.498714 -131.819157) (xy 73.53612 -131.848271) (xy 73.568224 -131.883145) (xy 73.59415 -131.922828)
			(xy 73.61319 -131.966236) (xy 73.624827 -132.012187) (xy 73.628741 -132.059426) (xy 73.854835 -132.059426)
			(xy 73.858749 -132.012187) (xy 73.870386 -131.966236) (xy 73.889426 -131.922828) (xy 73.915352 -131.883145)
			(xy 73.947456 -131.848271) (xy 73.984862 -131.819157) (xy 74.02655 -131.796596) (xy 74.071383 -131.781205)
			(xy 74.118137 -131.773403) (xy 74.141838 -131.772914) (xy 74.165539 -131.773403) (xy 74.212293 -131.781205)
			(xy 74.257126 -131.796596) (xy 74.298814 -131.819157) (xy 74.33622 -131.848271) (xy 74.368324 -131.883145)
			(xy 74.39425 -131.922828) (xy 74.41329 -131.966236) (xy 74.424927 -132.012187) (xy 74.428841 -132.059426)
			(xy 74.424927 -132.106665) (xy 74.41329 -132.152616) (xy 74.39425 -132.196024) (xy 74.368324 -132.235707)
			(xy 74.33622 -132.270581) (xy 74.298814 -132.299695) (xy 74.257126 -132.322256) (xy 74.212293 -132.337647)
			(xy 74.165539 -132.345449) (xy 74.118137 -132.345449) (xy 74.071383 -132.337647) (xy 74.02655 -132.322256)
			(xy 73.984862 -132.299695) (xy 73.947456 -132.270581) (xy 73.915352 -132.235707) (xy 73.889426 -132.196024)
			(xy 73.870386 -132.152616) (xy 73.858749 -132.106665) (xy 73.854835 -132.059426) (xy 73.628741 -132.059426)
			(xy 73.624827 -132.106665) (xy 73.61319 -132.152616) (xy 73.59415 -132.196024) (xy 73.568224 -132.235707)
			(xy 73.53612 -132.270581) (xy 73.498714 -132.299695) (xy 73.457026 -132.322256) (xy 73.412193 -132.337647)
			(xy 73.365439 -132.345449) (xy 73.318037 -132.345449) (xy 73.271283 -132.337647) (xy 73.22645 -132.322256)
			(xy 73.184762 -132.299695) (xy 73.147356 -132.270581) (xy 73.115252 -132.235707) (xy 73.089326 -132.196024)
			(xy 73.070286 -132.152616) (xy 73.058649 -132.106665) (xy 73.054735 -132.059426) (xy 72.828895 -132.059426)
			(xy 72.824981 -132.106665) (xy 72.813344 -132.152616) (xy 72.794304 -132.196024) (xy 72.768378 -132.235707)
			(xy 72.736274 -132.270581) (xy 72.698868 -132.299695) (xy 72.65718 -132.322256) (xy 72.612347 -132.337647)
			(xy 72.565593 -132.345449) (xy 72.518191 -132.345449) (xy 72.471437 -132.337647) (xy 72.426604 -132.322256)
			(xy 72.384916 -132.299695) (xy 72.34751 -132.270581) (xy 72.315406 -132.235707) (xy 72.28948 -132.196024)
			(xy 72.27044 -132.152616) (xy 72.258803 -132.106665) (xy 72.254889 -132.059426) (xy 72.028795 -132.059426)
			(xy 72.024881 -132.106665) (xy 72.013244 -132.152616) (xy 71.994204 -132.196024) (xy 71.968278 -132.235707)
			(xy 71.936174 -132.270581) (xy 71.898768 -132.299695) (xy 71.85708 -132.322256) (xy 71.812247 -132.337647)
			(xy 71.765493 -132.345449) (xy 71.718091 -132.345449) (xy 71.671337 -132.337647) (xy 71.626504 -132.322256)
			(xy 71.584816 -132.299695) (xy 71.54741 -132.270581) (xy 71.515306 -132.235707) (xy 71.48938 -132.196024)
			(xy 71.47034 -132.152616) (xy 71.458703 -132.106665) (xy 71.454789 -132.059426) (xy 71.228695 -132.059426)
			(xy 71.224781 -132.106665) (xy 71.213144 -132.152616) (xy 71.194104 -132.196024) (xy 71.168178 -132.235707)
			(xy 71.136074 -132.270581) (xy 71.098668 -132.299695) (xy 71.05698 -132.322256) (xy 71.012147 -132.337647)
			(xy 70.965393 -132.345449) (xy 70.917991 -132.345449) (xy 70.871237 -132.337647) (xy 70.826404 -132.322256)
			(xy 70.784716 -132.299695) (xy 70.74731 -132.270581) (xy 70.715206 -132.235707) (xy 70.68928 -132.196024)
			(xy 70.67024 -132.152616) (xy 70.658603 -132.106665) (xy 70.654689 -132.059426) (xy 68.550916 -132.059426)
			(xy 68.565357 -132.073539) (xy 68.608616 -132.127464) (xy 68.645063 -132.186209) (xy 68.674165 -132.248917)
			(xy 68.695499 -132.314675) (xy 68.708754 -132.382525) (xy 68.713736 -132.451477) (xy 68.710374 -132.520528)
			(xy 68.698716 -132.58867) (xy 68.678931 -132.654911) (xy 68.665598 -132.686806) (xy 68.66128 -132.696458)
			(xy 68.66128 -132.859526) (xy 70.654689 -132.859526) (xy 70.658603 -132.812287) (xy 70.67024 -132.766336)
			(xy 70.68928 -132.722928) (xy 70.715206 -132.683245) (xy 70.74731 -132.648371) (xy 70.784716 -132.619257)
			(xy 70.826404 -132.596696) (xy 70.871237 -132.581305) (xy 70.917991 -132.573503) (xy 70.941692 -132.573014)
			(xy 70.965393 -132.573503) (xy 71.012147 -132.581305) (xy 71.05698 -132.596696) (xy 71.098668 -132.619257)
			(xy 71.136074 -132.648371) (xy 71.168178 -132.683245) (xy 71.194104 -132.722928) (xy 71.213144 -132.766336)
			(xy 71.224781 -132.812287) (xy 71.228695 -132.859526) (xy 71.454789 -132.859526) (xy 71.458703 -132.812287)
			(xy 71.47034 -132.766336) (xy 71.48938 -132.722928) (xy 71.515306 -132.683245) (xy 71.54741 -132.648371)
			(xy 71.584816 -132.619257) (xy 71.626504 -132.596696) (xy 71.671337 -132.581305) (xy 71.718091 -132.573503)
			(xy 71.741792 -132.573014) (xy 71.765493 -132.573503) (xy 71.812247 -132.581305) (xy 71.85708 -132.596696)
			(xy 71.898768 -132.619257) (xy 71.936174 -132.648371) (xy 71.968278 -132.683245) (xy 71.994204 -132.722928)
			(xy 72.013244 -132.766336) (xy 72.024881 -132.812287) (xy 72.028795 -132.859526) (xy 72.254889 -132.859526)
			(xy 72.258803 -132.812287) (xy 72.27044 -132.766336) (xy 72.28948 -132.722928) (xy 72.315406 -132.683245)
			(xy 72.34751 -132.648371) (xy 72.384916 -132.619257) (xy 72.426604 -132.596696) (xy 72.471437 -132.581305)
			(xy 72.518191 -132.573503) (xy 72.541892 -132.573014) (xy 72.565593 -132.573503) (xy 72.612347 -132.581305)
			(xy 72.65718 -132.596696) (xy 72.698868 -132.619257) (xy 72.736274 -132.648371) (xy 72.768378 -132.683245)
			(xy 72.794304 -132.722928) (xy 72.813344 -132.766336) (xy 72.824981 -132.812287) (xy 72.828895 -132.859526)
			(xy 73.054735 -132.859526) (xy 73.058649 -132.812287) (xy 73.070286 -132.766336) (xy 73.089326 -132.722928)
			(xy 73.115252 -132.683245) (xy 73.147356 -132.648371) (xy 73.184762 -132.619257) (xy 73.22645 -132.596696)
			(xy 73.271283 -132.581305) (xy 73.318037 -132.573503) (xy 73.341738 -132.573014) (xy 73.365439 -132.573503)
			(xy 73.412193 -132.581305) (xy 73.457026 -132.596696) (xy 73.498714 -132.619257) (xy 73.53612 -132.648371)
			(xy 73.568224 -132.683245) (xy 73.59415 -132.722928) (xy 73.61319 -132.766336) (xy 73.624827 -132.812287)
			(xy 73.628741 -132.859526) (xy 73.854835 -132.859526) (xy 73.858749 -132.812287) (xy 73.870386 -132.766336)
			(xy 73.889426 -132.722928) (xy 73.915352 -132.683245) (xy 73.947456 -132.648371) (xy 73.984862 -132.619257)
			(xy 74.02655 -132.596696) (xy 74.071383 -132.581305) (xy 74.118137 -132.573503) (xy 74.141838 -132.573014)
			(xy 74.165539 -132.573503) (xy 74.212293 -132.581305) (xy 74.257126 -132.596696) (xy 74.298814 -132.619257)
			(xy 74.33622 -132.648371) (xy 74.368324 -132.683245) (xy 74.39425 -132.722928) (xy 74.41329 -132.766336)
			(xy 74.424927 -132.812287) (xy 74.428841 -132.859526) (xy 74.424927 -132.906765) (xy 74.41329 -132.952716)
			(xy 74.39425 -132.996124) (xy 74.368324 -133.035807) (xy 74.33622 -133.070681) (xy 74.298814 -133.099795)
			(xy 74.257126 -133.122356) (xy 74.212293 -133.137747) (xy 74.165539 -133.145549) (xy 74.118137 -133.145549)
			(xy 74.071383 -133.137747) (xy 74.02655 -133.122356) (xy 73.984862 -133.099795) (xy 73.947456 -133.070681)
			(xy 73.915352 -133.035807) (xy 73.889426 -132.996124) (xy 73.870386 -132.952716) (xy 73.858749 -132.906765)
			(xy 73.854835 -132.859526) (xy 73.628741 -132.859526) (xy 73.624827 -132.906765) (xy 73.61319 -132.952716)
			(xy 73.59415 -132.996124) (xy 73.568224 -133.035807) (xy 73.53612 -133.070681) (xy 73.498714 -133.099795)
			(xy 73.457026 -133.122356) (xy 73.412193 -133.137747) (xy 73.365439 -133.145549) (xy 73.318037 -133.145549)
			(xy 73.271283 -133.137747) (xy 73.22645 -133.122356) (xy 73.184762 -133.099795) (xy 73.147356 -133.070681)
			(xy 73.115252 -133.035807) (xy 73.089326 -132.996124) (xy 73.070286 -132.952716) (xy 73.058649 -132.906765)
			(xy 73.054735 -132.859526) (xy 72.828895 -132.859526) (xy 72.824981 -132.906765) (xy 72.813344 -132.952716)
			(xy 72.794304 -132.996124) (xy 72.768378 -133.035807) (xy 72.736274 -133.070681) (xy 72.698868 -133.099795)
			(xy 72.65718 -133.122356) (xy 72.612347 -133.137747) (xy 72.565593 -133.145549) (xy 72.518191 -133.145549)
			(xy 72.471437 -133.137747) (xy 72.426604 -133.122356) (xy 72.384916 -133.099795) (xy 72.34751 -133.070681)
			(xy 72.315406 -133.035807) (xy 72.28948 -132.996124) (xy 72.27044 -132.952716) (xy 72.258803 -132.906765)
			(xy 72.254889 -132.859526) (xy 72.028795 -132.859526) (xy 72.024881 -132.906765) (xy 72.013244 -132.952716)
			(xy 71.994204 -132.996124) (xy 71.968278 -133.035807) (xy 71.936174 -133.070681) (xy 71.898768 -133.099795)
			(xy 71.85708 -133.122356) (xy 71.812247 -133.137747) (xy 71.765493 -133.145549) (xy 71.718091 -133.145549)
			(xy 71.671337 -133.137747) (xy 71.626504 -133.122356) (xy 71.584816 -133.099795) (xy 71.54741 -133.070681)
			(xy 71.515306 -133.035807) (xy 71.48938 -132.996124) (xy 71.47034 -132.952716) (xy 71.458703 -132.906765)
			(xy 71.454789 -132.859526) (xy 71.228695 -132.859526) (xy 71.224781 -132.906765) (xy 71.213144 -132.952716)
			(xy 71.194104 -132.996124) (xy 71.168178 -133.035807) (xy 71.136074 -133.070681) (xy 71.098668 -133.099795)
			(xy 71.05698 -133.122356) (xy 71.012147 -133.137747) (xy 70.965393 -133.145549) (xy 70.917991 -133.145549)
			(xy 70.871237 -133.137747) (xy 70.826404 -133.122356) (xy 70.784716 -133.099795) (xy 70.74731 -133.070681)
			(xy 70.715206 -133.035807) (xy 70.68928 -132.996124) (xy 70.67024 -132.952716) (xy 70.658603 -132.906765)
			(xy 70.654689 -132.859526) (xy 68.66128 -132.859526) (xy 68.66128 -133.020308) (xy 68.665598 -133.02996)
			(xy 68.678303 -133.060211) (xy 68.697423 -133.122979) (xy 68.709237 -133.187523) (xy 68.713591 -133.252994)
			(xy 68.710428 -133.318533) (xy 68.699789 -133.383281) (xy 68.681814 -133.446387) (xy 68.656739 -133.507022)
			(xy 68.641214 -133.535928) (xy 68.634864 -133.547358) (xy 68.634864 -133.7691) (xy 68.641214 -133.78053)
			(xy 68.657102 -133.810159) (xy 68.682626 -133.872359) (xy 68.700681 -133.937123) (xy 68.711018 -134.003556)
			(xy 68.713495 -134.070744) (xy 68.708077 -134.137759) (xy 68.694838 -134.203676) (xy 68.673963 -134.267586)
			(xy 68.645738 -134.328607) (xy 68.610553 -134.385899) (xy 68.568893 -134.43867) (xy 68.545456 -134.462774)
			(xy 68.514722 -134.493762) (xy 68.514722 -135.222996) (xy 68.545456 -135.253984) (xy 68.569792 -135.279023)
			(xy 68.612812 -135.334021) (xy 68.648818 -135.393847) (xy 68.677272 -135.457612) (xy 68.697753 -135.524366)
			(xy 68.709954 -135.593117) (xy 68.713696 -135.662842) (xy 68.708921 -135.732504) (xy 68.695702 -135.801067)
			(xy 68.674235 -135.86751) (xy 68.66001 -135.899398) (xy 68.655184 -135.909558) (xy 68.655184 -136.207246)
			(xy 68.66001 -136.217406) (xy 68.674765 -136.250425) (xy 68.696705 -136.319343) (xy 68.70978 -136.390477)
			(xy 68.713782 -136.462691) (xy 68.708647 -136.534834) (xy 68.694458 -136.605754) (xy 68.67144 -136.674319)
			(xy 68.6562 -136.707118) (xy 68.65112 -136.717532) (xy 68.65112 -136.99871) (xy 68.6562 -137.009124)
			(xy 68.670325 -137.039474) (xy 68.692245 -137.102728) (xy 68.706634 -137.168108) (xy 68.713295 -137.23472)
			(xy 68.712137 -137.301655) (xy 68.703176 -137.367997) (xy 68.686535 -137.43284) (xy 68.66244 -137.495298)
			(xy 68.631221 -137.554518) (xy 68.593305 -137.609689) (xy 68.549209 -137.660059) (xy 68.499536 -137.704939)
			(xy 68.444966 -137.743716) (xy 68.386243 -137.77586) (xy 68.324171 -137.800931) (xy 68.259597 -137.818587)
			(xy 68.193403 -137.828587) (xy 68.126495 -137.830795) (xy 68.059786 -137.825179) (xy 67.994189 -137.811816)
			(xy 67.930599 -137.790891) (xy 67.900042 -137.77722) (xy 67.889882 -137.772394) (xy 67.592194 -137.772394)
			(xy 67.582034 -137.77722) (xy 67.550686 -137.791194) (xy 67.485435 -137.812478) (xy 67.418106 -137.825798)
			(xy 67.349666 -137.830962) (xy 67.281101 -137.827896) (xy 67.213395 -137.816645) (xy 67.147523 -137.79737)
			(xy 67.084432 -137.770349) (xy 67.054476 -137.753598) (xy 67.042792 -137.74674) (xy 66.83883 -137.74674)
			(xy 66.827146 -137.753598) (xy 66.797395 -137.770177) (xy 66.734794 -137.797013) (xy 66.669449 -137.816221)
			(xy 66.602285 -137.827531) (xy 66.534253 -137.830782) (xy 66.466316 -137.825928) (xy 66.399437 -137.813038)
			(xy 66.334563 -137.792294) (xy 66.272613 -137.76399) (xy 66.214464 -137.728528) (xy 66.160939 -137.686408)
			(xy 66.13652 -137.662666) (xy 66.105532 -137.631932) (xy 65.376298 -137.631932) (xy 65.34531 -137.662666)
			(xy 65.322016 -137.685319) (xy 65.271172 -137.725781) (xy 65.216069 -137.760218) (xy 65.157416 -137.788184)
			(xy 65.09597 -137.809319) (xy 65.032524 -137.82335) (xy 64.967897 -137.830097) (xy 64.902921 -137.829473)
			(xy 64.838435 -137.821484) (xy 64.775271 -137.806236) (xy 64.7446 -137.795508) (xy 64.735964 -137.79246)
			(xy 64.34582 -137.79246) (xy 64.337184 -137.795508) (xy 64.306322 -137.806312) (xy 64.242746 -137.821607)
			(xy 64.177839 -137.829544) (xy 64.112451 -137.830019) (xy 64.047436 -137.823025) (xy 63.983644 -137.808655)
			(xy 63.952628 -137.798302) (xy 63.9445 -137.795508) (xy 63.537846 -137.795508) (xy 63.529718 -137.798302)
			(xy 63.497966 -137.808864) (xy 63.43265 -137.823419) (xy 63.366082 -137.830253) (xy 63.299171 -137.829272)
			(xy 63.232831 -137.820491) (xy 63.16797 -137.804029) (xy 63.105472 -137.78011) (xy 63.046193 -137.749062)
			(xy 62.990941 -137.71131) (xy 62.940472 -137.667368) (xy 62.895475 -137.617837) (xy 62.856565 -137.563394)
			(xy 62.824274 -137.504782) (xy 62.799043 -137.442803) (xy 62.781216 -137.378303) (xy 62.771037 -137.312164)
			(xy 62.768645 -137.245289) (xy 62.774074 -137.178591) (xy 62.787247 -137.112982) (xy 62.807987 -137.049359)
			(xy 62.821566 -137.018776) (xy 62.826138 -137.008616) (xy 62.826138 -136.707626) (xy 62.821566 -136.697466)
			(xy 62.807296 -136.665181) (xy 62.785887 -136.597919) (xy 62.772915 -136.528534) (xy 62.768579 -136.45808)
			(xy 62.772945 -136.387627) (xy 62.785945 -136.318247) (xy 62.796166 -136.284462) (xy 62.798452 -136.276842)
			(xy 62.798452 -135.840216) (xy 62.796166 -135.832596) (xy 62.786083 -135.799281) (xy 62.773081 -135.7309)
			(xy 62.768478 -135.661447) (xy 61.902086 -135.661447) (xy 61.902086 -139.053062) (xy 62.568836 -139.719812)
			(xy 62.660022 -139.728448) (xy 62.697868 -139.70254) (xy 62.724939 -139.684716) (xy 62.783297 -139.656516)
			(xy 62.845215 -139.637357) (xy 62.909301 -139.627669) (xy 62.941708 -139.627102) (xy 63.12154 -139.627102)
			(xy 63.251334 -139.756896) (xy 63.263452 -139.768335) (xy 63.292291 -139.785011) (xy 63.324466 -139.793643)
			(xy 63.35778 -139.793643) (xy 63.389955 -139.785011) (xy 63.418794 -139.768335) (xy 63.430912 -139.756896)
			(xy 63.467742 -139.720066) (xy 63.560452 -139.627102) (xy 63.639446 -139.627102) (xy 63.70574 -139.560808)
			(xy 63.715138 -139.530074) (xy 63.723441 -139.503916) (xy 63.745608 -139.453709) (xy 63.773778 -139.406607)
			(xy 63.807522 -139.363324) (xy 63.826644 -139.343638) (xy 64.355472 -138.81481) (xy 64.541908 -138.81481)
			(xy 64.570957 -138.815238) (xy 64.628569 -138.822723) (xy 64.684714 -138.837654) (xy 64.738433 -138.859778)
			(xy 64.78881 -138.888717) (xy 64.812164 -138.905996) (xy 64.837056 -138.92657) (xy 64.853312 -138.941048)
			(xy 64.900048 -138.960098) (xy 64.914012 -138.96532) (xy 64.943479 -138.969803) (xy 64.973182 -138.967325)
			(xy 65.0015 -138.958023) (xy 65.026886 -138.942405) (xy 65.037716 -138.932158) (xy 65.155318 -138.81481)
			(xy 65.341754 -138.81481) (xy 65.370817 -138.815285) (xy 65.428448 -138.822859) (xy 65.484603 -138.83787)
			(xy 65.538326 -138.860064) (xy 65.588702 -138.889063) (xy 65.634875 -138.924372) (xy 65.676058 -138.965392)
			(xy 65.711551 -139.011424) (xy 65.74075 -139.061685) (xy 65.763158 -139.115319) (xy 65.771268 -139.143232)
			(xy 65.777005 -139.165521) (xy 65.784387 -139.210951) (xy 65.786 -139.23391) (xy 65.788794 -139.28217)
			(xy 66.133726 -139.627102) (xy 66.321432 -139.627102) (xy 66.415158 -139.720828) (xy 66.452242 -139.758166)
			(xy 66.465311 -139.770336) (xy 66.496579 -139.787556) (xy 66.531386 -139.795473) (xy 66.567026 -139.793472)
			(xy 66.584068 -139.788138) (xy 66.612008 -139.778232) (xy 66.632836 -139.75715) (xy 66.653227 -139.736963)
			(xy 66.698416 -139.701603) (xy 66.747888 -139.672536) (xy 66.800772 -139.650272) (xy 66.856138 -139.635204)
			(xy 66.91301 -139.627596) (xy 66.9417 -139.627102) (xy 67.121278 -139.627102) (xy 67.240658 -139.746482)
			(xy 67.252766 -139.75794) (xy 67.281601 -139.77465) (xy 67.313784 -139.783301) (xy 67.34711 -139.783301)
			(xy 67.379293 -139.77465) (xy 67.408128 -139.75794) (xy 67.420236 -139.746482) (xy 67.431478 -139.734478)
			(xy 67.447971 -139.706037) (xy 67.456648 -139.674325) (xy 67.45693 -139.64145) (xy 67.448801 -139.609593)
			(xy 67.432799 -139.580873) (xy 67.42176 -139.568682) (xy 67.40085 -139.546309) (xy 67.364739 -139.496852)
			(xy 67.335755 -139.442909) (xy 67.314444 -139.3855) (xy 67.301211 -139.32571) (xy 67.296306 -139.26467)
			(xy 67.29982 -139.203533) (xy 67.311689 -139.143458) (xy 67.331687 -139.085578) (xy 67.359436 -139.030989)
			(xy 67.394411 -138.980723) (xy 67.435952 -138.93573) (xy 67.483272 -138.896861) (xy 67.535477 -138.864852)
			(xy 67.59158 -138.840307) (xy 67.650519 -138.823691) (xy 67.711181 -138.815317) (xy 67.7418 -138.81481)
			(xy 67.926458 -138.81481) (xy 68.051426 -138.939524) (xy 68.051934 -138.940032) (xy 68.08978 -138.977624)
			(xy 68.193666 -138.977878) (xy 68.231004 -138.941556) (xy 68.25184 -138.921814) (xy 68.297706 -138.887303)
			(xy 68.34763 -138.858976) (xy 68.400781 -138.837306) (xy 68.456279 -138.822652) (xy 68.5132 -138.815257)
			(xy 68.5419 -138.81481) (xy 68.542154 -138.81481) (xy 68.571273 -138.815269) (xy 68.629012 -138.822879)
			(xy 68.685264 -138.83796) (xy 68.739065 -138.860255) (xy 68.789496 -138.889382) (xy 68.835693 -138.924844)
			(xy 68.856606 -138.945112) (xy 68.91401 -139.002262) (xy 69.166486 -139.002262) (xy 69.750686 -138.418062)
			(xy 69.750686 -137.873486) (xy 69.738748 -137.847832) (xy 69.727383 -137.822488) (xy 69.710328 -137.769626)
			(xy 69.699987 -137.715053) (xy 69.69652 -137.659616) (xy 69.699983 -137.60418) (xy 69.71032 -137.549605)
			(xy 69.727371 -137.496743) (xy 69.738748 -137.471404) (xy 69.750686 -137.44575) (xy 69.750686 -137.073386)
			(xy 69.738748 -137.047732) (xy 69.727383 -137.022388) (xy 69.710328 -136.969526) (xy 69.699987 -136.914953)
			(xy 69.69652 -136.859516) (xy 69.699983 -136.80408) (xy 69.71032 -136.749505) (xy 69.727371 -136.696643)
			(xy 69.738748 -136.671304) (xy 69.750686 -136.64565) (xy 69.750686 -136.273286) (xy 69.738748 -136.247632)
			(xy 69.727383 -136.222288) (xy 69.710328 -136.169426) (xy 69.699987 -136.114853) (xy 69.69652 -136.059416)
			(xy 69.699983 -136.00398) (xy 69.71032 -135.949405) (xy 69.727371 -135.896543) (xy 69.738748 -135.871204)
			(xy 69.750686 -135.84555) (xy 69.750686 -135.47344) (xy 69.738748 -135.447786) (xy 69.727386 -135.422442)
			(xy 69.710337 -135.369581) (xy 69.700001 -135.315009) (xy 69.69654 -135.259575) (xy 69.700008 -135.204141)
			(xy 69.71035 -135.14957) (xy 69.727405 -135.096711) (xy 69.738748 -135.071358) (xy 69.750686 -135.045704)
			(xy 69.750686 -134.67334) (xy 69.738748 -134.647686) (xy 69.727386 -134.622342) (xy 69.710337 -134.569481)
			(xy 69.700001 -134.514909) (xy 69.69654 -134.459475) (xy 69.700008 -134.404041) (xy 69.71035 -134.34947)
			(xy 69.727405 -134.296611) (xy 69.738748 -134.271258) (xy 69.750686 -134.245604) (xy 69.750686 -134.076948)
			(xy 69.726098 -134.053218) (xy 69.682165 -134.000877) (xy 69.644781 -133.943675) (xy 69.614477 -133.882427)
			(xy 69.591687 -133.818004) (xy 69.576734 -133.751326) (xy 69.569831 -133.68334) (xy 69.571077 -133.615017)
			(xy 69.580454 -133.547328) (xy 69.597829 -133.481239) (xy 69.622953 -133.41769) (xy 69.655469 -133.357587)
			(xy 69.694915 -133.301787) (xy 69.740727 -133.251083) (xy 69.792254 -133.206198) (xy 69.848761 -133.167771)
			(xy 69.909444 -133.13635) (xy 69.973438 -133.112383) (xy 70.039831 -133.09621) (xy 70.107679 -133.088062)
			(xy 70.141846 -133.087618) (xy 70.37959 -133.087618) (xy 70.664324 -133.372352) (xy 74.141838 -133.372352)
			(xy 74.16592 -133.372845) (xy 74.21341 -133.380882) (xy 74.258896 -133.396724) (xy 74.301103 -133.419928)
			(xy 74.33885 -133.449845) (xy 74.371081 -133.485637) (xy 74.384408 -133.505702) (xy 74.60996 -133.505702)
			(xy 75.30592 -134.201662) (xy 75.30592 -136.143247) (xy 80.635855 -136.143247) (xy 80.641958 -136.087773)
			(xy 80.656074 -136.03378) (xy 80.677901 -135.982417) (xy 80.706974 -135.934779) (xy 80.742673 -135.891883)
			(xy 80.784237 -135.854641) (xy 80.830781 -135.823847) (xy 80.881312 -135.800159) (xy 80.934754 -135.784081)
			(xy 80.989968 -135.775955) (xy 81.017872 -135.775446) (xy 81.045776 -135.775955) (xy 81.10099 -135.784081)
			(xy 81.154432 -135.800159) (xy 81.204963 -135.823847) (xy 81.251507 -135.854641) (xy 81.293071 -135.891883)
			(xy 81.32877 -135.934779) (xy 81.357843 -135.982417) (xy 81.37967 -136.03378) (xy 81.393786 -136.087773)
			(xy 81.399889 -136.143247) (xy 81.397851 -136.199018) (xy 81.387714 -136.253897) (xy 81.369695 -136.306717)
			(xy 81.344177 -136.356349) (xy 81.311705 -136.401737) (xy 81.27297 -136.441914) (xy 81.228798 -136.476022)
			(xy 81.18013 -136.503336) (xy 81.128004 -136.523272) (xy 81.073531 -136.535407) (xy 81.017872 -136.539481)
			(xy 80.962213 -136.535407) (xy 80.90774 -136.523272) (xy 80.855614 -136.503336) (xy 80.806946 -136.476022)
			(xy 80.762774 -136.441914) (xy 80.724039 -136.401737) (xy 80.691567 -136.356349) (xy 80.666049 -136.306717)
			(xy 80.64803 -136.253897) (xy 80.637893 -136.199018) (xy 80.635855 -136.143247) (xy 75.30592 -136.143247)
			(xy 75.30592 -136.575292) (xy 76.181712 -137.451084) (xy 78.95844 -137.451084) (xy 78.980792 -137.428732)
			(xy 80.119474 -137.428732) (xy 80.667352 -137.97661) (xy 80.667352 -139.173204) (xy 81.022952 -139.528804)
			(xy 81.022952 -141.561566) (xy 81.185512 -141.724126) (xy 81.439766 -141.724126)
		)
		(stroke
			(width 0)
			(type solid)
		)
		(fill yes)
		(layer "F.Cu")
		(net "P1V26_BMC_NODE1")
	)
	(gr_poly
		(pts
			(xy 65.00622 -79.083916) (xy 65.00622 -78.902814) (xy 64.982344 -78.86954) (xy 64.963198 -78.841569)
			(xy 64.934063 -78.780373) (xy 64.924432 -78.747874) (xy 64.915542 -78.715362) (xy 64.88684 -78.686406)
			(xy 64.823086 -78.622652) (xy 64.797178 -78.613) (xy 64.768985 -78.601897) (xy 64.716247 -78.572065)
			(xy 64.668897 -78.534262) (xy 64.628127 -78.48944) (xy 64.594966 -78.43873) (xy 64.58204 -78.411324)
			(xy 64.57471 -78.396273) (xy 64.553517 -78.370372) (xy 64.52633 -78.350857) (xy 64.49501 -78.339064)
			(xy 64.478408 -78.336902) (xy 64.449276 -78.333553) (xy 64.392332 -78.319554) (xy 64.337989 -78.297524)
			(xy 64.287371 -78.267921) (xy 64.241528 -78.231356) (xy 64.20141 -78.188588) (xy 64.167848 -78.140504)
			(xy 64.141537 -78.088098) (xy 64.123024 -78.032459) (xy 64.11269 -77.974737) (xy 64.110752 -77.91613)
			(xy 64.117247 -77.857852) (xy 64.132043 -77.80111) (xy 64.154833 -77.747081) (xy 64.169544 -77.721714)
			(xy 64.1731 -77.715872) (xy 64.180066 -77.704981) (xy 64.195191 -77.68401) (xy 64.203326 -77.673962)
			(xy 64.214787 -77.660332) (xy 64.239714 -77.634896) (xy 64.25311 -77.623162) (xy 64.25692 -77.61986)
			(xy 64.46647 -77.41031) (xy 64.72809 -77.148944) (xy 64.881506 -77.148944) (xy 64.896574 -77.148525)
			(xy 64.925869 -77.141458) (xy 64.95268 -77.127698) (xy 64.975502 -77.108017) (xy 64.993054 -77.083521)
			(xy 65.004351 -77.055583) (xy 65.006982 -77.04074) (xy 65.009425 -77.025591) (xy 65.016422 -76.995711)
			(xy 65.020952 -76.98105) (xy 65.020952 -76.980796) (xy 65.025663 -76.964068) (xy 65.026901 -76.929352)
			(xy 65.01874 -76.895585) (xy 65.001785 -76.865266) (xy 64.989964 -76.852526) (xy 64.93764 -76.800202)
			(xy 64.93764 -76.269342) (xy 64.937961 -76.248139) (xy 64.943641 -76.206117) (xy 64.95497 -76.165253)
			(xy 64.96304 -76.145644) (xy 64.972281 -76.125257) (xy 64.995743 -76.087137) (xy 65.009776 -76.069698)
			(xy 65.022985 -76.050857) (xy 65.043088 -76.009471) (xy 65.055419 -75.965145) (xy 65.059578 -75.919324)
			(xy 65.055428 -75.873502) (xy 65.043105 -75.829174) (xy 65.02301 -75.787785) (xy 65.009776 -75.768962)
			(xy 64.995732 -75.751531) (xy 64.972267 -75.71341) (xy 64.96304 -75.693016) (xy 64.954979 -75.673403)
			(xy 64.943639 -75.632542) (xy 64.937949 -75.590521) (xy 64.93764 -75.569318) (xy 64.93764 -75.43038)
			(xy 65.006982 -75.360784) (xy 65.250568 -75.117198) (xy 65.259204 -75.08367) (xy 65.262322 -75.072106)
			(xy 65.26982 -75.049355) (xy 65.27419 -75.038204) (xy 65.281905 -75.017766) (xy 65.291009 -74.975042)
			(xy 65.292681 -74.931392) (xy 65.286872 -74.888098) (xy 65.273753 -74.846432) (xy 65.253708 -74.80762)
			(xy 65.227328 -74.772802) (xy 65.195389 -74.743003) (xy 65.158828 -74.719098) (xy 65.11872 -74.70179)
			(xy 65.076246 -74.691588) (xy 65.05448 -74.689716) (xy 64.929766 -74.689716) (xy 64.900021 -74.689196)
			(xy 64.841166 -74.680525) (xy 64.784201 -74.663372) (xy 64.730344 -74.638104) (xy 64.680741 -74.60526)
			(xy 64.636453 -74.565541) (xy 64.598423 -74.519793) (xy 64.567463 -74.468993) (xy 64.55537 -74.441812)
			(xy 64.55537 -74.441558) (xy 64.545718 -74.418698) (xy 64.327786 -74.200766) (xy 64.29502 -74.191876)
			(xy 64.268233 -74.184138) (xy 64.216916 -74.162333) (xy 64.169057 -74.133726) (xy 64.125553 -74.09885)
			(xy 64.087219 -74.058361) (xy 64.054773 -74.013016) (xy 64.028823 -73.963666) (xy 64.009855 -73.911234)
			(xy 63.998225 -73.856703) (xy 63.994151 -73.801095) (xy 63.997708 -73.745451) (xy 64.00883 -73.690814)
			(xy 64.027309 -73.638208) (xy 64.052799 -73.588618) (xy 64.084821 -73.542974) (xy 64.122777 -73.50213)
			(xy 64.165955 -73.466851) (xy 64.213546 -73.4378) (xy 64.264658 -73.415519) (xy 64.318333 -73.400426)
			(xy 64.373567 -73.392805) (xy 64.401446 -73.392284) (xy 64.669924 -73.392284) (xy 65.154048 -73.876408)
			(xy 65.630044 -73.876408) (xy 65.658657 -73.876898) (xy 65.715318 -73.884924) (xy 65.770294 -73.900812)
			(xy 65.822501 -73.924249) (xy 65.870908 -73.95477) (xy 65.91456 -73.991775) (xy 65.952595 -74.034533)
			(xy 65.984261 -74.082199) (xy 66.008935 -74.133832) (xy 66.026129 -74.188414) (xy 66.035504 -74.244867)
			(xy 66.036874 -74.302077) (xy 66.030212 -74.358914) (xy 66.015651 -74.414257) (xy 66.004948 -74.440796)
			(xy 66.000376 -74.451464) (xy 65.98821 -74.477078) (xy 65.957824 -74.524953) (xy 65.921078 -74.56814)
			(xy 65.878685 -74.605799) (xy 65.855342 -74.621898) (xy 65.83045 -74.638408) (xy 65.804034 -74.684128)
			(xy 65.796202 -74.698667) (xy 65.787521 -74.730518) (xy 65.787318 -74.76353) (xy 65.795607 -74.795484)
			(xy 65.803272 -74.810112) (xy 65.827402 -74.853038) (xy 65.850516 -74.869548) (xy 65.880742 -74.893678)
			(xy 65.899482 -74.908153) (xy 65.941178 -74.930586) (xy 65.986307 -74.944908) (xy 66.033308 -74.950624)
			(xy 66.080554 -74.947535) (xy 66.126411 -74.935749) (xy 66.169292 -74.915674) (xy 66.188844 -74.902314)
			(xy 66.210783 -74.887066) (xy 66.25808 -74.862215) (xy 66.283078 -74.852784) (xy 66.31813 -74.840338)
			(xy 66.41084 -74.720704) (xy 66.407284 -74.67981) (xy 66.404998 -74.64171) (xy 66.406268 -74.606912)
			(xy 66.409315 -74.577118) (xy 66.423692 -74.518983) (xy 66.447168 -74.46389) (xy 66.462656 -74.438256)
			(xy 66.482468 -74.407014) (xy 66.482468 -73.822814) (xy 66.938144 -73.367138) (xy 66.954965 -73.350959)
			(xy 66.99262 -73.323387) (xy 67.034033 -73.30187) (xy 67.056 -73.293986) (xy 67.071092 -73.2884)
			(xy 67.098036 -73.270821) (xy 67.119727 -73.247062) (xy 67.134785 -73.218632) (xy 67.142254 -73.18734)
			(xy 67.141658 -73.155174) (xy 67.137788 -73.139554) (xy 67.130346 -73.110875) (xy 67.123391 -73.052037)
			(xy 67.125608 -72.992831) (xy 67.136943 -72.934678) (xy 67.157125 -72.878974) (xy 67.185669 -72.827056)
			(xy 67.20332 -72.803258) (xy 67.229736 -72.768968) (xy 67.229736 -72.296782) (xy 67.230168 -72.273548)
			(xy 67.237214 -72.227617) (xy 67.251156 -72.183289) (xy 67.27167 -72.141594) (xy 67.2846 -72.122284)
			(xy 67.29222 -72.11187) (xy 67.29476 -72.108568) (xy 67.298062 -72.104504) (xy 67.30111 -72.100948)
			(xy 67.31505 -72.081797) (xy 67.336298 -72.039466) (xy 67.349346 -71.993935) (xy 67.353743 -71.946776)
			(xy 67.349337 -71.899618) (xy 67.336281 -71.854089) (xy 67.315025 -71.811763) (xy 67.30111 -71.792592)
			(xy 67.290953 -71.78024) (xy 67.273003 -71.753772) (xy 67.265296 -71.73976) (xy 67.257963 -71.725419)
			(xy 67.245996 -71.695513) (xy 67.24142 -71.68007) (xy 67.23478 -71.654657) (xy 67.22929 -71.602423)
			(xy 67.230498 -71.576184) (xy 67.232855 -71.549515) (xy 67.245722 -71.497549) (xy 67.267459 -71.448626)
			(xy 67.2974 -71.404247) (xy 67.334625 -71.365773) (xy 67.355974 -71.349616) (xy 67.364102 -71.34352)
			(xy 67.536314 -71.171562) (xy 67.544696 -71.136256) (xy 67.551615 -71.108988) (xy 67.572376 -71.056705)
			(xy 67.600589 -71.008036) (xy 67.635641 -70.964036) (xy 67.676772 -70.925658) (xy 67.723092 -70.893735)
			(xy 67.773597 -70.868959) (xy 67.827192 -70.851865) (xy 67.882715 -70.842824) (xy 67.938965 -70.842033)
			(xy 67.994721 -70.849508) (xy 68.048775 -70.865088) (xy 68.099957 -70.888435) (xy 68.123816 -70.903338)
			(xy 68.149216 -70.921372) (xy 68.167842 -70.934105) (xy 68.208585 -70.953475) (xy 68.252108 -70.965346)
			(xy 68.297044 -70.969345) (xy 68.34198 -70.965346) (xy 68.385503 -70.953475) (xy 68.426246 -70.934105)
			(xy 68.444872 -70.921372) (xy 68.462134 -70.908397) (xy 68.499052 -70.885989) (xy 68.518532 -70.876668)
			(xy 68.543964 -70.865511) (xy 68.597245 -70.849846) (xy 68.652233 -70.84207) (xy 68.707768 -70.842347)
			(xy 68.762676 -70.850671) (xy 68.815797 -70.866866) (xy 68.86601 -70.890591) (xy 68.912253 -70.921343)
			(xy 68.95355 -70.958474) (xy 68.989029 -71.001199) (xy 69.01794 -71.048616) (xy 69.039672 -71.099723)
			(xy 69.053766 -71.15344) (xy 69.059925 -71.208633) (xy 69.058018 -71.264135) (xy 69.048087 -71.318775)
			(xy 69.030339 -71.371399) (xy 69.01815 -71.396352) (xy 69.017134 -71.398384) (xy 69.009768 -71.416418)
			(xy 68.985638 -71.449184) (xy 68.97611 -71.461867) (xy 68.955257 -71.485777) (xy 68.943982 -71.496936)
			(xy 68.924424 -71.514716) (xy 68.897754 -71.53529) (xy 68.877597 -71.548998) (xy 68.834477 -71.571736)
			(xy 68.78881 -71.588792) (xy 68.765166 -71.594726) (xy 68.72986 -71.603108) (xy 68.469256 -71.863712)
			(xy 68.458972 -71.87563) (xy 68.444036 -71.903328) (xy 68.436331 -71.933839) (xy 68.436324 -71.965308)
			(xy 68.444017 -71.995822) (xy 68.458941 -72.023527) (xy 68.469256 -72.035416) (xy 68.744592 -72.310752)
			(xy 68.779898 -72.319134) (xy 68.802059 -72.324678) (xy 68.844975 -72.340339) (xy 68.865496 -72.350376)
			(xy 68.881752 -72.359012) (xy 68.893243 -72.365693) (xy 68.915361 -72.380439) (xy 68.925948 -72.388476)
			(xy 68.944574 -72.401209) (xy 68.985317 -72.420579) (xy 69.02884 -72.43245) (xy 69.073776 -72.436449)
			(xy 69.118712 -72.43245) (xy 69.162235 -72.420579) (xy 69.202978 -72.401209) (xy 69.221604 -72.388476)
			(xy 69.241221 -72.373802) (xy 69.283517 -72.349084) (xy 69.305932 -72.3392) (xy 69.328792 -72.329548)
			(xy 69.346318 -72.312022) (xy 69.357676 -72.299852) (xy 69.374274 -72.27101) (xy 69.382867 -72.238862)
			(xy 69.382873 -72.205585) (xy 69.374292 -72.173434) (xy 69.357705 -72.144586) (xy 69.346318 -72.132444)
			(xy 69.304154 -72.09028) (xy 69.303646 -72.089772) (xy 69.24167 -72.027796) (xy 69.219826 -72.005698)
			(xy 69.215 -72.000872) (xy 69.215 -71.550276) (xy 69.220588 -71.544942) (xy 69.299328 -71.466202)
			(xy 69.47408 -71.291704) (xy 69.619622 -71.291704) (xy 69.634766 -71.291265) (xy 69.664197 -71.284114)
			(xy 69.691111 -71.270222) (xy 69.713988 -71.250372) (xy 69.731535 -71.225685) (xy 69.742763 -71.197555)
			(xy 69.747038 -71.167571) (xy 69.744118 -71.137424) (xy 69.734168 -71.108817) (xy 69.726302 -71.09587)
			(xy 69.706744 -71.06539) (xy 69.673724 -71.049642) (xy 69.663818 -71.044816) (xy 69.639251 -71.031867)
			(xy 69.593821 -70.999931) (xy 69.55351 -70.961737) (xy 69.519173 -70.918094) (xy 69.491537 -70.869927)
			(xy 69.471188 -70.818258) (xy 69.464428 -70.791324) (xy 69.456046 -70.756018) (xy 69.248274 -70.548246)
			(xy 69.243956 -70.54469) (xy 69.225524 -70.52862) (xy 69.193536 -70.491636) (xy 69.167875 -70.450013)
			(xy 69.158104 -70.427596) (xy 69.149085 -70.404568) (xy 69.137766 -70.356427) (xy 69.134339 -70.307092)
			(xy 69.138894 -70.257848) (xy 69.144642 -70.233794) (xy 69.153532 -70.205346) (xy 69.161973 -70.183671)
			(xy 69.184471 -70.14296) (xy 69.212883 -70.106132) (xy 69.246552 -70.074039) (xy 69.284699 -70.047424)
			(xy 69.326441 -70.026902) (xy 69.370813 -70.012948) (xy 69.416787 -70.005885) (xy 69.440044 -70.005448)
			(xy 69.568568 -70.005448) (xy 69.582538 -70.019418) (xy 69.647816 -70.084442) (xy 69.665546 -70.100465)
			(xy 69.705782 -70.12624) (xy 69.750125 -70.144043) (xy 69.797013 -70.153247) (xy 69.844795 -70.153529)
			(xy 69.891789 -70.144879) (xy 69.936339 -70.1276) (xy 69.976876 -70.102302) (xy 69.99478 -70.086474)
			(xy 69.995796 -70.085712) (xy 70.012771 -70.070696) (xy 70.050328 -70.045331) (xy 70.091225 -70.025804)
			(xy 70.134562 -70.012545) (xy 70.179384 -70.005844) (xy 70.202044 -70.005448) (xy 70.330568 -70.005448)
			(xy 70.649592 -70.324472) (xy 70.684898 -70.332854) (xy 70.708611 -70.338761) (xy 70.754397 -70.355845)
			(xy 70.797619 -70.378649) (xy 70.837566 -70.406798) (xy 70.85584 -70.423024) (xy 70.864997 -70.431595)
			(xy 70.882283 -70.449771) (xy 70.890384 -70.459346) (xy 70.895464 -70.465442) (xy 70.905159 -70.477874)
			(xy 70.922708 -70.504069) (xy 70.930516 -70.517766) (xy 70.932548 -70.521322) (xy 70.937374 -70.528942)
			(xy 70.945461 -70.540622) (xy 70.965851 -70.560394) (xy 70.9901 -70.575183) (xy 71.017013 -70.584259)
			(xy 71.0311 -70.586092) (xy 71.031354 -70.586092) (xy 71.045364 -70.587117) (xy 71.073244 -70.583734)
			(xy 71.099712 -70.574344) (xy 71.123491 -70.559401) (xy 71.133716 -70.54977) (xy 71.189088 -70.494652)
			(xy 71.19747 -70.459346) (xy 71.203993 -70.433581) (xy 71.223204 -70.384028) (xy 71.249099 -70.337616)
			(xy 71.281179 -70.295242) (xy 71.318824 -70.257725) (xy 71.361306 -70.22579) (xy 71.407806 -70.200052)
			(xy 71.457425 -70.181011) (xy 71.48322 -70.174612) (xy 71.510569 -70.168819) (xy 71.566295 -70.164356)
			(xy 71.594218 -70.165722) (xy 71.606944 -70.166694) (xy 71.632238 -70.170128) (xy 71.644764 -70.17258)
			(xy 71.65999 -70.175233) (xy 71.690862 -70.173935) (xy 71.720519 -70.165262) (xy 71.747226 -70.149721)
			(xy 71.769419 -70.128222) (xy 71.785801 -70.102022) (xy 71.791068 -70.08749) (xy 71.799707 -70.062742)
			(xy 71.824221 -70.016413) (xy 71.856281 -69.974946) (xy 71.894946 -69.939558) (xy 71.939082 -69.911286)
			(xy 71.987394 -69.890958) (xy 72.01281 -69.884544) (xy 72.039179 -69.879076) (xy 72.092961 -69.876396)
			(xy 72.119744 -69.87921) (xy 72.144627 -69.882876) (xy 72.192809 -69.897291) (xy 72.237971 -69.919421)
			(xy 72.278888 -69.948664) (xy 72.297036 -69.966078) (xy 72.531478 -70.20052) (xy 72.548476 -70.216793)
			(xy 72.587304 -70.24337) (xy 72.630362 -70.262343) (xy 72.676177 -70.273064) (xy 72.723182 -70.275167)
			(xy 72.769771 -70.268578) (xy 72.814351 -70.253525) (xy 72.855397 -70.23052) (xy 72.891505 -70.200352)
			(xy 72.921442 -70.164051) (xy 72.944182 -70.122858) (xy 72.952102 -70.100698) (xy 72.953626 -70.095872)
			(xy 72.954642 -70.093078) (xy 72.956674 -70.087236) (xy 72.958452 -70.08241) (xy 72.96658 -70.063106)
			(xy 72.972494 -70.049304) (xy 72.978367 -70.019866) (xy 72.977199 -69.98987) (xy 72.969053 -69.960977)
			(xy 72.95438 -69.934789) (xy 72.933994 -69.912754) (xy 72.909023 -69.896093) (xy 72.88085 -69.885729)
			(xy 72.865996 -69.883528) (xy 72.842918 -69.880398) (xy 72.798013 -69.868055) (xy 72.7555 -69.849045)
			(xy 72.735694 -69.836792) (xy 72.726794 -69.830913) (xy 72.709761 -69.818074) (xy 72.701658 -69.811138)
			(xy 72.685669 -69.796792) (xy 72.657471 -69.764385) (xy 72.634083 -69.728352) (xy 72.624696 -69.70903)
			(xy 72.615295 -69.687721) (xy 72.602339 -69.642987) (xy 72.596324 -69.596805) (xy 72.597389 -69.550244)
			(xy 72.60551 -69.504385) (xy 72.620498 -69.46029) (xy 72.642006 -69.418981) (xy 72.669535 -69.381416)
			(xy 72.685656 -69.364606) (xy 72.825356 -69.224906) (xy 72.836816 -69.212774) (xy 72.853524 -69.183896)
			(xy 72.862172 -69.151674) (xy 72.86217 -69.118312) (xy 72.853518 -69.086091) (xy 72.836807 -69.057215)
			(xy 72.825356 -69.045074) (xy 72.695816 -68.915534) (xy 72.694292 -68.914264) (xy 72.68083 -68.900548)
			(xy 72.664122 -68.882191) (xy 72.636295 -68.841091) (xy 72.625458 -68.81876) (xy 72.615543 -68.796094)
			(xy 72.60238 -68.748409) (xy 72.597113 -68.699221) (xy 72.59988 -68.64983) (xy 72.610608 -68.601538)
			(xy 72.629015 -68.555621) (xy 72.654614 -68.513291) (xy 72.68673 -68.475664) (xy 72.724514 -68.443735)
			(xy 72.766971 -68.418346) (xy 72.789796 -68.408804) (xy 72.809727 -68.400457) (xy 72.846638 -68.377999)
			(xy 72.879214 -68.349615) (xy 72.906514 -68.316126) (xy 72.927749 -68.278497) (xy 72.942307 -68.237817)
			(xy 72.949766 -68.195259) (xy 72.949912 -68.152052) (xy 72.946768 -68.130674) (xy 72.945752 -68.124578)
			(xy 72.943965 -68.111257) (xy 72.942442 -68.084422) (xy 72.942704 -68.070984) (xy 72.942958 -68.065142)
			(xy 72.94347 -68.056337) (xy 72.945376 -68.0388) (xy 72.946768 -68.03009) (xy 72.948546 -68.019676)
			(xy 72.948546 -68.009008) (xy 72.948004 -67.992357) (xy 72.939388 -67.960188) (xy 72.922742 -67.931345)
			(xy 72.899198 -67.907791) (xy 72.870362 -67.891133) (xy 72.838197 -67.882503) (xy 72.821546 -67.882008)
			(xy 72.752204 -67.882008) (xy 72.726971 -67.881516) (xy 72.677193 -67.87321) (xy 72.629461 -67.856824)
			(xy 72.585077 -67.832806) (xy 72.545252 -67.801809) (xy 72.511072 -67.76468) (xy 72.483469 -67.722431)
			(xy 72.463197 -67.676216) (xy 72.450808 -67.627294) (xy 72.44664 -67.577) (xy 72.450808 -67.526706)
			(xy 72.463197 -67.477784) (xy 72.483469 -67.431569) (xy 72.511072 -67.38932) (xy 72.545252 -67.352191)
			(xy 72.585077 -67.321194) (xy 72.629461 -67.297176) (xy 72.677193 -67.28079) (xy 72.726971 -67.272484)
			(xy 72.752204 -67.2719) (xy 72.897746 -67.2719) (xy 72.91438 -67.271325) (xy 72.9465 -67.262652)
			(xy 72.97528 -67.245961) (xy 72.987408 -67.234562) (xy 73.039732 -67.182492) (xy 73.049828 -67.171761)
			(xy 73.065275 -67.146679) (xy 73.074554 -67.118723) (xy 73.077171 -67.089383) (xy 73.072986 -67.060226)
			(xy 73.062222 -67.032806) (xy 73.05421 -67.02044) (xy 73.03854 -66.996658) (xy 73.015397 -66.944627)
			(xy 73.008236 -66.917062) (xy 73.00341 -66.891662) (xy 73.000326 -66.867996) (xy 73.000681 -66.820273)
			(xy 73.008463 -66.773188) (xy 73.023483 -66.727888) (xy 73.045372 -66.685481) (xy 73.073599 -66.646999)
			(xy 73.107474 -66.613382) (xy 73.14617 -66.58545) (xy 73.188744 -66.563885) (xy 73.234156 -66.549212)
			(xy 73.2813 -66.54179) (xy 73.305162 -66.541396) (xy 73.358756 -66.541396) (xy 73.871836 -66.028316)
			(xy 74.181208 -66.028316) (xy 74.250804 -65.95872) (xy 74.250804 -63.068454) (xy 74.574908 -62.74435)
			(xy 74.574908 -61.186568) (xy 74.007472 -60.619132) (xy 72.255888 -60.619132) (xy 71.534528 -61.340492)
			(xy 71.534528 -63.224156) (xy 71.355204 -63.40348) (xy 71.355204 -63.937388) (xy 71.241412 -64.05118)
			(xy 71.235062 -64.092836) (xy 71.230745 -64.118292) (xy 71.214685 -64.167359) (xy 71.190588 -64.213018)
			(xy 71.159142 -64.253964) (xy 71.140574 -64.271906) (xy 71.126013 -64.284951) (xy 71.094165 -64.307626)
			(xy 71.077074 -64.317118) (xy 71.055023 -64.328352) (xy 71.008181 -64.344312) (xy 70.983856 -64.348868)
			(xy 70.974712 -64.350392) (xy 70.930008 -64.356996) (xy 70.687692 -64.356996) (xy 70.637908 -64.379602)
			(xy 70.619874 -64.399922) (xy 70.601681 -64.419864) (xy 70.560644 -64.45493) (xy 70.515073 -64.483863)
			(xy 70.46588 -64.506083) (xy 70.414046 -64.521148) (xy 70.360606 -64.528756) (xy 70.306626 -64.528756)
			(xy 70.253186 -64.521148) (xy 70.201352 -64.506083) (xy 70.152159 -64.483863) (xy 70.106588 -64.45493)
			(xy 70.065551 -64.419864) (xy 70.047358 -64.399922) (xy 70.029324 -64.379602) (xy 69.97954 -64.356996)
			(xy 68.789296 -64.356996) (xy 68.7324 -64.388238) (xy 68.714874 -64.415924) (xy 68.699778 -64.438792)
			(xy 68.664072 -64.480356) (xy 68.622789 -64.516385) (xy 68.576778 -64.546141) (xy 68.526983 -64.569009)
			(xy 68.47443 -64.584522) (xy 68.420199 -64.592358) (xy 68.365405 -64.592358) (xy 68.311174 -64.584522)
			(xy 68.258621 -64.569009) (xy 68.208826 -64.546141) (xy 68.162815 -64.516385) (xy 68.121532 -64.480356)
			(xy 68.085826 -64.438792) (xy 68.07073 -64.415924) (xy 68.053204 -64.388238) (xy 67.996308 -64.356996)
			(xy 67.876674 -64.356996) (xy 67.876674 -64.340486) (xy 67.853498 -64.346921) (xy 67.80582 -64.353257)
			(xy 67.757739 -64.352039) (xy 67.710443 -64.343297) (xy 67.665103 -64.327247) (xy 67.622841 -64.304286)
			(xy 67.584701 -64.274983) (xy 67.551628 -64.240062) (xy 67.52444 -64.200387) (xy 67.503809 -64.15694)
			(xy 67.490245 -64.110795) (xy 67.486784 -64.086994) (xy 67.481196 -64.044068) (xy 67.405758 -63.96863)
			(xy 67.257422 -63.96863) (xy 67.251834 -63.974218) (xy 67.25031 -63.972694) (xy 67.00266 -63.972694)
			(xy 66.986015 -63.973242) (xy 66.953861 -63.981866) (xy 66.925033 -63.998517) (xy 66.901497 -64.022061)
			(xy 66.884853 -64.050892) (xy 66.876238 -64.083049) (xy 66.87566 -64.099694) (xy 66.87566 -64.536574)
			(xy 67.117468 -64.778382) (xy 67.141598 -64.788034) (xy 67.167033 -64.798836) (xy 67.214745 -64.82671)
			(xy 67.257931 -64.861182) (xy 67.295685 -64.901531) (xy 67.327217 -64.946909) (xy 67.339972 -64.971422)
			(xy 67.352133 -64.997038) (xy 67.369605 -65.050982) (xy 67.37477 -65.078864) (xy 67.379308 -65.109441)
			(xy 67.379594 -65.171252) (xy 67.369893 -65.232298) (xy 67.350462 -65.290976) (xy 67.33667 -65.31864)
			(xy 67.336416 -65.319148) (xy 67.321938 -65.346834) (xy 67.321938 -66.050934) (xy 68.824407 -66.050934)
			(xy 68.825573 -65.994991) (xy 68.834898 -65.939818) (xy 68.852183 -65.8866) (xy 68.877056 -65.836477)
			(xy 68.908985 -65.790525) (xy 68.947284 -65.749731) (xy 68.991131 -65.714969) (xy 69.039586 -65.686984)
			(xy 69.091609 -65.666379) (xy 69.118734 -65.659508) (xy 69.15404 -65.651126) (xy 69.38264 -65.422526)
			(xy 69.390768 -65.386966) (xy 69.397 -65.361999) (xy 69.416724 -65.314474) (xy 69.444141 -65.27093)
			(xy 69.478472 -65.232602) (xy 69.518746 -65.200575) (xy 69.563821 -65.175757) (xy 69.61242 -65.158851)
			(xy 69.663167 -65.150336) (xy 69.714622 -65.150454) (xy 69.765329 -65.1592) (xy 69.813851 -65.176327)
			(xy 69.858813 -65.201351) (xy 69.87921 -65.21704) (xy 69.89625 -65.230139) (xy 69.933817 -65.251016)
			(xy 69.974361 -65.265273) (xy 70.016725 -65.272505) (xy 70.059703 -65.272505) (xy 70.102067 -65.265273)
			(xy 70.142611 -65.251016) (xy 70.180178 -65.230139) (xy 70.197218 -65.21704) (xy 70.21769 -65.201311)
			(xy 70.262817 -65.176246) (xy 70.311523 -65.159146) (xy 70.362415 -65.150499) (xy 70.388226 -65.149984)
			(xy 70.579234 -65.149984) (xy 70.86981 -65.44056) (xy 70.905116 -65.448942) (xy 70.93076 -65.455407)
			(xy 70.980086 -65.474486) (xy 71.026309 -65.500184) (xy 71.068548 -65.532009) (xy 71.105997 -65.569354)
			(xy 71.137938 -65.611505) (xy 71.151242 -65.634362) (xy 71.162936 -65.654221) (xy 71.19227 -65.689758)
			(xy 71.227532 -65.71942) (xy 71.267567 -65.742236) (xy 71.31106 -65.757456) (xy 71.356585 -65.764581)
			(xy 71.402649 -65.763378) (xy 71.44774 -65.753885) (xy 71.46925 -65.745614) (xy 71.483749 -65.739844)
			(xy 71.513507 -65.730439) (xy 71.528686 -65.726818) (xy 71.564246 -65.71869) (xy 71.73468 -65.548256)
			(xy 71.782178 -65.548256) (xy 71.866252 -65.464182) (xy 71.884395 -65.446774) (xy 71.925312 -65.417559)
			(xy 71.97048 -65.395478) (xy 72.018666 -65.381132) (xy 72.068556 -65.374914) (xy 72.11879 -65.376991)
			(xy 72.167996 -65.387309) (xy 72.214833 -65.405585) (xy 72.258023 -65.43132) (xy 72.296388 -65.463814)
			(xy 72.328882 -65.502179) (xy 72.354617 -65.545369) (xy 72.372893 -65.592206) (xy 72.383211 -65.641412)
			(xy 72.385288 -65.691646) (xy 72.37907 -65.741536) (xy 72.364724 -65.789722) (xy 72.342643 -65.83489)
			(xy 72.313428 -65.875807) (xy 72.29602 -65.89395) (xy 72.236584 -65.953386) (xy 72.225255 -65.965578)
			(xy 72.208664 -65.994411) (xy 72.200075 -66.026549) (xy 72.20007 -66.059815) (xy 72.20865 -66.091956)
			(xy 72.225234 -66.120794) (xy 72.236584 -66.132964) (xy 72.24268 -66.13906) (xy 72.249284 -66.14414)
			(xy 72.267576 -66.15866) (xy 72.299923 -66.192348) (xy 72.326763 -66.230567) (xy 72.34747 -66.272428)
			(xy 72.361562 -66.316953) (xy 72.36871 -66.363105) (xy 72.369172 -66.386456) (xy 72.369172 -66.51498)
			(xy 72.049894 -66.834004) (xy 72.041512 -66.86931) (xy 72.034773 -66.896089) (xy 72.014586 -66.947487)
			(xy 71.987195 -66.995434) (xy 71.953172 -67.038928) (xy 71.91323 -67.077058) (xy 71.868205 -67.109026)
			(xy 71.819039 -67.134164) (xy 71.76676 -67.151945) (xy 71.712463 -67.161998) (xy 71.657284 -67.164112)
			(xy 71.629778 -67.161664) (xy 71.613484 -67.160413) (xy 71.581185 -67.165312) (xy 71.55119 -67.178257)
			(xy 71.525469 -67.198398) (xy 71.505709 -67.224413) (xy 71.493208 -67.254595) (xy 71.488785 -67.286964)
			(xy 71.492732 -67.319393) (xy 71.504789 -67.349756) (xy 71.524164 -67.376059) (xy 71.53656 -67.386708)
			(xy 71.560944 -67.408298) (xy 72.01154 -67.859148) (xy 72.01154 -68.458588) (xy 72.030844 -68.489576)
			(xy 72.044706 -68.512875) (xy 72.066456 -68.562534) (xy 72.080959 -68.614772) (xy 72.087922 -68.668536)
			(xy 72.087205 -68.722745) (xy 72.078822 -68.776306) (xy 72.062943 -68.828142) (xy 72.039887 -68.877208)
			(xy 72.010118 -68.922517) (xy 71.974236 -68.963156) (xy 71.932963 -68.998308) (xy 71.88713 -69.027263)
			(xy 71.83766 -69.04944) (xy 71.78555 -69.064392) (xy 71.731847 -69.071818) (xy 71.677634 -69.071568)
			(xy 71.624003 -69.063646) (xy 71.572032 -69.048214) (xy 71.522769 -69.025581) (xy 71.49973 -69.011292)
			(xy 71.480836 -68.999723) (xy 71.440006 -68.982543) (xy 71.396816 -68.972703) (xy 71.352573 -68.970503)
			(xy 71.308619 -68.976007) (xy 71.266286 -68.989051) (xy 71.226856 -69.009238) (xy 71.2089 -69.022214)
			(xy 71.186816 -69.038362) (xy 71.138899 -69.064764) (xy 71.087703 -69.084054) (xy 71.034277 -69.095836)
			(xy 70.979716 -69.099868) (xy 70.925139 -69.096069) (xy 70.871663 -69.084515) (xy 70.820385 -69.065445)
			(xy 70.772356 -69.039247) (xy 70.750176 -69.02323) (xy 70.731164 -69.009634) (xy 70.689281 -68.988902)
			(xy 70.644313 -68.976176) (xy 70.597776 -68.971886) (xy 70.551239 -68.976176) (xy 70.506271 -68.988902)
			(xy 70.464388 -69.009634) (xy 70.445376 -69.02323) (xy 70.423285 -69.039192) (xy 70.375454 -69.065315)
			(xy 70.324391 -69.084364) (xy 70.271137 -69.09595) (xy 70.216776 -69.099839) (xy 70.162415 -69.09595)
			(xy 70.109161 -69.084364) (xy 70.058098 -69.065315) (xy 70.010267 -69.039192) (xy 69.988176 -69.02323)
			(xy 69.969164 -69.009634) (xy 69.927281 -68.988902) (xy 69.882313 -68.976176) (xy 69.835776 -68.971886)
			(xy 69.789239 -68.976176) (xy 69.744271 -68.988902) (xy 69.702388 -69.009634) (xy 69.683376 -69.02323)
			(xy 69.661388 -69.039134) (xy 69.613792 -69.065198) (xy 69.562982 -69.084254) (xy 69.509985 -69.095917)
			(xy 69.455869 -69.099952) (xy 69.401728 -69.096277) (xy 69.348654 -69.084966) (xy 69.297719 -69.066248)
			(xy 69.24995 -69.040501) (xy 69.206312 -69.008245) (xy 69.167686 -68.970129) (xy 69.134851 -68.926925)
			(xy 69.108471 -68.879503) (xy 69.089077 -68.828821) (xy 69.077061 -68.775903) (xy 69.072665 -68.721815)
			(xy 69.075979 -68.667651) (xy 69.086936 -68.614503) (xy 69.105313 -68.563444) (xy 69.130741 -68.515505)
			(xy 69.162707 -68.471653) (xy 69.200564 -68.432773) (xy 69.243548 -68.399651) (xy 69.290793 -68.372955)
			(xy 69.341344 -68.353224) (xy 69.367654 -68.346574) (xy 69.40296 -68.338192) (xy 69.542152 -68.199)
			(xy 69.551042 -68.181982) (xy 69.560299 -68.165049) (xy 69.582467 -68.133459) (xy 69.595238 -68.11899)
			(xy 69.606166 -68.106363) (xy 69.621438 -68.076672) (xy 69.628493 -68.044037) (xy 69.626848 -68.010688)
			(xy 69.616617 -67.978906) (xy 69.598497 -67.950861) (xy 69.573728 -67.928471) (xy 69.544003 -67.913266)
			(xy 69.511352 -67.906284) (xy 69.494654 -67.906646) (xy 69.467021 -67.907726) (xy 69.411947 -67.902702)
			(xy 69.358175 -67.889781) (xy 69.306831 -67.869233) (xy 69.258992 -67.841488) (xy 69.215658 -67.807128)
			(xy 69.177739 -67.766872) (xy 69.146029 -67.721564) (xy 69.12119 -67.672153) (xy 69.103745 -67.619674)
			(xy 69.094059 -67.565226) (xy 69.092334 -67.50995) (xy 69.098606 -67.455005) (xy 69.112744 -67.40154)
			(xy 69.134453 -67.350676) (xy 69.163276 -67.303479) (xy 69.198611 -67.260937) (xy 69.239717 -67.223941)
			(xy 69.285734 -67.193267) (xy 69.310504 -67.180968) (xy 69.343778 -67.16522) (xy 69.383148 -67.103244)
			(xy 69.383148 -66.979038) (xy 69.383669 -66.953804) (xy 69.391976 -66.904023) (xy 69.408363 -66.856289)
			(xy 69.432384 -66.811903) (xy 69.463382 -66.772077) (xy 69.500513 -66.737895) (xy 69.542764 -66.710291)
			(xy 69.588981 -66.690018) (xy 69.637906 -66.677629) (xy 69.688202 -66.673462) (xy 69.738498 -66.677629)
			(xy 69.787423 -66.690018) (xy 69.83364 -66.710291) (xy 69.875891 -66.737895) (xy 69.913022 -66.772077)
			(xy 69.94402 -66.811903) (xy 69.968041 -66.856289) (xy 69.984428 -66.904023) (xy 69.992735 -66.953804)
			(xy 69.993256 -66.979038) (xy 69.993256 -67.43827) (xy 69.854064 -67.577462) (xy 69.845682 -67.612768)
			(xy 69.840251 -67.634518) (xy 69.824973 -67.676666) (xy 69.815202 -67.696842) (xy 69.805348 -67.717642)
			(xy 69.792418 -67.761807) (xy 69.787658 -67.80758) (xy 69.791222 -67.853461) (xy 69.802995 -67.897949)
			(xy 69.82259 -67.939587) (xy 69.849367 -67.977014) (xy 69.88245 -68.009003) (xy 69.920755 -68.034508)
			(xy 69.941694 -68.04406) (xy 69.965564 -68.054907) (xy 70.009499 -68.083509) (xy 70.02907 -68.100956)
			(xy 70.046866 -68.116777) (xy 70.087153 -68.142147) (xy 70.131461 -68.15957) (xy 70.178239 -68.168437)
			(xy 70.225849 -68.168437) (xy 70.272627 -68.15957) (xy 70.316935 -68.142147) (xy 70.357222 -68.116777)
			(xy 70.375018 -68.100956) (xy 70.393985 -68.08398) (xy 70.436464 -68.055942) (xy 70.483007 -68.035341)
			(xy 70.532322 -68.022747) (xy 70.583044 -68.01851) (xy 70.633766 -68.022747) (xy 70.683081 -68.035341)
			(xy 70.729624 -68.055942) (xy 70.772103 -68.08398) (xy 70.79107 -68.100956) (xy 70.808866 -68.116777)
			(xy 70.849153 -68.142147) (xy 70.893461 -68.15957) (xy 70.940239 -68.168437) (xy 70.987849 -68.168437)
			(xy 71.034627 -68.15957) (xy 71.078935 -68.142147) (xy 71.119222 -68.116777) (xy 71.137018 -68.100956)
			(xy 71.162926 -68.079366) (xy 71.170292 -68.073778) (xy 71.176642 -68.067428) (xy 71.188092 -68.055286)
			(xy 71.204805 -68.026411) (xy 71.213459 -67.99419) (xy 71.213461 -67.960827) (xy 71.204812 -67.928605)
			(xy 71.188103 -67.899727) (xy 71.176642 -67.887596) (xy 71.129144 -67.840098) (xy 71.113228 -67.82358)
			(xy 71.086026 -67.786649) (xy 71.064664 -67.746059) (xy 71.056754 -67.724528) (xy 71.051335 -67.710135)
			(xy 71.034633 -67.68432) (xy 71.012223 -67.663269) (xy 70.985416 -67.648212) (xy 70.955778 -67.640028)
			(xy 70.940422 -67.639184) (xy 70.911866 -67.637834) (xy 70.855603 -67.627709) (xy 70.801482 -67.6093)
			(xy 70.750715 -67.58302) (xy 70.704438 -67.549458) (xy 70.663689 -67.509365) (xy 70.629379 -67.463639)
			(xy 70.602278 -67.413306) (xy 70.582993 -67.359491) (xy 70.571955 -67.3034) (xy 70.569411 -67.246291)
			(xy 70.57542 -67.189441) (xy 70.589845 -67.134125) (xy 70.612365 -67.081582) (xy 70.626986 -67.057016)
			(xy 70.646036 -67.026028) (xy 70.646036 -66.906648) (xy 70.172326 -66.432938) (xy 70.15425 -66.414167)
			(xy 70.12423 -66.371572) (xy 70.101872 -66.324502) (xy 70.087824 -66.274321) (xy 70.082491 -66.222485)
			(xy 70.086031 -66.170495) (xy 70.098338 -66.119858) (xy 70.119058 -66.072044) (xy 70.147589 -66.028438)
			(xy 70.16496 -66.009012) (xy 70.179244 -65.993016) (xy 70.202759 -65.957156) (xy 70.219911 -65.917853)
			(xy 70.230212 -65.876227) (xy 70.233368 -65.833461) (xy 70.229291 -65.790773) (xy 70.218095 -65.749378)
			(xy 70.2001 -65.710454) (xy 70.188328 -65.692528) (xy 70.181724 -65.682622) (xy 70.173596 -65.674494)
			(xy 70.161464 -65.663033) (xy 70.132585 -65.646324) (xy 70.100362 -65.637673) (xy 70.066998 -65.637673)
			(xy 70.034775 -65.646324) (xy 70.005896 -65.663033) (xy 69.993764 -65.674494) (xy 69.585586 -66.082672)
			(xy 69.577204 -66.117978) (xy 69.570441 -66.145129) (xy 69.549844 -66.197155) (xy 69.521868 -66.245615)
			(xy 69.487114 -66.289468) (xy 69.446326 -66.327774) (xy 69.40038 -66.35971) (xy 69.350261 -66.384592)
			(xy 69.297046 -66.401886) (xy 69.241875 -66.411221) (xy 69.185932 -66.412397) (xy 69.130417 -66.405387)
			(xy 69.076522 -66.390344) (xy 69.025403 -66.367589) (xy 68.978156 -66.33761) (xy 68.935795 -66.301051)
			(xy 68.899229 -66.258697) (xy 68.869242 -66.211455) (xy 68.846479 -66.16034) (xy 68.831426 -66.106447)
			(xy 68.824407 -66.050934) (xy 67.321938 -66.050934) (xy 67.321938 -66.592196) (xy 67.253358 -66.660776)
			(xy 67.247008 -66.701416) (xy 67.242228 -66.728594) (xy 67.225872 -66.781295) (xy 67.202101 -66.831094)
			(xy 67.17141 -66.876953) (xy 67.153282 -66.897758) (xy 67.135804 -66.916472) (xy 67.096691 -66.949519)
			(xy 67.053508 -66.977037) (xy 67.007032 -66.998532) (xy 66.958099 -67.013617) (xy 66.907588 -67.022021)
			(xy 66.88201 -67.023234) (xy 66.856674 -67.02363) (xy 66.80626 -67.018526) (xy 66.756967 -67.006782)
			(xy 66.733166 -66.998088) (xy 66.710718 -66.989072) (xy 66.66811 -66.966163) (xy 66.628746 -66.938042)
			(xy 66.610738 -66.921888) (xy 66.594483 -66.907084) (xy 66.557879 -66.882735) (xy 66.517632 -66.865047)
			(xy 66.474942 -66.854546) (xy 66.431082 -66.851545) (xy 66.387359 -66.856135) (xy 66.345078 -66.868178)
			(xy 66.305499 -66.887314) (xy 66.287396 -66.89979) (xy 66.280538 -66.90487) (xy 66.253238 -66.923656)
			(xy 66.193591 -66.952519) (xy 66.16192 -66.962274) (xy 66.140838 -66.967862) (xy 66.109596 -66.974974)
			(xy 66.008758 -67.062604) (xy 65.996566 -67.09537) (xy 65.995042 -67.098672) (xy 65.984178 -67.122692)
			(xy 65.955442 -67.166884) (xy 65.937892 -67.186556) (xy 65.922118 -67.204389) (xy 65.89685 -67.244734)
			(xy 65.879535 -67.289078) (xy 65.870778 -67.335871) (xy 65.870885 -67.383475) (xy 65.879854 -67.430228)
			(xy 65.897369 -67.474493) (xy 65.92282 -67.514724) (xy 65.938654 -67.532504) (xy 65.94856 -67.54368)
			(xy 65.964816 -67.562984) (xy 66.007742 -67.585082) (xy 66.021336 -67.591556) (xy 66.050603 -67.598603)
			(xy 66.080705 -67.598603) (xy 66.109972 -67.591556) (xy 66.123566 -67.585082) (xy 66.160142 -67.566286)
			(xy 66.176906 -67.545712) (xy 66.194653 -67.524919) (xy 66.236153 -67.489343) (xy 66.283271 -67.461633)
			(xy 66.334533 -67.442656) (xy 66.388335 -67.433005) (xy 66.415666 -67.432428) (xy 66.57086 -67.432428)
			(xy 66.86677 -67.728592) (xy 66.901314 -67.736974) (xy 66.938144 -67.74815) (xy 66.962113 -67.757181)
			(xy 67.007582 -67.780768) (xy 67.049477 -67.810238) (xy 67.087044 -67.845059) (xy 67.119603 -67.884601)
			(xy 67.13347 -67.906138) (xy 67.147298 -67.929315) (xy 67.169004 -67.978728) (xy 67.183536 -68.030704)
			(xy 67.190604 -68.084209) (xy 67.190068 -68.138176) (xy 67.181937 -68.19153) (xy 67.166374 -68.243207)
			(xy 67.143689 -68.292178) (xy 67.129406 -68.315078) (xy 67.111372 -68.340478) (xy 67.098641 -68.359104)
			(xy 67.079274 -68.399847) (xy 67.067405 -68.44337) (xy 67.063408 -68.488305) (xy 67.067407 -68.533239)
			(xy 67.079277 -68.576762) (xy 67.098646 -68.617504) (xy 67.111372 -68.636134) (xy 67.125565 -68.655146)
			(xy 67.149633 -68.696035) (xy 67.159378 -68.717668) (xy 67.169944 -68.743306) (xy 67.184388 -68.796843)
			(xy 67.190928 -68.851907) (xy 67.189425 -68.907338) (xy 67.179912 -68.961967) (xy 67.162588 -69.014643)
			(xy 67.137819 -69.064254) (xy 67.106127 -69.109756) (xy 67.06818 -69.15019) (xy 67.024778 -69.184702)
			(xy 66.976836 -69.212566) (xy 66.925364 -69.233194) (xy 66.89852 -69.240146) (xy 66.863722 -69.248528)
			(xy 66.737738 -69.374512) (xy 66.631566 -69.480938) (xy 66.613338 -69.498429) (xy 66.572227 -69.527781)
			(xy 66.526846 -69.549967) (xy 66.478431 -69.56438) (xy 66.428305 -69.570628) (xy 66.377834 -69.568541)
			(xy 66.328395 -69.558175) (xy 66.281337 -69.539812) (xy 66.237943 -69.513955) (xy 66.199396 -69.481308)
			(xy 66.166749 -69.442761) (xy 66.140892 -69.399367) (xy 66.122529 -69.352309) (xy 66.112163 -69.30287)
			(xy 66.110076 -69.252399) (xy 66.116324 -69.202273) (xy 66.130737 -69.153858) (xy 66.152923 -69.108477)
			(xy 66.182275 -69.067366) (xy 66.199766 -69.049138) (xy 66.388488 -68.860416) (xy 66.429382 -68.819776)
			(xy 66.43751 -68.783962) (xy 66.442601 -68.763051) (xy 66.456862 -68.722442) (xy 66.465958 -68.702936)
			(xy 66.474781 -68.685335) (xy 66.495523 -68.651867) (xy 66.50736 -68.636134) (xy 66.520095 -68.617509)
			(xy 66.539469 -68.576766) (xy 66.551343 -68.533242) (xy 66.555343 -68.488305) (xy 66.551345 -68.443368)
			(xy 66.539472 -68.399843) (xy 66.5201 -68.359099) (xy 66.50736 -68.340478) (xy 66.499329 -68.329887)
			(xy 66.484584 -68.307769) (xy 66.477896 -68.296282) (xy 66.465287 -68.273285) (xy 66.445785 -68.224598)
			(xy 66.439034 -68.199254) (xy 66.439034 -68.199) (xy 66.430398 -68.16471) (xy 66.288666 -68.022978)
			(xy 66.271648 -68.014088) (xy 66.252201 -68.003372) (xy 66.216329 -67.977205) (xy 66.184585 -67.946159)
			(xy 66.17081 -67.928744) (xy 66.16573 -67.921886) (xy 66.159888 -67.916044) (xy 66.147756 -67.904583)
			(xy 66.118877 -67.887874) (xy 66.086654 -67.879223) (xy 66.05329 -67.879223) (xy 66.021067 -67.887874)
			(xy 65.992188 -67.904583) (xy 65.980056 -67.916044) (xy 65.949322 -67.946778) (xy 65.934427 -67.96231)
			(xy 65.909561 -67.997427) (xy 65.890972 -68.036235) (xy 65.879192 -68.077621) (xy 65.874558 -68.1204)
			(xy 65.877203 -68.163349) (xy 65.887051 -68.205236) (xy 65.903819 -68.244864) (xy 65.927029 -68.281098)
			(xy 65.941194 -68.297298) (xy 65.958478 -68.317089) (xy 65.986698 -68.361407) (xy 65.997328 -68.385436)
			(xy 66.00698 -68.411852) (xy 66.009816 -68.421301) (xy 66.014393 -68.440493) (xy 66.016124 -68.450206)
			(xy 66.01827 -68.463308) (xy 66.02056 -68.489762) (xy 66.020696 -68.503038) (xy 66.020696 -68.63715)
			(xy 65.721992 -68.935854) (xy 65.71361 -68.97116) (xy 65.70768 -68.994804) (xy 65.690615 -69.040467)
			(xy 65.667873 -69.083584) (xy 65.654174 -69.103748) (xy 65.6336 -69.130418) (xy 65.61582 -69.149976)
			(xy 65.596998 -69.168696) (xy 65.555086 -69.201277) (xy 65.509061 -69.227728) (xy 65.459811 -69.24754)
			(xy 65.408289 -69.260329) (xy 65.355492 -69.265847) (xy 65.302439 -69.263988) (xy 65.250157 -69.254789)
			(xy 65.199657 -69.238426) (xy 65.151914 -69.215216) (xy 65.107852 -69.185608) (xy 65.087754 -69.168264)
			(xy 65.079408 -69.160679) (xy 65.063523 -69.144666) (xy 65.056004 -69.13626) (xy 65.038179 -69.115289)
			(xy 65.008114 -69.06919) (xy 64.984979 -69.019252) (xy 64.969252 -68.96651) (xy 64.96126 -68.912056)
			(xy 64.961168 -68.857019) (xy 64.968978 -68.802539) (xy 64.984528 -68.749745) (xy 64.995552 -68.724526)
			(xy 65.004865 -68.705042) (xy 65.027272 -68.668122) (xy 65.040256 -68.650866) (xy 65.052994 -68.632241)
			(xy 65.072374 -68.591497) (xy 65.084253 -68.547971) (xy 65.088259 -68.503031) (xy 65.084264 -68.45809)
			(xy 65.072395 -68.414561) (xy 65.053025 -68.373812) (xy 65.040256 -68.35521) (xy 65.022222 -68.32981)
			(xy 65.007323 -68.305947) (xy 64.983942 -68.25478) (xy 64.968328 -68.200735) (xy 64.960819 -68.144983)
			(xy 64.961579 -68.088732) (xy 64.970589 -68.033203) (xy 64.987656 -67.979598) (xy 65.012409 -67.929081)
			(xy 65.044312 -67.882746) (xy 65.082673 -67.841598) (xy 65.12666 -67.806529) (xy 65.17532 -67.778299)
			(xy 65.227597 -67.75752) (xy 65.254886 -67.75069) (xy 65.290446 -67.742308) (xy 65.320926 -67.711574)
			(xy 65.462658 -67.569842) (xy 65.472056 -67.557142) (xy 65.476374 -67.551554) (xy 65.498726 -67.526408)
			(xy 65.511426 -67.514216) (xy 65.519554 -67.507104) (xy 65.533237 -67.49473) (xy 65.553417 -67.463865)
			(xy 65.563914 -67.428515) (xy 65.564512 -67.410076) (xy 65.563966 -67.393429) (xy 65.555344 -67.361271)
			(xy 65.538695 -67.332439) (xy 65.515151 -67.308898) (xy 65.486318 -67.292251) (xy 65.454159 -67.283632)
			(xy 65.437512 -67.283076) (xy 65.407032 -67.283076) (xy 65.20688 -67.08267) (xy 65.17132 -67.074542)
			(xy 65.144169 -67.067799) (xy 65.09206 -67.047444) (xy 65.043481 -67.019699) (xy 64.999474 -66.985159)
			(xy 64.96098 -66.944565) (xy 64.928825 -66.898786) (xy 64.903698 -66.848803) (xy 64.886137 -66.795687)
			(xy 64.876518 -66.740577) (xy 64.875048 -66.684653) (xy 64.881759 -66.629113) (xy 64.896505 -66.575148)
			(xy 64.918972 -66.523914) (xy 64.948678 -66.476509) (xy 64.984986 -66.433949) (xy 65.005712 -66.415158)
			(xy 65.021495 -66.400795) (xy 65.048496 -66.367753) (xy 65.069601 -66.330667) (xy 65.084218 -66.290577)
			(xy 65.091935 -66.24861) (xy 65.092536 -66.205943) (xy 65.086005 -66.163774) (xy 65.072524 -66.123289)
			(xy 65.062862 -66.104262) (xy 65.044352 -66.084315) (xy 65.012531 -66.040171) (xy 64.987202 -65.992009)
			(xy 64.968863 -65.940775) (xy 64.957874 -65.88748) (xy 64.954453 -65.83317) (xy 64.958666 -65.778917)
			(xy 64.970431 -65.725787) (xy 64.97955 -65.700148) (xy 64.98485 -65.684598) (xy 64.988169 -65.651926)
			(xy 64.983022 -65.619492) (xy 64.969749 -65.589453) (xy 64.949235 -65.563809) (xy 64.93637 -65.55359)
			(xy 64.935608 -65.553082) (xy 64.921892 -65.54216) (xy 64.902105 -65.52532) (xy 64.866823 -65.487177)
			(xy 64.837042 -65.444601) (xy 64.813314 -65.398377) (xy 64.80429 -65.374012) (xy 64.795627 -65.352692)
			(xy 64.771758 -65.313353) (xy 64.741195 -65.278954) (xy 64.704938 -65.250621) (xy 64.664172 -65.229279)
			(xy 64.620229 -65.215627) (xy 64.574546 -65.21011) (xy 64.528617 -65.212909) (xy 64.483942 -65.223933)
			(xy 64.441982 -65.24282) (xy 64.40411 -65.268955) (xy 64.387476 -65.284858) (xy 64.037718 -65.634616)
			(xy 64.020954 -65.704212) (xy 64.031876 -65.738248) (xy 64.038988 -65.763902) (xy 64.04229 -65.779904)
			(xy 64.042798 -65.783714) (xy 64.044833 -65.796699) (xy 64.046995 -65.822895) (xy 64.047116 -65.836038)
			(xy 64.047116 -65.97523) (xy 63.995808 -66.026792) (xy 63.973964 -66.048636) (xy 63.958688 -66.065732)
			(xy 63.933942 -66.104321) (xy 63.916522 -66.146725) (xy 63.906996 -66.191567) (xy 63.905671 -66.23739)
			(xy 63.912591 -66.282707) (xy 63.927532 -66.326046) (xy 63.950007 -66.366001) (xy 63.964312 -66.383916)
			(xy 63.967106 -66.386964) (xy 63.974001 -66.394901) (xy 63.98684 -66.41155) (xy 63.99276 -66.420238)
			(xy 64.005597 -66.440042) (xy 64.025912 -66.482638) (xy 64.039711 -66.527768) (xy 64.046692 -66.574442)
			(xy 64.047116 -66.598038) (xy 64.047116 -66.73723) (xy 64.044068 -66.740278) (xy 64.043814 -66.740786)
			(xy 64.043306 -66.741294) (xy 64.026963 -66.758375) (xy 64.000297 -66.797404) (xy 63.981311 -66.840692)
			(xy 63.970661 -66.886745) (xy 63.968712 -66.933974) (xy 63.975534 -66.980747) (xy 63.990891 -67.025452)
			(xy 64.014251 -67.066545) (xy 64.029082 -67.084956) (xy 64.041099 -67.098305) (xy 64.062977 -67.126795)
			(xy 64.07277 -67.141852) (xy 64.084278 -67.160573) (xy 64.103624 -67.200031) (xy 64.111378 -67.220592)
			(xy 64.122887 -67.254297) (xy 64.135272 -67.324429) (xy 64.136016 -67.360038) (xy 64.136016 -67.58432)
			(xy 64.024764 -67.695572) (xy 64.01689 -67.703446) (xy 63.823596 -67.896994) (xy 63.716154 -68.004436)
			(xy 63.344552 -68.004436) (xy 63.328416 -68.004909) (xy 63.297179 -68.01301) (xy 63.268982 -68.028706)
			(xy 63.245637 -68.050986) (xy 63.228645 -68.078421) (xy 63.219096 -68.109247) (xy 63.217806 -68.12534)
			(xy 63.215943 -68.153675) (xy 63.204881 -68.209371) (xy 63.185687 -68.262812) (xy 63.158784 -68.312819)
			(xy 63.124766 -68.358285) (xy 63.084386 -68.398208) (xy 63.038535 -68.431705) (xy 62.988225 -68.458036)
			(xy 62.934569 -68.47662) (xy 62.878751 -68.487047) (xy 62.822004 -68.489085) (xy 62.765581 -68.48269)
			(xy 62.71073 -68.468004) (xy 62.658661 -68.44535) (xy 62.634368 -68.430648) (xy 62.60338 -68.411344)
			(xy 62.553342 -68.411344) (xy 62.304422 -68.162424) (xy 62.29229 -68.150963) (xy 62.263411 -68.134254)
			(xy 62.231188 -68.125603) (xy 62.197824 -68.125603) (xy 62.165601 -68.134254) (xy 62.136722 -68.150963)
			(xy 62.12459 -68.162424) (xy 62.113523 -68.174212) (xy 62.097194 -68.20211) (xy 62.0884 -68.233215)
			(xy 62.087703 -68.265532) (xy 62.09515 -68.296987) (xy 62.102238 -68.311522) (xy 62.107509 -68.321631)
			(xy 62.117043 -68.342343) (xy 62.121288 -68.352924) (xy 62.128145 -68.370864) (xy 62.138828 -68.407757)
			(xy 62.142624 -68.426584) (xy 62.143386 -68.431156) (xy 62.146376 -68.448975) (xy 62.149559 -68.48497)
			(xy 62.149736 -68.503038) (xy 62.149736 -68.67906) (xy 62.085982 -68.743068) (xy 62.034674 -68.794376)
			(xy 62.023329 -68.806523) (xy 62.006751 -68.835316) (xy 61.998174 -68.867414) (xy 61.998181 -68.900639)
			(xy 62.006771 -68.932734) (xy 62.023362 -68.96152) (xy 62.034674 -68.9737) (xy 62.085982 -69.025008)
			(xy 62.149736 -69.089016) (xy 62.149736 -69.265038) (xy 62.149218 -69.294488) (xy 62.140731 -69.352774)
			(xy 62.123926 -69.409227) (xy 62.099153 -69.462665) (xy 62.066932 -69.51197) (xy 62.027936 -69.556113)
			(xy 61.98298 -69.594169) (xy 61.933005 -69.625343) (xy 61.879057 -69.648982) (xy 61.822262 -69.664593)
			(xy 61.76381 -69.671848) (xy 61.704923 -69.670596) (xy 61.646832 -69.660863) (xy 61.618622 -69.652388)
			(xy 61.589851 -69.642548) (xy 61.535377 -69.615533) (xy 61.485533 -69.580707) (xy 61.441432 -69.538847)
			(xy 61.42228 -69.515228) (xy 61.421264 -69.513704) (xy 61.420502 -69.512688) (xy 61.417708 -69.509132)
			(xy 61.41212 -69.501766) (xy 61.140594 -69.23024) (xy 61.12974 -69.219927) (xy 61.104252 -69.204235)
			(xy 61.075802 -69.194936) (xy 61.045965 -69.192546) (xy 61.016397 -69.197196) (xy 61.002418 -69.202554)
			(xy 60.94222 -69.227446) (xy 60.928506 -69.233548) (xy 60.904194 -69.251139) (xy 60.884657 -69.273918)
			(xy 60.870975 -69.300627) (xy 60.863903 -69.32979) (xy 60.86348 -69.344794) (xy 60.86348 -69.646038)
			(xy 60.862962 -69.675085) (xy 60.854694 -69.732589) (xy 60.838327 -69.788331) (xy 60.814194 -69.841175)
			(xy 60.782785 -69.890048) (xy 60.744741 -69.933953) (xy 60.700836 -69.971997) (xy 60.651963 -70.003406)
			(xy 60.599119 -70.027539) (xy 60.543377 -70.043906) (xy 60.485873 -70.052174) (xy 60.427779 -70.052174)
			(xy 60.370275 -70.043906) (xy 60.314533 -70.027539) (xy 60.261689 -70.003406) (xy 60.212816 -69.971997)
			(xy 60.168911 -69.933953) (xy 60.130867 -69.890048) (xy 60.099458 -69.841175) (xy 60.075325 -69.788331)
			(xy 60.058958 -69.732589) (xy 60.05069 -69.675085) (xy 60.050172 -69.646038) (xy 60.050172 -68.713604)
			(xy 60.24372 -68.520056) (xy 60.255069 -68.507886) (xy 60.27165 -68.479048) (xy 60.280228 -68.446909)
			(xy 60.280222 -68.413645) (xy 60.271632 -68.381508) (xy 60.255041 -68.352677) (xy 60.24372 -68.340478)
			(xy 60.242958 -68.339716) (xy 60.238894 -68.335652) (xy 60.236862 -68.33362) (xy 60.21832 -68.312538)
			(xy 60.204102 -68.294029) (xy 60.180861 -68.253556) (xy 60.164048 -68.210018) (xy 60.15863 -68.187316)
			(xy 60.148978 -68.143628) (xy 60.079382 -68.087494) (xy 59.712098 -68.087494) (xy 59.689324 -68.108413)
			(xy 59.639333 -68.144814) (xy 59.585063 -68.17446) (xy 59.527422 -68.196856) (xy 59.467372 -68.211627)
			(xy 59.405919 -68.218526) (xy 59.344089 -68.217438) (xy 59.282916 -68.208381) (xy 59.223424 -68.191507)
			(xy 59.166606 -68.167097) (xy 59.113412 -68.13556) (xy 59.064733 -68.097424) (xy 59.021381 -68.053324)
			(xy 58.984082 -68.004) (xy 58.953459 -67.950275) (xy 58.930024 -67.893048) (xy 58.91417 -67.833276)
			(xy 58.90616 -67.771957) (xy 58.905648 -67.741038) (xy 58.905648 -67.511168) (xy 59.05627 -67.360546)
			(xy 59.06639 -67.349863) (xy 59.0819 -67.324866) (xy 59.091257 -67.296976) (xy 59.093963 -67.267682)
			(xy 59.089872 -67.23855) (xy 59.079203 -67.211135) (xy 59.071256 -67.198748) (xy 59.032902 -67.142868)
			(xy 58.9153 -67.1195) (xy 58.831226 -67.169538) (xy 58.81497 -67.195446) (xy 58.798909 -67.220017)
			(xy 58.760843 -67.2647) (xy 58.716752 -67.303451) (xy 58.66755 -67.335464) (xy 58.614259 -67.360076)
			(xy 58.557985 -67.376775) (xy 58.499896 -67.385216) (xy 58.470546 -67.385692) (xy 57.97042 -67.385692)
			(xy 57.58942 -67.766692) (xy 57.397142 -67.766692) (xy 57.368217 -67.766179) (xy 57.310952 -67.757973)
			(xy 57.255427 -67.741735) (xy 57.202764 -67.717793) (xy 57.154025 -67.68663) (xy 57.110194 -67.648875)
			(xy 57.072155 -67.605289) (xy 57.040676 -67.556754) (xy 57.016393 -67.504247) (xy 56.999795 -67.448829)
			(xy 56.991218 -67.391618) (xy 56.990834 -67.333769) (xy 56.998652 -67.27645) (xy 57.014513 -67.220817)
			(xy 57.025794 -67.194176) (xy 57.026048 -67.193414) (xy 57.036058 -67.171901) (xy 57.060378 -67.131156)
			(xy 57.074562 -67.112134) (xy 57.088019 -67.093737) (xy 57.108846 -67.053198) (xy 57.122111 -67.009595)
			(xy 57.127388 -66.964326) (xy 57.124509 -66.918841) (xy 57.113566 -66.874598) (xy 57.09491 -66.833016)
			(xy 57.082436 -66.813938) (xy 57.067867 -66.79192) (xy 57.04428 -66.744687) (xy 57.027432 -66.694652)
			(xy 57.017646 -66.642772) (xy 57.01511 -66.590038) (xy 57.01987 -66.537458) (xy 57.031837 -66.486037)
			(xy 57.050782 -66.436758) (xy 57.076342 -66.390562) (xy 57.091834 -66.369184) (xy 57.105396 -66.350178)
			(xy 57.126072 -66.308323) (xy 57.138763 -66.263397) (xy 57.143042 -66.216909) (xy 57.138766 -66.170421)
			(xy 57.126078 -66.125494) (xy 57.105405 -66.083637) (xy 57.091834 -66.064638) (xy 57.075896 -66.042534)
			(xy 57.049781 -65.994706) (xy 57.030737 -65.943649) (xy 57.01915 -65.890403) (xy 57.015257 -65.836049)
			(xy 57.019136 -65.781694) (xy 57.030709 -65.728444) (xy 57.049741 -65.677383) (xy 57.075843 -65.629548)
			(xy 57.108485 -65.585914) (xy 57.127394 -65.56629) (xy 57.31256 -65.381124) (xy 57.327325 -65.364939)
			(xy 57.351633 -65.328495) (xy 57.369331 -65.288423) (xy 57.379897 -65.24591) (xy 57.383017 -65.202214)
			(xy 57.378599 -65.158631) (xy 57.366773 -65.116451) (xy 57.347891 -65.076923) (xy 57.32251 -65.041218)
			(xy 57.307226 -65.025524) (xy 57.299123 -65.017404) (xy 57.283746 -65.000376) (xy 57.276492 -64.991488)
			(xy 57.254902 -64.962278) (xy 57.240015 -64.939145) (xy 57.215929 -64.889686) (xy 57.198723 -64.837435)
			(xy 57.188712 -64.783342) (xy 57.186078 -64.728394) (xy 57.190869 -64.673591) (xy 57.202997 -64.619933)
			(xy 57.222243 -64.568398) (xy 57.234836 -64.54394) (xy 57.249822 -64.515746) (xy 57.249822 -64.431164)
			(xy 57.144412 -64.325754) (xy 57.144412 -64.30772) (xy 57.070244 -64.233552) (xy 57.00776 -64.233552)
			(xy 56.998362 -64.235076) (xy 56.961582 -64.240129) (xy 56.887404 -64.243236) (xy 56.813323 -64.238317)
			(xy 56.740207 -64.22543) (xy 56.668908 -64.204726) (xy 56.600262 -64.176446) (xy 56.535069 -64.140922)
			(xy 56.474091 -64.098568) (xy 56.418042 -64.04988) (xy 56.367576 -63.995425) (xy 56.323282 -63.935842)
			(xy 56.28568 -63.871825) (xy 56.255207 -63.804123) (xy 56.24322 -63.768986) (xy 56.23552 -63.747025)
			(xy 56.213295 -63.706142) (xy 56.183996 -63.669991) (xy 56.148604 -63.639781) (xy 56.108302 -63.61652)
			(xy 56.064437 -63.600989) (xy 56.018478 -63.593706) (xy 55.971961 -63.594915) (xy 55.926442 -63.604574)
			(xy 55.883443 -63.622363) (xy 55.844403 -63.647684) (xy 55.827168 -63.663322) (xy 55.700676 -63.789814)
			(xy 55.700676 -63.898526) (xy 55.700212 -63.923148) (xy 55.692317 -63.971753) (xy 55.676721 -64.018461)
			(xy 55.653828 -64.062059) (xy 55.624231 -64.101415) (xy 55.5887 -64.135509) (xy 55.548155 -64.163455)
			(xy 55.50365 -64.184529) (xy 55.456338 -64.198184) (xy 55.431944 -64.201548) (xy 55.406566 -64.20409)
			(xy 55.355622 -64.201698) (xy 55.305784 -64.190877) (xy 55.258435 -64.171929) (xy 55.21489 -64.14538)
			(xy 55.17636 -64.111967) (xy 55.143914 -64.072619) (xy 55.118455 -64.028429) (xy 55.10911 -64.004698)
			(xy 55.099309 -63.98297) (xy 55.072845 -63.94333) (xy 55.039453 -63.909322) (xy 55.000305 -63.882138)
			(xy 54.956773 -63.862733) (xy 54.910386 -63.851786) (xy 54.862771 -63.849683) (xy 54.839108 -63.852552)
			(xy 54.82082 -63.855346) (xy 54.811961 -63.856304) (xy 54.79417 -63.857319) (xy 54.78526 -63.857378)
			(xy 54.772376 -63.857301) (xy 54.746688 -63.855263) (xy 54.733952 -63.853314) (xy 54.723538 -63.851536)
			(xy 54.713124 -63.851536) (xy 54.696469 -63.852028) (xy 54.664293 -63.860646) (xy 54.635445 -63.8773)
			(xy 54.611892 -63.900855) (xy 54.595241 -63.929704) (xy 54.586626 -63.961881) (xy 54.586124 -63.978536)
			(xy 54.586124 -64.047878) (xy 54.585602 -64.073133) (xy 54.577289 -64.122955) (xy 54.560888 -64.170729)
			(xy 54.536847 -64.215152) (xy 54.505823 -64.255012) (xy 54.468661 -64.289222) (xy 54.426375 -64.316848)
			(xy 54.380119 -64.337138) (xy 54.331154 -64.349538) (xy 54.280816 -64.353709) (xy 54.230478 -64.349538)
			(xy 54.181513 -64.337138) (xy 54.135257 -64.316848) (xy 54.092971 -64.289222) (xy 54.055809 -64.255012)
			(xy 54.024785 -64.215152) (xy 54.000744 -64.170729) (xy 53.984343 -64.122955) (xy 53.97603 -64.073133)
			(xy 53.975508 -64.047878) (xy 53.975508 -63.947548) (xy 53.975019 -63.930889) (xy 53.966406 -63.898703)
			(xy 53.949755 -63.869844) (xy 53.926201 -63.846279) (xy 53.897349 -63.829615) (xy 53.865167 -63.820988)
			(xy 53.848508 -63.820548) (xy 53.595778 -63.820548) (xy 53.523134 -63.887604) (xy 53.51907 -63.937134)
			(xy 53.516596 -63.961733) (xy 53.504729 -64.009724) (xy 53.495448 -64.032638) (xy 53.483466 -64.059072)
			(xy 53.450985 -64.107161) (xy 53.430932 -64.128142) (xy 53.338476 -64.220598) (xy 53.317456 -64.240315)
			(xy 53.269514 -64.272286) (xy 53.243226 -64.284098) (xy 53.22062 -64.29375) (xy 52.971192 -64.543178)
			(xy 52.971192 -64.843406) (xy 52.889404 -64.925194) (xy 52.889404 -65.028572) (xy 52.118768 -65.799208)
			(xy 52.116736 -65.848738) (xy 52.115372 -65.871421) (xy 52.106771 -65.916039) (xy 52.091653 -65.95889)
			(xy 52.070354 -65.999028) (xy 52.043342 -66.035568) (xy 52.027582 -66.051938) (xy 51.939952 -66.139568)
			(xy 51.939952 -66.249296) (xy 51.99126 -66.350134) (xy 52.01031 -66.36639) (xy 52.011072 -66.366898)
			(xy 52.011834 -66.36766) (xy 52.013358 -66.36893) (xy 52.020662 -66.375458) (xy 52.034514 -66.389314)
			(xy 52.041044 -66.396616) (xy 52.058748 -66.417683) (xy 52.087034 -66.464879) (xy 52.106396 -66.516383)
			(xy 52.116206 -66.570526) (xy 52.116736 -66.598038) (xy 52.116736 -66.755518) (xy 51.775106 -67.097148)
			(xy 51.765454 -67.12204) (xy 51.755992 -67.14513) (xy 51.731923 -67.188842) (xy 51.702363 -67.229044)
			(xy 51.667814 -67.265051) (xy 51.628868 -67.296248) (xy 51.60772 -67.309492) (xy 51.593686 -67.318569)
			(xy 51.570568 -67.342691) (xy 51.554501 -67.371985) (xy 51.546585 -67.404445) (xy 51.547363 -67.437847)
			(xy 51.551586 -67.454018) (xy 51.559162 -67.481519) (xy 51.566948 -67.538027) (xy 51.566222 -67.595064)
			(xy 51.556999 -67.651355) (xy 51.539485 -67.705641) (xy 51.527202 -67.731386) (xy 51.520467 -67.744658)
			(xy 51.505211 -67.770216) (xy 51.496722 -67.78244) (xy 51.484122 -67.800976) (xy 51.464964 -67.841491)
			(xy 51.453225 -67.884742) (xy 51.449269 -67.929383) (xy 51.453219 -67.974024) (xy 51.464953 -68.017277)
			(xy 51.484104 -68.057795) (xy 51.496722 -68.076318) (xy 51.513971 -68.101661) (xy 51.528273 -68.130753)
			(xy 53.03496 -68.130753) (xy 53.038637 -68.076616) (xy 53.049948 -68.023546) (xy 53.068666 -67.972614)
			(xy 53.094413 -67.924849) (xy 53.126669 -67.881215) (xy 53.164782 -67.842592) (xy 53.207984 -67.809759)
			(xy 53.255403 -67.783381) (xy 53.306082 -67.763988) (xy 53.358997 -67.751972) (xy 53.413081 -67.747577)
			(xy 53.467242 -67.75089) (xy 53.520387 -67.761845) (xy 53.571443 -67.78022) (xy 53.61938 -67.805645)
			(xy 53.66323 -67.837607) (xy 53.702108 -67.87546) (xy 53.73523 -67.918441) (xy 53.761927 -67.965681)
			(xy 53.781659 -68.016228) (xy 53.78831 -68.042536) (xy 53.796692 -68.077842) (xy 53.968904 -68.250054)
			(xy 53.977032 -68.255896) (xy 53.996344 -68.270458) (xy 54.030542 -68.304656) (xy 54.045104 -68.323968)
			(xy 54.054243 -68.335883) (xy 54.077041 -68.355414) (xy 54.103776 -68.36907) (xy 54.132964 -68.376093)
			(xy 54.162984 -68.376093) (xy 54.192172 -68.36907) (xy 54.218907 -68.355414) (xy 54.241705 -68.335883)
			(xy 54.250844 -68.323968) (xy 54.256462 -68.316272) (xy 54.268538 -68.30153) (xy 54.274974 -68.294504)
			(xy 54.290871 -68.276717) (xy 54.316395 -68.236422) (xy 54.33395 -68.192071) (xy 54.342921 -68.145224)
			(xy 54.342991 -68.097525) (xy 54.334159 -68.050651) (xy 54.316735 -68.006249) (xy 54.291331 -67.965878)
			(xy 54.275482 -67.948048) (xy 54.260267 -67.931078) (xy 54.234541 -67.893456) (xy 54.214712 -67.85242)
			(xy 54.201224 -67.808885) (xy 54.194378 -67.763826) (xy 54.193948 -67.741038) (xy 54.193948 -67.608704)
			(xy 54.266846 -67.53606) (xy 54.281787 -67.520499) (xy 54.306663 -67.485258) (xy 54.325232 -67.446323)
			(xy 54.336961 -67.404811) (xy 54.341513 -67.361916) (xy 54.338756 -67.318867) (xy 54.328771 -67.276902)
			(xy 54.311843 -67.237225) (xy 54.28846 -67.200976) (xy 54.274212 -67.184778) (xy 54.257627 -67.166057)
			(xy 54.230267 -67.12419) (xy 54.21013 -67.07841) (xy 54.197757 -67.029951) (xy 54.193483 -66.980121)
			(xy 54.197423 -66.930262) (xy 54.20947 -66.881722) (xy 54.229301 -66.835808) (xy 54.256379 -66.793759)
			(xy 54.289975 -66.756709) (xy 54.309264 -66.740786) (xy 54.315106 -66.736214) (xy 54.510686 -66.540634)
			(xy 54.51856 -66.503804) (xy 54.524803 -66.476905) (xy 54.543966 -66.425119) (xy 54.570398 -66.376637)
			(xy 54.603545 -66.332475) (xy 54.642715 -66.293554) (xy 54.66461 -66.276728) (xy 54.683015 -66.262461)
			(xy 54.71483 -66.228465) (xy 54.739915 -66.189239) (xy 54.757429 -66.146098) (xy 54.766785 -66.100487)
			(xy 54.767669 -66.053934) (xy 54.760052 -66.008001) (xy 54.74419 -65.964225) (xy 54.720613 -65.924075)
			(xy 54.705758 -65.906142) (xy 54.695195 -65.893669) (xy 54.67599 -65.867218) (xy 54.667404 -65.85331)
			(xy 54.658505 -65.839616) (xy 54.635041 -65.816915) (xy 54.606593 -65.800896) (xy 54.575016 -65.792605)
			(xy 54.558692 -65.792096) (xy 54.497986 -65.792096) (xy 54.473578 -65.791664) (xy 54.425275 -65.784608)
			(xy 54.378494 -65.770662) (xy 54.334212 -65.750115) (xy 54.293357 -65.723398) (xy 54.25678 -65.691069)
			(xy 54.240684 -65.672716) (xy 54.237382 -65.668652) (xy 54.233572 -65.664842) (xy 54.221454 -65.653403)
			(xy 54.192615 -65.636727) (xy 54.16044 -65.628095) (xy 54.127126 -65.628095) (xy 54.094951 -65.636727)
			(xy 54.066112 -65.653403) (xy 54.053994 -65.664842) (xy 54.044088 -65.674748) (xy 54.027714 -65.69189)
			(xy 54.00097 -65.731022) (xy 53.981948 -65.774435) (xy 53.971308 -65.820623) (xy 53.969419 -65.867983)
			(xy 53.976346 -65.914872) (xy 53.99185 -65.959662) (xy 54.015392 -66.0008) (xy 54.030372 -66.019172)
			(xy 54.047368 -66.040057) (xy 54.074505 -66.08656) (xy 54.093062 -66.137103) (xy 54.102466 -66.190117)
			(xy 54.103016 -66.217038) (xy 54.103016 -66.367406) (xy 53.7972 -66.673222) (xy 53.788818 -66.708528)
			(xy 53.781934 -66.735854) (xy 53.76113 -66.788224) (xy 53.732847 -66.836964) (xy 53.697702 -66.881013)
			(xy 53.656458 -66.919412) (xy 53.610014 -66.951325) (xy 53.559381 -66.976057) (xy 53.505659 -66.993072)
			(xy 53.450019 -67.001998) (xy 53.393671 -67.00264) (xy 53.337842 -66.994986) (xy 53.283746 -66.979202)
			(xy 53.232562 -66.95563) (xy 53.185402 -66.924785) (xy 53.143293 -66.887337) (xy 53.107152 -66.844102)
			(xy 53.077765 -66.796019) (xy 53.055771 -66.744137) (xy 53.04165 -66.689584) (xy 53.035709 -66.633546)
			(xy 53.038076 -66.577245) (xy 53.048701 -66.521904) (xy 53.067352 -66.468728) (xy 53.093624 -66.418876)
			(xy 53.109876 -66.395854) (xy 53.123069 -66.377025) (xy 53.143169 -66.33568) (xy 53.155498 -66.291393)
			(xy 53.159654 -66.245611) (xy 53.155502 -66.199827) (xy 53.143176 -66.155539) (xy 53.12308 -66.114193)
			(xy 53.109876 -66.095372) (xy 53.094385 -66.073389) (xy 53.068992 -66.025986) (xy 53.050509 -65.975486)
			(xy 53.039303 -65.92289) (xy 53.035595 -65.869242) (xy 53.03946 -65.815605) (xy 53.05082 -65.763042)
			(xy 53.06945 -65.712596) (xy 53.094982 -65.665268) (xy 53.126908 -65.621994) (xy 53.164596 -65.583634)
			(xy 53.207298 -65.550948) (xy 53.254168 -65.524584) (xy 53.304277 -65.505064) (xy 53.330348 -65.498472)
			(xy 53.365654 -65.49009) (xy 53.513736 -65.342008) (xy 53.523134 -65.322704) (xy 53.534045 -65.301161)
			(xy 53.56157 -65.261486) (xy 53.595003 -65.226645) (xy 53.633509 -65.197508) (xy 53.676126 -65.174802)
			(xy 53.721788 -65.159096) (xy 53.769354 -65.150782) (xy 53.817636 -65.150068) (xy 53.865428 -65.156971)
			(xy 53.911535 -65.171319) (xy 53.954804 -65.192754) (xy 53.974746 -65.206372) (xy 53.994411 -65.219708)
			(xy 54.037567 -65.239577) (xy 54.083665 -65.251074) (xy 54.131097 -65.253798) (xy 54.178207 -65.247654)
			(xy 54.223354 -65.232856) (xy 54.264961 -65.20992) (xy 54.28361 -65.195196) (xy 54.306416 -65.177152)
			(xy 54.356926 -65.148341) (xy 54.411633 -65.128632) (xy 54.468912 -65.118611) (xy 54.497986 -65.11798)
			(xy 54.781196 -65.11798) (xy 54.804692 -65.118445) (xy 54.851217 -65.125066) (xy 54.873906 -65.131188)
			(xy 54.894607 -65.136707) (xy 54.937188 -65.141424) (xy 54.979957 -65.138926) (xy 55.021699 -65.129285)
			(xy 55.061231 -65.112774) (xy 55.09743 -65.089861) (xy 55.129269 -65.061196) (xy 55.155845 -65.027594)
			(xy 55.166514 -65.009014) (xy 55.180416 -64.984831) (xy 55.214096 -64.940371) (xy 55.25389 -64.901289)
			(xy 55.298951 -64.868416) (xy 55.348317 -64.842455) (xy 55.400937 -64.823957) (xy 55.45569 -64.813318)
			(xy 55.511408 -64.810764) (xy 55.566905 -64.816349) (xy 55.620997 -64.829954) (xy 55.672531 -64.85129)
			(xy 55.72041 -64.879902) (xy 55.763614 -64.915179) (xy 55.801221 -64.956371) (xy 55.832429 -65.0026)
			(xy 55.856575 -65.052879) (xy 55.873143 -65.106138) (xy 55.881781 -65.161242) (xy 55.882304 -65.217016)
			(xy 55.8747 -65.272273) (xy 55.859133 -65.325833) (xy 55.847996 -65.351406) (xy 55.831486 -65.387474)
			(xy 55.845456 -65.465452) (xy 56.000142 -65.620138) (xy 56.017633 -65.638366) (xy 56.046985 -65.679477)
			(xy 56.069171 -65.724858) (xy 56.083584 -65.773273) (xy 56.089832 -65.823399) (xy 56.087745 -65.87387)
			(xy 56.077379 -65.923309) (xy 56.059016 -65.970367) (xy 56.033159 -66.013761) (xy 56.000512 -66.052308)
			(xy 55.961965 -66.084955) (xy 55.918571 -66.110812) (xy 55.871513 -66.129175) (xy 55.822074 -66.139541)
			(xy 55.771603 -66.141628) (xy 55.721477 -66.13538) (xy 55.673062 -66.120967) (xy 55.627681 -66.098781)
			(xy 55.58657 -66.069429) (xy 55.568342 -66.051938) (xy 55.44312 -65.926462) (xy 55.431002 -65.915023)
			(xy 55.402163 -65.898347) (xy 55.369988 -65.889715) (xy 55.336674 -65.889715) (xy 55.304499 -65.898347)
			(xy 55.27566 -65.915023) (xy 55.263542 -65.926462) (xy 55.253531 -65.936273) (xy 55.232301 -65.95458)
			(xy 55.221124 -65.963038) (xy 55.202662 -65.977236) (xy 55.170843 -66.011242) (xy 55.145756 -66.050478)
			(xy 55.128244 -66.093631) (xy 55.118893 -66.139253) (xy 55.118017 -66.185816) (xy 55.125645 -66.231757)
			(xy 55.141521 -66.275539) (xy 55.165113 -66.315691) (xy 55.179976 -66.333624) (xy 55.198432 -66.355684)
			(xy 55.229131 -66.404321) (xy 55.25218 -66.457016) (xy 55.267055 -66.512575) (xy 55.273419 -66.569737)
			(xy 55.271128 -66.627207) (xy 55.260233 -66.683682) (xy 55.240983 -66.73788) (xy 55.213812 -66.788573)
			(xy 55.196994 -66.811906) (xy 55.183393 -66.830914) (xy 55.162662 -66.872799) (xy 55.149937 -66.917768)
			(xy 55.145648 -66.964305) (xy 55.149939 -67.010842) (xy 55.162665 -67.05581) (xy 55.183398 -67.097694)
			(xy 55.196994 -67.116706) (xy 55.212636 -67.13836) (xy 55.238406 -67.185149) (xy 55.257393 -67.235077)
			(xy 55.269227 -67.287166) (xy 55.273675 -67.340397) (xy 55.270651 -67.393727) (xy 55.260214 -67.446114)
			(xy 55.242568 -67.496532) (xy 55.218058 -67.543993) (xy 55.187164 -67.587569) (xy 55.150491 -67.626407)
			(xy 55.108757 -67.659747) (xy 55.085996 -67.673728) (xy 55.071903 -67.682742) (xy 55.048588 -67.706713)
			(xy 55.032304 -67.73592) (xy 55.02417 -67.768355) (xy 55.024744 -67.80179) (xy 55.033988 -67.833927)
			(xy 55.051266 -67.862557) (xy 55.075391 -67.885713) (xy 55.089806 -67.8942) (xy 55.09768 -67.898772)
			(xy 55.127144 -67.916044) (xy 55.285894 -67.916044) (xy 56.089296 -68.719446) (xy 56.089296 -68.884038)
			(xy 56.088832 -68.908386) (xy 56.081107 -68.956466) (xy 56.065843 -69.002708) (xy 56.043427 -69.045939)
			(xy 56.01443 -69.08506) (xy 55.979586 -69.119079) (xy 55.939781 -69.147131) (xy 55.896026 -69.168504)
			(xy 55.849431 -69.182656) (xy 55.80118 -69.189227) (xy 55.752498 -69.18805) (xy 55.704621 -69.179156)
			(xy 55.658764 -69.162769) (xy 55.616092 -69.139307) (xy 55.577689 -69.109364) (xy 55.54453 -69.073702)
			(xy 55.517456 -69.033226) (xy 55.506874 -69.011292) (xy 55.497476 -68.990718) (xy 55.45963 -68.952872)
			(xy 55.447498 -68.941411) (xy 55.418619 -68.924702) (xy 55.386396 -68.916051) (xy 55.353032 -68.916051)
			(xy 55.320809 -68.924702) (xy 55.29193 -68.941411) (xy 55.279798 -68.952872) (xy 55.259986 -68.972684)
			(xy 55.250334 -68.999354) (xy 55.240691 -69.02445) (xy 55.215449 -69.071916) (xy 55.183792 -69.115367)
			(xy 55.146347 -69.153942) (xy 55.103857 -69.186878) (xy 55.057164 -69.213521) (xy 55.007192 -69.233344)
			(xy 54.954931 -69.245954) (xy 54.901418 -69.251101) (xy 54.847712 -69.248683) (xy 54.794878 -69.238748)
			(xy 54.743962 -69.221493) (xy 54.695974 -69.19726) (xy 54.651863 -69.166528) (xy 54.612505 -69.129908)
			(xy 54.578678 -69.088123) (xy 54.551054 -69.042004) (xy 54.530179 -68.992462) (xy 54.522878 -68.966588)
			(xy 54.513988 -68.933314) (xy 54.35219 -68.771516) (xy 54.339236 -68.763642) (xy 54.330854 -68.758458)
			(xy 54.314711 -68.747146) (xy 54.306978 -68.741036) (xy 54.289938 -68.727937) (xy 54.252371 -68.70706)
			(xy 54.211827 -68.692803) (xy 54.169463 -68.685571) (xy 54.126485 -68.685571) (xy 54.084121 -68.692803)
			(xy 54.043577 -68.70706) (xy 54.00601 -68.727937) (xy 53.98897 -68.741036) (xy 53.979777 -68.748287)
			(xy 53.960453 -68.761513) (xy 53.950362 -68.767452) (xy 53.935884 -68.775834) (xy 53.9242 -68.787518)
			(xy 53.912708 -68.799622) (xy 53.896006 -68.82851) (xy 53.887363 -68.86074) (xy 53.88737 -68.894108)
			(xy 53.896025 -68.926335) (xy 53.912738 -68.955216) (xy 53.9242 -68.96735) (xy 53.968904 -69.012054)
			(xy 53.977032 -69.017896) (xy 53.996902 -69.032885) (xy 54.031964 -69.068206) (xy 54.060815 -69.108758)
			(xy 54.082687 -69.153463) (xy 54.090316 -69.177154) (xy 54.09484 -69.190797) (xy 54.109074 -69.215758)
			(xy 54.128549 -69.236886) (xy 54.152271 -69.253102) (xy 54.179029 -69.263576) (xy 54.193186 -69.266054)
			(xy 54.220895 -69.270647) (xy 54.274642 -69.286956) (xy 54.325418 -69.310968) (xy 54.372125 -69.342162)
			(xy 54.413756 -69.379866) (xy 54.430222 -69.399908) (xy 56.579547 -69.399908) (xy 56.58369 -69.341967)
			(xy 56.596036 -69.285205) (xy 56.616334 -69.230778) (xy 56.644171 -69.179793) (xy 56.67898 -69.133289)
			(xy 56.69915 -69.112384) (xy 56.95315 -68.858384) (xy 57.770522 -68.858384) (xy 57.799732 -68.8594)
			(xy 57.822575 -68.860523) (xy 57.868033 -68.855546) (xy 57.911869 -68.842519) (xy 57.952668 -68.821863)
			(xy 57.989115 -68.794244) (xy 58.020035 -68.760551) (xy 58.044431 -68.721872) (xy 58.061516 -68.679453)
			(xy 58.07074 -68.634663) (xy 58.071804 -68.588945) (xy 58.068718 -68.566284) (xy 58.064668 -68.537284)
			(xy 58.063975 -68.478735) (xy 58.071684 -68.42069) (xy 58.087634 -68.364351) (xy 58.111497 -68.31088)
			(xy 58.142779 -68.261383) (xy 58.180834 -68.216882) (xy 58.224876 -68.178297) (xy 58.273996 -68.146424)
			(xy 58.327177 -68.121923) (xy 58.383321 -68.1053) (xy 58.441269 -68.096897) (xy 58.470546 -68.096384)
			(xy 58.66638 -68.096384) (xy 59.36488 -68.79463) (xy 59.36488 -68.983098) (xy 59.36442 -69.009842)
			(xy 59.357385 -69.062866) (xy 59.343462 -69.114512) (xy 59.322892 -69.163887) (xy 59.29603 -69.210141)
			(xy 59.263338 -69.252477) (xy 59.22538 -69.290163) (xy 59.204352 -69.306694) (xy 59.192504 -69.316227)
			(xy 59.173404 -69.339884) (xy 59.160438 -69.367386) (xy 59.154342 -69.397173) (xy 59.155461 -69.427558)
			(xy 59.163732 -69.456816) (xy 59.170824 -69.47027) (xy 59.183917 -69.494492) (xy 59.203808 -69.545833)
			(xy 59.216111 -69.599501) (xy 59.220571 -69.654379) (xy 59.217094 -69.709329) (xy 59.205755 -69.763208)
			(xy 59.186786 -69.814897) (xy 59.160584 -69.863322) (xy 59.127693 -69.907477) (xy 59.088794 -69.946445)
			(xy 59.044698 -69.979416) (xy 58.99632 -70.005705) (xy 58.944665 -70.024765) (xy 58.890806 -70.036202)
			(xy 58.835863 -70.039776) (xy 58.780976 -70.035415) (xy 58.727287 -70.023208) (xy 58.67591 -70.003409)
			(xy 58.627914 -69.976429) (xy 58.584295 -69.94283) (xy 58.56478 -69.923406) (xy 58.552791 -69.911893)
			(xy 58.524254 -69.894878) (xy 58.492292 -69.885802) (xy 58.459072 -69.885282) (xy 58.426842 -69.893352)
			(xy 58.397786 -69.909466) (xy 58.385456 -69.920612) (xy 58.366084 -69.93865) (xy 58.323263 -69.969764)
			(xy 58.27655 -69.994657) (xy 58.251852 -70.004178) (xy 58.236528 -70.010322) (xy 58.209491 -70.029253)
			(xy 58.188204 -70.054477) (xy 58.174087 -70.084311) (xy 58.170572 -70.100444) (xy 58.165047 -70.128045)
			(xy 58.147376 -70.181489) (xy 58.122501 -70.231983) (xy 58.090897 -70.278563) (xy 58.053168 -70.320337)
			(xy 58.010037 -70.356506) (xy 57.962329 -70.386378) (xy 57.910955 -70.409383) (xy 57.88406 -70.41769)
			(xy 57.868906 -70.422569) (xy 57.841508 -70.438764) (xy 57.818973 -70.461239) (xy 57.802704 -70.488594)
			(xy 57.793715 -70.519126) (xy 57.792566 -70.550932) (xy 57.799327 -70.582032) (xy 57.813578 -70.610491)
			(xy 57.834431 -70.634534) (xy 57.84723 -70.644004) (xy 57.8629 -70.655158) (xy 57.892409 -70.67983)
			(xy 57.906158 -70.69328) (xy 58.21172 -70.998842) (xy 58.793651 -70.998842) (xy 58.797795 -70.940899)
			(xy 58.810143 -70.884136) (xy 58.830443 -70.829708) (xy 58.858283 -70.778723) (xy 58.893096 -70.732218)
			(xy 58.934172 -70.691142) (xy 58.980677 -70.656329) (xy 59.031662 -70.628489) (xy 59.08609 -70.608189)
			(xy 59.142853 -70.595841) (xy 59.200796 -70.591697) (xy 59.258739 -70.595841) (xy 59.315502 -70.608189)
			(xy 59.36993 -70.628489) (xy 59.420915 -70.656329) (xy 59.46742 -70.691142) (xy 59.488324 -70.711314)
			(xy 59.511184 -70.734174) (xy 59.523331 -70.745525) (xy 59.552126 -70.762114) (xy 59.58423 -70.7707)
			(xy 59.617462 -70.7707) (xy 59.649566 -70.762114) (xy 59.678361 -70.745525) (xy 59.690508 -70.734174)
			(xy 59.713368 -70.711314) (xy 59.734272 -70.691142) (xy 59.780777 -70.656329) (xy 59.831762 -70.628489)
			(xy 59.88619 -70.608189) (xy 59.942953 -70.595841) (xy 60.000896 -70.591697) (xy 60.058839 -70.595841)
			(xy 60.115602 -70.608189) (xy 60.17003 -70.628489) (xy 60.221015 -70.656329) (xy 60.26752 -70.691142)
			(xy 60.288424 -70.711314) (xy 60.311792 -70.734682) (xy 60.323963 -70.746035) (xy 60.352802 -70.762624)
			(xy 60.384946 -70.771209) (xy 60.418216 -70.771209) (xy 60.45036 -70.762624) (xy 60.479199 -70.746035)
			(xy 60.49137 -70.734682) (xy 60.494164 -70.731888) (xy 60.496704 -70.72884) (xy 60.516082 -70.707724)
			(xy 60.559774 -70.670632) (xy 60.608242 -70.640044) (xy 60.660526 -70.616567) (xy 60.715589 -70.600667)
			(xy 60.772339 -70.592658) (xy 60.800996 -70.592188) (xy 61.601096 -70.592188) (xy 61.627719 -70.592635)
			(xy 61.680509 -70.599595) (xy 61.731939 -70.613382) (xy 61.781132 -70.633762) (xy 61.827244 -70.660386)
			(xy 61.869489 -70.692798) (xy 61.888624 -70.711314) (xy 61.911484 -70.734174) (xy 61.923631 -70.745525)
			(xy 61.952426 -70.762114) (xy 61.98453 -70.7707) (xy 62.017762 -70.7707) (xy 62.049866 -70.762114)
			(xy 62.078661 -70.745525) (xy 62.090808 -70.734174) (xy 62.113668 -70.711314) (xy 62.132797 -70.692789)
			(xy 62.175036 -70.660363) (xy 62.221148 -70.63373) (xy 62.270342 -70.613345) (xy 62.321776 -70.599558)
			(xy 62.374571 -70.592605) (xy 62.401196 -70.592188) (xy 63.068708 -70.592188) (xy 63.743332 -69.917564)
			(xy 64.70142 -69.917564) (xy 64.728659 -69.918058) (xy 64.782583 -69.92581) (xy 64.834855 -69.941154)
			(xy 64.884414 -69.963776) (xy 64.93025 -69.993219) (xy 64.971433 -70.028881) (xy 65.007124 -70.07004)
			(xy 65.036598 -70.115856) (xy 65.059255 -70.165399) (xy 65.074634 -70.217661) (xy 65.082423 -70.271579)
			(xy 65.082928 -70.298818) (xy 65.082928 -70.815454) (xy 65.131188 -70.863714) (xy 65.131188 -71.515732)
			(xy 64.845184 -71.801736) (xy 64.825572 -71.82066) (xy 64.781944 -71.85332) (xy 64.734111 -71.879438)
			(xy 64.683049 -71.898484) (xy 64.629796 -71.910068) (xy 64.575436 -71.913956) (xy 64.521076 -71.910068)
			(xy 64.467823 -71.898484) (xy 64.416761 -71.879438) (xy 64.368928 -71.85332) (xy 64.3253 -71.82066)
			(xy 64.305688 -71.801736) (xy 64.129412 -71.62546) (xy 64.117294 -71.614021) (xy 64.088455 -71.597345)
			(xy 64.05628 -71.588713) (xy 64.022966 -71.588713) (xy 63.990791 -71.597345) (xy 63.961952 -71.614021)
			(xy 63.949834 -71.62546) (xy 63.888874 -71.68642) (xy 63.867697 -71.706877) (xy 63.820515 -71.742099)
			(xy 63.768747 -71.770146) (xy 63.713474 -71.790434) (xy 63.655852 -71.802536) (xy 63.597088 -71.8062)
			(xy 63.53841 -71.80135) (xy 63.481044 -71.788086) (xy 63.426192 -71.766686) (xy 63.375001 -71.737599)
			(xy 63.32854 -71.701431) (xy 63.287782 -71.65894) (xy 63.25358 -71.611014) (xy 63.23965 -71.585074)
			(xy 63.23076 -71.567548) (xy 63.068708 -71.405496) (xy 62.569598 -71.405496) (xy 62.288674 -71.68642)
			(xy 62.26777 -71.706592) (xy 62.221265 -71.741405) (xy 62.17028 -71.769245) (xy 62.115852 -71.789545)
			(xy 62.059089 -71.801893) (xy 62.001146 -71.806037) (xy 61.943203 -71.801893) (xy 61.88644 -71.789545)
			(xy 61.832012 -71.769245) (xy 61.781027 -71.741405) (xy 61.734522 -71.706592) (xy 61.713618 -71.68642)
			(xy 61.432694 -71.405496) (xy 60.994544 -71.405496) (xy 60.705238 -71.694802) (xy 60.686092 -71.713309)
			(xy 60.643858 -71.74574) (xy 60.597751 -71.772377) (xy 60.54856 -71.792766) (xy 60.497127 -71.806555)
			(xy 60.444334 -71.81351) (xy 60.41771 -71.813928) (xy 60.240926 -71.813928) (xy 60.090558 -71.663814)
			(xy 60.078411 -71.652463) (xy 60.049616 -71.635874) (xy 60.017512 -71.627288) (xy 59.98428 -71.627288)
			(xy 59.952176 -71.635874) (xy 59.923381 -71.652463) (xy 59.911234 -71.663814) (xy 59.888374 -71.68642)
			(xy 59.86747 -71.706592) (xy 59.820965 -71.741405) (xy 59.76998 -71.769245) (xy 59.715552 -71.789545)
			(xy 59.658789 -71.801893) (xy 59.600846 -71.806037) (xy 59.542903 -71.801893) (xy 59.48614 -71.789545)
			(xy 59.431712 -71.769245) (xy 59.380727 -71.741405) (xy 59.334222 -71.706592) (xy 59.313318 -71.68642)
			(xy 58.913268 -71.28637) (xy 58.893096 -71.265466) (xy 58.858283 -71.218961) (xy 58.830443 -71.167976)
			(xy 58.810143 -71.113548) (xy 58.797795 -71.056785) (xy 58.793651 -70.998842) (xy 58.21172 -70.998842)
			(xy 59.506358 -72.29348) (xy 59.514151 -72.301401) (xy 59.529017 -72.317918) (xy 59.536076 -72.3265)
			(xy 59.546141 -72.338166) (xy 59.570708 -72.356746) (xy 59.599017 -72.368885) (xy 59.629412 -72.373875)
			(xy 59.660116 -72.371424) (xy 59.689333 -72.361675) (xy 59.715357 -72.345197) (xy 59.726322 -72.334374)
			(xy 59.745817 -72.314877) (xy 59.789378 -72.281079) (xy 59.837352 -72.253909) (xy 59.88874 -72.233933)
			(xy 59.942469 -72.221567) (xy 59.99742 -72.21707) (xy 60.052445 -72.220536) (xy 60.106397 -72.231891)
			(xy 60.15815 -72.2509) (xy 60.206626 -72.277166) (xy 60.250812 -72.31014) (xy 60.270644 -72.329294)
			(xy 60.29325 -72.3519) (xy 60.305419 -72.363267) (xy 60.334219 -72.379951) (xy 60.366355 -72.388615)
			(xy 60.399639 -72.388668) (xy 60.431803 -72.380107) (xy 60.460656 -72.363516) (xy 60.472828 -72.352154)
			(xy 60.513468 -72.311514) (xy 60.534458 -72.291187) (xy 60.581252 -72.256194) (xy 60.632571 -72.228255)
			(xy 60.687359 -72.207945) (xy 60.744489 -72.195682) (xy 60.802785 -72.191719) (xy 60.861049 -72.196136)
			(xy 60.918082 -72.208843) (xy 60.97271 -72.229579) (xy 61.02381 -72.257916) (xy 61.047376 -72.275192)
			(xy 61.066477 -72.289058) (xy 61.108678 -72.310188) (xy 61.154054 -72.323164) (xy 61.201046 -72.327539)
			(xy 61.248038 -72.323164) (xy 61.293414 -72.310188) (xy 61.335615 -72.289058) (xy 61.354716 -72.275192)
			(xy 61.378297 -72.257937) (xy 61.429391 -72.229594) (xy 61.484016 -72.208854) (xy 61.541046 -72.196143)
			(xy 61.599307 -72.191724) (xy 61.657602 -72.195687) (xy 61.71473 -72.207952) (xy 61.769515 -72.228264)
			(xy 61.820829 -72.256207) (xy 61.867617 -72.291205) (xy 61.888624 -72.311514) (xy 61.911484 -72.334374)
			(xy 61.923631 -72.345725) (xy 61.952426 -72.362314) (xy 61.98453 -72.3709) (xy 62.017762 -72.3709)
			(xy 62.049866 -72.362314) (xy 62.078661 -72.345725) (xy 62.090808 -72.334374) (xy 62.113668 -72.311514)
			(xy 62.133668 -72.292131) (xy 62.178044 -72.258475) (xy 62.2266 -72.231194) (xy 62.278426 -72.210797)
			(xy 62.332552 -72.197668) (xy 62.387963 -72.192051) (xy 62.443622 -72.194053) (xy 62.498487 -72.203636)
			(xy 62.525148 -72.211692) (xy 62.543944 -72.217788) (xy 63.201296 -72.217788) (xy 63.231269 -72.218303)
			(xy 63.290484 -72.227626) (xy 63.347509 -72.246107) (xy 63.400937 -72.273289) (xy 63.449449 -72.308502)
			(xy 63.471044 -72.329294) (xy 63.51143 -72.36968) (xy 63.523562 -72.381141) (xy 63.552441 -72.39785)
			(xy 63.584664 -72.406501) (xy 63.618028 -72.406501) (xy 63.650251 -72.39785) (xy 63.67913 -72.381141)
			(xy 63.691262 -72.36968) (xy 63.731648 -72.329294) (xy 63.75126 -72.31037) (xy 63.794888 -72.27771)
			(xy 63.842721 -72.251591) (xy 63.893783 -72.232546) (xy 63.947036 -72.220962) (xy 64.001396 -72.217074)
			(xy 64.055756 -72.220962) (xy 64.109009 -72.232546) (xy 64.160071 -72.251591) (xy 64.207904 -72.27771)
			(xy 64.251532 -72.31037) (xy 64.290068 -72.348906) (xy 64.322728 -72.392534) (xy 64.348847 -72.440367)
			(xy 64.367892 -72.491429) (xy 64.379476 -72.544682) (xy 64.383364 -72.599042) (xy 64.379476 -72.653402)
			(xy 64.367892 -72.706655) (xy 64.348847 -72.757717) (xy 64.322728 -72.80555) (xy 64.290068 -72.849178)
			(xy 64.271144 -72.86879) (xy 64.196722 -72.943212) (xy 64.867536 -72.943212) (xy 64.867536 -72.296782)
			(xy 64.867985 -72.268623) (xy 64.876282 -72.212919) (xy 64.892677 -72.15904) (xy 64.916814 -72.108157)
			(xy 64.948169 -72.061374) (xy 64.986061 -72.019709) (xy 65.029666 -71.984067) (xy 65.078037 -71.955223)
			(xy 65.130123 -71.933802) (xy 65.184791 -71.920272) (xy 65.240855 -71.914924) (xy 65.297096 -71.917877)
			(xy 65.352292 -71.929065) (xy 65.405243 -71.948246) (xy 65.4548 -71.975002) (xy 65.477644 -71.991474)
			(xy 65.496656 -72.00507) (xy 65.538539 -72.025802) (xy 65.583507 -72.038528) (xy 65.630044 -72.042818)
			(xy 65.676581 -72.038528) (xy 65.721549 -72.025802) (xy 65.763432 -72.00507) (xy 65.782444 -71.991474)
			(xy 65.805241 -71.97493) (xy 65.8548 -71.948154) (xy 65.907757 -71.928958) (xy 65.962961 -71.917758)
			(xy 66.019213 -71.914799) (xy 66.075288 -71.920145) (xy 66.129967 -71.933678) (xy 66.182061 -71.955106)
			(xy 66.230438 -71.983962) (xy 66.274045 -72.019618) (xy 66.311934 -72.0613) (xy 66.343281 -72.108101)
			(xy 66.367405 -72.159003) (xy 66.383781 -72.212899) (xy 66.392053 -72.268617) (xy 66.392552 -72.296782)
			(xy 66.392552 -72.4662) (xy 65.661286 -73.197466) (xy 65.641674 -73.21639) (xy 65.598046 -73.24905)
			(xy 65.550213 -73.275168) (xy 65.499151 -73.294214) (xy 65.445898 -73.305798) (xy 65.391538 -73.309686)
			(xy 65.337178 -73.305798) (xy 65.283925 -73.294214) (xy 65.232863 -73.275168) (xy 65.18503 -73.24905)
			(xy 65.141402 -73.21639) (xy 65.12179 -73.197466) (xy 64.867536 -72.943212) (xy 64.196722 -72.943212)
			(xy 63.871094 -73.26884) (xy 63.851482 -73.287764) (xy 63.807854 -73.320424) (xy 63.760021 -73.346542)
			(xy 63.708959 -73.365588) (xy 63.655706 -73.377172) (xy 63.601346 -73.38106) (xy 63.546986 -73.377172)
			(xy 63.493733 -73.365588) (xy 63.442671 -73.346542) (xy 63.394838 -73.320424) (xy 63.35121 -73.287764)
			(xy 63.331598 -73.26884) (xy 63.080392 -73.017634) (xy 63.068301 -73.006188) (xy 63.039506 -72.989493)
			(xy 63.007371 -72.98082) (xy 62.99073 -72.980296) (xy 62.647576 -72.980296) (xy 62.630943 -72.980879)
			(xy 62.598827 -72.989557) (xy 62.570044 -73.006239) (xy 62.557914 -73.017634) (xy 62.272926 -73.302368)
			(xy 62.261612 -73.314574) (xy 62.245013 -73.343402) (xy 62.236419 -73.375537) (xy 62.236411 -73.408802)
			(xy 62.24499 -73.440942) (xy 62.261575 -73.469778) (xy 62.272926 -73.481946) (xy 62.808104 -74.017124)
			(xy 62.808104 -74.199242) (xy 62.807564 -74.22804) (xy 62.799435 -74.285061) (xy 62.783346 -74.340365)
			(xy 62.759618 -74.392848) (xy 62.728726 -74.441459) (xy 62.691287 -74.485229) (xy 62.64805 -74.52328)
			(xy 62.599878 -74.554854) (xy 62.547735 -74.579319) (xy 62.492663 -74.596186) (xy 62.435763 -74.605117)
			(xy 62.378172 -74.605934) (xy 62.321041 -74.598622) (xy 62.265512 -74.583325) (xy 62.212696 -74.56035)
			(xy 62.163648 -74.530156) (xy 62.119348 -74.493347) (xy 62.080682 -74.450658) (xy 62.064138 -74.42708)
			(xy 62.05728 -74.41692) (xy 61.69787 -74.05751) (xy 61.685738 -74.046049) (xy 61.656859 -74.02934)
			(xy 61.624636 -74.020689) (xy 61.591272 -74.020689) (xy 61.559049 -74.02934) (xy 61.53017 -74.046049)
			(xy 61.518038 -74.05751) (xy 60.570872 -75.004676) (xy 60.559442 -75.004676) (xy 60.340494 -75.223624)
			(xy 60.334144 -75.232768) (xy 60.317394 -75.255977) (xy 60.278315 -75.297798) (xy 60.233761 -75.33373)
			(xy 60.18461 -75.363063) (xy 60.131834 -75.385219) (xy 60.076474 -75.399761) (xy 60.019623 -75.406401)
			(xy 59.962402 -75.405009) (xy 59.905941 -75.395611) (xy 59.851353 -75.378394) (xy 59.799718 -75.353697)
			(xy 59.752053 -75.322007) (xy 59.709299 -75.283951) (xy 59.6723 -75.240278) (xy 59.641786 -75.191852)
			(xy 59.61836 -75.139627) (xy 59.602484 -75.084635) (xy 59.594471 -75.027961) (xy 59.593988 -74.999342)
			(xy 59.593988 -74.81951) (xy 60.103512 -74.31024) (xy 60.11615 -74.297798) (xy 60.143237 -74.274904)
			(xy 60.157614 -74.26452) (xy 60.166758 -74.25817) (xy 60.936124 -73.488804) (xy 60.947547 -73.476673)
			(xy 60.964222 -73.447837) (xy 60.972856 -73.415665) (xy 60.972859 -73.382356) (xy 60.96423 -73.350183)
			(xy 60.94756 -73.321344) (xy 60.936124 -73.309226) (xy 60.913518 -73.28662) (xy 60.896754 -73.269094)
			(xy 60.894214 -73.266046) (xy 60.89142 -73.263252) (xy 60.879302 -73.251813) (xy 60.850463 -73.235137)
			(xy 60.818288 -73.226505) (xy 60.784974 -73.226505) (xy 60.752799 -73.235137) (xy 60.72396 -73.251813)
			(xy 60.711842 -73.263252) (xy 60.688474 -73.28662) (xy 60.665777 -73.308528) (xy 60.614877 -73.345785)
			(xy 60.587128 -73.360788) (xy 60.569602 -73.369678) (xy 60.270644 -73.66889) (xy 60.251032 -73.687814)
			(xy 60.207404 -73.720474) (xy 60.159571 -73.746593) (xy 60.108509 -73.765638) (xy 60.055256 -73.777222)
			(xy 60.000896 -73.78111) (xy 59.946536 -73.777222) (xy 59.893283 -73.765638) (xy 59.842221 -73.746593)
			(xy 59.794388 -73.720474) (xy 59.75076 -73.687814) (xy 59.712224 -73.649278) (xy 59.679564 -73.60565)
			(xy 59.653445 -73.557817) (xy 59.6344 -73.506755) (xy 59.622816 -73.453502) (xy 59.618928 -73.399142)
			(xy 59.622816 -73.344782) (xy 59.6344 -73.291529) (xy 59.653445 -73.240467) (xy 59.679564 -73.192634)
			(xy 59.712224 -73.149006) (xy 59.731148 -73.129394) (xy 59.771534 -73.089008) (xy 59.783005 -73.076884)
			(xy 59.799717 -73.048004) (xy 59.808369 -73.015778) (xy 59.808367 -72.982411) (xy 59.799713 -72.950186)
			(xy 59.782998 -72.921307) (xy 59.771534 -72.909176) (xy 59.731148 -72.86879) (xy 59.726322 -72.86371)
			(xy 59.71537 -72.852876) (xy 59.689334 -72.836422) (xy 59.660112 -72.826688) (xy 59.62941 -72.824241)
			(xy 59.599016 -72.829224) (xy 59.570702 -72.841346) (xy 59.546118 -72.859901) (xy 59.536076 -72.871584)
			(xy 59.516696 -72.894683) (xy 59.472531 -72.935733) (xy 59.423088 -72.970243) (xy 59.369327 -72.997544)
			(xy 59.312292 -73.017106) (xy 59.253092 -73.028547) (xy 59.192875 -73.031647) (xy 59.132813 -73.026344)
			(xy 59.074071 -73.012741) (xy 59.017791 -72.991104) (xy 58.965066 -72.961852) (xy 58.91692 -72.925553)
			(xy 58.895234 -72.904604) (xy 57.295034 -71.304404) (xy 57.27471 -71.283387) (xy 57.23931 -71.236856)
			(xy 57.210508 -71.185977) (xy 57.18883 -71.131678) (xy 57.174672 -71.074953) (xy 57.168292 -71.016836)
			(xy 57.169807 -70.95839) (xy 57.17919 -70.900682) (xy 57.196269 -70.844766) (xy 57.220732 -70.791664)
			(xy 57.252132 -70.742346) (xy 57.289895 -70.697712) (xy 57.31129 -70.677786) (xy 57.328038 -70.66213)
			(xy 57.356051 -70.625841) (xy 57.3771 -70.585114) (xy 57.390501 -70.541273) (xy 57.395819 -70.495738)
			(xy 57.392882 -70.449988) (xy 57.381786 -70.405507) (xy 57.36289 -70.363739) (xy 57.336807 -70.326038)
			(xy 57.320942 -70.309486) (xy 56.69915 -69.68744) (xy 56.678991 -69.666524) (xy 56.64418 -69.620021)
			(xy 56.616341 -69.569037) (xy 56.596041 -69.514611) (xy 56.583692 -69.457849) (xy 56.579547 -69.399908)
			(xy 54.430222 -69.399908) (xy 54.449411 -69.423265) (xy 54.478319 -69.471421) (xy 54.499856 -69.523295)
			(xy 54.513557 -69.577765) (xy 54.519127 -69.633655) (xy 54.516444 -69.689757) (xy 54.505566 -69.744861)
			(xy 54.486729 -69.797775) (xy 54.46034 -69.847356) (xy 54.426968 -69.892534) (xy 54.387335 -69.932332)
			(xy 54.342296 -69.965891) (xy 54.292824 -69.992486) (xy 54.239989 -70.011542) (xy 54.184931 -70.022648)
			(xy 54.12884 -70.025564) (xy 54.072927 -70.020227) (xy 54.018401 -70.006752) (xy 53.966439 -69.98543)
			(xy 53.918163 -69.956722) (xy 53.874616 -69.921248) (xy 53.83674 -69.879774) (xy 53.805352 -69.833196)
			(xy 53.78113 -69.78252) (xy 53.764597 -69.728842) (xy 53.759862 -69.701156) (xy 53.753512 -69.660008)
			(xy 53.365146 -69.271388) (xy 53.32984 -69.263006) (xy 53.303621 -69.256433) (xy 53.253268 -69.236775)
			(xy 53.206195 -69.210206) (xy 53.163343 -69.177258) (xy 53.125572 -69.13859) (xy 53.093638 -69.094978)
			(xy 53.06818 -69.047294) (xy 53.049708 -68.996494) (xy 53.038593 -68.943595) (xy 53.035056 -68.889657)
			(xy 53.03917 -68.835759) (xy 53.05085 -68.782982) (xy 53.069864 -68.732383) (xy 53.095831 -68.684974)
			(xy 53.111654 -68.663058) (xy 53.125291 -68.644073) (xy 53.146024 -68.602184) (xy 53.158747 -68.557209)
			(xy 53.163032 -68.510666) (xy 53.158735 -68.464125) (xy 53.145999 -68.419153) (xy 53.125256 -68.377269)
			(xy 53.111654 -68.358258) (xy 53.095763 -68.336263) (xy 53.069703 -68.288668) (xy 53.050651 -68.23786)
			(xy 53.038992 -68.184865) (xy 53.03496 -68.130753) (xy 51.528273 -68.130753) (xy 51.541016 -68.156673)
			(xy 51.558916 -68.215302) (xy 51.56721 -68.276039) (xy 51.56708 -68.306696) (xy 51.566228 -68.32834)
			(xy 51.560247 -68.371243) (xy 51.555142 -68.392294) (xy 51.550777 -68.40845) (xy 51.539582 -68.439991)
			(xy 51.53279 -68.455286) (xy 51.518688 -68.484613) (xy 51.482035 -68.538375) (xy 51.459892 -68.56222)
			(xy 51.459638 -68.562474) (xy 51.448622 -68.574688) (xy 51.432662 -68.603434) (xy 51.424575 -68.635303)
			(xy 51.424897 -68.66818) (xy 51.433608 -68.699885) (xy 51.450129 -68.728312) (xy 51.461416 -68.740274)
			(xy 51.923188 -69.202046) (xy 51.935316 -69.213445) (xy 51.964098 -69.230136) (xy 51.996216 -69.238822)
			(xy 52.01285 -69.239384) (xy 52.511706 -69.239384) (xy 52.543336 -69.239968) (xy 52.605839 -69.249723)
			(xy 52.66608 -69.269028) (xy 52.722611 -69.297419) (xy 52.748688 -69.31533) (xy 52.76164 -69.324827)
			(xy 52.786179 -69.345552) (xy 52.79771 -69.356732) (xy 52.799234 -69.358256) (xy 52.998878 -69.557646)
			(xy 53.206904 -69.76618) (xy 53.206904 -70.243954) (xy 53.20741 -70.266742) (xy 53.215533 -70.311589)
			(xy 53.231529 -70.354266) (xy 53.254882 -70.393405) (xy 53.284845 -70.427749) (xy 53.320454 -70.456195)
			(xy 53.360567 -70.477832) (xy 53.403897 -70.491964) (xy 53.449054 -70.498138) (xy 53.494587 -70.496155)
			(xy 53.539036 -70.486081) (xy 53.580974 -70.468237) (xy 53.619056 -70.443196) (xy 53.63591 -70.42785)
			(xy 53.664104 -70.399656) (xy 53.67655 -70.387464) (xy 54.32806 -70.387464) (xy 54.330854 -70.390258)
			(xy 54.488334 -70.390258) (xy 54.491128 -70.387464) (xy 54.543452 -70.387464) (xy 54.543706 -70.386956)
			(xy 54.592728 -70.386956) (xy 54.595268 -70.384416) (xy 55.125366 -70.384416) (xy 55.127906 -70.386956)
			(xy 55.12816 -70.386956) (xy 55.471822 -70.730872) (xy 55.485792 -70.74535) (xy 55.487824 -70.747636)
			(xy 55.509922 -70.769988) (xy 55.522054 -70.781449) (xy 55.550933 -70.798158) (xy 55.583156 -70.806809)
			(xy 55.61652 -70.806809) (xy 55.648743 -70.798158) (xy 55.677622 -70.781449) (xy 55.689754 -70.769988)
			(xy 55.730648 -70.729094) (xy 55.75026 -70.71017) (xy 55.793888 -70.67751) (xy 55.841721 -70.651391)
			(xy 55.892783 -70.632346) (xy 55.946036 -70.620762) (xy 56.000396 -70.616874) (xy 56.054756 -70.620762)
			(xy 56.108009 -70.632346) (xy 56.159071 -70.651391) (xy 56.206904 -70.67751) (xy 56.250532 -70.71017)
			(xy 56.289068 -70.748706) (xy 56.321728 -70.792334) (xy 56.347847 -70.840167) (xy 56.366892 -70.891229)
			(xy 56.378476 -70.944482) (xy 56.382364 -70.998842) (xy 56.378476 -71.053202) (xy 56.366892 -71.106455)
			(xy 56.347847 -71.157517) (xy 56.321728 -71.20535) (xy 56.289068 -71.248978) (xy 56.270144 -71.26859)
			(xy 55.97144 -71.567548) (xy 55.970424 -71.568564) (xy 55.969916 -71.56958) (xy 55.96763 -71.571358)
			(xy 55.874666 -71.664322) (xy 55.855742 -71.68327) (xy 55.813523 -71.716213) (xy 55.767113 -71.742928)
			(xy 55.717423 -71.762892) (xy 55.691532 -71.769732) (xy 55.650854 -71.798942) (xy 56.393351 -71.798942)
			(xy 56.397495 -71.740999) (xy 56.409843 -71.684236) (xy 56.430143 -71.629808) (xy 56.457983 -71.578823)
			(xy 56.492796 -71.532318) (xy 56.533872 -71.491242) (xy 56.580377 -71.456429) (xy 56.631362 -71.428589)
			(xy 56.68579 -71.408289) (xy 56.742553 -71.395941) (xy 56.800496 -71.391797) (xy 56.858439 -71.395941)
			(xy 56.915202 -71.408289) (xy 56.96963 -71.428589) (xy 57.020615 -71.456429) (xy 57.06712 -71.491242)
			(xy 57.088024 -71.511414) (xy 57.383934 -71.807324) (xy 57.401206 -71.816214) (xy 57.429891 -71.831937)
			(xy 57.482568 -71.870716) (xy 57.506108 -71.89343) (xy 57.906158 -72.29348) (xy 57.926679 -72.314713)
			(xy 57.962358 -72.361763) (xy 57.991298 -72.413232) (xy 58.01296 -72.468164) (xy 58.02694 -72.525533)
			(xy 58.032979 -72.584271) (xy 58.030963 -72.643285) (xy 58.02093 -72.701475) (xy 58.003067 -72.757756)
			(xy 57.977707 -72.811081) (xy 57.945322 -72.860456) (xy 57.906515 -72.904961) (xy 57.86201 -72.943768)
			(xy 57.812635 -72.976153) (xy 57.75931 -73.001513) (xy 57.703029 -73.019376) (xy 57.644839 -73.029409)
			(xy 57.585825 -73.031425) (xy 57.527087 -73.025386) (xy 57.469718 -73.011406) (xy 57.414786 -72.989744)
			(xy 57.363317 -72.960804) (xy 57.316267 -72.925125) (xy 57.295034 -72.904604) (xy 56.894984 -72.504554)
			(xy 56.872273 -72.481012) (xy 56.833499 -72.428332) (xy 56.817768 -72.399652) (xy 56.808878 -72.38238)
			(xy 56.512968 -72.08647) (xy 56.492796 -72.065566) (xy 56.457983 -72.019061) (xy 56.430143 -71.968076)
			(xy 56.409843 -71.913648) (xy 56.397495 -71.856885) (xy 56.393351 -71.798942) (xy 55.650854 -71.798942)
			(xy 55.64378 -71.804022) (xy 55.632604 -71.805038) (xy 55.631814 -71.831087) (xy 55.624757 -71.882723)
			(xy 55.611546 -71.933136) (xy 55.592371 -71.981596) (xy 55.58028 -72.004682) (xy 55.56504 -72.032876)
			(xy 55.56504 -72.065388) (xy 55.56551 -72.081585) (xy 55.573638 -72.112941) (xy 55.5894 -72.14124)
			(xy 55.61178 -72.164659) (xy 55.639336 -72.181688) (xy 55.670291 -72.191231) (xy 55.686452 -72.192388)
			(xy 55.853076 -72.192388) (xy 55.871618 -72.186546) (xy 55.899826 -72.178257) (xy 55.957805 -72.168506)
			(xy 56.016571 -72.166706) (xy 56.075038 -72.172891) (xy 56.132126 -72.186947) (xy 56.186782 -72.208614)
			(xy 56.237994 -72.237491) (xy 56.284819 -72.273046) (xy 56.305958 -72.29348) (xy 57.106058 -73.09358)
			(xy 57.117397 -73.105126) (xy 57.138504 -73.129661) (xy 57.148222 -73.142602) (xy 57.157056 -73.154731)
			(xy 57.173201 -73.180027) (xy 57.18048 -73.193148) (xy 57.183274 -73.198482) (xy 57.192418 -73.215754)
			(xy 57.888124 -73.911714) (xy 57.907412 -73.931671) (xy 57.940953 -73.975891) (xy 57.96817 -74.02426)
			(xy 57.988556 -74.075881) (xy 58.001734 -74.129795) (xy 58.007459 -74.185) (xy 58.005623 -74.240471)
			(xy 57.996262 -74.295177) (xy 57.979549 -74.348102) (xy 57.955794 -74.398262) (xy 57.92544 -74.444727)
			(xy 57.889049 -74.486632) (xy 57.847297 -74.5232) (xy 57.82437 -74.53884) (xy 57.813448 -74.545952)
			(xy 57.517538 -74.842116) (xy 57.420764 -74.93889) (xy 57.420764 -75.0443) (xy 57.50433 -75.127866)
			(xy 57.556908 -75.180698) (xy 57.888124 -75.511914) (xy 57.892188 -75.515978) (xy 57.90288 -75.526409)
			(xy 57.92809 -75.542415) (xy 57.956334 -75.552113) (xy 57.98606 -75.554969) (xy 58.015634 -75.550828)
			(xy 58.043431 -75.539916) (xy 58.067925 -75.522832) (xy 58.078116 -75.511914) (xy 58.089599 -75.49926)
			(xy 58.114266 -75.47561) (xy 58.127392 -75.46467) (xy 58.128154 -75.463908) (xy 58.148474 -75.447652)
			(xy 58.173112 -75.399646) (xy 58.17616 -75.345544) (xy 58.156856 -75.294998) (xy 58.137552 -75.275694)
			(xy 58.130948 -75.26909) (xy 58.112057 -75.249512) (xy 58.079446 -75.205966) (xy 58.053351 -75.158229)
			(xy 58.034301 -75.10727) (xy 58.022681 -75.054121) (xy 58.020204 -75.027028) (xy 58.018608 -74.996572)
			(xy 58.023956 -74.935824) (xy 58.0389 -74.8767) (xy 58.05043 -74.848466) (xy 58.060284 -74.826491)
			(xy 58.084732 -74.784996) (xy 58.114204 -74.746904) (xy 58.130948 -74.729594) (xy 58.495438 -74.365104)
			(xy 58.499756 -74.35977) (xy 58.507554 -74.350226) (xy 58.524203 -74.33205) (xy 58.53303 -74.323448)
			(xy 58.54065 -74.315828) (xy 58.552055 -74.303666) (xy 58.56874 -74.274816) (xy 58.577399 -74.242632)
			(xy 58.577444 -74.209304) (xy 58.56887 -74.177098) (xy 58.552262 -74.148203) (xy 58.540904 -74.135996)
			(xy 57.993788 -73.58888) (xy 57.993788 -73.399142) (xy 57.994259 -73.371351) (xy 58.001821 -73.316285)
			(xy 58.01681 -73.262761) (xy 58.038947 -73.211777) (xy 58.067819 -73.164281) (xy 58.102889 -73.121159)
			(xy 58.143504 -73.083213) (xy 58.188907 -73.05115) (xy 58.238252 -73.025568) (xy 58.290621 -73.006942)
			(xy 58.345038 -72.99562) (xy 58.400491 -72.991813) (xy 58.455945 -72.99559) (xy 58.510368 -73.006883)
			(xy 58.562747 -73.025481) (xy 58.612107 -73.051037) (xy 58.657527 -73.083075) (xy 58.698162 -73.120999)
			(xy 58.733255 -73.164102) (xy 58.748168 -73.18756) (xy 58.756042 -73.200514) (xy 59.399424 -73.843896)
			(xy 59.412378 -73.85177) (xy 59.436094 -73.866763) (xy 59.479552 -73.902251) (xy 59.517726 -73.943371)
			(xy 59.549892 -73.989342) (xy 59.57544 -74.039295) (xy 59.585098 -74.065638) (xy 59.59345 -74.090991)
			(xy 59.604201 -74.143277) (xy 59.608023 -74.19652) (xy 59.60485 -74.249805) (xy 59.594736 -74.302218)
			(xy 59.577855 -74.352858) (xy 59.566556 -74.377042) (xy 59.552084 -74.405406) (xy 59.515669 -74.457638)
			(xy 59.471564 -74.503563) (xy 59.420846 -74.542059) (xy 59.393074 -74.557636) (xy 59.376564 -74.566526)
			(xy 59.08421 -74.859134) (xy 59.082686 -74.860912) (xy 59.070494 -74.873358) (xy 59.059567 -74.884668)
			(xy 59.043107 -74.911454) (xy 59.033692 -74.94145) (xy 59.031892 -74.972838) (xy 59.037816 -75.003714)
			(xy 59.044078 -75.018138) (xy 59.07024 -75.073764) (xy 59.088274 -75.090528) (xy 59.109231 -75.11074)
			(xy 59.145955 -75.155922) (xy 59.176129 -75.205717) (xy 59.188096 -75.23226) (xy 59.192668 -75.242928)
			(xy 59.192922 -75.243436) (xy 59.199526 -75.258676) (xy 59.30773 -75.367134) (xy 59.427364 -75.486768)
			(xy 59.470544 -75.529694) (xy 59.490865 -75.550771) (xy 59.525451 -75.598009) (xy 59.552416 -75.649976)
			(xy 59.571128 -75.705451) (xy 59.581146 -75.763134) (xy 59.582237 -75.82167) (xy 59.574374 -75.879685)
			(xy 59.566556 -75.9079) (xy 59.559662 -75.92997) (xy 59.541251 -75.972386) (xy 59.517837 -76.012258)
			(xy 59.504072 -76.030836) (xy 59.496256 -76.040905) (xy 59.479478 -76.060098) (xy 59.470544 -76.06919)
			(xy 59.465972 -76.073762) (xy 59.454506 -76.085893) (xy 59.437786 -76.114772) (xy 59.429128 -76.147)
			(xy 59.429124 -76.18037) (xy 59.437774 -76.212599) (xy 59.454487 -76.241482) (xy 59.465972 -76.253594)
			(xy 59.511946 -76.299568) (xy 59.520836 -76.308966) (xy 59.535822 -76.326238) (xy 59.539886 -76.331318)
			(xy 59.544966 -76.336398) (xy 59.557098 -76.347859) (xy 59.585977 -76.364568) (xy 59.6182 -76.373219)
			(xy 59.651564 -76.373219) (xy 59.683787 -76.364568) (xy 59.712666 -76.347859) (xy 59.724798 -76.336398)
			(xy 59.731148 -76.329794) (xy 59.750375 -76.311195) (xy 59.793107 -76.279017) (xy 59.839919 -76.253129)
			(xy 59.889889 -76.234038) (xy 59.942037 -76.222121) (xy 59.99534 -76.21761) (xy 60.04875 -76.220594)
			(xy 60.075064 -76.2254) (xy 60.093098 -76.229464) (xy 60.120751 -76.236886) (xy 60.173614 -76.258877)
			(xy 60.222602 -76.288514) (xy 60.266616 -76.325132) (xy 60.30467 -76.36791) (xy 60.335912 -76.41589)
			(xy 60.359641 -76.467996) (xy 60.367926 -76.495402) (xy 60.376816 -76.527152) (xy 60.473082 -76.623672)
			(xy 60.505086 -76.632562) (xy 60.52929 -76.639874) (xy 60.57567 -76.660009) (xy 60.597542 -76.672694)
			(xy 60.617306 -76.684986) (xy 60.653986 -76.713641) (xy 60.670694 -76.729844) (xy 60.748418 -76.807568)
			(xy 60.853574 -76.807568) (xy 60.890658 -76.77023) (xy 60.971684 -76.689204) (xy 60.983141 -76.677071)
			(xy 60.999845 -76.648193) (xy 61.008491 -76.615972) (xy 61.008489 -76.582611) (xy 60.999838 -76.550391)
			(xy 60.983131 -76.521516) (xy 60.971684 -76.509372) (xy 60.966858 -76.504546) (xy 60.96127 -76.499974)
			(xy 60.960762 -76.49972) (xy 60.93999 -76.482464) (xy 60.903021 -76.4431) (xy 60.871931 -76.398945)
			(xy 60.847334 -76.35087) (xy 60.829715 -76.299823) (xy 60.82411 -76.273406) (xy 60.820856 -76.258767)
			(xy 60.808452 -76.231473) (xy 60.790016 -76.20783) (xy 60.766568 -76.189147) (xy 60.739405 -76.176457)
			(xy 60.724796 -76.173076) (xy 60.710642 -76.170073) (xy 60.682797 -76.162192) (xy 60.66917 -76.157328)
			(xy 60.646767 -76.148711) (xy 60.604144 -76.126637) (xy 60.564627 -76.099389) (xy 60.546488 -76.083668)
			(xy 60.526764 -76.065391) (xy 60.492136 -76.024252) (xy 60.463629 -75.978656) (xy 60.441809 -75.929509)
			(xy 60.427108 -75.877785) (xy 60.419818 -75.824508) (xy 60.420083 -75.770736) (xy 60.423552 -75.74407)
			(xy 60.42781 -75.718072) (xy 60.442553 -75.667494) (xy 60.464122 -75.61943) (xy 60.492107 -75.574795)
			(xy 60.525973 -75.53444) (xy 60.565075 -75.499136) (xy 60.58662 -75.483974) (xy 60.596526 -75.477116)
			(xy 60.87872 -75.194922) (xy 60.888626 -75.180444) (xy 60.891166 -75.176888) (xy 60.909729 -75.152067)
			(xy 60.953545 -75.108233) (xy 61.003881 -75.072074) (xy 61.031374 -75.057762) (xy 61.049547 -75.049045)
			(xy 61.087346 -75.035049) (xy 61.106812 -75.029822) (xy 61.120845 -75.025817) (xy 61.14673 -75.012358)
			(xy 61.168882 -74.993373) (xy 61.186143 -74.969852) (xy 61.197612 -74.943026) (xy 61.200538 -74.92873)
			(xy 61.205816 -74.901494) (xy 61.222782 -74.848676) (xy 61.246771 -74.798655) (xy 61.277339 -74.752359)
			(xy 61.313916 -74.710649) (xy 61.355824 -74.674299) (xy 61.402285 -74.643985) (xy 61.452437 -74.620268)
			(xy 61.505347 -74.603589) (xy 61.560033 -74.594259) (xy 61.61548 -74.59245) (xy 61.670657 -74.598196)
			(xy 61.724542 -74.61139) (xy 61.776132 -74.631788) (xy 61.824471 -74.65901) (xy 61.868659 -74.692551)
			(xy 61.888624 -74.711814) (xy 62.288674 -75.111864) (xy 62.305946 -75.130152) (xy 62.316464 -75.14142)
			(xy 62.341802 -75.158958) (xy 62.370606 -75.169908) (xy 62.401196 -75.17363) (xy 62.431786 -75.169908)
			(xy 62.46059 -75.158958) (xy 62.485928 -75.14142) (xy 62.496446 -75.130152) (xy 62.513718 -75.111864)
			(xy 62.913768 -74.711814) (xy 62.934672 -74.691642) (xy 62.981177 -74.656829) (xy 63.032162 -74.628989)
			(xy 63.08659 -74.608689) (xy 63.143353 -74.596341) (xy 63.201296 -74.592197) (xy 63.259239 -74.596341)
			(xy 63.316002 -74.608689) (xy 63.37043 -74.628989) (xy 63.421415 -74.656829) (xy 63.46792 -74.691642)
			(xy 63.508996 -74.732718) (xy 63.543809 -74.779223) (xy 63.571649 -74.830208) (xy 63.591949 -74.884636)
			(xy 63.604297 -74.941399) (xy 63.608441 -74.999342) (xy 63.604297 -75.057285) (xy 63.591949 -75.114048)
			(xy 63.571649 -75.168476) (xy 63.543809 -75.219461) (xy 63.508996 -75.265966) (xy 63.488824 -75.28687)
			(xy 63.088774 -75.68692) (xy 63.070174 -75.704978) (xy 63.029183 -75.736713) (xy 62.984488 -75.762977)
			(xy 62.936816 -75.783342) (xy 62.91199 -75.790806) (xy 62.884304 -75.797664) (xy 62.8523 -75.802998)
			(xy 62.817756 -75.807316) (xy 62.707012 -75.892914) (xy 62.694058 -75.923648) (xy 62.685093 -75.94383)
			(xy 62.66239 -75.981709) (xy 62.634652 -76.016072) (xy 62.602416 -76.046255) (xy 62.584584 -76.059284)
			(xy 62.575694 -76.065634) (xy 62.379098 -76.26223) (xy 62.370462 -76.295504) (xy 62.364139 -76.318391)
			(xy 62.346575 -76.362505) (xy 62.32366 -76.404092) (xy 62.31001 -76.42352) (xy 62.296426 -76.443118)
			(xy 62.276065 -76.48623) (xy 62.264101 -76.532382) (xy 62.260953 -76.579956) (xy 62.266732 -76.627283)
			(xy 62.281236 -76.672702) (xy 62.303955 -76.714619) (xy 62.318646 -76.7334) (xy 62.335558 -76.753422)
			(xy 62.364306 -76.797244) (xy 62.386784 -76.84459) (xy 62.402566 -76.894568) (xy 62.411357 -76.946236)
			(xy 62.412626 -76.972414) (xy 62.412978 -76.998363) (xy 62.407511 -77.049971) (xy 62.395101 -77.100361)
			(xy 62.375979 -77.148606) (xy 62.350497 -77.193815) (xy 62.319125 -77.235155) (xy 62.30112 -77.253846)
			(xy 62.012322 -77.542644) (xy 61.973714 -77.580998) (xy 61.78804 -77.766926) (xy 61.777309 -77.779162)
			(xy 61.761868 -77.807798) (xy 61.754177 -77.839411) (xy 61.754736 -77.87194) (xy 61.76351 -77.903269)
			(xy 61.779927 -77.931358) (xy 61.791088 -77.943202) (xy 61.795914 -77.948028) (xy 61.800994 -77.952346)
			(xy 61.819046 -77.967485) (xy 61.850921 -78.002176) (xy 61.864494 -78.021434) (xy 61.882916 -78.032164)
			(xy 61.922501 -78.047985) (xy 61.96417 -78.056982) (xy 62.006756 -78.058903) (xy 62.049066 -78.053694)
			(xy 62.089915 -78.041502) (xy 62.128158 -78.022667) (xy 62.145672 -78.010512) (xy 62.156178 -77.996717)
			(xy 62.179729 -77.971263) (xy 62.192662 -77.959712) (xy 62.19825 -77.954886) (xy 62.217808 -77.9399)
			(xy 62.226698 -77.93355) (xy 62.423294 -77.736954) (xy 62.43193 -77.703426) (xy 62.439559 -77.67613)
			(xy 62.461772 -77.62399) (xy 62.491454 -77.57571) (xy 62.527952 -77.532351) (xy 62.570461 -77.494868)
			(xy 62.618048 -77.464086) (xy 62.669665 -77.440682) (xy 62.724175 -77.425171) (xy 62.780381 -77.417895)
			(xy 62.837045 -77.419012) (xy 62.89292 -77.428499) (xy 62.946776 -77.446147) (xy 62.99743 -77.471568)
			(xy 63.043766 -77.504203) (xy 63.084765 -77.543332) (xy 63.119524 -77.588096) (xy 63.14728 -77.637509)
			(xy 63.157862 -77.663802) (xy 63.171832 -77.700886) (xy 63.236856 -77.745844) (xy 63.236856 -77.764386)
			(xy 64.255142 -78.782672) (xy 64.631316 -79.158592) (xy 64.931544 -79.158592)
		)
		(stroke
			(width 0)
			(type solid)
		)
		(fill yes)
		(layer "F.Cu")
		(net "GND")
	)
	(gr_poly
		(pts
			(xy 165.3159 -140.901674) (xy 158.83636 -140.901674) (xy 158.83636 -143.152114) (xy 165.3159 -143.152114)
		)
		(stroke
			(width 0)
			(type solid)
		)
		(fill yes)
		(layer "B.Cu")
		(net "GND")
	)
	(gr_poly
		(pts
			(xy 26.13406 -163.147756) (xy 23.53818 -163.147756) (xy 23.39086 -163.295076) (xy 23.39086 -164.904166)
			(xy 23.71852 -165.231826) (xy 26.13406 -165.231826)
		)
		(stroke
			(width 0)
			(type solid)
		)
		(fill yes)
		(layer "B.Cu")
		(net "P1V9_LAN1")
	)
	(gr_poly
		(pts
			(xy 14.1986 -114.120422) (xy 14.1986 -104.572816) (xy 10.510012 -104.572816) (xy 9.8933 -105.189528)
			(xy 9.8933 -114.2111) (xy 10.2616 -114.5794) (xy 13.739368 -114.5794)
		)
		(stroke
			(width 0)
			(type solid)
		)
		(fill yes)
		(layer "B.Cu")
		(net "GND")
	)
	(gr_poly
		(pts
			(xy 42.36085 -72.026018) (xy 42.260774 -71.925942) (xy 40.22979 -71.925942) (xy 39.828978 -72.326754)
			(xy 39.828978 -72.700134) (xy 40.821864 -73.69302) (xy 42.36085 -73.69302)
		)
		(stroke
			(width 0)
			(type solid)
		)
		(fill yes)
		(layer "B.Cu")
		(net "GND")
	)
	(gr_poly
		(pts
			(xy 12.86891 -125.90653) (xy 12.86891 -121.278904) (xy 12.742418 -121.152412) (xy 10.93978 -121.152412)
			(xy 10.847832 -121.24436) (xy 10.847832 -125.793246) (xy 11.02741 -125.972824) (xy 12.802616 -125.972824)
		)
		(stroke
			(width 0)
			(type solid)
		)
		(fill yes)
		(layer "B.Cu")
		(net "GND")
	)
	(gr_poly
		(pts
			(xy 26.2255 -158.123636) (xy 26.2255 -155.206192) (xy 26.20264 -155.183332) (xy 23.475696 -155.183332)
			(xy 23.28418 -155.374848) (xy 23.28418 -157.976824) (xy 23.56612 -158.258764) (xy 26.090372 -158.258764)
		)
		(stroke
			(width 0)
			(type solid)
		)
		(fill yes)
		(layer "B.Cu")
		(net "P1V9_LAN1")
	)
	(gr_poly
		(pts
			(xy 28.22448 -165.175438) (xy 28.22448 -163.327842) (xy 28.128976 -163.232338) (xy 26.59126 -163.232338)
			(xy 26.5303 -163.293298) (xy 26.5303 -165.186868) (xy 26.60904 -165.265608) (xy 28.13431 -165.265608)
		)
		(stroke
			(width 0)
			(type solid)
		)
		(fill yes)
		(layer "B.Cu")
		(net "GND")
	)
	(gr_poly
		(pts
			(xy 38.954202 -11.09091) (xy 38.954202 -9.393682) (xy 38.927024 -9.366504) (xy 37.202618 -9.366504)
			(xy 37.16655 -9.402572) (xy 37.16655 -11.08202) (xy 37.220652 -11.136122) (xy 38.90899 -11.136122)
		)
		(stroke
			(width 0)
			(type solid)
		)
		(fill yes)
		(layer "B.Cu")
		(net "GND")
	)
	(gr_poly
		(pts
			(xy 48.19904 -146.06397) (xy 48.19904 -145.01876) (xy 48.071532 -144.891252) (xy 45.9867 -144.891252)
			(xy 45.83938 -145.038572) (xy 45.83938 -146.122898) (xy 45.898562 -146.18208) (xy 48.08093 -146.18208)
		)
		(stroke
			(width 0)
			(type solid)
		)
		(fill yes)
		(layer "B.Cu")
		(net "GND")
	)
	(gr_poly
		(pts
			(xy 51.980592 -125.476762) (xy 51.980592 -123.493022) (xy 51.810412 -123.322842) (xy 49.938432 -123.322842)
			(xy 49.867312 -123.393962) (xy 49.867312 -125.067822) (xy 50.357532 -125.558042) (xy 51.899312 -125.558042)
		)
		(stroke
			(width 0)
			(type solid)
		)
		(fill yes)
		(layer "B.Cu")
		(net "P1V26_BMC_NODE1")
	)
	(gr_poly
		(pts
			(xy 54.894226 -89.852754) (xy 54.894226 -88.522048) (xy 54.72938 -88.357202) (xy 52.462684 -88.357202)
			(xy 52.09794 -88.721946) (xy 52.09794 -89.86012) (xy 52.244244 -90.006424) (xy 54.740556 -90.006424)
		)
		(stroke
			(width 0)
			(type solid)
		)
		(fill yes)
		(layer "B.Cu")
		(net "GND")
	)
	(gr_poly
		(pts
			(xy 64.58458 -6.325108) (xy 64.58458 -1.965198) (xy 64.16802 -1.548638) (xy 53.362098 -1.548638)
			(xy 53.12156 -1.789176) (xy 53.12156 -6.1849) (xy 53.52034 -6.58368) (xy 64.326008 -6.58368)
		)
		(stroke
			(width 0)
			(type solid)
		)
		(fill yes)
		(layer "B.Cu")
		(net "GND")
	)
	(gr_poly
		(pts
			(xy 84.024724 -8.217662) (xy 84.024724 -1.965706) (xy 83.739228 -1.68021) (xy 79.534258 -1.68021)
			(xy 79.318866 -1.895602) (xy 79.318866 -8.160512) (xy 79.490062 -8.331708) (xy 83.910678 -8.331708)
		)
		(stroke
			(width 0)
			(type solid)
		)
		(fill yes)
		(layer "B.Cu")
		(net "P3V3_NODE1")
	)
	(gr_poly
		(pts
			(xy 85.51926 -86.813644) (xy 85.51926 -82.564224) (xy 85.45068 -82.495644) (xy 83.48472 -82.495644)
			(xy 83.37804 -82.602324) (xy 83.37804 -86.760304) (xy 83.5279 -86.910164) (xy 85.42274 -86.910164)
		)
		(stroke
			(width 0)
			(type solid)
		)
		(fill yes)
		(layer "B.Cu")
		(net "GND")
	)
	(gr_poly
		(pts
			(xy 86.9061 -8.10133) (xy 86.9061 -2.0193) (xy 86.607142 -1.720342) (xy 84.464652 -1.720342) (xy 84.289646 -1.895348)
			(xy 84.289646 -8.065262) (xy 84.594192 -8.369808) (xy 86.637622 -8.369808)
		)
		(stroke
			(width 0)
			(type solid)
		)
		(fill yes)
		(layer "B.Cu")
		(net "GND")
	)
	(gr_poly
		(pts
			(xy 91.331034 -79.74838) (xy 91.331034 -79.531718) (xy 91.196414 -79.397098) (xy 89.013792 -79.397098)
			(xy 88.91651 -79.49438) (xy 88.91651 -80.98917) (xy 89.013792 -81.086452) (xy 89.992962 -81.086452)
		)
		(stroke
			(width 0)
			(type solid)
		)
		(fill yes)
		(layer "B.Cu")
		(net "P1V05_NODE1")
	)
	(gr_poly
		(pts
			(xy 119.14886 -123.660916) (xy 119.14886 -120.595898) (xy 119.02059 -120.467628) (xy 114.36985 -120.467628)
			(xy 114.23777 -120.599708) (xy 114.23777 -123.744482) (xy 114.264186 -123.770898) (xy 119.038878 -123.770898)
		)
		(stroke
			(width 0)
			(type solid)
		)
		(fill yes)
		(layer "B.Cu")
		(net "GND")
	)
	(gr_poly
		(pts
			(xy 120.99798 -114.993166) (xy 120.99798 -103.608378) (xy 120.743472 -103.35387) (xy 116.74348 -103.35387)
			(xy 115.14074 -104.95661) (xy 115.14074 -113.7285) (xy 116.498624 -115.086384) (xy 120.904762 -115.086384)
		)
		(stroke
			(width 0)
			(type solid)
		)
		(fill yes)
		(layer "B.Cu")
		(net "GND")
	)
	(gr_poly
		(pts
			(xy 126.118874 -123.634754) (xy 126.118874 -122.543824) (xy 125.895608 -122.320558) (xy 124.959872 -122.320558)
			(xy 124.786136 -122.494294) (xy 124.786136 -123.678188) (xy 124.941076 -123.833128) (xy 125.9205 -123.833128)
		)
		(stroke
			(width 0)
			(type solid)
		)
		(fill yes)
		(layer "B.Cu")
		(net "P1V05_NODE1")
	)
	(gr_poly
		(pts
			(xy 131.5593 -143.204692) (xy 131.5593 -142.60195) (xy 131.42468 -142.46733) (xy 129.24663 -142.46733)
			(xy 129.20218 -142.51178) (xy 129.20218 -143.209264) (xy 129.26314 -143.270224) (xy 131.493768 -143.270224)
		)
		(stroke
			(width 0)
			(type solid)
		)
		(fill yes)
		(layer "B.Cu")
		(net "P1V0_NODE1")
	)
	(gr_poly
		(pts
			(xy 145.893028 -51.282346) (xy 145.893028 -49.199546) (xy 145.664428 -48.970946) (xy 144.521428 -48.970946)
			(xy 144.267428 -49.224946) (xy 144.267428 -51.460146) (xy 144.394428 -51.587146) (xy 145.588228 -51.587146)
		)
		(stroke
			(width 0)
			(type solid)
		)
		(fill yes)
		(layer "B.Cu")
		(net "P5V_NODE1")
	)
	(gr_poly
		(pts
			(xy 147.211288 -73.887838) (xy 147.211288 -70.407022) (xy 147.135596 -70.33133) (xy 146.271996 -70.33133)
			(xy 145.967196 -70.63613) (xy 145.967196 -73.81113) (xy 146.119596 -73.96353) (xy 147.135596 -73.96353)
		)
		(stroke
			(width 0)
			(type solid)
		)
		(fill yes)
		(layer "B.Cu")
		(net "GND")
	)
	(gr_poly
		(pts
			(xy 154.933396 -68.40093) (xy 154.933396 -67.46113) (xy 154.857196 -67.38493) (xy 151.42083 -67.38493)
			(xy 151.224996 -67.580764) (xy 151.224996 -68.35013) (xy 151.402796 -68.52793) (xy 154.806396 -68.52793)
		)
		(stroke
			(width 0)
			(type solid)
		)
		(fill yes)
		(layer "B.Cu")
		(net "GND")
	)
	(gr_poly
		(pts
			(xy 154.933396 -64.76873) (xy 154.933396 -63.49873) (xy 154.730196 -63.29553) (xy 151.428196 -63.29553)
			(xy 151.275796 -63.44793) (xy 151.275796 -64.74333) (xy 151.351996 -64.81953) (xy 154.882596 -64.81953)
		)
		(stroke
			(width 0)
			(type solid)
		)
		(fill yes)
		(layer "B.Cu")
		(net "GND")
	)
	(gr_poly
		(pts
			(xy 157.193996 -62.91453) (xy 157.193996 -62.33033) (xy 157.117796 -62.25413) (xy 150.539196 -62.25413)
			(xy 150.335996 -62.45733) (xy 150.335996 -62.91453) (xy 150.437596 -63.01613) (xy 157.092396 -63.01613)
		)
		(stroke
			(width 0)
			(type solid)
		)
		(fill yes)
		(layer "B.Cu")
		(net "P1V8_SATA_VAA2_1_NODE1")
	)
	(gr_poly
		(pts
			(xy 162.651948 -108.585508) (xy 162.651948 -107.903772) (xy 162.478212 -107.730036) (xy 160.755076 -107.730036)
			(xy 160.63722 -107.847892) (xy 160.63722 -108.560616) (xy 160.786064 -108.70946) (xy 162.527996 -108.70946)
		)
		(stroke
			(width 0)
			(type solid)
		)
		(fill yes)
		(layer "B.Cu")
		(net "P3V3_NODE1")
	)
	(gr_poly
		(pts
			(xy 183.863488 -159.161226) (xy 183.863488 -157.033214) (xy 183.731408 -156.901134) (xy 180.782976 -156.901134)
			(xy 180.271928 -157.412182) (xy 180.271928 -159.165798) (xy 180.378608 -159.272478) (xy 183.752236 -159.272478)
		)
		(stroke
			(width 0)
			(type solid)
		)
		(fill yes)
		(layer "B.Cu")
		(net "GND")
	)
	(gr_poly
		(pts
			(xy 194.193668 -27.366722) (xy 194.193668 -26.051764) (xy 193.96202 -25.820116) (xy 191.904112 -25.820116)
			(xy 191.76746 -25.956514) (xy 191.76746 -27.472132) (xy 191.917828 -27.6225) (xy 193.93789 -27.6225)
		)
		(stroke
			(width 0)
			(type solid)
		)
		(fill yes)
		(layer "B.Cu")
		(net "GND")
	)
	(gr_poly
		(pts
			(xy 51.119024 -114.71783) (xy 51.119024 -112.806226) (xy 50.859944 -112.547146) (xy 50.238406 -112.547146)
			(xy 47.80661 -112.547146) (xy 47.80661 -115.260628) (xy 47.846996 -115.301014) (xy 50.345848 -115.301014)
			(xy 50.53584 -115.301014)
		)
		(stroke
			(width 0)
			(type solid)
		)
		(fill yes)
		(layer "B.Cu")
		(net "GND")
	)
	(gr_poly
		(pts
			(xy 76.875132 -149.457664) (xy 76.834746 -149.417278) (xy 74.335894 -149.417278) (xy 73.020936 -149.417278)
			(xy 72.845422 -149.592792) (xy 72.845422 -151.971248) (xy 73.04532 -152.171146) (xy 74.443336 -152.171146)
			(xy 76.875132 -152.171146)
		)
		(stroke
			(width 0)
			(type solid)
		)
		(fill yes)
		(layer "B.Cu")
		(net "GND")
	)
	(gr_poly
		(pts
			(xy 100.393754 -149.492208) (xy 100.353368 -149.451822) (xy 97.854516 -149.451822) (xy 97.001584 -149.451822)
			(xy 96.746568 -149.706838) (xy 96.746568 -152.020524) (xy 96.931734 -152.20569) (xy 97.961958 -152.20569)
			(xy 100.393754 -152.20569)
		)
		(stroke
			(width 0)
			(type solid)
		)
		(fill yes)
		(layer "B.Cu")
		(net "GND")
	)
	(gr_poly
		(pts
			(xy 177.66538 -49.665128) (xy 177.66538 -47.491142) (xy 177.66538 -47.15002) (xy 177.405284 -46.889924)
			(xy 171.442634 -46.889924) (xy 171.24934 -47.083218) (xy 171.24934 -49.746408) (xy 171.38142 -49.878488)
			(xy 177.45202 -49.878488)
		)
		(stroke
			(width 0)
			(type solid)
		)
		(fill yes)
		(layer "B.Cu")
		(net "P5V_NODE1")
	)
	(gr_poly
		(pts
			(xy 188.37402 -29.344874) (xy 188.37402 -29.051504) (xy 188.37402 -26.04643) (xy 187.933838 -25.606248)
			(xy 184.214516 -25.606248) (xy 183.85282 -25.967944) (xy 183.85282 -29.39669) (xy 184.1881 -29.73197)
			(xy 187.986924 -29.73197)
		)
		(stroke
			(width 0)
			(type solid)
		)
		(fill yes)
		(layer "B.Cu")
		(net "GND")
	)
	(gr_poly
		(pts
			(xy 20.085558 -76.680568) (xy 20.085558 -74.472546) (xy 19.984466 -74.371454) (xy 17.978882 -74.371454)
			(xy 17.757648 -74.15022) (xy 16.59509 -74.15022) (xy 16.043656 -74.701654) (xy 16.043656 -76.952094)
			(xy 16.2814 -77.189838) (xy 19.576288 -77.189838)
		)
		(stroke
			(width 0)
			(type solid)
		)
		(fill yes)
		(layer "B.Cu")
		(net "VCC5_CRTXX")
	)
	(gr_poly
		(pts
			(xy 43.161458 -9.721088) (xy 43.161458 -6.694932) (xy 42.983404 -6.516878) (xy 41.820338 -6.516878)
			(xy 41.757092 -6.580124) (xy 41.757092 -9.13765) (xy 40.601138 -10.293604) (xy 40.601138 -10.574528)
			(xy 41.195244 -11.168634) (xy 41.713912 -11.168634)
		)
		(stroke
			(width 0)
			(type solid)
		)
		(fill yes)
		(layer "B.Cu")
		(net "SW_PV_VDDR_NODE1_DRVH")
	)
	(gr_poly
		(pts
			(xy 57.3405 -143.24965) (xy 57.3405 -139.850114) (xy 57.906412 -139.284202) (xy 57.906412 -138.695176)
			(xy 57.67832 -138.467084) (xy 56.771794 -138.467084) (xy 55.874412 -139.364466) (xy 55.874412 -143.216122)
			(xy 56.077612 -143.419322) (xy 57.171082 -143.419322)
		)
		(stroke
			(width 0)
			(type solid)
		)
		(fill yes)
		(layer "B.Cu")
		(net "GND")
	)
	(gr_poly
		(pts
			(xy 70.9422 -31.387034) (xy 70.9422 -29.802328) (xy 70.69709 -29.557218) (xy 69.820282 -29.557218)
			(xy 66.990722 -29.557218) (xy 66.919602 -29.628338) (xy 66.919602 -31.413958) (xy 66.970402 -31.464758)
			(xy 69.921882 -31.464758) (xy 70.864476 -31.464758)
		)
		(stroke
			(width 0)
			(type solid)
		)
		(fill yes)
		(layer "B.Cu")
		(net "P1V5_NODE1_DDR3_VREF_A_A")
	)
	(gr_poly
		(pts
			(xy 108.973112 -132.00253) (xy 108.973112 -130.521456) (xy 108.713524 -130.261868) (xy 107.81919 -130.261868)
			(xy 107.646216 -130.434842) (xy 107.646216 -130.877056) (xy 108.040424 -131.271264) (xy 108.040424 -131.982972)
			(xy 108.175044 -132.117592) (xy 108.85805 -132.117592)
		)
		(stroke
			(width 0)
			(type solid)
		)
		(fill yes)
		(layer "B.Cu")
		(net "VR_PVCCP_NODE1_LGATE1")
	)
	(gr_poly
		(pts
			(xy 110.908084 -137.956798) (xy 110.908084 -136.81075) (xy 110.785148 -136.687814) (xy 110.258098 -136.687814)
			(xy 109.852206 -137.093706) (xy 108.930186 -137.093706) (xy 108.880656 -137.093706) (xy 108.880656 -137.893044)
			(xy 109.153198 -138.165586) (xy 110.699296 -138.165586)
		)
		(stroke
			(width 0)
			(type solid)
		)
		(fill yes)
		(layer "B.Cu")
		(net "VR_PVCCP_NODE1_VCC")
	)
	(gr_poly
		(pts
			(xy 119.099076 -131.09321) (xy 119.099076 -129.280412) (xy 119.099076 -128.458722) (xy 118.951248 -128.310894)
			(xy 117.05844 -128.310894) (xy 116.652548 -128.716786) (xy 116.652548 -129.145792) (xy 116.652548 -130.827272)
			(xy 117.201442 -131.376166) (xy 118.81612 -131.376166)
		)
		(stroke
			(width 0)
			(type solid)
		)
		(fill yes)
		(layer "B.Cu")
		(net "P12V_AUX")
	)
	(gr_poly
		(pts
			(xy 154.984196 -61.82233) (xy 154.984196 -60.95873) (xy 154.755596 -60.73013) (xy 151.402796 -60.73013)
			(xy 151.352504 -60.780422) (xy 151.352504 -61.57214) (xy 151.275796 -61.648594) (xy 151.275796 -61.87313)
			(xy 151.326596 -61.92393) (xy 154.882596 -61.92393)
		)
		(stroke
			(width 0)
			(type solid)
		)
		(fill yes)
		(layer "B.Cu")
		(net "GND")
	)
	(gr_poly
		(pts
			(xy 157.105096 -65.67043) (xy 157.105096 -65.18783) (xy 157.041596 -65.12433) (xy 151.148796 -65.12433)
			(xy 150.996396 -64.97193) (xy 150.716996 -64.97193) (xy 150.539196 -65.14973) (xy 150.539196 -65.63233)
			(xy 150.666196 -65.75933) (xy 157.016196 -65.75933)
		)
		(stroke
			(width 0)
			(type solid)
		)
		(fill yes)
		(layer "B.Cu")
		(net "P1V8_SATA_VAA2_0_NODE1")
	)
	(gr_poly
		(pts
			(xy 191.22136 -29.573474) (xy 191.22136 -29.446728) (xy 191.22136 -25.20823) (xy 190.96736 -24.95423)
			(xy 188.984636 -24.95423) (xy 188.79058 -25.148286) (xy 188.79058 -29.616654) (xy 189.00902 -29.835094)
			(xy 190.832994 -29.835094) (xy 190.95974 -29.835094)
		)
		(stroke
			(width 0)
			(type solid)
		)
		(fill yes)
		(layer "B.Cu")
		(net "P5V_NODE1")
	)
	(gr_poly
		(pts
			(xy 75.656186 -14.011656) (xy 76.22032 -13.447522) (xy 76.22032 -9.50087) (xy 75.734926 -9.015476)
			(xy 75.349862 -9.015476) (xy 74.477118 -9.015476) (xy 72.045322 -9.015476) (xy 72.045322 -11.728958)
			(xy 72.045322 -13.987272) (xy 72.132952 -14.075156) (xy 75.592686 -14.075156)
		)
		(stroke
			(width 0)
			(type solid)
		)
		(fill yes)
		(layer "B.Cu")
		(net "GND")
	)
	(gr_poly
		(pts
			(xy 117.96014 -23.76932) (xy 117.96014 -23.012146) (xy 117.96014 -22.554438) (xy 117.96014 -21.672296)
			(xy 117.790468 -21.502624) (xy 110.751112 -21.502624) (xy 110.60684 -21.646896) (xy 110.60684 -23.649432)
			(xy 110.885224 -23.927816) (xy 113.54308 -23.927816) (xy 117.801644 -23.927816)
		)
		(stroke
			(width 0)
			(type solid)
		)
		(fill yes)
		(layer "B.Cu")
		(net "GND")
	)
	(gr_poly
		(pts
			(xy 122.656092 -32.051498) (xy 122.648472 -32.043878) (xy 122.648472 -31.716726) (xy 122.57659 -31.644844)
			(xy 122.27433 -31.644844) (xy 122.261884 -31.65729) (xy 120.306338 -31.65729) (xy 120.117362 -31.84652)
			(xy 120.117362 -33.840928) (xy 120.566688 -34.290254) (xy 122.656092 -34.290254)
		)
		(stroke
			(width 0)
			(type solid)
		)
		(fill yes)
		(layer "B.Cu")
		(net "GND")
	)
	(gr_poly
		(pts
			(xy 16.198596 -125.695202) (xy 16.198596 -123.325382) (xy 16.198596 -121.148348) (xy 15.998444 -120.948196)
			(xy 15.532862 -120.948196) (xy 13.511784 -120.948196) (xy 13.251434 -121.208546) (xy 13.251434 -123.948952)
			(xy 13.251434 -125.75286) (xy 13.416534 -125.91796) (xy 14.58341 -125.91796) (xy 15.975838 -125.91796)
		)
		(stroke
			(width 0)
			(type solid)
		)
		(fill yes)
		(layer "B.Cu")
		(net "SW_P1V05_NODE1_VIN_FLT")
	)
	(gr_poly
		(pts
			(xy 19.126708 -149.069552) (xy 19.126708 -147.90166) (xy 18.483072 -147.258024) (xy 18.483072 -139.889992)
			(xy 18.483072 -138.954256) (xy 18.064734 -138.535918) (xy 16.08328 -138.535918) (xy 15.909036 -138.710162)
			(xy 15.909036 -141.141704) (xy 15.909036 -147.460716) (xy 17.78 -149.33168) (xy 18.86458 -149.33168)
		)
		(stroke
			(width 0)
			(type solid)
		)
		(fill yes)
		(layer "B.Cu")
		(net "GND")
	)
	(gr_poly
		(pts
			(arc
				(start 63.718948 -159.115252)
				(mid 63.746518 -159.07413)
				(end 63.756286 -159.02559)
			)
			(xy 63.756286 -152.828752) (xy 63.501778 -152.574244) (xy 61.628782 -152.574244) (xy 61.45403 -152.748996)
			(xy 61.45403 -158.700724) (xy 61.912246 -159.15894) (xy 63.675006 -159.15894)
		)
		(stroke
			(width 0)
			(type solid)
		)
		(fill yes)
		(layer "B.Cu")
		(net "GND")
	)
	(gr_poly
		(pts
			(arc
				(start 91.739974 -84.963762)
				(mid 91.767544 -84.92264)
				(end 91.777312 -84.8741)
			)
			(xy 91.777312 -83.347052) (xy 91.46794 -83.03768) (xy 89.02319 -83.03768) (xy 88.69426 -83.36661)
			(xy 88.69426 -84.922868) (xy 88.89238 -85.120988) (xy 91.582748 -85.120988)
		)
		(stroke
			(width 0)
			(type solid)
		)
		(fill yes)
		(layer "B.Cu")
		(net "GND")
	)
	(gr_poly
		(pts
			(xy 102.85984 -117.703854) (xy 102.85984 -114.44224) (xy 103.64216 -113.65992) (xy 104.692958 -113.65992)
			(xy 104.8131 -113.539778) (xy 104.8131 -104.243632) (xy 104.42194 -103.852472) (xy 101.38918 -103.852472)
			(xy 100.8507 -104.390952) (xy 100.8507 -117.428772) (xy 101.135942 -117.714014) (xy 102.84968 -117.714014)
		)
		(stroke
			(width 0)
			(type solid)
		)
		(fill yes)
		(layer "B.Cu")
		(net "GND")
	)
	(gr_poly
		(pts
			(xy 106.586528 -127.37719) (xy 106.586528 -124.310648) (xy 106.444288 -124.168408) (xy 103.440992 -124.168408)
			(xy 102.449122 -124.168408) (xy 102.319836 -124.168408) (xy 102.238048 -124.250196) (xy 102.238048 -127.23114)
			(xy 102.33025 -127.323342) (xy 102.494842 -127.487934) (xy 103.425244 -127.487934) (xy 106.475784 -127.487934)
		)
		(stroke
			(width 0)
			(type solid)
		)
		(fill yes)
		(layer "B.Cu")
		(net "GND")
	)
	(gr_poly
		(pts
			(xy 109.205014 -136.635998) (xy 109.205014 -132.68198) (xy 108.982256 -132.459222) (xy 107.876594 -132.459222)
			(xy 107.199684 -133.136132) (xy 105.81132 -133.136132) (xy 105.746042 -133.20141) (xy 105.746042 -136.632188)
			(xy 105.749344 -136.63549) (xy 108.380022 -136.63549) (xy 108.401104 -136.656826) (xy 109.184186 -136.656826)
		)
		(stroke
			(width 0)
			(type solid)
		)
		(fill yes)
		(layer "B.Cu")
		(net "GND")
	)
	(gr_poly
		(pts
			(xy 126.1618 -34.49066) (xy 126.1618 -33.71977) (xy 125.95606 -33.51403) (xy 125.4887 -33.51403)
			(xy 125.329696 -33.355026) (xy 125.329696 -31.107634) (xy 124.999242 -30.77718) (xy 123.909328 -30.77718)
			(xy 122.989848 -31.69666) (xy 122.989848 -34.43478) (xy 123.16206 -34.606992) (xy 126.045468 -34.606992)
		)
		(stroke
			(width 0)
			(type solid)
		)
		(fill yes)
		(layer "B.Cu")
		(net "SIO_VCCH")
	)
	(gr_poly
		(pts
			(arc
				(start 175.02378 -159.3088)
				(mid 175.113583 -159.271603)
				(end 175.15078 -159.1818)
			)
			(xy 175.15078 -157.642306) (xy 175.099726 -157.591252) (xy 173.29658 -157.591252) (xy 173.29658 -159.3088)
		)
		(stroke
			(width 0)
			(type solid)
		)
		(fill yes)
		(layer "B.Cu")
		(net "GND")
	)
	(gr_poly
		(pts
			(xy 12.949174 -120.524016) (xy 12.949174 -118.855998) (xy 13.55344 -118.251732) (xy 13.55344 -117.12448)
			(xy 13.467334 -117.038374) (xy 12.19708 -117.038374) (xy 10.885424 -118.35003) (xy 10.885424 -118.635272)
			(xy 10.885424 -118.688104) (xy 10.885424 -119.05488) (xy 10.885424 -120.631966) (xy 12.53744 -120.631966)
			(xy 12.841224 -120.631966)
		)
		(stroke
			(width 0)
			(type solid)
		)
		(fill yes)
		(layer "B.Cu")
		(net "P12V_AUX")
	)
	(gr_poly
		(pts
			(xy 57.578752 -124.980192) (xy 58.229246 -124.980192) (xy 58.261504 -124.947934) (xy 58.261504 -123.361958)
			(xy 58.052208 -123.152662) (xy 57.996328 -123.152662) (xy 57.330086 -123.152662) (xy 57.203086 -123.279662)
			(xy 57.203086 -124.295662) (xy 56.695086 -124.803662) (xy 56.695086 -125.057662) (xy 56.822086 -125.184662)
			(xy 57.374282 -125.184662)
		)
		(stroke
			(width 0)
			(type solid)
		)
		(fill yes)
		(layer "B.Cu")
		(net "BMC_NODE1_HPLLAV33")
	)
	(gr_poly
		(pts
			(xy 64.96304 -14.743938) (xy 64.96304 -9.071356) (xy 64.39916 -8.507476) (xy 64.39916 -7.467346)
			(xy 64.043052 -7.111238) (xy 53.54955 -7.111238) (xy 53.082444 -7.578344) (xy 51.5493 -9.111488)
			(xy 51.5493 -13.170154) (xy 52.117752 -13.738606) (xy 55.201312 -13.738606) (xy 56.27624 -14.813534)
			(xy 64.893444 -14.813534)
		)
		(stroke
			(width 0)
			(type solid)
		)
		(fill yes)
		(layer "B.Cu")
		(net "PV_VDDR_NODE1")
	)
	(gr_poly
		(pts
			(xy 138.503406 -104.73436) (xy 138.503406 -103.701596) (xy 138.494262 -103.689658) (xy 138.494262 -102.36581)
			(xy 137.65403 -101.525578) (xy 136.855708 -101.525578) (xy 134.929626 -101.525578) (xy 134.527036 -101.928168)
			(xy 134.527036 -102.859078) (xy 134.523734 -102.86238) (xy 134.523734 -104.672384) (xy 134.79653 -104.94518)
			(xy 138.292586 -104.94518)
		)
		(stroke
			(width 0)
			(type solid)
		)
		(fill yes)
		(layer "B.Cu")
		(net "P3V3_CLK_NODE1_R")
	)
	(gr_poly
		(pts
			(xy 167.644064 -78.36916) (xy 167.894254 -78.11897) (xy 167.894254 -76.655168) (xy 167.894254 -76.467462)
			(xy 167.894254 -75.536298) (xy 167.66794 -75.309984) (xy 166.527226 -75.309984) (xy 165.914578 -75.922632)
			(xy 164.70376 -75.922632) (xy 164.45738 -76.169012) (xy 164.45738 -78.320392) (xy 164.604446 -78.467458)
			(xy 167.545766 -78.467458)
		)
		(stroke
			(width 0)
			(type solid)
		)
		(fill yes)
		(layer "B.Cu")
		(net "P1V8_NODE1")
	)
	(gr_poly
		(pts
			(xy 16.87449 -131.04114) (xy 16.87449 -129.537206) (xy 16.819626 -129.482342) (xy 15.297404 -129.482342)
			(xy 15.260828 -129.518918)
			(arc
				(start 15.260828 -130.95986)
				(mid 15.298025 -131.049663)
				(end 15.387828 -131.08686)
			)
			(xy 16.82877 -131.08686)
		)
		(stroke
			(width 0)
			(type solid)
		)
		(fill yes)
		(layer "B.Cu")
		(net "GND")
	)
	(gr_poly
		(pts
			(xy 37.72916 -160.096962) (xy 37.72916 -159.67329) (xy 37.72916 -157.47365) (xy 37.75456 -157.44825)
			(xy 37.75456 -155.03017) (xy 37.34816 -154.62377) (xy 36.43884 -154.62377) (xy 36.30422 -154.75839)
			(xy 36.30422 -156.69641) (xy 36.30422 -159.65805) (xy 36.304728 -159.658812) (xy 36.304728 -160.259268)
			(xy 36.55822 -160.51276) (xy 37.313362 -160.51276)
		)
		(stroke
			(width 0)
			(type solid)
		)
		(fill yes)
		(layer "B.Cu")
		(net "GND")
	)
	(gr_poly
		(pts
			(xy 48.91913 -3.891026) (xy 48.91913 -1.505204) (xy 48.87595 -1.462024) (xy 41.41724 -1.462024) (xy 40.930322 -1.948942)
			(xy 40.930322 -2.879598) (xy 40.930322 -3.747516) (xy 41.170352 -3.987546) (xy 42.221404 -3.987546)
			(xy 42.234104 -4.000246) (xy 43.07586 -4.000246) (xy 44.5516 -4.000246) (xy 48.456088 -4.000246)
			(xy 48.80991 -4.000246)
		)
		(stroke
			(width 0)
			(type solid)
		)
		(fill yes)
		(layer "B.Cu")
		(net "GND")
	)
	(gr_poly
		(pts
			(xy 52.42814 -4.003548) (xy 52.42814 -1.922526) (xy 52.229766 -1.724152) (xy 49.3903 -1.724152) (xy 49.285144 -1.829308)
			(arc
				(start 49.285144 -4.056126)
				(mid 49.322341 -4.145929)
				(end 49.412144 -4.183126)
			)
			(xy 52.248562 -4.183126)
		)
		(stroke
			(width 0)
			(type solid)
		)
		(fill yes)
		(layer "B.Cu")
		(net "P12V_AUX")
	)
	(gr_poly
		(pts
			(xy 62.414658 -111.51616) (xy 62.414658 -105.754424) (xy 62.146434 -105.4862) (xy 60.256928 -105.4862)
			(xy 59.978544 -105.764584)
			(arc
				(start 59.978544 -112.017048)
				(mid 60.015741 -112.106851)
				(end 60.105544 -112.144048)
			)
			(xy 61.78677 -112.144048)
		)
		(stroke
			(width 0)
			(type solid)
		)
		(fill yes)
		(layer "B.Cu")
		(net "GND")
	)
	(gr_poly
		(pts
			(xy 64.010286 -131.285488) (xy 64.010286 -130.696462) (xy 63.629286 -130.315462) (xy 63.629286 -130.188462)
			(xy 63.629286 -130.068828) (xy 63.629286 -129.840228) (xy 63.527686 -129.738628) (xy 62.359286 -129.738628)
			(xy 62.257686 -129.840228) (xy 62.257686 -130.576828) (xy 62.867286 -131.186428) (xy 62.867286 -131.253992)
			(xy 63.101728 -131.488434) (xy 63.80734 -131.488434)
		)
		(stroke
			(width 0)
			(type solid)
		)
		(fill yes)
		(layer "B.Cu")
		(net "P1V26_BMC_NODE1")
	)
	(gr_poly
		(pts
			(xy 64.94272 -17.111726) (xy 64.94272 -15.210028) (xy 64.809624 -15.076932) (xy 56.132476 -15.076932)
			(xy 55.71998 -15.489428)
			(arc
				(start 55.71998 -17.183608)
				(mid 55.757177 -17.273411)
				(end 55.84698 -17.310608)
			)
			(xy 64.743838 -17.310608)
		)
		(stroke
			(width 0)
			(type solid)
		)
		(fill yes)
		(layer "B.Cu")
		(net "GND")
	)
	(gr_poly
		(pts
			(xy 106.167428 -116.632736) (xy 113.628424 -116.632736) (xy 114.3381 -115.92306) (xy 114.3381 -104.722422)
			(xy 113.410746 -103.795068) (xy 105.9561 -103.795068) (xy 105.50652 -104.244648) (xy 105.50652 -113.614454)
			(xy 105.085896 -114.035078) (xy 103.85552 -114.035078) (xy 103.65994 -114.230658) (xy 103.65994 -117.60835)
			(xy 103.85552 -117.80393) (xy 104.996234 -117.80393)
		)
		(stroke
			(width 0)
			(type solid)
		)
		(fill yes)
		(layer "B.Cu")
		(net "PV_VCCP_NODE1")
	)
	(gr_poly
		(pts
			(xy 140.995146 -104.746806) (xy 140.995146 -103.271574) (xy 140.741146 -103.017574) (xy 139.191238 -103.017574)
			(xy 139.000738 -103.208074)
			(arc
				(start 138.994642 -103.24973)
				(mid 138.973364 -103.335514)
				(end 138.935968 -103.415592)
			)
			(xy 138.918442 -103.445564) (xy 138.918442 -104.920542) (xy 139.011406 -105.013506) (xy 140.728446 -105.013506)
		)
		(stroke
			(width 0)
			(type solid)
		)
		(fill yes)
		(layer "B.Cu")
		(net "P3V3_NODE1")
	)
	(gr_poly
		(pts
			(xy 142.253716 -160.98266) (xy 142.253716 -158.190438) (xy 142.226538 -158.16326) (xy 138.788394 -158.16326)
			(xy 138.66114 -158.290514)
			(arc
				(start 138.66114 -160.919414)
				(mid 138.698337 -161.009217)
				(end 138.78814 -161.046414)
			)
			(xy 142.189962 -161.046414)
		)
		(stroke
			(width 0)
			(type solid)
		)
		(fill yes)
		(layer "B.Cu")
		(net "GND")
	)
	(gr_poly
		(pts
			(xy 150.746968 -51.300888) (xy 150.746968 -48.490886) (xy 150.492968 -48.236886) (xy 146.657568 -48.236886)
			(xy 146.39036 -48.504094)
			(arc
				(start 146.39036 -51.363626)
				(mid 146.427557 -51.453429)
				(end 146.51736 -51.490626)
			)
			(xy 150.556976 -51.490626)
		)
		(stroke
			(width 0)
			(type solid)
		)
		(fill yes)
		(layer "B.Cu")
		(net "GND")
	)
	(gr_poly
		(pts
			(xy 170.71848 -55.356252) (xy 170.71848 -54.408832) (xy 170.71848 -48.203104) (xy 170.71848 -47.66056)
			(xy 170.716448 -47.658528) (xy 170.94454 -47.430436) (xy 170.94454 -46.829472) (xy 170.393614 -46.278546)
			(xy 167.55872 -46.278546) (xy 166.9923 -46.844966) (xy 166.9923 -47.643288) (xy 166.9923 -55.523638)
			(xy 167.25646 -55.787798) (xy 170.286934 -55.787798)
		)
		(stroke
			(width 0)
			(type solid)
		)
		(fill yes)
		(layer "B.Cu")
		(net "GND")
	)
	(gr_poly
		(pts
			(xy 176.963832 -124.031248) (xy 176.963832 -123.635008) (xy 177.146712 -123.452128) (xy 177.30216 -123.452128)
			(xy 177.754026 -123.000516) (xy 177.754026 -122.66803) (xy 177.678842 -122.592846) (xy 177.221642 -122.592846)
			(xy 177.018442 -122.796046) (xy 176.535842 -122.796046) (xy 176.053242 -123.278646) (xy 176.053242 -123.958858)
			(xy 176.222406 -124.128022) (xy 176.867312 -124.128022)
		)
		(stroke
			(width 0)
			(type solid)
		)
		(fill yes)
		(layer "B.Cu")
		(net "GND")
	)
	(gr_poly
		(pts
			(xy 65.966086 -131.335018) (xy 66.068702 -131.232402) (xy 66.068702 -130.359912) (xy 66.068702 -129.930906)
			(xy 65.37579 -129.930906) (xy 65.081912 -129.637028) (xy 63.984886 -129.637028) (xy 63.883794 -129.738374)
			(xy 63.883794 -129.963418) (xy 63.894462 -129.974086) (xy 63.894462 -130.112262) (xy 64.333374 -130.551174)
			(xy 64.333374 -131.42595) (xy 64.391286 -131.483862) (xy 65.817242 -131.483862)
		)
		(stroke
			(width 0)
			(type solid)
		)
		(fill yes)
		(layer "B.Cu")
		(net "P3V3_NODE1")
	)
	(gr_poly
		(pts
			(xy 66.46799 -31.83255) (xy 66.46799 -30.505908)
			(arc
				(start 66.476118 -30.49778)
				(mid 66.487104 -30.469088)
				(end 66.49085 -30.438598)
			)
			(xy 66.49085 -29.594048) (xy 66.342514 -29.445712) (xy 65.458086 -29.445712) (xy 65.383918 -29.51988)
			(xy 65.383918 -30.383988) (xy 65.1764 -30.591506) (xy 65.1764 -31.914592) (xy 65.303908 -32.0421)
			(xy 66.25844 -32.0421)
		)
		(stroke
			(width 0)
			(type solid)
		)
		(fill yes)
		(layer "B.Cu")
		(net "GND")
	)
	(gr_poly
		(pts
			(xy 199.0471 -151.117046) (xy 199.0471 -139.49807) (xy 198.762366 -139.213336) (xy 193.52006 -139.213336)
			(xy 193.29908 -139.434316) (xy 193.29908 -141.641322) (xy 193.29908 -142.665704) (xy 193.3956 -142.762224)
			(xy 193.3956 -145.62582) (xy 193.65976 -145.88998) (xy 193.65976 -149.446488) (xy 193.65976 -150.987506)
			(xy 193.90106 -151.228806) (xy 196.86016 -151.228806) (xy 198.93534 -151.228806)
		)
		(stroke
			(width 0)
			(type solid)
		)
		(fill yes)
		(layer "B.Cu")
		(net "GND")
	)
	(gr_poly
		(pts
			(xy 48.328834 -17.107916) (xy 48.328834 -13.11275) (xy 48.20539 -12.989306) (xy 47.864776 -12.989306)
			(xy 45.717714 -12.989306) (xy 45.3898 -12.661392) (xy 45.3898 -11.59002) (xy 45.249338 -11.449558)
			(xy 43.461686 -11.449558) (xy 43.415458 -11.495532) (xy 43.415458 -13.4366) (xy 43.415458 -13.901166)
			(xy 43.415458 -16.934942) (xy 43.600878 -17.120362) (xy 47.802546 -17.120362) (xy 48.316388 -17.120362)
		)
		(stroke
			(width 0)
			(type solid)
		)
		(fill yes)
		(layer "B.Cu")
		(net "GND")
	)
	(gr_poly
		(pts
			(xy 56.568086 -130.010662) (xy 56.568086 -129.629662) (xy 57.076086 -129.121662) (xy 57.076086 -127.851662)
			(xy 56.441086 -127.216662) (xy 56.441086 -126.454662) (xy 56.060086 -126.073662) (xy 54.028086 -126.073662)
			(xy 53.824886 -126.276862) (xy 53.824886 -126.886462) (xy 53.913786 -126.975362) (xy 55.437786 -126.975362)
			(xy 55.679086 -127.216662) (xy 55.679086 -130.010662) (xy 55.806086 -130.137662) (xy 56.441086 -130.137662)
		)
		(stroke
			(width 0)
			(type solid)
		)
		(fill yes)
		(layer "B.Cu")
		(net "BMC_NODE1_MPLLAV33")
	)
	(gr_poly
		(pts
			(xy 64.418972 -78.889098) (xy 64.418972 -78.457298) (xy 64.342772 -78.381098) (xy 63.199772 -78.381098)
			(xy 63.035942 -78.217268) (xy 62.145418 -78.217268) (xy 61.840618 -78.217268) (xy 61.739272 -78.318614)
			(xy 61.739272 -78.801468) (xy 61.796422 -78.858872) (xy 61.844174 -78.878176) (xy 61.870336 -78.877668)
			(xy 61.877448 -78.877414) (xy 62.386972 -78.877414) (xy 62.500256 -78.990698) (xy 64.317372 -78.990698)
		)
		(stroke
			(width 0)
			(type solid)
		)
		(fill yes)
		(layer "B.Cu")
		(net "GND")
	)
	(gr_poly
		(pts
			(xy 67.566286 -139.815062) (xy 67.566286 -139.611862) (xy 67.210686 -139.256262) (xy 67.210686 -137.808462)
			(xy 67.083686 -137.681462) (xy 66.677286 -137.681462) (xy 66.550286 -137.808462) (xy 66.550286 -138.367262)
			(xy 66.651886 -138.468862) (xy 66.651886 -139.307062) (xy 66.575686 -139.383262) (xy 66.372486 -139.383262)
			(xy 66.207386 -139.548362) (xy 66.207386 -139.802362) (xy 66.372486 -139.967462) (xy 67.413886 -139.967462)
		)
		(stroke
			(width 0)
			(type solid)
		)
		(fill yes)
		(layer "B.Cu")
		(net "P1V26_BMC_NODE1")
	)
	(gr_poly
		(pts
			(xy 79.31531 -153.300684) (xy 79.31531 -152.5397) (xy 79.518002 -152.337008) (xy 79.576676 -152.278334)
			(xy 79.586582 -152.268428) (xy 79.586582 -151.270208) (xy 79.845662 -151.011128) (xy 79.845662 -149.784816)
			(xy 79.558642 -149.497796) (xy 77.228446 -149.497796) (xy 77.22362 -149.502622) (xy 77.22362 -152.217374)
			(xy 77.962506 -152.95626) (xy 77.962506 -153.640028) (xy 77.979524 -153.657046) (xy 78.958948 -153.657046)
		)
		(stroke
			(width 0)
			(type solid)
		)
		(fill yes)
		(layer "B.Cu")
		(net "P12V_AUX")
	)
	(gr_poly
		(pts
			(xy 88.000332 -158.516574)
			(arc
				(start 88.000332 -151.926544)
				(mid 87.963135 -151.836741)
				(end 87.873332 -151.799544)
			)
			(xy 86.414356 -151.799544) (xy 85.430868 -152.783032) (xy 85.430868 -154.406092) (xy 85.378798 -154.458162)
			(xy 85.378798 -158.476696) (xy 85.593682 -158.69158) (xy 87.825326 -158.69158)
		)
		(stroke
			(width 0)
			(type solid)
		)
		(fill yes)
		(layer "B.Cu")
		(net "GND")
	)
	(gr_poly
		(pts
			(xy 102.193344 -151.807672) (xy 102.193344 -150.396194) (xy 102.193344 -149.848316) (xy 102.193344 -148.832316)
			(xy 101.994208 -148.63318) (xy 100.954078 -148.63318) (xy 100.742242 -148.845016) (xy 100.742242 -149.537166)
			(xy 100.742242 -151.384254) (xy 100.742242 -151.989028) (xy 100.742242 -152.251918) (xy 100.89769 -152.407366)
			(xy 101.481128 -152.990804) (xy 101.481128 -153.025348) (xy 101.481128 -153.674572) (xy 101.498146 -153.69159)
			(xy 102.193344 -153.69159)
		)
		(stroke
			(width 0)
			(type solid)
		)
		(fill yes)
		(layer "B.Cu")
		(net "P12V_AUX")
	)
	(gr_poly
		(pts
			(xy 23.732236 -149.558248) (xy 23.732236 -148.604986) (xy 23.52802 -148.40077) (xy 23.52802 -143.417036)
			(xy 23.227792 -143.116808) (xy 22.267926 -142.156942) (xy 22.267926 -139.32662) (xy 22.08784 -139.146534)
			(xy 19.340068 -139.146534) (xy 19.168872 -139.31773) (xy 19.168872 -139.803378) (xy 19.168872 -141.322806)
			(xy 19.144234 -141.347698) (xy 19.144234 -147.186904) (xy 19.704304 -147.746974) (xy 19.704304 -149.10562)
			(xy 20.645628 -150.046944) (xy 23.24354 -150.046944)
		)
		(stroke
			(width 0)
			(type solid)
		)
		(fill yes)
		(layer "B.Cu")
		(net "P3V3_NODE1")
	)
	(gr_poly
		(pts
			(arc
				(start 34.33191 -126.910338)
				(mid 34.421713 -126.873141)
				(end 34.45891 -126.783338)
			)
			(arc
				(start 34.45891 -125.164342)
				(mid 34.44916 -125.115795)
				(end 34.421572 -125.07468)
			)
			(xy 34.150554 -124.803662) (xy 33.221168 -124.803662) (xy 32.778954 -125.245876) (xy 32.778954 -126.876556)
			(xy 32.812736 -126.910338)
		)
		(stroke
			(width 0)
			(type solid)
		)
		(fill yes)
		(layer "B.Cu")
		(net "GND")
	)
	(gr_poly
		(pts
			(xy 46.704758 -110.795562) (xy 46.704758 -108.92409) (xy 47.266606 -108.362242) (xy 47.266606 -107.925362)
			(xy 47.278036 -107.913932) (xy 47.278036 -106.838496) (xy 47.259748 -106.820208) (xy 46.328076 -106.820208)
			(xy 46.13021 -107.018074) (xy 46.13021 -107.968034) (xy 46.001686 -108.096558) (xy 46.001686 -109.06887)
			(xy 45.941488 -109.129068) (xy 45.045376 -109.129068) (xy 45.012102 -109.162342) (xy 45.012102 -110.782862)
			(xy 45.025818 -110.796578) (xy 46.703742 -110.796578)
		)
		(stroke
			(width 0)
			(type solid)
		)
		(fill yes)
		(layer "B.Cu")
		(net "GND")
	)
	(gr_poly
		(pts
			(xy 54.916578 -125.33757) (xy 54.916578 -124.48159) (xy 54.916578 -124.444252) (xy 55.298086 -124.062998)
			(arc
				(start 55.298086 -123.406662)
				(mid 55.260889 -123.316859)
				(end 55.171086 -123.279662)
			)
			(xy 52.758086 -123.279662) (xy 52.631086 -123.406662) (xy 52.631086 -125.49251) (xy 52.72405 -125.585474)
			(xy 53.502306 -125.585474) (xy 54.668674 -125.585474)
		)
		(stroke
			(width 0)
			(type solid)
		)
		(fill yes)
		(layer "B.Cu")
		(net "GND")
	)
	(gr_poly
		(pts
			(xy 70.94347 -7.263892) (xy 70.94347 -5.39242) (xy 71.505318 -4.830572) (xy 71.505318 -4.393692)
			(xy 71.516748 -4.382262) (xy 71.516748 -3.306826) (xy 71.49846 -3.288538) (xy 70.566788 -3.288538)
			(xy 70.368922 -3.486404) (xy 70.368922 -4.436364) (xy 70.240398 -4.564888) (xy 70.240398 -5.5372)
			(xy 70.1802 -5.597398) (xy 69.284088 -5.597398) (xy 69.250814 -5.630672) (xy 69.250814 -7.251192)
			(xy 69.26453 -7.264908) (xy 70.942454 -7.264908)
		)
		(stroke
			(width 0)
			(type solid)
		)
		(fill yes)
		(layer "B.Cu")
		(net "GND")
	)
	(gr_poly
		(pts
			(xy 78.551532 -157.700218) (xy 78.551532 -156.750258) (xy 78.680056 -156.621734) (xy 78.680056 -155.649422)
			(xy 78.740254 -155.589224) (xy 79.636366 -155.589224) (xy 79.66964 -155.55595) (xy 79.66964 -153.93543)
			(xy 79.655924 -153.921714) (xy 77.978 -153.921714) (xy 77.976984 -153.92273) (xy 77.976984 -155.794202)
			(xy 77.415136 -156.35605) (xy 77.415136 -156.79293) (xy 77.403706 -156.80436) (xy 77.403706 -157.879796)
			(xy 77.421994 -157.898084) (xy 78.353666 -157.898084)
		)
		(stroke
			(width 0)
			(type solid)
		)
		(fill yes)
		(layer "B.Cu")
		(net "GND")
	)
	(gr_poly
		(pts
			(xy 102.070154 -157.734762) (xy 102.070154 -156.784802) (xy 102.198678 -156.656278) (xy 102.198678 -155.683966)
			(xy 102.258876 -155.623768) (xy 103.154988 -155.623768) (xy 103.188262 -155.590494) (xy 103.188262 -153.969974)
			(xy 103.174546 -153.956258) (xy 101.496622 -153.956258) (xy 101.495606 -153.957274) (xy 101.495606 -155.828746)
			(xy 100.933758 -156.390594) (xy 100.933758 -156.827474) (xy 100.922328 -156.838904) (xy 100.922328 -157.91434)
			(xy 100.940616 -157.932628) (xy 101.872288 -157.932628)
		)
		(stroke
			(width 0)
			(type solid)
		)
		(fill yes)
		(layer "B.Cu")
		(net "GND")
	)
	(gr_poly
		(pts
			(arc
				(start 55.297578 -130.010662)
				(mid 55.387381 -129.973465)
				(end 55.424578 -129.883662)
			)
			(xy 55.424578 -127.322072) (xy 55.332376 -127.22987) (xy 53.968904 -127.22987) (xy 53.808376 -127.22987)
			(xy 53.570632 -126.991872) (xy 53.570632 -126.831598) (xy 52.949094 -126.21006) (xy 52.581302 -126.21006)
			(xy 51.453796 -127.337566) (xy 51.453796 -129.847086) (xy 51.617372 -130.010662)
		)
		(stroke
			(width 0)
			(type solid)
		)
		(fill yes)
		(layer "B.Cu")
		(net "GND")
	)
	(gr_poly
		(pts
			(xy 26.429208 -125.660912) (xy 26.429208 -125.325886) (xy 26.429208 -121.130568) (xy 26.136092 -120.837452)
			(xy 25.204928 -120.837452) (xy 22.076918 -120.837452) (xy 21.919692 -120.994678) (xy 21.919692 -123.575572)
			(xy 21.752306 -123.742958) (xy 20.31365 -123.742958) (xy 20.209002 -123.847606) (xy 20.209002 -124.210064)
			(xy 20.20443 -124.214636) (xy 20.20443 -125.858524) (xy 20.241514 -125.895608) (xy 22.218396 -125.895608)
			(xy 22.682962 -125.895608) (xy 25.419812 -125.895608) (xy 25.859486 -125.895608) (xy 26.194512 -125.895608)
		)
		(stroke
			(width 0)
			(type solid)
		)
		(fill yes)
		(layer "B.Cu")
		(net "GND")
	)
	(gr_poly
		(pts
			(xy 52.14112 -7.107936) (xy 52.14112 -4.760976) (xy 51.859942 -4.479798) (xy 50.95367 -4.479798)
			(xy 48.116744 -4.479798) (xy 45.376338 -4.479798) (xy 43.730926 -4.479798) (xy 43.516042 -4.479798)
			(xy 43.277028 -4.718812) (xy 43.277028 -5.769102) (xy 43.288204 -5.780278) (xy 43.288204 -5.973064)
			(xy 43.77944 -6.4643) (xy 43.77944 -7.01421) (xy 44.19219 -7.42696) (xy 44.93514 -7.42696) (xy 45.999908 -7.42696)
			(xy 48.176942 -7.42696) (xy 51.035712 -7.42696) (xy 51.822096 -7.42696)
		)
		(stroke
			(width 0)
			(type solid)
		)
		(fill yes)
		(layer "B.Cu")
		(net "SW_PV_VDDR_NODE1_VIN_FLT")
	)
	(gr_poly
		(pts
			(arc
				(start 57.331864 -71.614538)
				(mid 57.350611 -71.613109)
				(end 57.368948 -71.60895)
			)
			(xy 57.972706 -71.60895) (xy 58.07456 -71.507096) (xy 58.07456 -71.139558) (xy 58.017664 -71.082662)
			(xy 57.54878 -71.082662) (xy 57.528968 -71.082662) (xy 57.458864 -71.012558) (xy 57.458864 -70.15226)
			(xy 57.352946 -70.046088) (xy 56.982106 -70.046088) (xy 56.90997 -70.046088) (xy 56.690768 -70.26529)
			(xy 56.690768 -70.580758) (xy 56.800496 -70.690486) (xy 56.800496 -71.514462) (xy 56.900572 -71.614538)
		)
		(stroke
			(width 0)
			(type solid)
		)
		(fill yes)
		(layer "B.Cu")
		(net "GND")
	)
	(gr_poly
		(pts
			(xy 59.064398 -77.289406) (xy 59.064398 -77.019404) (xy 59.03341 -76.988416) (xy 59.03341 -76.736448)
			(xy 59.006232 -76.70927) (xy 57.949084 -76.70927) (xy 57.949084 -76.680822) (xy 57.601358 -76.680822)
			(xy 57.587134 -76.666344) (xy 56.843676 -76.666344) (xy 56.767984 -76.74229) (xy 56.152796 -76.74229)
			(xy 56.152034 -76.743052) (xy 56.152034 -77.16774) (xy 56.26481 -77.280516) (xy 58.342276 -77.280516)
			(xy 58.373772 -77.24902) (xy 58.56224 -77.24902) (xy 58.653426 -77.340206) (xy 59.013598 -77.340206)
		)
		(stroke
			(width 0)
			(type solid)
		)
		(fill yes)
		(layer "B.Cu")
		(net "GND")
	)
	(gr_poly
		(pts
			(xy 61.546486 -134.412228) (xy 61.978286 -134.412228) (xy 62.054486 -134.336028) (xy 62.054486 -133.802628)
			(xy 61.978286 -133.726428) (xy 61.444886 -133.726428) (xy 61.292486 -133.574028) (xy 61.292486 -133.116828)
			(xy 61.165486 -132.989828) (xy 60.657486 -132.989828) (xy 60.632594 -133.014974)
			(arc
				(start 60.632594 -134.386574)
				(mid 60.669791 -134.476377)
				(end 60.759594 -134.513574)
			)
			(xy 61.44514 -134.513574)
		)
		(stroke
			(width 0)
			(type solid)
		)
		(fill yes)
		(layer "B.Cu")
		(net "P1V26_BMC_NODE1")
	)
	(gr_poly
		(pts
			(xy 71.696834 -13.87094) (xy 71.696834 -12.328398) (xy 71.696834 -8.969248) (xy 70.957948 -8.230362)
			(xy 70.957948 -7.546594) (xy 70.94093 -7.529576)
			(arc
				(start 70.372732 -7.529576)
				(mid 70.282929 -7.566773)
				(end 70.245732 -7.656576)
			)
			(xy 70.245732 -10.74293) (xy 70.245732 -11.0236) (xy 69.36232 -11.907012) (xy 69.36232 -13.731748)
			(xy 69.535802 -13.90523) (xy 71.66229 -13.90523)
		)
		(stroke
			(width 0)
			(type solid)
		)
		(fill yes)
		(layer "B.Cu")
		(net "P12V_AUX")
	)
	(gr_poly
		(pts
			(arc
				(start 147.059396 -75.127866)
				(mid 147.149199 -75.090669)
				(end 147.186396 -75.000866)
			)
			(xy 147.186396 -74.36993) (xy 147.084796 -74.26833) (xy 146.081496 -74.26833) (xy 145.852896 -74.49693)
			(arc
				(start 145.852896 -74.937874)
				(mid 145.881601 -75.018546)
				(end 145.955004 -75.062588)
			)
			(xy 146.28241 -75.127866)
		)
		(stroke
			(width 0)
			(type solid)
		)
		(fill yes)
		(layer "B.Cu")
		(net "P1V8_NODE1")
	)
	(gr_poly
		(pts
			(xy 29.090874 -128.332484) (xy 29.15666 -128.266698) (xy 29.15666 -127.781812) (xy 29.2354 -127.703072)
			(xy 29.295852 -127.64262) (xy 30.47746 -127.64262) (xy 31.835344 -127.64262) (xy 32.14878 -127.64262)
			(xy 32.14878 -125.943868) (xy 31.898082 -125.943868) (xy 29.8958 -125.943868) (xy 29.355796 -125.943868)
			(xy 28.985718 -125.57379) (xy 27.522678 -125.57379) (xy 27.10434 -125.992128) (xy 26.685748 -126.41072)
			(xy 25.698958 -126.41072) (xy 25.56002 -126.549658) (xy 25.56002 -128.47828) (xy 25.91308 -128.83134)
			(xy 28.592018 -128.83134)
		)
		(stroke
			(width 0)
			(type solid)
		)
		(fill yes)
		(layer "B.Cu")
		(net "GND")
	)
	(gr_poly
		(pts
			(xy 65.983358 -163.83508) (xy 65.983358 -163.487354) (xy 65.983358 -161.31794) (xy 65.929764 -161.264346)
			(xy 65.908682 -161.264346) (xy 65.146682 -161.264346) (xy 65.031112 -161.379916) (xy 64.96939 -161.379916)
			(xy 64.798956 -161.550604) (xy 61.692028 -161.550604) (xy 61.648848 -161.593784) (xy 61.648594 -161.593784)
			(xy 61.53023 -161.712148) (xy 61.53023 -162.087052) (xy 61.545216 -162.102038) (xy 61.736478 -162.102038)
			(xy 61.98108 -162.34664) (xy 61.98108 -164.097462) (xy 62.027054 -164.143436) (xy 63.754762 -164.143436)
			(xy 65.675002 -164.143436)
		)
		(stroke
			(width 0)
			(type solid)
		)
		(fill yes)
		(layer "B.Cu")
		(net "P5V_NODE1")
	)
	(gr_poly
		(pts
			(xy 136.382252 -120.020842) (xy 136.382252 -119.803418)
			(arc
				(start 136.360662 -119.771414)
				(mid 136.273951 -119.487442)
				(end 136.360662 -119.20347)
			)
			(xy 136.382252 -119.171466) (xy 136.382252 -114.712242) (xy 135.721852 -114.051842) (xy 130.413252 -114.051842)
			(xy 129.727452 -114.737642) (xy 129.727452 -120.122442) (xy 130.438652 -120.833642) (xy 135.569452 -120.833642)
		)
		(stroke
			(width 0)
			(type solid)
		)
		(fill yes)
		(layer "B.Cu")
		(net "GND")
	)
	(gr_poly
		(pts
			(xy 40.16629 -114.616992) (xy 40.16629 -113.990882) (xy 40.16629 -112.900714) (xy 39.942516 -112.67694)
			(xy 38.650672 -112.67694)
			(arc
				(start 38.60546 -112.67694)
				(mid 38.495988 -112.718813)
				(end 38.379654 -112.733074)
			)
			(arc
				(start 37.54628 -112.733074)
				(mid 37.442781 -112.721801)
				(end 37.344096 -112.688624)
			)
			(xy 37.318696 -112.67694) (xy 36.309046 -112.67694) (xy 36.244784 -112.741202) (xy 36.244784 -114.59972)
			(xy 36.28898 -114.64417) (xy 40.139112 -114.64417)
		)
		(stroke
			(width 0)
			(type solid)
		)
		(fill yes)
		(layer "B.Cu")
		(net "P1V5_NODE1")
	)
	(gr_poly
		(pts
			(xy 37.45611 -111.45647) (xy 39.27602 -111.45647) (xy 39.79418 -110.93831) (xy 39.79418 -104.418384)
			(xy 38.165024 -102.789228) (xy 34.9885 -99.612704) (xy 33.460436 -99.612704) (xy 32.825182 -100.247958)
			(xy 32.825182 -101.460808) (xy 32.500062 -101.785928) (xy 31.547816 -101.785928) (xy 31.430214 -101.90353)
			(xy 31.430214 -104.466644) (xy 31.441898 -104.478328) (xy 37.20338 -104.478328) (xy 37.207952 -104.473502)
			(xy 37.620448 -104.473502) (xy 37.89426 -104.747314) (xy 37.89426 -107.535472) (xy 34.3408 -111.088932)
			(xy 34.3408 -112.176052) (xy 34.47542 -112.310672) (xy 36.601908 -112.310672)
		)
		(stroke
			(width 0)
			(type solid)
		)
		(fill yes)
		(layer "B.Cu")
		(net "P1V5_SUS_NODE1")
	)
	(gr_poly
		(pts
			(xy 47.458122 -115.21567) (xy 47.458122 -113.368582) (xy 47.458122 -112.763808) (xy 47.458122 -112.500918)
			(xy 47.302674 -112.34547) (xy 46.719236 -111.762032) (xy 46.719236 -111.727488) (xy 46.719236 -111.078264)
			(xy 46.702218 -111.061246) (xy 46.00702 -111.061246) (xy 46.00702 -112.945164) (xy 46.00702 -114.356642)
			(xy 45.919898 -114.443764) (xy 45.026072 -114.443764) (xy 44.91863 -114.443764) (xy 44.905168 -114.457226)
			(xy 44.874942 -114.487452) (xy 44.874942 -115.185952) (xy 44.909486 -115.220496) (xy 45.123354 -115.220496)
			(xy 46.00702 -115.220496) (xy 47.125382 -115.220496) (xy 47.453296 -115.220496)
		)
		(stroke
			(width 0)
			(type solid)
		)
		(fill yes)
		(layer "B.Cu")
		(net "P12V_AUX")
	)
	(gr_poly
		(pts
			(xy 77.820774 -95.29064) (xy 77.820774 -94.323154) (xy 77.781404 -94.283784) (xy 76.286106 -94.283784)
			(xy 76.150216 -94.419674)
			(arc
				(start 76.150216 -94.881446)
				(mid 76.207656 -95.008859)
				(end 76.226162 -95.147384)
			)
			(arc
				(start 76.226162 -95.147384)
				(mid 76.299378 -95.329135)
				(end 76.480162 -95.404686)
			)
			(xy 77.706728 -95.404686)
		)
		(stroke
			(width 0)
			(type solid)
		)
		(fill yes)
		(layer "B.Cu")
		(net "P3V3_NODE1")
	)
	(gr_poly
		(pts
			(arc
				(start 150.640034 -67.05473)
				(mid 150.703903 -67.015841)
				(end 150.774146 -66.990214)
			)
			(arc
				(start 150.774146 -66.990214)
				(mid 150.959438 -66.977046)
				(end 151.128984 -67.052952)
			)
			(xy 151.163528 -67.08013) (xy 157.016196 -67.08013) (xy 157.143196 -66.95313) (xy 157.143196 -66.52133)
			(xy 156.939996 -66.31813) (xy 150.615396 -66.31813) (xy 150.386796 -66.54673) (xy 150.386796 -66.97853)
			(xy 150.488396 -67.08013) (xy 150.606252 -67.08013)
		)
		(stroke
			(width 0)
			(type solid)
		)
		(fill yes)
		(layer "B.Cu")
		(net "P1V8_SATA_VAA1_NODE1")
	)
	(gr_poly
		(pts
			(xy 27.74696 -117.716808) (xy 27.74696 -114.431826) (xy 27.6479 -114.332766) (xy 24.185626 -114.332766)
			(xy 23.691596 -113.838736) (xy 23.691596 -110.935516) (xy 23.6728 -110.916466) (xy 23.6728 -107.440984)
			(xy 23.82266 -107.291124) (xy 23.82266 -105.647744) (xy 23.57374 -105.398824)
			(arc
				(start 16.08328 -105.398824)
				(mid 15.993477 -105.436021)
				(end 15.95628 -105.525824)
			)
			(xy 15.95628 -117.564662) (xy 16.06042 -117.668802) (xy 17.91716 -117.668802) (xy 18.493486 -118.245128)
			(xy 27.21864 -118.245128)
		)
		(stroke
			(width 0)
			(type solid)
		)
		(fill yes)
		(layer "B.Cu")
		(net "P1V05_NODE1")
	)
	(gr_poly
		(pts
			(arc
				(start 75.867514 -99.685602)
				(mid 76.067982 -99.632977)
				(end 76.27112 -99.674172)
			)
			(xy 76.296266 -99.685602) (xy 78.250796 -99.685602) (xy 78.382622 -99.553776) (xy 78.382622 -96.344232)
			(xy 78.356206 -96.317816)
			(arc
				(start 75.801474 -96.317816)
				(mid 75.711671 -96.355013)
				(end 75.674474 -96.444816)
			)
			(xy 75.674474 -99.53625) (xy 75.823826 -99.685602)
		)
		(stroke
			(width 0)
			(type solid)
		)
		(fill yes)
		(layer "B.Cu")
		(net "GND")
	)
	(gr_poly
		(pts
			(xy 128.188974 -126.278894)
			(arc
				(start 128.188974 -126.272544)
				(mid 128.181723 -126.230244)
				(end 128.16078 -126.192788)
			)
			(arc
				(start 128.16078 -126.192788)
				(mid 128.07643 -125.95352)
				(end 128.16078 -125.714252)
			)
			(xy 128.188974 -125.6792) (xy 128.188974 -124.546106) (xy 128.01473 -124.371862) (xy 124.460762 -124.371862)
			(xy 124.164852 -124.667772) (xy 124.164852 -126.51232) (xy 124.46381 -126.811278) (xy 127.65659 -126.811278)
		)
		(stroke
			(width 0)
			(type solid)
		)
		(fill yes)
		(layer "B.Cu")
		(net "P1V05_CLK_NODE1_R")
	)
	(gr_poly
		(pts
			(xy 56.187086 -125.438662) (xy 56.187086 -124.930662) (xy 56.822086 -124.295662)
			(arc
				(start 56.822086 -123.254262)
				(mid 56.784889 -123.164459)
				(end 56.695086 -123.127262)
			)
			(arc
				(start 56.130698 -123.127262)
				(mid 55.996752 -123.215738)
				(end 55.8419 -123.258072)
			)
			(xy 55.79745 -123.262898) (xy 55.679086 -123.381262) (xy 55.679086 -124.041662) (xy 55.171086 -124.549662)
			(xy 55.171086 -125.438662) (xy 55.298086 -125.565662) (xy 56.060086 -125.565662)
		)
		(stroke
			(width 0)
			(type solid)
		)
		(fill yes)
		(layer "B.Cu")
		(net "P3V3_NODE1")
	)
	(gr_poly
		(pts
			(xy 25.338024 -147.272756) (xy 25.61209 -147.272756) (xy 25.8318 -147.053046) (xy 25.8318 -144.992598)
			(xy 26.111708 -144.712436) (xy 27.560016 -144.712436) (xy 27.75712 -144.515332) (xy 27.75712 -144.17167)
			(xy 28.172156 -143.75638) (xy 30.921198 -143.75638) (xy 31.06674 -143.610838) (xy 31.06674 -143.5227)
			(xy 31.06674 -143.217138) (xy 31.06674 -139.380214) (xy 30.83306 -139.146534) (xy 27.380692 -139.146534)
			(xy 26.943304 -138.709146) (xy 26.943304 -135.013954) (xy 26.296874 -134.367524) (xy 23.608792 -134.367524)
			(xy 22.676866 -135.299704) (xy 22.676866 -141.901672) (xy 23.880572 -143.105378) (xy 23.880572 -147.169124)
			(xy 23.98776 -147.276312) (xy 25.334468 -147.276312)
		)
		(stroke
			(width 0)
			(type solid)
		)
		(fill yes)
		(layer "B.Cu")
		(net "P1V9_LAN1")
	)
	(gr_poly
		(pts
			(xy 77.539088 -179.755292) (xy 77.539088 -178.650138) (xy 77.474318 -178.54041)
			(arc
				(start 77.448156 -178.524154)
				(mid 77.264169 -178.32158)
				(end 77.211936 -178.052984)
			)
			(arc
				(start 77.211936 -178.052984)
				(mid 77.204504 -177.998914)
				(end 77.175106 -177.952908)
			)
			(xy 76.578968 -177.357024) (xy 76.42098 -177.357024) (xy 76.08951 -177.68824) (xy 76.08951 -178.865784)
			(xy 75.777852 -179.177442) (xy 75.777852 -179.850542) (xy 75.854052 -179.926742) (xy 77.367638 -179.926742)
		)
		(stroke
			(width 0)
			(type solid)
		)
		(fill yes)
		(layer "B.Cu")
		(net "GND")
	)
	(gr_poly
		(pts
			(xy 149.345396 -68.24853) (xy 149.345396 -60.32373) (xy 149.116796 -60.09513) (xy 141.445996 -60.09513)
			(xy 140.861796 -60.67933) (xy 140.861796 -61.73978)
			(arc
				(start 140.863066 -61.748924)
				(mid 140.868395 -61.82233)
				(end 140.863066 -61.895736)
			)
			(xy 140.861796 -61.90488) (xy 140.861796 -62.80658)
			(arc
				(start 140.863066 -62.815724)
				(mid 140.868395 -62.88913)
				(end 140.863066 -62.962536)
			)
			(xy 140.861796 -62.97168) (xy 140.861796 -65.47358)
			(arc
				(start 140.863066 -65.482724)
				(mid 140.868395 -65.55613)
				(end 140.863066 -65.629536)
			)
			(xy 140.861796 -65.63868) (xy 140.861796 -68.29933) (xy 141.166596 -68.60413) (xy 148.989796 -68.60413)
		)
		(stroke
			(width 0)
			(type solid)
		)
		(fill yes)
		(layer "B.Cu")
		(net "GND")
	)
	(gr_poly
		(pts
			(xy 171.053252 -104.11079) (xy 171.053252 -97.35439) (xy 170.900852 -97.20199) (xy 164.017452 -97.20199)
			(xy 163.230052 -97.98939) (xy 163.230052 -98.287332)
			(arc
				(start 163.231322 -98.296476)
				(mid 163.236725 -98.37039)
				(end 163.231322 -98.444304)
			)
			(xy 163.230052 -98.453448) (xy 163.230052 -99.506532)
			(arc
				(start 163.231322 -99.515676)
				(mid 163.236725 -99.58959)
				(end 163.231322 -99.663504)
			)
			(xy 163.230052 -99.672648) (xy 163.230052 -100.751132)
			(arc
				(start 163.231322 -100.760276)
				(mid 163.236725 -100.83419)
				(end 163.231322 -100.908104)
			)
			(xy 163.230052 -100.917248) (xy 163.230052 -103.72979) (xy 164.220652 -104.72039) (xy 170.443652 -104.72039)
		)
		(stroke
			(width 0)
			(type solid)
		)
		(fill yes)
		(layer "B.Cu")
		(net "GND")
	)
	(gr_poly
		(pts
			(xy 28.8163 -138.848846) (xy 30.87878 -138.848846) (xy 31.09214 -138.635486) (xy 31.09214 -133.677152)
			(xy 30.890972 -133.475984) (xy 29.516832 -133.475984) (xy 29.266896 -133.226048) (xy 28.551886 -132.511038)
			(xy 22.569678 -132.511038) (xy 21.688552 -132.511038) (xy 21.54428 -132.65531) (xy 21.54428 -133.15823)
			(xy 21.03374 -133.66877) (xy 19.44116 -133.66877) (xy 19.20748 -133.90245) (xy 19.20748 -138.61034)
			(xy 19.43608 -138.83894) (xy 20.472146 -138.83894) (xy 22.045422 -138.83894) (xy 22.259798 -138.624564)
			(xy 22.259798 -135.226806) (xy 23.44674 -134.039864) (xy 26.420318 -134.039864) (xy 27.205178 -134.824724)
			(xy 27.205178 -138.469624) (xy 27.586686 -138.851132) (xy 28.814014 -138.851132)
		)
		(stroke
			(width 0)
			(type solid)
		)
		(fill yes)
		(layer "B.Cu")
		(net "GND")
	)
	(gr_poly
		(pts
			(xy 53.257704 -77.547978) (xy 53.52415 -77.281532) (xy 54.040278 -77.281532) (xy 54.412388 -76.909422)
			(xy 54.948074 -76.909422) (xy 55.21325 -76.644246) (xy 55.21325 -76.031852) (xy 55.700676 -75.544426)
			(xy 55.700676 -74.969878) (xy 55.661814 -74.931016) (xy 54.999382 -74.931016) (xy 54.938168 -74.99223)
			(xy 54.58714 -74.99223) (xy 54.351428 -74.756518) (xy 54.351428 -73.809098) (xy 54.082188 -73.539858)
			(xy 53.77307 -73.539858) (xy 53.681376 -73.631552) (xy 53.681376 -74.8792) (xy 53.58638 -74.974196)
			(xy 53.002688 -74.974196) (xy 52.979574 -74.99731) (xy 52.979574 -76.786486) (xy 52.859686 -76.906374)
			(xy 52.859686 -77.410564) (xy 53.00218 -77.553058) (xy 53.257704 -77.553058)
		)
		(stroke
			(width 0)
			(type solid)
		)
		(fill yes)
		(layer "B.Cu")
		(net "GND")
	)
	(gr_poly
		(pts
			(xy 60.759594 -131.186174) (xy 61.14034 -131.186174) (xy 61.241686 -131.084828) (xy 61.241686 -129.687828)
			(xy 61.165486 -129.611628) (xy 61.060584 -129.611628)
			(arc
				(start 61.043566 -129.616454)
				(mid 60.94095 -129.630865)
				(end 60.838334 -129.616454)
			)
			(xy 60.821316 -129.611628) (xy 60.260738 -129.611628) (xy 60.24372 -129.616454) (xy 60.218066 -129.622804)
			(xy 60.181236 -129.630678) (xy 60.045092 -129.766822) (xy 60.045092 -130.18897) (xy 60.446412 -130.59029)
			(xy 60.446412 -130.595878) (xy 60.457842 -130.607562) (xy 60.457842 -130.631438) (xy 60.530486 -130.703828)
			(xy 60.530486 -131.110228) (xy 60.606686 -131.186428) (xy 60.750958 -131.186428)
		)
		(stroke
			(width 0)
			(type solid)
		)
		(fill yes)
		(layer "B.Cu")
		(net "BMC_NODE1_HPLLAV33")
	)
	(gr_poly
		(pts
			(xy 61.73724 -139.62507) (xy 61.73724 -139.318746) (xy 61.797184 -139.258802) (xy 61.797184 -137.735564)
			(xy 61.876686 -137.656062) (xy 62.054486 -137.478262) (xy 62.054486 -136.876028)
			(arc
				(start 61.990732 -136.81202)
				(mid 61.949492 -136.784401)
				(end 61.900816 -136.774682)
			)
			(xy 61.474096 -136.774682) (xy 61.270896 -136.977882) (xy 61.193172 -137.055606) (xy 60.774834 -137.055606)
			(xy 60.661042 -137.169398) (xy 60.598558 -137.262108)
			(arc
				(start 60.567824 -137.292588)
				(mid 60.540157 -137.333945)
				(end 60.530486 -137.382758)
			)
			(xy 60.530486 -139.071604) (xy 60.530486 -139.776708) (xy 60.716922 -139.963144) (xy 61.399166 -139.963144)
		)
		(stroke
			(width 0)
			(type solid)
		)
		(fill yes)
		(layer "B.Cu")
		(net "P3V3_NODE1")
	)
	(gr_poly
		(pts
			(arc
				(start 63.125858 -140.078968)
				(mid 63.222212 -140.040357)
				(end 63.324994 -140.025882)
			)
			(xy 63.376048 -140.024866) (xy 63.502032 -139.898882) (xy 63.502032 -139.898628)
			(arc
				(start 63.541148 -139.859512)
				(mid 63.568767 -139.818272)
				(end 63.578486 -139.769596)
			)
			(xy 63.578486 -139.332462) (xy 63.730886 -139.180062) (xy 63.730886 -138.748262) (xy 63.620142 -138.637518)
			(xy 62.994286 -138.637518) (xy 62.939422 -138.692382) (xy 62.458346 -138.692382) (xy 62.201552 -138.949176)
			(xy 62.201552 -139.606528) (xy 62.232286 -139.637262) (xy 62.232286 -140.069062) (xy 62.257686 -140.094462)
			(xy 63.09741 -140.094462)
		)
		(stroke
			(width 0)
			(type solid)
		)
		(fill yes)
		(layer "B.Cu")
		(net "P1V26_BMC_NODE1")
	)
	(gr_poly
		(pts
			(xy 64.002666 -70.86219) (xy 64.002666 -70.30974) (xy 63.807848 -70.114922) (xy 63.807848 -69.8373)
			(xy 63.262764 -69.292216) (xy 61.787532 -69.292216) (xy 61.576712 -69.503036) (xy 61.38926 -69.503036)
			(xy 61.005974 -69.503036) (xy 61.001148 -69.507862)
			(arc
				(start 61.001148 -69.733668)
				(mid 60.983431 -69.85773)
				(end 60.931806 -69.97192)
			)
			(xy 60.912248 -70.002908) (xy 60.912248 -70.064122) (xy 60.906152 -70.064122) (xy 60.738512 -70.231762)
			(xy 60.224924 -70.231762) (xy 60.124848 -70.331838) (xy 60.124848 -70.756272) (xy 60.262008 -70.893432)
			(xy 60.988702 -70.893432) (xy 60.98921 -70.893686) (xy 63.97117 -70.893686)
		)
		(stroke
			(width 0)
			(type solid)
		)
		(fill yes)
		(layer "B.Cu")
		(net "GND")
	)
	(gr_poly
		(pts
			(xy 54.080664 -72.408288) (xy 54.080664 -71.671688) (xy 54.283864 -71.468488)
			(arc
				(start 54.283864 -71.265288)
				(mid 54.282624 -71.247071)
				(end 54.278784 -71.22922)
			)
			(arc
				(start 53.77434 -71.22922)
				(mid 53.684537 -71.266417)
				(end 53.64734 -71.35622)
			)
			(xy 53.64734 -71.528432) (xy 53.34254 -71.833232) (xy 52.813712 -71.833232) (xy 52.71643 -71.930514)
			(arc
				(start 52.71643 -72.33539)
				(mid 52.753627 -72.425193)
				(end 52.84343 -72.46239)
			)
			(xy 54.026562 -72.46239)
		)
		(stroke
			(width 0)
			(type solid)
		)
		(fill yes)
		(layer "B.Cu")
		(net "GND")
	)
	(gr_poly
		(pts
			(arc
				(start 148.227796 -75.127866)
				(mid 148.317599 -75.090669)
				(end 148.354796 -75.000866)
			)
			(xy 148.354796 -72.08393) (xy 148.430996 -72.00773) (xy 149.065996 -72.00773) (xy 149.269196 -71.80453)
			(xy 149.269196 -71.32193) (xy 149.116796 -71.16953) (xy 148.481796 -71.16953) (xy 148.354796 -71.04253)
			(xy 148.354796 -69.84873) (xy 148.049996 -69.54393) (xy 147.592796 -69.54393) (xy 147.465796 -69.67093)
			(arc
				(start 147.465796 -75.000866)
				(mid 147.502993 -75.090669)
				(end 147.592796 -75.127866)
			)
		)
		(stroke
			(width 0)
			(type solid)
		)
		(fill yes)
		(layer "B.Cu")
		(net "P1V8_SATA_AVDD_NODE1")
	)
	(gr_poly
		(pts
			(xy 165.42258 -143.51635) (xy 165.42258 -143.089376)
			(arc
				(start 165.42258 -140.472922)
				(mid 165.385383 -140.383119)
				(end 165.29558 -140.345922)
			)
			(arc
				(start 158.76778 -140.345922)
				(mid 158.677977 -140.383119)
				(end 158.64078 -140.472922)
			)
			(arc
				(start 158.64078 -143.622522)
				(mid 158.677977 -143.712325)
				(end 158.76778 -143.749522)
			)
			(xy 164.762434 -143.749522) (xy 165.189408 -143.749522)
		)
		(stroke
			(width 0)
			(type solid)
		)
		(fill yes)
		(layer "B.Cu")
		(net "GND")
	)
	(gr_poly
		(pts
			(xy 14.962632 -130.07975) (xy 14.962632 -129.521712) (xy 14.85138 -129.41046) (xy 14.845538 -129.41046)
			(xy 13.770864 -128.335786) (xy 13.770864 -126.295658) (xy 13.714476 -126.23927) (xy 12.476734 -126.23927)
			(xy 12.358624 -126.35738) (xy 12.358624 -129.76479) (xy 12.554966 -129.961132) (xy 13.358622 -129.961132)
			(arc
				(start 13.391896 -129.93751)
				(mid 13.73958 -129.860137)
				(end 14.037564 -130.055366)
			)
			(xy 14.055344 -130.082036) (xy 14.111224 -130.111754) (xy 14.930628 -130.111754)
		)
		(stroke
			(width 0)
			(type solid)
		)
		(fill yes)
		(layer "B.Cu")
		(net "GND")
	)
	(gr_poly
		(pts
			(xy 119.075708 -127.312928) (xy 119.075708 -124.290836) (xy 118.965726 -124.180854) (xy 118.171722 -124.180854)
			(xy 118.171468 -124.1806) (xy 115.619276 -124.1806) (xy 114.842798 -124.1806) (xy 114.770408 -124.10821)
			(xy 114.20983 -124.10821) (xy 111.373412 -124.10821) (xy 111.186214 -123.921012)
			(arc
				(start 111.186214 -123.220734)
				(mid 111.149017 -123.130931)
				(end 111.059214 -123.093734)
			)
			(xy 110.493556 -123.093734) (xy 110.431326 -123.155964) (xy 110.431326 -127.219202) (xy 110.585758 -127.37338)
			(xy 111.152178 -127.37338) (xy 111.238284 -127.459486) (xy 112.64773 -127.459486) (xy 115.619276 -127.459486)
			(xy 117.937534 -127.459486) (xy 118.92915 -127.459486)
		)
		(stroke
			(width 0)
			(type solid)
		)
		(fill yes)
		(layer "B.Cu")
		(net "SW_VR_PVCCP_NODE1_VIN_FLT")
	)
	(gr_poly
		(pts
			(xy 64.69634 -76.172314) (xy 64.69634 -74.89317) (xy 65.028572 -74.560938) (xy 65.208404 -74.560938)
			(xy 65.272666 -74.496676) (xy 65.272666 -74.17308) (xy 65.244472 -74.144886)
			(arc
				(start 64.934084 -74.144886)
				(mid 64.8854 -74.154588)
				(end 64.844168 -74.182224)
			)
			(xy 64.75984 -74.266552)
			(arc
				(start 64.7192 -74.307192)
				(mid 64.704943 -74.30473)
				(end 64.690498 -74.30389)
			)
			(arc
				(start 64.651128 -74.30389)
				(mid 64.602307 -74.313543)
				(end 64.560958 -74.341228)
			)
			(xy 64.544194 -74.358246) (xy 63.467996 -74.358246) (xy 63.351156 -74.47534) (xy 63.351156 -75.245976)
			(xy 63.35522 -75.25004) (xy 63.35522 -76.242164) (xy 63.40094 -76.287884) (xy 64.580516 -76.287884)
		)
		(stroke
			(width 0)
			(type solid)
		)
		(fill yes)
		(layer "B.Cu")
		(net "GND")
	)
	(gr_poly
		(pts
			(xy 69.652642 -131.081018) (xy 69.87413 -131.081018) (xy 69.979286 -130.975862) (xy 70.868286 -130.975862)
			(xy 70.919086 -130.925062) (xy 70.919086 -129.756662) (xy 70.792086 -129.629662) (xy 70.632574 -129.629662)
			(arc
				(start 70.61962 -129.632456)
				(mid 70.561052 -129.640038)
				(end 70.502018 -129.638298)
			)
			(xy 70.473316 -129.63525) (xy 70.419214 -129.6543) (xy 70.411086 -129.662428)
			(arc
				(start 68.027042 -129.662428)
				(mid 67.937239 -129.699625)
				(end 67.900042 -129.789428)
			)
			(xy 67.900042 -130.1877) (xy 68.176394 -130.464052) (xy 68.176394 -130.515614) (xy 68.353686 -130.692906)
			(xy 68.353686 -130.975862) (xy 68.471542 -131.093718) (xy 69.640196 -131.093718)
		)
		(stroke
			(width 0)
			(type solid)
		)
		(fill yes)
		(layer "B.Cu")
		(net "P3V3_NODE1")
	)
	(gr_poly
		(pts
			(arc
				(start 89.42832 -34.13506)
				(mid 89.09304 -34.13506)
				(end 89.42832 -34.13506)
			)
		)
		(stroke
			(width 0)
			(type solid)
		)
		(fill yes)
		(layer "B.Cu")
		(net "GND")
	)
	(gr_poly
		(pts
			(xy 158.794196 -68.37553) (xy 158.794196 -61.87313) (xy 158.794196 -60.836556) (xy 158.346648 -60.389008)
			(xy 156.112718 -60.389008) (xy 155.517596 -60.98413) (xy 155.339796 -61.16193) (xy 155.339796 -61.82233)
			(xy 155.441396 -61.92393) (xy 157.346396 -61.92393) (xy 157.473396 -62.05093) (xy 157.473396 -63.27013)
			(xy 157.244796 -63.49873) (xy 155.542996 -63.49873) (xy 155.365196 -63.67653) (xy 155.365196 -64.74333)
			(xy 155.441396 -64.81953) (xy 157.295596 -64.81953) (xy 157.397196 -64.92113) (xy 157.397196 -66.415666)
			(xy 157.397704 -66.41592) (xy 157.397704 -67.05854) (xy 157.397196 -67.058794) (xy 157.397196 -67.30873)
			(xy 157.346396 -67.35953) (xy 155.365196 -67.35953) (xy 155.212796 -67.51193) (xy 155.212796 -68.52793)
			(xy 155.466796 -68.78193) (xy 158.387796 -68.78193)
		)
		(stroke
			(width 0)
			(type solid)
		)
		(fill yes)
		(layer "B.Cu")
		(net "P1V8_NODE1")
	)
	(gr_poly
		(pts
			(xy 59.440064 -83.359752) (xy 59.440064 -83.31454) (xy 59.485276 -83.31454) (xy 60.036964 -82.763106)
			(xy 60.036964 -81.152492) (xy 59.916568 -81.032096) (xy 58.940446 -81.032096) (xy 58.551826 -81.420716)
			(xy 58.551826 -81.994502) (xy 58.924444 -82.36712) (xy 58.924444 -82.399378)
			(arc
				(start 58.952638 -82.43443)
				(mid 59.0508 -82.738948)
				(end 58.92038 -83.031076)
			)
			(xy 58.881772 -83.069684) (xy 58.881772 -83.23961) (xy 58.894726 -83.26628) (xy 58.90514 -83.288378)
			(xy 58.920126 -83.323684) (xy 58.983626 -83.36534) (xy 59.434476 -83.36534)
		)
		(stroke
			(width 0)
			(type solid)
		)
		(fill yes)
		(layer "B.Cu")
		(net "P3V3_NODE1")
	)
	(gr_poly
		(pts
			(arc
				(start 28.03652 -158.28137)
				(mid 28.126323 -158.244173)
				(end 28.16352 -158.15437)
			)
			(arc
				(start 28.16352 -155.242768)
				(mid 28.126323 -155.152965)
				(end 28.03652 -155.115768)
			)
			(arc
				(start 26.69032 -155.115768)
				(mid 26.600517 -155.152965)
				(end 26.56332 -155.242768)
			)
			(arc
				(start 26.56332 -158.15437)
				(mid 26.600517 -158.244173)
				(end 26.69032 -158.28137)
			)
		)
		(stroke
			(width 0)
			(type solid)
		)
		(fill yes)
		(layer "B.Cu")
		(net "GND")
	)
	(gr_poly
		(pts
			(arc
				(start 46.79442 -167.674544)
				(mid 46.884223 -167.637347)
				(end 46.92142 -167.547544)
			)
			(arc
				(start 46.92142 -164.394896)
				(mid 46.884223 -164.305093)
				(end 46.79442 -164.267896)
			)
			(arc
				(start 40.31234 -164.267896)
				(mid 40.222537 -164.305093)
				(end 40.18534 -164.394896)
			)
			(arc
				(start 40.18534 -167.547544)
				(mid 40.222537 -167.637347)
				(end 40.31234 -167.674544)
			)
		)
		(stroke
			(width 0)
			(type solid)
		)
		(fill yes)
		(layer "B.Cu")
		(net "GND")
	)
	(gr_poly
		(pts
			(arc
				(start 115.180872 -27.160728)
				(mid 115.270675 -27.123531)
				(end 115.307872 -27.033728)
			)
			(xy 115.307872 -26.284174) (xy 115.40236 -26.18994) (xy 115.40236 -25.93213) (xy 115.80368 -25.53081)
			(xy 115.80368 -24.774398) (xy 115.682268 -24.652986) (xy 115.062 -24.652986) (xy 114.916204 -24.798782)
			(arc
				(start 114.910108 -24.839676)
				(mid 114.906243 -24.860502)
				(end 114.901218 -24.881078)
			)
			(xy 114.8969 -24.897334) (xy 114.8969 -24.970994) (xy 114.558572 -25.309576) (xy 113.792 -26.076148)
			(arc
				(start 113.792 -27.033728)
				(mid 113.829197 -27.123531)
				(end 113.919 -27.160728)
			)
		)
		(stroke
			(width 0)
			(type solid)
		)
		(fill yes)
		(layer "B.Cu")
		(net "PV_VTT_DDR_NODE1")
	)
	(gr_poly
		(pts
			(arc
				(start 51.817524 -70.131178)
				(mid 51.907327 -70.093981)
				(end 51.944524 -70.004178)
			)
			(xy 51.944524 -69.782944) (xy 51.635406 -69.473572)
			(arc
				(start 51.028346 -69.473572)
				(mid 50.938543 -69.510769)
				(end 50.901346 -69.600572)
			)
			(xy 50.901346 -69.945758) (xy 51.07051 -70.114922) (xy 51.15814 -70.125082)
			(arc
				(start 51.195732 -70.101968)
				(mid 51.457271 -70.029832)
				(end 51.716432 -70.110096)
			)
			(xy 51.748436 -70.131178)
		)
		(stroke
			(width 0)
			(type solid)
		)
		(fill yes)
		(layer "B.Cu")
		(net "GND")
	)
	(gr_poly
		(pts
			(arc
				(start 70.709536 -163.702238)
				(mid 70.799339 -163.665041)
				(end 70.836536 -163.575238)
			)
			(xy 70.836536 -161.3535) (xy 71.447406 -160.74263) (xy 71.447406 -150.823676) (xy 70.892162 -150.268432)
			(arc
				(start 65.75679 -150.268432)
				(mid 65.666987 -150.305629)
				(end 65.62979 -150.395432)
			)
			(xy 65.62979 -159.539432) (xy 65.928748 -159.83839) (xy 66.077084 -159.83839) (xy 66.55943 -160.320736)
			(xy 66.55943 -160.469072) (xy 66.895218 -160.80486)
			(arc
				(start 66.895218 -163.575238)
				(mid 66.932415 -163.665041)
				(end 67.022218 -163.702238)
			)
		)
		(stroke
			(width 0)
			(type solid)
		)
		(fill yes)
		(layer "B.Cu")
		(net "P5V_STB_NODE1")
	)
	(gr_poly
		(pts
			(xy 30.90291 -104.625648) (xy 30.90291 -101.690678) (xy 30.71749 -101.505258)
			(arc
				(start 28.84932 -101.505258)
				(mid 28.653969 -101.596918)
				(end 28.599638 -101.80574)
			)
			(arc
				(start 28.599638 -101.80574)
				(mid 28.570088 -102.037021)
				(end 28.411424 -102.207822)
			)
			(arc
				(start 28.411424 -102.207822)
				(mid 28.364014 -102.254411)
				(end 28.346654 -102.318566)
			)
			(xy 28.346654 -102.498398) (xy 28.346654 -104.294686) (xy 28.695142 -104.643174) (xy 29.50972 -104.643174)
			(xy 30.885384 -104.643174)
		)
		(stroke
			(width 0)
			(type solid)
		)
		(fill yes)
		(layer "B.Cu")
		(net "P1V8_STB_NODE1")
	)
	(gr_poly
		(pts
			(xy 59.445398 -112.98682) (xy 59.7154 -112.98682) (xy 59.871356 -112.830864)
			(arc
				(start 59.871356 -112.374934)
				(mid 59.861792 -112.326582)
				(end 59.834526 -112.285526)
			)
			(arc
				(start 59.834526 -112.285526)
				(mid 59.752755 -112.162206)
				(end 59.724036 -112.017048)
			)
			(arc
				(start 59.724036 -105.745026)
				(mid 59.648108 -105.563901)
				(end 59.465718 -105.491026)
			)
			(arc
				(start 55.077868 -105.568242)
				(mid 54.989532 -105.606237)
				(end 54.953154 -105.695242)
			)
			(xy 54.953154 -112.86109) (xy 55.103014 -113.01095) (xy 59.421268 -113.01095)
		)
		(stroke
			(width 0)
			(type solid)
		)
		(fill yes)
		(layer "B.Cu")
		(net "P3V3_STB_NODE1")
	)
	(gr_poly
		(pts
			(xy 62.054486 -133.320028) (xy 62.054486 -131.770628) (xy 61.825886 -131.542028) (xy 61.394086 -131.542028)
			(xy 61.292994 -131.440682)
			(arc
				(start 60.759594 -131.440682)
				(mid 60.669791 -131.477879)
				(end 60.632594 -131.567682)
			)
			(arc
				(start 60.632594 -132.608574)
				(mid 60.669791 -132.698377)
				(end 60.759594 -132.735574)
			)
			(xy 61.270896 -132.735574) (xy 61.32195 -132.786628) (xy 61.343286 -132.786628) (xy 61.495686 -132.939028)
			(xy 61.495686 -132.960364) (xy 61.546994 -133.011418)
			(arc
				(start 61.546994 -133.269228)
				(mid 61.584191 -133.359031)
				(end 61.673994 -133.396228)
			)
			(xy 61.978286 -133.396228)
		)
		(stroke
			(width 0)
			(type solid)
		)
		(fill yes)
		(layer "B.Cu")
		(net "P1V538_BMC_NODE1")
	)
	(gr_poly
		(pts
			(xy 170.812968 -81.657698) (xy 170.812968 -76.570332) (xy 170.3578 -76.115418) (xy 168.745154 -76.115418)
			(xy 168.421304 -76.439268) (xy 168.421304 -78.444344) (xy 168.05656 -78.809088) (xy 167.039036 -78.809088)
			(xy 166.915338 -78.93304) (xy 166.915338 -80.44815) (xy 166.763192 -80.600296) (xy 165.525704 -80.600296)
			(xy 165.278308 -80.3529) (xy 165.278308 -79.953104) (xy 165.278308 -79.264764) (xy 164.80282 -78.789276)
			(xy 164.18814 -78.789276) (xy 164.02177 -78.622906) (xy 164.02177 -75.818492) (xy 164.225224 -75.615038)
			(xy 164.225224 -74.603864) (xy 163.890198 -74.268838) (xy 161.810954 -74.268838) (xy 161.61004 -74.469752)
			(xy 161.61004 -75.57135) (xy 161.613088 -75.574398) (xy 161.613088 -76.463652) (xy 162.32759 -77.178154)
			(xy 162.32759 -79.476854) (xy 162.41268 -79.561944) (xy 162.822636 -79.561944) (xy 163.28644 -80.025748)
			(xy 163.28644 -82.927444) (xy 163.546536 -83.18754) (xy 163.629848 -83.270852) (xy 169.199814 -83.270852)
		)
		(stroke
			(width 0)
			(type solid)
		)
		(fill yes)
		(layer "B.Cu")
		(net "GND")
	)
	(gr_poly
		(pts
			(arc
				(start 73.638156 -127.21336)
				(mid 73.742042 -127.201415)
				(end 73.845928 -127.21336)
			)
			(xy 73.860152 -127.216662) (xy 73.990708 -127.216662) (xy 74.060812 -127.146558) (xy 74.499978 -127.146558)
			(xy 74.499978 -127.121158) (xy 75.212194 -127.121158) (xy 75.212194 -127.146558) (xy 75.412854 -127.146558)
			(xy 75.482958 -127.216662) (xy 76.634086 -127.216662) (xy 77.269086 -126.581662) (xy 77.269086 -125.141736)
			(xy 76.804012 -124.676662) (xy 76.524612 -124.676662) (xy 76.518008 -124.676916) (xy 76.507086 -124.67717)
			(xy 75.420982 -124.67717) (xy 75.420474 -124.676662) (xy 74.983086 -124.676662) (xy 74.475086 -125.184662)
			(xy 74.274426 -125.184662) (xy 74.262996 -125.196092) (xy 73.314052 -125.196092) (xy 72.926194 -125.58395)
			(xy 72.926194 -126.219204)
			(arc
				(start 72.861424 -126.28372)
				(mid 72.833805 -126.32496)
				(end 72.824086 -126.373636)
			)
			(xy 72.824086 -126.581662) (xy 72.697086 -126.708662) (xy 72.697086 -127.089662) (xy 72.824086 -127.216662)
			(xy 73.623932 -127.216662)
		)
		(stroke
			(width 0)
			(type solid)
		)
		(fill yes)
		(layer "B.Cu")
		(net "BMC_NODE1_VCC_1V8_PCIEA")
	)
	(gr_poly
		(pts
			(xy 38.915086 -141.313662) (xy 38.915086 -140.729462) (xy 38.919404 -140.725144) (xy 38.919404 -140.606272)
			(xy 38.98138 -140.544296) (xy 39.398956 -140.544296) (xy 39.579296 -140.544296) (xy 39.60876 -140.514832)
			(xy 39.60876 -140.002006) (xy 39.50589 -139.899136) (xy 38.97376 -139.899136) (xy 38.915086 -139.840462)
			(xy 38.915086 -138.926062) (xy 39.016686 -138.824462) (xy 39.20617 -138.824462) (xy 39.208456 -138.826748)
			(xy 39.473886 -138.826748) (xy 39.549578 -138.751056)
			(arc
				(start 39.549578 -137.59561)
				(mid 39.512381 -137.505807)
				(end 39.422578 -137.46861)
			)
			(xy 39.15156 -137.46861) (xy 38.93693 -137.25398) (xy 38.93693 -136.754362) (xy 39.189406 -136.501886)
			(xy 39.448486 -136.501886) (xy 39.66337 -136.287002) (xy 39.66337 -136.158224) (xy 39.483284 -135.978138)
			(xy 38.020244 -135.978138) (xy 37.820346 -136.178036) (xy 37.820346 -141.209522) (xy 37.820346 -141.41196)
			(xy 37.899848 -141.491462) (xy 38.102286 -141.491462) (xy 38.737286 -141.491462)
		)
		(stroke
			(width 0)
			(type solid)
		)
		(fill yes)
		(layer "B.Cu")
		(net "GND")
	)
	(gr_poly
		(pts
			(xy 64.565784 -140.457936) (xy 64.57061 -140.412978)
			(arc
				(start 64.57061 -140.412724)
				(mid 64.610827 -140.281966)
				(end 64.697356 -140.175996)
			)
			(arc
				(start 64.697356 -140.175996)
				(mid 64.798682 -140.113572)
				(end 64.914526 -140.086334)
			)
			(xy 64.96177 -140.082778) (xy 65.381886 -139.662662) (xy 65.381886 -137.783062) (xy 65.305686 -137.706862)
			(xy 64.797686 -137.706862) (xy 64.721486 -137.783062) (xy 64.721486 -139.256262) (xy 64.619886 -139.357862)
			(xy 64.061086 -139.357862) (xy 63.883286 -139.535662) (xy 63.883286 -139.840462) (xy 63.832994 -139.890754)
			(xy 63.832994 -139.927838)
			(arc
				(start 63.793624 -139.966954)
				(mid 63.765957 -140.008311)
				(end 63.756286 -140.057124)
			)
			(xy 63.756286 -140.337286)
			(arc
				(start 63.760096 -140.352526)
				(mid 63.770175 -140.407605)
				(end 63.77305 -140.463524)
			)
			(arc
				(start 63.77305 -140.463524)
				(mid 63.782453 -140.513031)
				(end 63.810388 -140.554964)
			)
			(xy 63.923672 -140.668248) (xy 64.355472 -140.668248)
		)
		(stroke
			(width 0)
			(type solid)
		)
		(fill yes)
		(layer "B.Cu")
		(net "P3V3_NODE1")
	)
	(gr_poly
		(pts
			(xy 43.64228 -75.228704) (xy 43.64228 -75.153774) (xy 45.936408 -75.153774) (xy 46.036484 -75.053698)
			(xy 46.036484 -74.832718) (xy 45.195236 -73.99147) (xy 40.62095 -73.99147) (xy 40.562784 -74.024744)
			(arc
				(start 40.545512 -74.053954)
				(mid 40.115523 -74.277637)
				(end 39.7256 -73.989692)
			)
			(arc
				(start 39.7256 -73.989692)
				(mid 39.678897 -73.931379)
				(end 39.60749 -73.909428)
			)
			(xy 39.300912 -73.909428) (xy 39.065708 -74.144632)
			(arc
				(start 39.065708 -75.81646)
				(mid 39.102905 -75.906263)
				(end 39.192708 -75.94346)
			)
			(xy 42.927524 -75.94346)
		)
		(stroke
			(width 0)
			(type solid)
		)
		(fill yes)
		(layer "B.Cu")
		(net "GND")
	)
	(gr_poly
		(pts
			(xy 19.326352 -127.075946) (xy 20.804124 -127.075946)
			(arc
				(start 20.837398 -127.052324)
				(mid 21.05914 -126.981254)
				(end 21.280882 -127.052324)
			)
			(xy 21.314156 -127.075946) (xy 22.163532 -127.075946) (xy 22.242526 -126.996952)
			(arc
				(start 22.242526 -126.337314)
				(mid 22.205329 -126.247511)
				(end 22.115526 -126.210314)
			)
			(xy 18.739612 -126.210314) (xy 16.976598 -127.973074) (xy 15.955264 -127.973074) (xy 15.904464 -127.922274)
			(xy 15.904464 -126.88697) (xy 15.760192 -126.742698) (xy 15.220188 -126.742698)
			(arc
				(start 15.184882 -126.771654)
				(mid 15.166013 -126.786224)
				(end 15.146274 -126.799594)
			)
			(xy 15.134082 -126.807214) (xy 14.877796 -127.0635)
			(arc
				(start 14.877796 -128.678432)
				(mid 14.914993 -128.768235)
				(end 15.004796 -128.805432)
			)
			(xy 17.596866 -128.805432)
		)
		(stroke
			(width 0)
			(type solid)
		)
		(fill yes)
		(layer "B.Cu")
		(net "SW_P1V05_NODE1_DRVL")
	)
	(gr_poly
		(pts
			(arc
				(start 129.128774 -109.831124)
				(mid 129.409444 -109.734946)
				(end 129.690114 -109.831124)
			)
			(xy 129.724658 -109.857794)
			(arc
				(start 131.572 -109.857794)
				(mid 131.661803 -109.820597)
				(end 131.699 -109.730794)
			)
			(arc
				(start 131.699 -106.71048)
				(mid 131.661803 -106.620677)
				(end 131.572 -106.58348)
			)
			(arc
				(start 126.814072 -106.58348)
				(mid 126.724269 -106.620677)
				(end 126.687072 -106.71048)
			)
			(arc
				(start 126.687072 -109.730794)
				(mid 126.724269 -109.820597)
				(end 126.814072 -109.857794)
			)
			(xy 129.09423 -109.857794)
		)
		(stroke
			(width 0)
			(type solid)
		)
		(fill yes)
		(layer "B.Cu")
		(net "GND")
	)
	(gr_poly
		(pts
			(arc
				(start 153.525982 -55.073042)
				(mid 153.708083 -54.996116)
				(end 153.779982 -54.81193)
			)
			(arc
				(start 153.779982 -54.81193)
				(mid 153.877927 -54.327551)
				(end 154.17927 -53.935884)
			)
			(arc
				(start 154.17927 -53.935884)
				(mid 154.213593 -53.891967)
				(end 154.225752 -53.837586)
			)
			(xy 154.225752 -51.330352) (xy 154.0764 -51.181) (xy 151.356314 -51.181) (xy 150.79218 -51.745134)
			(arc
				(start 145.842482 -51.745134)
				(mid 145.793798 -51.754836)
				(end 145.752566 -51.782472)
			)
			(xy 145.693638 -51.841654) (xy 144.677384 -51.841654) (xy 144.676876 -51.842162) (xy 144.50568 -51.842162)
			(arc
				(start 144.389348 -51.95824)
				(mid 144.361729 -51.99948)
				(end 144.35201 -52.048156)
			)
			(xy 144.35201 -54.869334) (xy 144.555718 -55.073042)
		)
		(stroke
			(width 0)
			(type solid)
		)
		(fill yes)
		(layer "B.Cu")
		(net "SATA_P7")
	)
	(gr_poly
		(pts
			(xy 113.06302 -46.18228) (xy 113.064798 -46.184058) (xy 117.16512 -46.184058)
			(arc
				(start 117.195346 -46.16577)
				(mid 117.428887 -46.100131)
				(end 117.663214 -46.162976)
			)
			(arc
				(start 117.663214 -46.162976)
				(mid 117.684717 -46.169179)
				(end 117.705886 -46.176438)
			)
			(xy 117.726968 -46.184058)
			(arc
				(start 117.990874 -46.184058)
				(mid 118.080677 -46.146861)
				(end 118.117874 -46.057058)
			)
			(arc
				(start 118.117874 -38.945058)
				(mid 118.080677 -38.855255)
				(end 117.990874 -38.818058)
			)
			(arc
				(start 112.910874 -38.818058)
				(mid 112.821071 -38.855255)
				(end 112.783874 -38.945058)
			)
			(arc
				(start 112.783874 -46.057058)
				(mid 112.821071 -46.146861)
				(end 112.910874 -46.184058)
			)
			(xy 113.060988 -46.184058)
		)
		(stroke
			(width 0)
			(type solid)
		)
		(fill yes)
		(layer "B.Cu")
		(net "GND")
	)
	(gr_poly
		(pts
			(arc
				(start 55.123842 -119.980964)
				(mid 55.38216 -119.901077)
				(end 55.640478 -119.980964)
			)
			(xy 55.67299 -120.003062)
			(arc
				(start 56.085486 -120.003062)
				(mid 56.175289 -119.965865)
				(end 56.212486 -119.876062)
			)
			(xy 56.212486 -116.92509) (xy 56.136794 -116.849398) (xy 54.66715 -116.849398) (xy 54.663086 -116.853462)
			(arc
				(start 52.453286 -116.853462)
				(mid 52.363483 -116.890659)
				(end 52.326286 -116.980462)
			)
			(xy 52.326286 -117.18671)
			(arc
				(start 52.347114 -117.21846)
				(mid 52.422043 -117.469412)
				(end 52.347114 -117.720364)
			)
			(xy 52.326286 -117.752114)
			(arc
				(start 52.326286 -119.876062)
				(mid 52.363483 -119.965865)
				(end 52.453286 -120.003062)
			)
			(xy 55.09133 -120.003062)
		)
		(stroke
			(width 0)
			(type solid)
		)
		(fill yes)
		(layer "B.Cu")
		(net "GND")
	)
	(gr_poly
		(pts
			(arc
				(start 51.076352 -80.095598)
				(mid 51.166155 -80.058401)
				(end 51.203352 -79.968598)
			)
			(xy 51.203352 -79.251556) (xy 51.447954 -79.006954) (xy 52.98948 -79.006954)
			(arc
				(start 53.01488 -78.995524)
				(mid 53.200046 -78.955145)
				(end 53.385212 -78.995524)
			)
			(xy 53.410612 -79.006954) (xy 53.522626 -79.006954) (xy 53.614828 -79.099156) (xy 53.614828 -79.237586)
			(arc
				(start 53.621432 -79.257398)
				(mid 53.638933 -79.327691)
				(end 53.6448 -79.399892)
			)
			(xy 53.6448 -79.762096) (xy 53.688488 -79.80553) (xy 54.225698 -79.80553) (xy 54.281832 -79.749396)
			(xy 54.281832 -78.293214) (xy 54.574694 -78.000352) (xy 55.020718 -78.000352) (xy 55.071772 -77.949298)
			(xy 55.071772 -77.314298) (xy 55.020972 -77.263498) (xy 54.417976 -77.263498) (xy 54.145688 -77.53604)
			(xy 53.859684 -77.53604) (xy 53.573172 -77.822298) (xy 52.927758 -77.822298) (xy 52.539392 -78.210664)
			(xy 52.39004 -78.210664) (xy 52.387246 -78.213458) (xy 52.115212 -78.213458) (xy 52.057808 -78.156054)
			(xy 51.991768 -78.090268) (xy 51.803554 -77.902054) (xy 50.060606 -77.902054) (xy 49.81448 -78.14818)
			(xy 49.81448 -78.412594) (xy 50.505868 -79.103982) (xy 50.505868 -79.985616) (xy 50.61585 -80.095598)
		)
		(stroke
			(width 0)
			(type solid)
		)
		(fill yes)
		(layer "B.Cu")
		(net "P1V05_NODE1")
	)
	(gr_poly
		(pts
			(arc
				(start 55.007002 -98.629724)
				(mid 55.112961 -98.796959)
				(end 55.306722 -98.837242)
			)
			(xy 55.337202 -98.832162) (xy 55.384954 -98.826066) (xy 55.4482 -98.754438) (xy 55.4482 -96.948498)
			(xy 55.387494 -96.887792)
			(arc
				(start 54.627018 -96.887792)
				(mid 54.537215 -96.924989)
				(end 54.500018 -97.014792)
			)
			(xy 54.500018 -97.023428)
			(arc
				(start 54.501034 -97.03181)
				(mid 54.504297 -97.064249)
				(end 54.505352 -97.096834)
			)
			(xy 54.505352 -97.296224)
			(arc
				(start 54.699662 -97.49028)
				(mid 54.835013 -97.755025)
				(end 54.789578 -98.048826)
			)
			(arc
				(start 54.789578 -98.048826)
				(mid 54.767629 -98.213435)
				(end 54.852062 -98.35642)
			)
			(arc
				(start 54.852062 -98.35642)
				(mid 54.953755 -98.479347)
				(end 55.007002 -98.629724)
			)
		)
		(stroke
			(width 0)
			(type solid)
		)
		(fill yes)
		(layer "B.Cu")
		(net "P1V8_NODE1")
	)
	(gr_poly
		(pts
			(xy 92.2147 -168.175178) (xy 92.2147 -167.047164) (xy 92.242132 -167.029638) (xy 92.27312 -166.972996)
			(xy 92.27312 -166.589964)
			(arc
				(start 92.267532 -166.571676)
				(mid 92.247803 -166.46012)
				(end 92.256102 -166.34714)
			)
			(xy 92.258642 -166.334694) (xy 92.258642 -165.750494) (xy 92.20708 -165.682422)
			(arc
				(start 92.165678 -165.670992)
				(mid 91.830706 -165.224133)
				(end 92.177108 -164.786056)
			)
			(xy 92.219526 -164.775388) (xy 92.27312 -164.706554) (xy 92.27312 -163.221162) (xy 92.223082 -163.171124)
			(xy 92.24645 -163.153344) (xy 92.27312 -163.100004) (xy 92.27312 -162.654996) (xy 92.253308 -162.635184)
			(arc
				(start 91.108784 -162.635184)
				(mid 91.018981 -162.672381)
				(end 90.981784 -162.762184)
			)
			(arc
				(start 90.981784 -168.115234)
				(mid 91.018981 -168.205037)
				(end 91.108784 -168.242234)
			)
			(xy 92.147644 -168.242234)
		)
		(stroke
			(width 0)
			(type solid)
		)
		(fill yes)
		(layer "B.Cu")
		(net "P3V3_NODE1")
	)
	(gr_poly
		(pts
			(xy 167.7543 -85.753702) (xy 167.7543 -84.538058) (xy 166.93769 -83.721448) (xy 163.46932 -83.721448)
			(xy 162.97656 -83.228688) (xy 162.97656 -80.108298) (xy 162.86734 -79.999078) (xy 162.69589 -79.827628)
			(xy 162.318954 -79.827628) (xy 162.307524 -79.816452) (xy 162.30727 -79.816452) (xy 162.073336 -79.582264)
			(xy 162.073336 -79.581756) (xy 162.06089 -79.56931) (xy 162.06089 -77.538326) (xy 161.767012 -77.244448)
			(xy 161.070036 -77.244448) (xy 160.973008 -77.244448) (xy 160.967674 -77.249782) (xy 160.744662 -77.249782)
			(xy 160.7439 -77.24902) (xy 160.031684 -77.24902) (xy 159.724598 -76.941934) (xy 158.973012 -76.941934)
			(xy 158.850584 -77.064362) (xy 158.850584 -77.146404) (xy 155.162504 -77.146404) (xy 154.38628 -77.922628)
			(xy 154.38628 -84.478622)
			(arc
				(start 155.144216 -85.236558)
				(mid 155.324153 -85.310941)
				(end 155.50388 -85.23605)
			)
			(arc
				(start 155.50388 -85.23605)
				(mid 156.058394 -85.124375)
				(end 156.373068 -85.594444)
			)
			(arc
				(start 156.373068 -85.686392)
				(mid 156.410265 -85.776195)
				(end 156.500068 -85.813392)
			)
			(xy 163.490656 -85.813392) (xy 164.04844 -86.371176) (xy 167.136826 -86.371176)
		)
		(stroke
			(width 0)
			(type solid)
		)
		(fill yes)
		(layer "B.Cu")
		(net "P1V0_NODE1")
	)
	(gr_poly
		(pts
			(xy 147.309078 -39.676832) (xy 147.32254 -39.597076)
			(arc
				(start 147.305014 -39.5605)
				(mid 147.393855 -39.038471)
				(end 147.915884 -38.94963)
			)
			(arc
				(start 147.915884 -38.94963)
				(mid 147.992313 -38.960423)
				(end 148.060918 -38.924992)
			)
			(xy 149.473412 -37.512498)
			(arc
				(start 149.473412 -35.831018)
				(mid 149.436035 -35.741036)
				(end 149.345904 -35.704018)
			)
			(arc
				(start 149.345904 -35.704018)
				(mid 148.886159 -35.24631)
				(end 149.345904 -34.788602)
			)
			(arc
				(start 149.345904 -34.788602)
				(mid 149.436035 -34.751585)
				(end 149.473412 -34.661602)
			)
			(xy 149.473412 -33.074864) (xy 149.381972 -32.983424) (xy 145.227802 -32.983424) (xy 145.012156 -33.19907)
			(xy 145.012156 -40.926766) (xy 145.086832 -41.001188) (xy 145.984468 -41.001188)
		)
		(stroke
			(width 0)
			(type solid)
		)
		(fill yes)
		(layer "B.Cu")
		(net "P3V3_NODE1")
	)
	(gr_poly
		(pts
			(xy 50.251614 -79.819246) (xy 50.251614 -79.209392) (xy 49.560226 -78.518004) (xy 49.560226 -78.04277)
			(xy 49.973738 -77.629258) (xy 51.903122 -77.629258) (xy 51.99634 -77.53604) (xy 51.99634 -76.694284)
			(xy 51.971956 -76.694284) (xy 51.971956 -76.582016)
			(arc
				(start 51.952144 -76.551028)
				(mid 51.933333 -76.518492)
				(end 51.917346 -76.48448)
			)
			(arc
				(start 51.917346 -76.48448)
				(mid 51.870577 -76.427821)
				(end 51.800252 -76.406502)
			)
			(xy 51.537108 -76.406502)
			(arc
				(start 51.523646 -76.40955)
				(mid 51.44135 -76.41853)
				(end 51.359054 -76.40955)
			)
			(xy 51.345592 -76.406502) (xy 51.08575 -76.406502) (xy 50.76317 -76.083922) (xy 49.272444 -76.083922)
			(xy 49.195228 -76.161138) (xy 49.195228 -76.61275) (xy 49.138078 -76.6699)
			(arc
				(start 49.1363 -76.71943)
				(mid 49.024834 -76.974486)
				(end 48.769778 -77.085952)
			)
			(xy 48.720248 -77.08773) (xy 48.491648 -77.31633) (xy 48.479456 -77.399388)
			(arc
				(start 48.499522 -77.436472)
				(mid 48.556306 -77.743798)
				(end 48.42256 -78.02626)
			)
			(xy 48.42256 -78.442312) (xy 48.502824 -78.522576)
			(arc
				(start 48.502824 -79.147162)
				(mid 48.486754 -79.271205)
				(end 48.439324 -79.386938)
			)
			(xy 48.42256 -79.416148)
			(arc
				(start 48.42256 -79.845408)
				(mid 48.432213 -79.894229)
				(end 48.459898 -79.935578)
			)
			(xy 48.496474 -79.9719) (xy 49.69637 -79.9719) (xy 49.69764 -79.97317) (xy 50.09769 -79.97317)
		)
		(stroke
			(width 0)
			(type solid)
		)
		(fill yes)
		(layer "B.Cu")
		(net "GND")
	)
	(gr_poly
		(pts
			(arc
				(start 88.05418 -85.221064)
				(mid 88.143983 -85.183867)
				(end 88.18118 -85.094064)
			)
			(xy 88.18118 -82.881724) (xy 87.241888 -81.942432) (xy 85.983572 -81.942432) (xy 85.97138 -81.954624)
			(xy 85.97138 -82.432144) (xy 85.95106 -82.452464)
			(arc
				(start 85.95106 -82.975196)
				(mid 86.024738 -83.154081)
				(end 86.203028 -83.229196)
			)
			(arc
				(start 86.203028 -83.229196)
				(mid 86.532823 -83.424228)
				(end 86.526878 -83.8073)
			)
			(arc
				(start 86.526878 -83.8073)
				(mid 86.491396 -83.958231)
				(end 86.550246 -84.101686)
			)
			(arc
				(start 86.550246 -84.101686)
				(mid 86.597167 -84.522631)
				(end 86.226396 -84.727542)
			)
			(arc
				(start 86.226396 -84.727542)
				(mid 86.033247 -84.793613)
				(end 85.95106 -84.980526)
			)
			(xy 85.95106 -85.096604) (xy 86.07552 -85.221064)
		)
		(stroke
			(width 0)
			(type solid)
		)
		(fill yes)
		(layer "B.Cu")
		(net "P3V3_RTC_NODE1")
	)
	(gr_poly
		(pts
			(arc
				(start 58.139076 -74.23023)
				(mid 58.228879 -74.193033)
				(end 58.266076 -74.10323)
			)
			(xy 58.266076 -73.59142) (xy 58.52033 -73.33742) (xy 59.11596 -73.33742) (xy 59.317128 -73.538334)
			(arc
				(start 59.317128 -73.902824)
				(mid 59.354325 -73.992627)
				(end 59.444128 -74.029824)
			)
			(arc
				(start 60.63869 -74.029824)
				(mid 60.722992 -73.998034)
				(end 60.764928 -73.918318)
			)
			(xy 60.765944 -73.909428) (xy 60.765944 -73.547478) (xy 60.746386 -73.500742) (xy 60.745878 -73.500234)
			(xy 60.418726 -73.500234) (xy 60.412376 -73.49998) (xy 60.260738 -73.49998) (xy 60.254388 -73.49363)
			(xy 60.140088 -73.379584) (xy 60.111132 -73.350374) (xy 59.979052 -73.218294) (xy 59.979052 -72.704706)
			(arc
				(start 59.939174 -72.664828)
				(mid 59.892721 -72.635179)
				(end 59.838082 -72.627998)
			)
			(xy 59.795918 -72.63003) (xy 59.303158 -72.63003) (xy 59.074812 -72.858122)
			(arc
				(start 57.070244 -72.858122)
				(mid 57.021423 -72.867775)
				(end 56.980074 -72.89546)
			)
			(xy 56.947816 -72.927972) (xy 56.942228 -72.970898)
			(arc
				(start 56.94172 -72.973946)
				(mid 56.942994 -73.054522)
				(end 56.969406 -73.130664)
			)
			(xy 56.97093 -73.133458) (xy 56.971438 -73.13422) (xy 56.982868 -73.152508)
			(arc
				(start 56.983376 -73.153524)
				(mid 57.011464 -73.187854)
				(end 57.045098 -73.21677)
			)
			(xy 57.049924 -73.220072) (xy 57.069228 -73.23201) (xy 57.06999 -73.232264)
			(arc
				(start 57.07507 -73.235058)
				(mid 57.132347 -73.256863)
				(end 57.19318 -73.264268)
			)
			(xy 57.495186 -73.264268) (xy 57.775856 -73.544938) (xy 57.775856 -74.17816) (xy 57.827926 -74.23023)
		)
		(stroke
			(width 0)
			(type solid)
		)
		(fill yes)
		(layer "B.Cu")
		(net "GND")
	)
	(gr_poly
		(pts
			(arc
				(start 59.639454 -133.834886)
				(mid 59.741054 -133.885788)
				(end 59.842654 -133.834886)
			)
			(arc
				(start 59.842654 -133.834886)
				(mid 60.009473 -133.70945)
				(end 60.217558 -133.693408)
			)
			(arc
				(start 60.217558 -133.693408)
				(mid 60.334184 -133.600001)
				(end 60.378086 -133.457188)
			)
			(arc
				(start 60.378086 -133.05917)
				(mid 60.33415 -132.91638)
				(end 60.217558 -132.82295)
			)
			(arc
				(start 60.217558 -132.82295)
				(mid 60.003542 -132.804559)
				(end 59.835288 -132.671058)
			)
			(arc
				(start 59.835288 -132.671058)
				(mid 59.741054 -132.652937)
				(end 59.64682 -132.671058)
			)
			(arc
				(start 59.64682 -132.671058)
				(mid 59.608979 -132.717168)
				(end 59.56427 -132.756656)
			)
			(arc
				(start 59.56427 -132.756656)
				(mid 59.513368 -132.858256)
				(end 59.56427 -132.959856)
			)
			(arc
				(start 59.56427 -132.959856)
				(mid 59.713671 -133.26458)
				(end 59.55411 -133.564122)
			)
			(arc
				(start 59.55411 -133.564122)
				(mid 59.535971 -133.658238)
				(end 59.55411 -133.752336)
			)
			(arc
				(start 59.55411 -133.752336)
				(mid 59.600099 -133.790183)
				(end 59.639454 -133.834886)
			)
		)
		(stroke
			(width 0)
			(type solid)
		)
		(fill yes)
		(layer "B.Cu")
		(net "P0V75_BMC_VTTREF_NODE1")
	)
	(gr_poly
		(pts
			(arc
				(start 44.595034 -134.660894)
				(mid 44.761024 -134.707277)
				(end 44.918376 -134.637018)
			)
			(arc
				(start 44.918376 -134.637018)
				(mid 45.096598 -134.5307)
				(end 45.30344 -134.514082)
			)
			(arc
				(start 45.30344 -134.514082)
				(mid 45.520092 -134.443029)
				(end 45.592492 -134.226808)
			)
			(arc
				(start 45.592492 -134.226808)
				(mid 45.596605 -134.077223)
				(end 45.65015 -133.937502)
			)
			(xy 45.667676 -133.90753)
			(arc
				(start 45.667676 -133.822186)
				(mid 45.579839 -133.630077)
				(end 45.3771 -133.57098)
			)
			(arc
				(start 45.3771 -133.57098)
				(mid 45.34493 -133.574561)
				(end 45.312584 -133.575806)
			)
			(arc
				(start 44.952412 -133.575806)
				(mid 44.740887 -133.689189)
				(end 44.718224 -133.928104)
			)
			(arc
				(start 44.718224 -133.928104)
				(mid 44.740759 -134.215195)
				(end 44.587414 -134.458964)
			)
			(arc
				(start 44.587414 -134.458964)
				(mid 44.541143 -134.561528)
				(end 44.594526 -134.66064)
			)
		)
		(stroke
			(width 0)
			(type solid)
		)
		(fill yes)
		(layer "B.Cu")
		(net "P1V538_BMC_NODE1")
	)
	(gr_poly
		(pts
			(arc
				(start 44.643294 -134.73938)
				(mid 44.749449 -134.783772)
				(end 44.847764 -134.72414)
			)
			(arc
				(start 44.847764 -134.72414)
				(mid 45.044247 -134.551079)
				(end 45.30344 -134.514082)
			)
			(arc
				(start 45.30344 -134.514082)
				(mid 45.520092 -134.443029)
				(end 45.592492 -134.226808)
			)
			(arc
				(start 45.592492 -134.226808)
				(mid 45.596605 -134.077223)
				(end 45.65015 -133.937502)
			)
			(xy 45.667676 -133.90753)
			(arc
				(start 45.667676 -133.822186)
				(mid 45.579839 -133.630077)
				(end 45.3771 -133.57098)
			)
			(arc
				(start 45.3771 -133.57098)
				(mid 45.344925 -133.574432)
				(end 45.312584 -133.575552)
			)
			(arc
				(start 44.952412 -133.575552)
				(mid 44.740822 -133.689032)
				(end 44.718224 -133.928104)
			)
			(arc
				(start 44.718224 -133.928104)
				(mid 44.748374 -134.177578)
				(end 44.642278 -134.40537)
			)
			(arc
				(start 44.642278 -134.40537)
				(mid 44.580169 -134.571382)
				(end 44.64177 -134.737602)
			)
		)
		(stroke
			(width 0)
			(type solid)
		)
		(fill yes)
		(layer "B.Cu")
		(net "P1V538_BMC_NODE1")
	)
	(gr_poly
		(pts
			(xy 70.1548 -127.77851) (xy 70.1548 -127.599694)
			(arc
				(start 70.174612 -127.579882)
				(mid 70.205468 -127.492559)
				(end 70.256908 -127.415544)
			)
			(xy 70.259956 -127.412242) (xy 70.260464 -127.41148) (xy 70.286372 -127.381) (xy 70.287388 -127.381)
			(arc
				(start 70.320662 -127.35687)
				(mid 70.538848 -127.286348)
				(end 70.757034 -127.35687)
			)
			(xy 70.790308 -127.381) (xy 71.090536 -127.381)
			(arc
				(start 71.12381 -127.35687)
				(mid 71.218564 -127.307444)
				(end 71.323454 -127.28702)
			)
			(xy 71.372476 -127.28448) (xy 71.767446 -126.88951)
			(arc
				(start 71.769986 -126.840488)
				(mid 71.878648 -126.595582)
				(end 72.123554 -126.48692)
			)
			(xy 72.172576 -126.48438) (xy 72.289162 -126.367794) (xy 72.417686 -126.367794) (xy 72.569832 -126.215902)
			(xy 72.569832 -126.215394)
			(arc
				(start 72.637396 -126.14783)
				(mid 72.662791 -126.107784)
				(end 72.671686 -126.061216)
			)
			(xy 72.671686 -125.400308) (xy 72.392286 -125.120908) (xy 71.480934 -125.120908) (xy 71.341488 -124.981462)
			(xy 69.88556 -124.981462)
			(arc
				(start 69.860414 -124.992892)
				(mid 69.757226 -125.027269)
				(end 69.649086 -125.038866)
			)
			(xy 68.843652 -125.038866) (xy 68.665852 -125.216666)
			(arc
				(start 68.53428 -125.216666)
				(mid 68.444477 -125.253863)
				(end 68.40728 -125.343666)
			)
			(arc
				(start 68.40728 -126.404878)
				(mid 68.416933 -126.453699)
				(end 68.444618 -126.495048)
			)
			(xy 68.481194 -126.53137) (xy 68.481194 -126.727458) (xy 68.481194 -127.214122) (xy 69.194172 -127.9271)
			(xy 70.00621 -127.9271)
		)
		(stroke
			(width 0)
			(type solid)
		)
		(fill yes)
		(layer "B.Cu")
		(net "BMC_NODE1_VCC_1V8_PCIE")
	)
	(gr_poly
		(pts
			(xy 65.384172 -72.335898) (xy 65.384172 -71.726298) (xy 65.390522 -71.719948)
			(arc
				(start 65.390522 -71.527924)
				(mid 65.355631 -71.440489)
				(end 65.270126 -71.401178)
			)
			(arc
				(start 65.270126 -71.401178)
				(mid 65.016618 -71.286596)
				(end 64.90843 -71.030338)
			)
			(xy 64.906906 -70.979792) (xy 64.83604 -70.908926) (xy 64.83604 -70.234302) (xy 64.717168 -70.115684)
			(arc
				(start 64.371474 -70.115684)
				(mid 64.291734 -70.154673)
				(end 64.25692 -70.236334)
			)
			(xy 64.25692 -70.9676) (xy 64.196468 -71.028052) (xy 64.07658 -71.148194) (xy 60.929266 -71.148194)
			(xy 60.928758 -71.14794) (xy 60.156598 -71.14794) (xy 60.07481 -71.065898) (xy 60.024772 -71.065898)
			(xy 59.923172 -70.964298) (xy 59.923172 -70.941692) (xy 59.903614 -70.894956) (xy 59.87034 -70.861682)
			(arc
				(start 59.87034 -70.329298)
				(mid 59.833143 -70.239495)
				(end 59.74334 -70.202298)
			)
			(xy 59.389772 -70.202298) (xy 59.300872 -70.291198) (xy 59.313572 -70.303898) (xy 59.313572 -72.259698)
			(xy 59.338972 -72.285098) (xy 59.821572 -72.285098) (xy 59.897772 -72.208898) (xy 59.897772 -71.878698)
			(xy 59.999372 -71.777098) (xy 61.82233 -71.777098)
			(arc
				(start 61.843412 -71.769224)
				(mid 62.001146 -71.741192)
				(end 62.15888 -71.769224)
			)
			(xy 62.179962 -71.777098) (xy 63.394082 -71.777098) (xy 63.48349 -71.68769)
			(arc
				(start 64.247522 -71.68769)
				(mid 64.371416 -71.705358)
				(end 64.48552 -71.756778)
			)
			(xy 64.516508 -71.77659) (xy 64.647064 -71.77659) (xy 64.723772 -71.853298) (xy 64.723772 -72.335898)
			(xy 64.799972 -72.412098) (xy 65.307972 -72.412098)
		)
		(stroke
			(width 0)
			(type solid)
		)
		(fill yes)
		(layer "B.Cu")
		(net "P1V05_NODE1")
	)
	(gr_poly
		(pts
			(xy 37.50818 -141.352524) (xy 37.50818 -139.400534) (xy 37.502084 -139.394438) (xy 37.502084 -136.13638)
			(xy 37.684202 -135.954262) (xy 37.803074 -135.835644) (xy 37.914834 -135.72363)
			(arc
				(start 39.511732 -135.72363)
				(mid 39.601535 -135.686433)
				(end 39.638732 -135.59663)
			)
			(arc
				(start 39.638732 -135.423402)
				(mid 39.544568 -135.225998)
				(end 39.3319 -135.17499)
			)
			(arc
				(start 39.3319 -135.17499)
				(mid 38.77883 -134.727188)
				(end 39.3319 -134.279386)
			)
			(arc
				(start 39.3319 -134.279386)
				(mid 39.544548 -134.228354)
				(end 39.638732 -134.030974)
			)
			(xy 39.638732 -133.693408) (xy 39.556436 -133.611112) (xy 39.351712 -133.611112)
			(arc
				(start 39.327836 -133.621272)
				(mid 39.12236 -133.657477)
				(end 38.922198 -133.598666)
			)
			(xy 38.892988 -133.581902) (xy 36.52266 -133.581902) (xy 36.359592 -133.581902) (xy 36.3474 -133.594094)
			(xy 35.97275 -133.968744) (xy 35.51047 -134.431024) (xy 35.51047 -139.117578) (xy 35.51047 -140.8811)
			(xy 36.14166 -141.51229) (xy 36.472622 -141.51229) (xy 37.348414 -141.51229)
		)
		(stroke
			(width 0)
			(type solid)
		)
		(fill yes)
		(layer "B.Cu")
		(net "P0V75_BMC_VTTREF_NODE1")
	)
	(gr_poly
		(pts
			(xy 56.953912 -68.198492) (xy 56.953912 -67.553586)
			(arc
				(start 56.94553 -67.531742)
				(mid 56.927805 -67.474327)
				(end 56.917336 -67.415156)
			)
			(arc
				(start 56.917336 -67.415156)
				(mid 56.945883 -67.187941)
				(end 57.075832 -66.999358)
			)
			(arc
				(start 57.075832 -66.999358)
				(mid 57.117904 -66.91695)
				(end 57.09285 -66.827908)
			)
			(arc
				(start 57.09285 -66.827908)
				(mid 57.025152 -66.682483)
				(end 57.023254 -66.522092)
			)
			(arc
				(start 57.023254 -66.522092)
				(mid 56.971118 -66.310612)
				(end 56.774334 -66.217292)
			)
			(xy 56.64581 -66.217292) (xy 56.5404 -66.111882) (xy 56.16448 -66.111882) (xy 56.031384 -65.978786)
			(arc
				(start 55.36819 -65.978786)
				(mid 55.324956 -65.986372)
				(end 55.28691 -66.00825)
			)
			(arc
				(start 55.28691 -66.00825)
				(mid 55.263716 -66.026285)
				(end 55.239412 -66.042794)
			)
			(xy 55.227474 -66.050414) (xy 55.16372 -66.114168) (xy 55.16372 -66.312288)
			(arc
				(start 55.191152 -66.346832)
				(mid 55.273261 -66.583306)
				(end 55.191152 -66.81978)
			)
			(xy 55.16372 -66.854324) (xy 55.16372 -67.074288)
			(arc
				(start 55.191152 -67.108832)
				(mid 55.273261 -67.345306)
				(end 55.191152 -67.58178)
			)
			(xy 55.16372 -67.616324) (xy 55.16372 -67.860672) (xy 55.409846 -68.106798)
			(arc
				(start 55.452264 -68.11264)
				(mid 55.548841 -68.140216)
				(end 55.633874 -68.193666)
			)
			(xy 55.669434 -68.223892) (xy 56.928512 -68.223892)
		)
		(stroke
			(width 0)
			(type solid)
		)
		(fill yes)
		(layer "B.Cu")
		(net "GND")
	)
	(gr_poly
		(pts
			(arc
				(start 81.804002 -80.756506)
				(mid 81.852549 -80.746756)
				(end 81.893664 -80.719168)
			)
			(xy 82.228436 -80.384396) (xy 82.228436 -79.539592) (xy 82.054954 -79.365856) (xy 82.017362 -79.328264)
			(xy 78.854808 -79.328264) (xy 78.472284 -79.710788) (xy 78.36662 -79.710788) (xy 78.366366 -79.711296)
			(xy 73.921366 -79.711296) (xy 73.921112 -79.710788) (xy 70.914006 -79.710788) (xy 70.521576 -79.318358)
			(xy 70.521576 -79.108554) (xy 70.42785 -79.014828)
			(arc
				(start 70.407022 -79.00543)
				(mid 70.389259 -78.996739)
				(end 70.37197 -78.987142)
			)
			(xy 70.3707 -78.98638) (xy 70.369938 -78.985872) (xy 70.352666 -78.97495) (xy 70.320408 -78.95336)
			(xy 70.193662 -78.95336) (xy 70.153784 -78.993238)
			(arc
				(start 70.152768 -78.994254)
				(mid 69.852611 -79.141079)
				(end 69.528944 -79.058008)
			)
			(xy 69.496178 -79.035402) (xy 68.160646 -79.035402) (xy 68.068952 -78.943708) (xy 67.80657 -78.943708)
			(xy 67.702684 -79.047594) (xy 66.99377 -79.047594) (xy 66.75628 -79.285084)
			(arc
				(start 66.746628 -79.309214)
				(mid 66.661795 -79.438249)
				(end 66.53276 -79.523082)
			)
			(xy 66.50863 -79.532734) (xy 66.487294 -79.55407) (xy 66.131694 -79.55407) (xy 65.689988 -79.112364)
			(xy 65.374266 -79.112364)
			(arc
				(start 65.36436 -79.113888)
				(mid 65.295018 -79.119326)
				(end 65.225676 -79.113888)
			)
			(xy 65.21577 -79.112364) (xy 64.55537 -79.112364) (xy 64.422782 -79.244952) (xy 62.394846 -79.244952)
			(xy 62.291468 -79.141574)
			(arc
				(start 61.952886 -79.141574)
				(mid 61.863083 -79.178771)
				(end 61.825886 -79.268574)
			)
			(xy 61.825886 -79.618078) (xy 61.966856 -79.759048) (xy 63.91021 -79.759048) (xy 64.15278 -80.001618)
			(xy 64.15278 -80.384142) (xy 64.231012 -80.462374) (xy 64.58458 -80.462374) (xy 64.70396 -80.342994)
			(xy 65.210944 -80.342994) (xy 65.235328 -80.367378) (xy 76.22667 -80.367378) (xy 76.615798 -80.756506)
		)
		(stroke
			(width 0)
			(type solid)
		)
		(fill yes)
		(layer "B.Cu")
		(net "PV_VCCP_NODE1")
	)
	(gr_poly
		(pts
			(arc
				(start 34.421826 -151.9301)
				(mid 34.53696 -151.87119)
				(end 34.665158 -151.854154)
			)
			(arc
				(start 34.665158 -151.854154)
				(mid 34.716437 -151.845562)
				(end 34.7599 -151.81707)
			)
			(xy 35.266376 -151.310594) (xy 35.644582 -151.310594) (xy 36.552886 -150.402544)
			(arc
				(start 37.512752 -150.402544)
				(mid 37.561747 -150.404886)
				(end 37.610288 -150.411942)
			)
			(xy 37.64153 -150.418038) (xy 37.701982 -150.399496) (xy 38.074092 -150.027386)
			(arc
				(start 38.074346 -149.974808)
				(mid 38.113132 -149.780581)
				(end 38.22319 -149.615906)
			)
			(xy 38.36416 -149.474682) (xy 38.36416 -149.366224)
			(arc
				(start 37.658802 -148.660866)
				(mid 37.56905 -148.623801)
				(end 37.479224 -148.660866)
			)
			(arc
				(start 37.41293 -148.72716)
				(mid 36.850243 -148.833614)
				(end 36.54552 -148.3487)
			)
			(arc
				(start 36.54552 -148.3487)
				(mid 36.474615 -148.163107)
				(end 36.291774 -148.085302)
			)
			(xy 29.71546 -148.085302) (xy 29.708348 -148.092414) (xy 28.361132 -148.092414) (xy 27.704542 -147.435824)
			(arc
				(start 27.704542 -145.308574)
				(mid 27.667345 -145.218771)
				(end 27.577542 -145.181574)
			)
			(xy 26.293572 -145.181574) (xy 26.194512 -145.280634) (xy 26.194512 -147.261834) (xy 25.285192 -148.171154)
			(xy 24.495252 -148.171154) (xy 24.266652 -148.399754) (xy 24.266652 -150.015194) (xy 24.293576 -150.042372)
			(xy 24.293576 -151.120856) (xy 25.12822 -151.9555) (xy 34.388044 -151.9555)
		)
		(stroke
			(width 0)
			(type solid)
		)
		(fill yes)
		(layer "B.Cu")
		(net "LAN1_CTRL_P1V9")
	)
	(gr_poly
		(pts
			(arc
				(start 54.69382 -87.912702)
				(mid 54.783623 -87.875505)
				(end 54.82082 -87.785702)
			)
			(xy 54.82082 -86.462616)
			(arc
				(start 54.804056 -86.433406)
				(mid 54.755535 -86.281778)
				(end 54.773068 -86.123526)
			)
			(xy 54.779418 -86.103968) (xy 54.779418 -85.48497)
			(arc
				(start 54.776878 -85.472524)
				(mid 54.769243 -85.396578)
				(end 54.776878 -85.320632)
			)
			(xy 54.779418 -85.308186) (xy 54.779418 -84.72297)
			(arc
				(start 54.776878 -84.710524)
				(mid 54.769243 -84.634578)
				(end 54.776878 -84.558632)
			)
			(xy 54.779418 -84.546186) (xy 54.779418 -84.455508) (xy 54.783482 -84.451444) (xy 54.783482 -84.400136)
			(xy 54.912514 -84.271104) (xy 55.033672 -84.271104)
			(arc
				(start 55.050182 -84.266532)
				(mid 55.150766 -84.253035)
				(end 55.25135 -84.266532)
			)
			(xy 55.26786 -84.271104) (xy 55.396638 -84.271104) (xy 55.406544 -84.281264) (xy 56.444642 -84.281264)
			(arc
				(start 56.468518 -84.27085)
				(mid 56.619394 -84.239758)
				(end 56.77027 -84.27085)
			)
			(xy 56.794146 -84.281264) (xy 57.255156 -84.281264) (xy 57.408064 -84.128356) (xy 57.408064 -82.832194)
			(xy 57.482994 -82.75701) (xy 57.482994 -81.877916) (xy 57.377838 -81.77276) (xy 56.91632 -81.77276)
			(xy 56.81472 -81.87436) (xy 56.81472 -82.73542) (xy 56.724042 -82.826098) (xy 56.723788 -82.826098)
			(xy 56.676036 -82.87385)
			(arc
				(start 55.738268 -82.87385)
				(mid 55.689447 -82.883503)
				(end 55.648098 -82.911188)
			)
			(xy 55.592472 -82.967068) (xy 55.592472 -83.306666)
			(arc
				(start 55.543958 -83.354672)
				(mid 55.516291 -83.396029)
				(end 55.50662 -83.444842)
			)
			(xy 55.50662 -83.494372) (xy 55.454804 -83.546188) (xy 54.684676 -83.546188) (xy 54.671722 -83.545426)
			(xy 53.69306 -83.545426) (xy 53.54574 -83.692746) (xy 53.54574 -85.329268) (xy 53.34254 -85.532468)
			(xy 52.50942 -85.532468)
			(arc
				(start 52.49672 -85.535008)
				(mid 52.404772 -85.54434)
				(end 52.312824 -85.535008)
			)
			(xy 52.300124 -85.532468) (xy 51.960018 -85.532468) (xy 51.567842 -85.924644) (xy 51.567842 -87.475568)
			(xy 52.004976 -87.912702)
		)
		(stroke
			(width 0)
			(type solid)
		)
		(fill yes)
		(layer "B.Cu")
		(net "P1V8_NODE1")
	)
	(gr_poly
		(pts
			(xy 65.414652 -146.035522) (xy 65.414652 -145.461482) (xy 64.675512 -144.722342) (xy 63.734442 -144.722342)
			(arc
				(start 63.700914 -144.746472)
				(mid 63.11935 -144.570516)
				(end 63.44539 -144.057624)
			)
			(arc
				(start 63.44539 -144.057624)
				(mid 63.468742 -144.056392)
				(end 63.492126 -144.056608)
			)
			(arc
				(start 63.492126 -144.056608)
				(mid 63.678227 -143.985988)
				(end 63.756286 -143.802862)
			)
			(xy 63.756286 -142.427452) (xy 63.87846 -142.305278) (xy 64.013588 -142.305278)
			(arc
				(start 64.045338 -142.284704)
				(mid 64.093375 -142.256989)
				(end 64.144144 -142.234666)
			)
			(arc
				(start 64.144144 -142.234666)
				(mid 64.231964 -142.210395)
				(end 64.322706 -142.202154)
			)
			(arc
				(start 64.371728 -142.202154)
				(mid 64.461531 -142.164957)
				(end 64.498728 -142.075154)
			)
			(xy 64.498728 -141.93139) (xy 64.394588 -141.82725) (xy 63.507874 -141.82725) (xy 63.502286 -141.821662)
			(xy 63.121286 -141.821662) (xy 62.918086 -142.024862) (xy 62.918086 -142.392908) (xy 62.95136 -142.477998)
			(arc
				(start 62.96533 -142.494254)
				(mid 63.06535 -142.66417)
				(end 63.100204 -142.858236)
			)
			(xy 63.100204 -143.373602) (xy 62.757304 -143.716248) (xy 62.537086 -143.936466)
			(arc
				(start 62.537086 -145.601944)
				(mid 62.556928 -145.670107)
				(end 62.610238 -145.717006)
			)
			(arc
				(start 62.610238 -145.717006)
				(mid 62.658265 -145.743924)
				(end 62.701932 -145.777458)
			)
			(arc
				(start 62.701932 -145.777458)
				(mid 62.741157 -145.80121)
				(end 62.78626 -145.809462)
			)
			(xy 64.061086 -145.809462) (xy 64.064896 -145.805906) (xy 64.507872 -146.248882) (xy 65.201292 -146.248882)
		)
		(stroke
			(width 0)
			(type solid)
		)
		(fill yes)
		(layer "B.Cu")
		(net "BMC_NODE1_ADCAV33")
	)
	(gr_poly
		(pts
			(xy 15.246604 -207.283558) (xy 15.263256 -207.283063) (xy 15.295426 -207.27444) (xy 15.324266 -207.257784)
			(xy 15.347812 -207.23423) (xy 15.364458 -207.205383) (xy 15.373069 -207.173211) (xy 15.373604 -207.156558)
			(xy 15.373604 -203.035154) (xy 15.396464 -203.012294) (xy 15.61084 -203.012294) (xy 15.64386 -203.045314)
			(xy 15.64386 -207.223106) (xy 15.652794 -207.236632) (xy 15.676216 -207.259026) (xy 15.704509 -207.274824)
			(xy 15.735862 -207.283015) (xy 15.752064 -207.283558) (xy 16.331184 -207.283558) (xy 16.366744 -207.247998)
			(xy 16.366744 -202.970892) (xy 16.45412 -202.883516) (xy 16.557244 -202.883516) (xy 16.651224 -202.977496)
			(xy 16.651224 -207.230218) (xy 16.661384 -207.240378) (xy 17.30375 -207.240378) (xy 17.372584 -207.171544)
			(xy 17.372584 -202.74407) (xy 17.408144 -202.70851) (xy 17.408144 -197.10908) (xy 17.00784 -196.708776)
			(xy 14.769338 -196.708776) (xy 13.434568 -198.043546) (xy 13.434568 -200.575418) (xy 13.968982 -200.575418)
			(xy 13.973053 -200.519796) (xy 13.985179 -200.465359) (xy 14.005102 -200.413268) (xy 14.032398 -200.364633)
			(xy 14.066484 -200.32049) (xy 14.106633 -200.281781) (xy 14.151991 -200.24933) (xy 14.201591 -200.223829)
			(xy 14.254375 -200.205822) (xy 14.309218 -200.195692) (xy 14.364952 -200.193655) (xy 14.420389 -200.199755)
			(xy 14.474346 -200.213861) (xy 14.525675 -200.235673) (xy 14.573281 -200.264727) (xy 14.616149 -200.300402)
			(xy 14.653366 -200.341939) (xy 14.684139 -200.388452) (xy 14.707811 -200.438949) (xy 14.723879 -200.492356)
			(xy 14.731999 -200.547532) (xy 14.732508 -200.575418) (xy 14.731999 -200.603304) (xy 14.723879 -200.65848)
			(xy 14.707811 -200.711887) (xy 14.684139 -200.762384) (xy 14.653366 -200.808897) (xy 14.616149 -200.850434)
			(xy 14.573281 -200.886109) (xy 14.525675 -200.915163) (xy 14.474346 -200.936975) (xy 14.420389 -200.951081)
			(xy 14.364952 -200.957181) (xy 14.309218 -200.955144) (xy 14.254375 -200.945014) (xy 14.201591 -200.927007)
			(xy 14.151991 -200.901506) (xy 14.106633 -200.869055) (xy 14.066484 -200.830346) (xy 14.032398 -200.786203)
			(xy 14.005102 -200.737568) (xy 13.985179 -200.685477) (xy 13.973053 -200.63104) (xy 13.968982 -200.575418)
			(xy 13.434568 -200.575418) (xy 13.434568 -201.764392) (xy 12.647676 -202.551284) (xy 12.647676 -207.225138)
			(xy 12.677648 -207.25511) (xy 13.201904 -207.25511) (xy 13.218552 -207.254566) (xy 13.250715 -207.245948)
			(xy 13.279551 -207.2293) (xy 13.303096 -207.205756) (xy 13.319746 -207.17692) (xy 13.328366 -207.144758)
			(xy 13.328904 -207.12811) (xy 13.328904 -203.058014) (xy 13.412724 -202.97394) (xy 13.59281 -202.97394)
			(xy 13.648944 -203.030074) (xy 13.648944 -207.229456) (xy 13.699744 -207.280256) (xy 14.310614 -207.280256)
			(xy 14.360144 -207.230726) (xy 14.360144 -203.030074) (xy 14.44498 -202.945492) (xy 14.558264 -202.945492)
			(xy 14.646402 -203.03363) (xy 14.646402 -207.26908) (xy 14.66088 -207.283558)
		)
		(stroke
			(width 0)
			(type solid)
		)
		(fill yes)
		(layer "B.Cu")
		(net "P12V_PDB")
	)
	(gr_poly
		(pts
			(arc
				(start 68.79209 -140.11656)
				(mid 68.940934 -140.085543)
				(end 69.089778 -140.11656)
			)
			(xy 69.114162 -140.127228) (xy 69.567806 -140.127228)
			(arc
				(start 69.59219 -140.11656)
				(mid 69.741034 -140.085543)
				(end 69.889878 -140.11656)
			)
			(xy 69.914262 -140.127228) (xy 70.370954 -140.127228)
			(arc
				(start 70.39483 -140.116814)
				(mid 70.554224 -140.08677)
				(end 70.711314 -140.127228)
			)
			(xy 70.741286 -140.127228) (xy 70.969886 -139.898628) (xy 70.969886 -139.678918) (xy 70.969632 -139.676124)
			(xy 70.969632 -139.642596) (xy 70.969886 -139.639802) (xy 70.969886 -138.878818) (xy 70.969632 -138.876024)
			(xy 70.969632 -138.842496) (xy 70.969886 -138.839702) (xy 70.969886 -138.078972) (xy 70.969632 -138.076178)
			(xy 70.969632 -138.04265) (xy 70.969886 -138.039856) (xy 70.969886 -137.344404)
			(arc
				(start 70.9676 -137.332212)
				(mid 70.960569 -137.259314)
				(end 70.9676 -137.186416)
			)
			(xy 70.969886 -137.174224) (xy 70.969886 -136.478772) (xy 70.969632 -136.475978) (xy 70.969632 -136.44245)
			(xy 70.969886 -136.439656) (xy 70.969886 -135.678926) (xy 70.969632 -135.676132) (xy 70.969632 -135.642604)
			(xy 70.969886 -135.63981) (xy 70.969886 -135.379714) (xy 71.05269 -135.29691) (xy 71.25462 -135.29691)
			(arc
				(start 71.26732 -135.29437)
				(mid 71.341996 -135.286809)
				(end 71.416672 -135.29437)
			)
			(xy 71.429372 -135.29691) (xy 72.05472 -135.29691)
			(arc
				(start 72.06742 -135.29437)
				(mid 72.142096 -135.286809)
				(end 72.216772 -135.29437)
			)
			(xy 72.229472 -135.29691) (xy 72.506078 -135.29691) (xy 72.683878 -135.11911) (xy 72.683878 -134.874254)
			(xy 72.328024 -134.5184) (xy 71.492364 -134.5184) (xy 71.421244 -134.5184) (xy 70.654672 -133.751828)
			(xy 69.558408 -133.751828) (xy 69.369686 -133.94055) (xy 69.369686 -137.815828) (xy 69.674486 -138.120628)
			(xy 69.674486 -139.238228) (xy 69.615812 -139.296902) (xy 69.615812 -139.421362) (xy 68.51142 -139.421362)
			(xy 68.47332 -139.383262) (xy 68.404486 -139.383262) (xy 68.277486 -139.256262) (xy 68.277486 -138.799062)
			(xy 67.998086 -138.519662) (xy 67.566286 -138.519662) (xy 67.465194 -138.620754) (xy 67.465194 -139.150852)
			(xy 67.820794 -139.506452) (xy 67.820794 -139.51077) (xy 67.871086 -139.561062) (xy 67.871086 -139.873228)
			(xy 68.06438 -140.066522) (xy 68.111624 -140.085826)
			(arc
				(start 68.137278 -140.085572)
				(mid 68.215241 -140.093005)
				(end 68.289932 -140.11656)
			)
			(xy 68.314316 -140.127228) (xy 68.767706 -140.127228)
		)
		(stroke
			(width 0)
			(type solid)
		)
		(fill yes)
		(layer "B.Cu")
		(net "P3V3_NODE1")
	)
	(gr_poly
		(pts
			(xy 62.4332 -148.578824) (xy 63.471298 -148.578824)
			(arc
				(start 63.65367 -148.396452)
				(mid 63.690987 -148.307165)
				(end 63.654432 -148.217636)
			)
			(arc
				(start 63.654432 -148.217636)
				(mid 63.546513 -148.053786)
				(end 63.508636 -147.861274)
			)
			(xy 63.508636 -147.769834) (xy 63.061596 -147.32254) (xy 63.044832 -147.32254) (xy 63.044832 -147.305776)
			(xy 63.019432 -147.280376) (xy 63.019432 -147.159472) (xy 62.246002 -146.386042)
			(arc
				(start 62.235842 -146.379184)
				(mid 62.178699 -146.332187)
				(end 62.131702 -146.275044)
			)
			(xy 62.124844 -146.264884)
			(arc
				(start 62.04585 -146.18589)
				(mid 61.982648 -146.151612)
				(end 61.910976 -146.157188)
			)
			(arc
				(start 61.910976 -146.157188)
				(mid 61.829232 -146.178231)
				(end 61.74486 -146.18081)
			)
			(arc
				(start 61.74486 -146.18081)
				(mid 61.575373 -146.228608)
				(end 61.477652 -146.37512)
			)
			(xy 61.296296 -146.37512) (xy 61.13526 -146.535902) (xy 58.56732 -146.535902) (xy 58.327798 -146.29638)
			(xy 56.608218 -146.29638) (xy 56.404256 -146.500342) (xy 56.404256 -147.06346)
			(arc
				(start 56.833516 -147.492974)
				(mid 57.06886 -147.561159)
				(end 57.252362 -147.39874)
			)
			(arc
				(start 57.252362 -147.39874)
				(mid 58.007041 -147.229023)
				(end 57.837324 -147.983702)
			)
			(arc
				(start 57.837324 -147.983702)
				(mid 57.674835 -148.167188)
				(end 57.74309 -148.402548)
			)
			(xy 57.934352 -148.59381) (xy 62.418214 -148.59381)
		)
		(stroke
			(width 0)
			(type solid)
		)
		(fill yes)
		(layer "B.Cu")
		(net "GND")
	)
	(gr_poly
		(pts
			(arc
				(start 48.612552 -159.480758)
				(mid 48.64342 -159.430279)
				(end 48.648112 -159.371284)
			)
			(arc
				(start 48.648112 -159.371284)
				(mid 48.643628 -159.250858)
				(end 48.66767 -159.132778)
			)
			(xy 48.67402 -159.11322) (xy 48.67402 -158.405068)
			(arc
				(start 48.669194 -158.38805)
				(mid 48.650202 -158.250382)
				(end 48.669194 -158.112714)
			)
			(xy 48.67402 -158.095696) (xy 48.67402 -156.32176)
			(arc
				(start 48.66767 -156.302202)
				(mid 48.641992 -156.14269)
				(end 48.66767 -155.983178)
			)
			(xy 48.67402 -155.96362) (xy 48.67402 -154.56916)
			(arc
				(start 48.66767 -154.549602)
				(mid 48.641992 -154.39009)
				(end 48.66767 -154.230578)
			)
			(xy 48.67402 -154.21102) (xy 48.67402 -153.528268)
			(arc
				(start 48.669194 -153.51125)
				(mid 48.650202 -153.373582)
				(end 48.669194 -153.235914)
			)
			(xy 48.67402 -153.218896) (xy 48.67402 -152.283668)
			(arc
				(start 48.669194 -152.26665)
				(mid 48.650202 -152.128982)
				(end 48.669194 -151.991314)
			)
			(xy 48.67402 -151.974296) (xy 48.67402 -151.24176)
			(arc
				(start 48.66767 -151.222202)
				(mid 48.641992 -151.06269)
				(end 48.66767 -150.903178)
			)
			(xy 48.67402 -150.88362) (xy 48.67402 -150.80869) (xy 48.26762 -150.40229) (xy 40.82542 -150.40229)
			(xy 40.36822 -150.85949) (xy 40.36822 -153.388314)
			(arc
				(start 40.38981 -153.420318)
				(mid 40.476521 -153.70429)
				(end 40.38981 -153.988262)
			)
			(xy 40.36822 -154.020266) (xy 40.36822 -154.850338)
			(arc
				(start 40.391588 -154.883358)
				(mid 40.484951 -155.176982)
				(end 40.391588 -155.470606)
			)
			(xy 40.36822 -155.503626)
			(arc
				(start 40.36822 -156.307028)
				(mid 40.467225 -156.4662)
				(end 40.501824 -156.650436)
			)
			(xy 40.501824 -157.91053) (xy 40.501824 -158.705296) (xy 40.798242 -159.001714) (xy 45.60189 -159.001714)
			(xy 45.740066 -159.13989) (xy 46.15815 -159.13989) (xy 46.177708 -159.13354)
			(arc
				(start 46.177962 -159.13354)
				(mid 46.33722 -159.107941)
				(end 46.496478 -159.13354)
			)
			(xy 46.496732 -159.13354) (xy 46.51629 -159.13989) (xy 47.02302 -159.13989) (xy 47.41164 -159.52851)
			(xy 47.54372 -159.52851) (xy 48.5648 -159.52851)
		)
		(stroke
			(width 0)
			(type solid)
		)
		(fill yes)
		(layer "B.Cu")
		(net "GND")
	)
	(gr_poly
		(pts
			(arc
				(start 131.04241 -122.84456)
				(mid 131.113755 -122.625816)
				(end 130.979164 -122.439176)
			)
			(arc
				(start 130.979164 -122.439176)
				(mid 130.960562 -121.770718)
				(end 131.534916 -122.11304)
			)
			(arc
				(start 131.534916 -122.11304)
				(mid 131.606193 -122.298217)
				(end 131.788916 -122.375676)
			)
			(xy 134.7343 -122.375676) (xy 135.013954 -122.096022) (xy 135.013954 -121.378218) (xy 134.723632 -121.08815)
			(xy 130.333242 -121.08815) (xy 130.313684 -121.068338) (xy 128.963928 -121.068338) (xy 128.07696 -120.18137)
			(xy 128.07696 -118.42115)
			(arc
				(start 128.05664 -118.389908)
				(mid 128.164868 -117.71881)
				(end 128.843532 -117.755162)
			)
			(xy 128.964182 -117.875558) (xy 128.969516 -117.875558) (xy 129.019046 -117.925088) (xy 129.42824 -117.925088)
			(xy 129.465578 -117.88775) (xy 129.465578 -117.466364) (xy 129.292096 -117.292882) (xy 127.577596 -117.292882)
			(xy 126.940056 -117.930422) (xy 126.940056 -119.194834)
			(arc
				(start 126.948692 -119.216932)
				(mid 126.912217 -119.622148)
				(end 126.567438 -119.838216)
			)
			(arc
				(start 126.567438 -119.838216)
				(mid 126.485711 -119.879346)
				(end 126.452884 -119.964708)
			)
			(xy 126.452884 -123.491498) (xy 126.626366 -123.66498) (xy 130.22199 -123.66498)
		)
		(stroke
			(width 0)
			(type solid)
		)
		(fill yes)
		(layer "B.Cu")
		(net "P1V05_CLK_NODE1")
	)
	(gr_poly
		(pts
			(arc
				(start 66.112644 -139.230862)
				(mid 66.161328 -139.22116)
				(end 66.20256 -139.193524)
			)
			(xy 66.267076 -139.128754) (xy 66.272918 -139.128754) (xy 66.347086 -139.054586)
			(arc
				(start 66.347086 -138.576558)
				(mid 66.337433 -138.527737)
				(end 66.309748 -138.486388)
			)
			(xy 66.295778 -138.472672) (xy 66.295778 -137.703052) (xy 66.571876 -137.426954) (xy 67.189096 -137.426954)
			(xy 67.465194 -137.703052) (xy 67.465194 -137.73277) (xy 67.591686 -137.859262) (xy 67.591686 -138.164062)
			(xy 67.681602 -138.253978) (xy 67.992752 -138.253978) (xy 68.004182 -138.265154) (xy 68.103496 -138.265154)
			(xy 68.531994 -138.693652) (xy 68.531994 -139.082018)
			(arc
				(start 68.574158 -139.124436)
				(mid 68.615515 -139.152103)
				(end 68.664328 -139.161774)
			)
			(xy 69.323966 -139.161774) (xy 69.333364 -139.152122) (xy 69.333364 -138.228832) (xy 69.194426 -138.089894)
			(xy 69.194426 -138.000232) (xy 69.127624 -137.93343) (xy 69.115178 -137.921238) (xy 69.115178 -134.205218)
			(xy 69.115432 -134.205218) (xy 69.115432 -133.83514) (xy 69.115432 -133.5659) (xy 69.099176 -133.536944)
			(xy 69.139816 -133.496304) (xy 69.139816 -132.407152) (xy 69.57187 -131.975098)
			(arc
				(start 70.247002 -131.975098)
				(mid 70.295549 -131.965348)
				(end 70.336664 -131.93776)
			)
			(xy 70.395084 -131.87934) (xy 71.017384 -131.87934) (xy 71.106284 -131.79044) (xy 71.106284 -131.2926)
			(xy 71.04761 -131.233926) (xy 70.71741 -131.233926)
			(arc
				(start 70.711822 -131.234434)
				(mid 70.688605 -131.236004)
				(end 70.66534 -131.236466)
			)
			(xy 70.329298 -131.236466) (xy 70.131178 -131.434586) (xy 68.27901 -131.434586) (xy 68.258182 -131.45516)
			(xy 67.982084 -131.45516) (xy 67.935348 -131.474718) (xy 67.925696 -131.48437) (xy 67.181476 -131.48437)
			(xy 67.171824 -131.474718) (xy 67.125088 -131.45516) (xy 66.956686 -131.45516) (xy 66.851784 -131.560062)
			(xy 66.83375 -131.560062) (xy 66.80454 -131.589526) (xy 66.343022 -131.589526) (xy 66.261742 -131.670806)
			(arc
				(start 66.042794 -131.670806)
				(mid 65.992292 -131.681279)
				(end 65.950084 -131.710938)
			)
			(xy 65.942464 -131.718304) (xy 65.922652 -131.73837) (xy 64.22898 -131.73837) (xy 64.187324 -131.779772)
			(xy 63.071756 -131.779772) (xy 63.045086 -131.806442)
			(arc
				(start 62.516258 -131.806442)
				(mid 62.426455 -131.843639)
				(end 62.389258 -131.933442)
			)
			(xy 62.389258 -137.54989) (xy 62.085982 -137.853166) (xy 62.085982 -138.38809) (xy 62.135766 -138.437874)
			(xy 62.805818 -138.437874) (xy 62.867286 -138.376406) (xy 63.74003 -138.376406) (xy 64.035686 -138.672062)
			(arc
				(start 64.035686 -138.976608)
				(mid 64.072883 -139.066411)
				(end 64.162686 -139.103608)
			)
			(arc
				(start 64.340232 -139.103608)
				(mid 64.430035 -139.066411)
				(end 64.467232 -138.976608)
			)
			(xy 64.467232 -138.56462) (xy 64.466978 -138.564366) (xy 64.466978 -137.677652) (xy 64.692276 -137.452354)
			(xy 65.411096 -137.452354) (xy 65.41135 -137.452862) (xy 65.483486 -137.452862) (xy 65.686686 -137.656062)
			(xy 65.686686 -139.154662) (xy 65.762886 -139.230862)
		)
		(stroke
			(width 0)
			(type solid)
		)
		(fill yes)
		(layer "B.Cu")
		(net "GND")
	)
	(gr_poly
		(pts
			(xy 56.81091 -81.518252)
			(arc
				(start 57.37225 -81.518252)
				(mid 57.405415 -81.474822)
				(end 57.417208 -81.421478)
			)
			(xy 57.417208 -81.060544) (xy 57.6707 -80.806798) (xy 58.068972 -80.806798) (xy 58.195972 -80.679798)
			(xy 58.195972 -79.879698) (xy 58.321702 -79.753968) (xy 61.431424 -79.753968) (xy 61.496194 -79.689198)
			(xy 61.496194 -78.918308) (xy 61.484764 -78.906878)
			(arc
				(start 61.484764 -78.357476)
				(mid 61.475062 -78.308792)
				(end 61.447426 -78.26756)
			)
			(arc
				(start 61.442346 -78.26248)
				(mid 61.384766 -78.229416)
				(end 61.318394 -78.229968)
			)
			(arc
				(start 61.318394 -78.229968)
				(mid 61.151674 -78.244973)
				(end 60.990734 -78.19898)
			)
			(xy 60.96381 -78.185518) (xy 60.12434 -78.185518) (xy 59.397138 -77.458316) (xy 59.255152 -77.458316)
			(xy 59.209686 -77.504036) (xy 59.119008 -77.594714) (xy 58.548016 -77.594714)
			(arc
				(start 58.525664 -77.572362)
				(mid 58.484424 -77.544743)
				(end 58.435748 -77.535024)
			)
			(xy 56.1594 -77.535024) (xy 56.082946 -77.458316) (xy 55.48503 -77.458316) (xy 55.354728 -77.588618)
			(xy 55.354728 -77.998066) (xy 55.404004 -78.047342) (xy 58.703972 -78.047342) (xy 58.703972 -78.051914)
			(xy 59.037982 -78.051914) (xy 59.227466 -78.241398) (xy 59.322716 -78.336902) (xy 59.322716 -78.808834)
			(xy 59.025028 -79.106776) (xy 57.092088 -79.106776) (xy 56.962548 -79.236062) (xy 56.962548 -79.567278)
			(arc
				(start 56.86425 -79.665322)
				(mid 56.826931 -79.755238)
				(end 56.86425 -79.845154)
			)
			(arc
				(start 56.86425 -79.845154)
				(mid 56.936413 -79.881007)
				(end 57.015634 -79.866236)
			)
			(arc
				(start 57.015634 -79.866236)
				(mid 57.470347 -80.469793)
				(end 56.86679 -80.01508)
			)
			(xy 56.887618 -79.977742) (xy 56.87568 -79.893922)
			(arc
				(start 56.845708 -79.863696)
				(mid 56.755792 -79.826377)
				(end 56.665876 -79.863696)
			)
			(xy 56.54802 -79.981552) (xy 56.396382 -79.981552) (xy 56.269636 -80.108298) (xy 56.269636 -81.430114)
			(xy 56.26989 -81.430368) (xy 56.26989 -81.57083) (xy 56.347614 -81.648554) (xy 56.680862 -81.648554)
		)
		(stroke
			(width 0)
			(type solid)
		)
		(fill yes)
		(layer "B.Cu")
		(net "P1V05_NODE1")
	)
	(gr_poly
		(pts
			(xy 172.120052 -94.043246) (xy 172.120052 -89.70899) (xy 172.119556 -89.692338) (xy 172.110932 -89.660171)
			(xy 172.094276 -89.631333) (xy 172.070721 -89.607789) (xy 172.041875 -89.591145) (xy 172.009704 -89.582536)
			(xy 171.993052 -89.58199) (xy 166.506652 -89.58199) (xy 166.490007 -89.582539) (xy 166.457855 -89.591165)
			(xy 166.429029 -89.607816) (xy 166.405493 -89.631359) (xy 166.38885 -89.66019) (xy 166.380234 -89.692345)
			(xy 166.379652 -89.70899) (xy 166.379652 -92.417646) (xy 166.405052 -92.451428) (xy 166.421126 -92.473568)
			(xy 166.447444 -92.521535) (xy 166.466639 -92.572769) (xy 166.478315 -92.626221) (xy 166.482235 -92.680792)
			(xy 166.478318 -92.735364) (xy 166.466643 -92.788815) (xy 166.447451 -92.840051) (xy 166.421135 -92.888018)
			(xy 166.405052 -92.910152) (xy 166.379652 -92.943934) (xy 166.379652 -93.21419) (xy 166.760652 -93.59519)
			(xy 167.879522 -93.59519) (xy 167.90311 -93.594671) (xy 167.949475 -93.585966) (xy 167.99344 -93.568858)
			(xy 168.033494 -93.543934) (xy 168.068264 -93.51205) (xy 168.096557 -93.4743) (xy 168.117401 -93.431979)
			(xy 168.130081 -93.386539) (xy 168.134163 -93.33954) (xy 168.129506 -93.292595) (xy 168.123362 -93.269816)
			(xy 168.115267 -93.240346) (xy 168.106063 -93.17993) (xy 168.104983 -93.118826) (xy 168.112046 -93.058122)
			(xy 168.127128 -92.998898) (xy 168.149959 -92.942209) (xy 168.180133 -92.889064) (xy 168.217113 -92.840409)
			(xy 168.260241 -92.797109) (xy 168.30875 -92.759936) (xy 168.361775 -92.729552) (xy 168.418372 -92.706496)
			(xy 168.477536 -92.69118) (xy 168.538211 -92.683875) (xy 168.599319 -92.684713) (xy 168.659772 -92.693678)
			(xy 168.718493 -92.71061) (xy 168.719985 -92.711266) (xy 169.449732 -92.711266) (xy 169.449732 -92.65133)
			(xy 169.457555 -92.591908) (xy 169.473068 -92.534015) (xy 169.496004 -92.478642) (xy 169.525971 -92.426736)
			(xy 169.562458 -92.379186) (xy 169.604838 -92.336806) (xy 169.652388 -92.300319) (xy 169.704294 -92.270352)
			(xy 169.759667 -92.247416) (xy 169.81756 -92.231903) (xy 169.876982 -92.22408) (xy 169.936918 -92.22408)
			(xy 169.99634 -92.231903) (xy 170.054233 -92.247416) (xy 170.109606 -92.270352) (xy 170.161512 -92.300319)
			(xy 170.209062 -92.336806) (xy 170.251442 -92.379186) (xy 170.287929 -92.426736) (xy 170.317896 -92.478642)
			(xy 170.340832 -92.534015) (xy 170.356345 -92.591908) (xy 170.364168 -92.65133) (xy 170.364658 -92.681298)
			(xy 170.364168 -92.711266) (xy 170.356345 -92.770688) (xy 170.340832 -92.828581) (xy 170.317896 -92.883954)
			(xy 170.287929 -92.93586) (xy 170.251442 -92.98341) (xy 170.209062 -93.02579) (xy 170.161512 -93.062277)
			(xy 170.109606 -93.092244) (xy 170.054233 -93.11518) (xy 169.99634 -93.130693) (xy 169.936918 -93.138516)
			(xy 169.876982 -93.138516) (xy 169.81756 -93.130693) (xy 169.759667 -93.11518) (xy 169.704294 -93.092244)
			(xy 169.652388 -93.062277) (xy 169.604838 -93.02579) (xy 169.562458 -92.98341) (xy 169.525971 -92.93586)
			(xy 169.496004 -92.883954) (xy 169.473068 -92.828581) (xy 169.457555 -92.770688) (xy 169.449732 -92.711266)
			(xy 168.719985 -92.711266) (xy 168.774438 -92.735209) (xy 168.82661 -92.767036) (xy 168.874081 -92.805525)
			(xy 168.916005 -92.84999) (xy 168.951638 -92.899641) (xy 168.980344 -92.953594) (xy 169.001612 -93.010887)
			(xy 169.015065 -93.070502) (xy 169.020462 -93.131377) (xy 169.017707 -93.192428) (xy 169.006849 -93.25257)
			(xy 168.988083 -93.310731) (xy 168.961741 -93.365876) (xy 168.928292 -93.417023) (xy 168.90873 -93.440504)
			(xy 168.893572 -93.458882) (xy 168.869699 -93.500101) (xy 168.853918 -93.545044) (xy 168.846779 -93.59214)
			(xy 168.848533 -93.63974) (xy 168.859119 -93.686183) (xy 168.878166 -93.729842) (xy 168.905008 -93.769192)
			(xy 168.92143 -93.786452) (xy 169.360342 -94.225364) (xy 171.937934 -94.225364)
		)
		(stroke
			(width 0)
			(type solid)
		)
		(fill yes)
		(layer "B.Cu")
		(net "GND")
	)
	(gr_poly
		(pts
			(xy 42.83456 -175.707802) (xy 43.385994 -175.707802) (xy 43.45686 -175.636936) (xy 43.45686 -174.427642)
			(xy 42.434002 -173.404784) (xy 42.434002 -170.164252) (xy 42.403014 -170.10761) (xy 42.375836 -170.090084)
			(xy 42.350483 -170.073154) (xy 42.304069 -170.033629) (xy 42.263312 -169.988293) (xy 42.228935 -169.937947)
			(xy 42.201545 -169.883484) (xy 42.181627 -169.825866) (xy 42.169535 -169.766114) (xy 42.165481 -169.705286)
			(xy 42.169539 -169.644458) (xy 42.181635 -169.584707) (xy 42.201556 -169.527091) (xy 42.228949 -169.472629)
			(xy 42.26333 -169.422285) (xy 42.304089 -169.376951) (xy 42.350506 -169.337429) (xy 42.375836 -169.320464)
			(xy 42.403014 -169.302938) (xy 42.434002 -169.246296) (xy 42.434002 -168.845484) (xy 42.433517 -168.823305)
			(xy 42.425812 -168.779621) (xy 42.410639 -168.737939) (xy 42.388458 -168.699525) (xy 42.359944 -168.665545)
			(xy 42.325963 -168.637033) (xy 42.287547 -168.614855) (xy 42.245864 -168.599684) (xy 42.20218 -168.591981)
			(xy 42.157822 -168.591981) (xy 42.114137 -168.599683) (xy 42.072454 -168.614854) (xy 42.053002 -168.62552)
			(xy 42.028456 -168.639121) (xy 41.976276 -168.659761) (xy 41.921635 -168.672537) (xy 41.865713 -168.677172)
			(xy 41.809714 -168.673566) (xy 41.754848 -168.661797) (xy 41.702296 -168.642119) (xy 41.653194 -168.614956)
			(xy 41.6086 -168.580894) (xy 41.569476 -168.540669) (xy 41.536665 -168.495146) (xy 41.510876 -168.445309)
			(xy 41.492664 -168.392232) (xy 41.482423 -168.33706) (xy 41.480994 -168.309036) (xy 41.479766 -168.287403)
			(xy 41.470866 -168.245001) (xy 41.454904 -168.204722) (xy 41.432342 -168.167733) (xy 41.403834 -168.135107)
			(xy 41.370206 -168.107788) (xy 41.332431 -168.086567) (xy 41.291606 -168.072061) (xy 41.248911 -168.064688)
			(xy 41.227248 -168.06418) (xy 39.195248 -168.06418) (xy 38.364414 -167.233346) (xy 36.83 -167.233346)
			(xy 36.813347 -167.233841) (xy 36.781178 -167.242463) (xy 36.752337 -167.259119) (xy 36.728791 -167.282673)
			(xy 36.712145 -167.31152) (xy 36.703535 -167.343693) (xy 36.703 -167.360346) (xy 36.703 -170.008038)
			(xy 37.185582 -170.008038) (xy 37.185582 -169.948102) (xy 37.193405 -169.88868) (xy 37.208918 -169.830787)
			(xy 37.231854 -169.775414) (xy 37.261821 -169.723508) (xy 37.298308 -169.675958) (xy 37.340688 -169.633578)
			(xy 37.388238 -169.597091) (xy 37.440144 -169.567124) (xy 37.495517 -169.544188) (xy 37.55341 -169.528675)
			(xy 37.612832 -169.520852) (xy 37.672768 -169.520852) (xy 37.73219 -169.528675) (xy 37.790083 -169.544188)
			(xy 37.845456 -169.567124) (xy 37.897362 -169.597091) (xy 37.944912 -169.633578) (xy 37.987292 -169.675958)
			(xy 38.023779 -169.723508) (xy 38.053746 -169.775414) (xy 38.076682 -169.830787) (xy 38.092195 -169.88868)
			(xy 38.100018 -169.948102) (xy 38.100508 -169.97807) (xy 38.100018 -170.008038) (xy 38.092195 -170.06746)
			(xy 38.076682 -170.125353) (xy 38.053746 -170.180726) (xy 38.023779 -170.232632) (xy 37.987292 -170.280182)
			(xy 37.944912 -170.322562) (xy 37.897362 -170.359049) (xy 37.845456 -170.389016) (xy 37.790083 -170.411952)
			(xy 37.73219 -170.427465) (xy 37.672768 -170.435288) (xy 37.612832 -170.435288) (xy 37.55341 -170.427465)
			(xy 37.495517 -170.411952) (xy 37.440144 -170.389016) (xy 37.388238 -170.359049) (xy 37.340688 -170.322562)
			(xy 37.298308 -170.280182) (xy 37.261821 -170.232632) (xy 37.231854 -170.180726) (xy 37.208918 -170.125353)
			(xy 37.193405 -170.06746) (xy 37.185582 -170.008038) (xy 36.703 -170.008038) (xy 36.703 -170.168824)
			(xy 37.221668 -170.687492) (xy 37.156644 -170.752516) (xy 37.156644 -173.156626) (xy 37.35197 -173.351952)
			(xy 37.858446 -173.351952) (xy 38.13429 -173.627796) (xy 38.13429 -175.479202) (xy 38.344094 -175.689006)
			(xy 38.903402 -175.689006) (xy 38.94455 -175.730154) (xy 41.050464 -175.730154) (xy 41.249092 -175.928528)
			(xy 42.61358 -175.928528)
		)
		(stroke
			(width 0)
			(type solid)
		)
		(fill yes)
		(layer "B.Cu")
		(net "P12V_AUX")
	)
	(gr_poly
		(pts
			(xy 63.100712 -76.248514) (xy 63.100712 -75.35545) (xy 63.096648 -75.351386) (xy 63.096648 -74.36993)
			(xy 63.199772 -74.266806) (xy 63.199772 -74.215498)
			(arc
				(start 63.2587 -74.15657)
				(mid 63.295161 -74.081393)
				(end 63.276988 -73.999852)
			)
			(arc
				(start 63.276988 -73.999852)
				(mid 63.527163 -73.425067)
				(end 63.977774 -73.860914)
			)
			(arc
				(start 63.977774 -73.860914)
				(mid 64.071486 -73.971153)
				(end 64.210184 -74.012298)
			)
			(xy 64.65443 -74.012298) (xy 64.667384 -73.999344) (xy 64.667384 -73.97242) (xy 64.694054 -73.97242)
			(xy 64.776096 -73.890378) (xy 64.794892 -73.890378) (xy 64.799972 -73.885298) (xy 65.536572 -73.885298)
			(xy 65.56756 -73.85431)
			(arc
				(start 65.56756 -72.818498)
				(mid 65.530363 -72.728695)
				(end 65.44056 -72.691498)
			)
			(xy 63.199772 -72.691498) (xy 63.123572 -72.767698) (xy 62.9666 -72.767698)
			(arc
				(start 62.940438 -72.780144)
				(mid 62.844043 -72.81386)
				(end 62.742572 -72.825356)
			)
			(xy 61.980318 -72.825356) (xy 61.92266 -72.767698) (xy 60.278772 -72.767698) (xy 60.23356 -72.81291)
			(xy 60.23356 -73.112884) (xy 60.320174 -73.199752) (xy 60.363862 -73.24344) (xy 60.421774 -73.245726)
			(xy 60.850272 -73.245726) (xy 61.020452 -73.41362) (xy 61.020452 -73.902824) (xy 61.01969 -73.924922)
			(xy 61.017658 -73.946766) (xy 61.016896 -73.954132)
			(arc
				(start 61.016896 -73.961498)
				(mid 61.054093 -74.051301)
				(end 61.143896 -74.088498)
			)
			(xy 61.447172 -74.088498) (xy 61.676788 -74.318114)
			(arc
				(start 61.683392 -74.318876)
				(mid 61.73017 -74.314762)
				(end 61.772292 -74.293984)
			)
			(arc
				(start 61.772292 -74.293984)
				(mid 62.379651 -74.551114)
				(end 61.856112 -74.952098)
			)
			(arc
				(start 61.856112 -74.952098)
				(mid 61.708327 -75.039941)
				(end 61.650372 -75.20178)
			)
			(xy 61.650372 -75.587098) (xy 61.777372 -75.714098) (xy 62.259972 -75.714098) (xy 62.437772 -75.891898)
			(xy 62.437772 -76.115418) (xy 62.610492 -76.287884) (xy 63.061088 -76.287884)
		)
		(stroke
			(width 0)
			(type solid)
		)
		(fill yes)
		(layer "B.Cu")
		(net "P1V05_NODE1")
	)
	(gr_poly
		(pts
			(xy 165.21938 -157.160722) (xy 165.21938 -154.631898)
			(arc
				(start 165.19779 -154.599894)
				(mid 165.111079 -154.315922)
				(end 165.19779 -154.03195)
			)
			(xy 165.21938 -153.999946) (xy 165.21938 -153.169874)
			(arc
				(start 165.196012 -153.136854)
				(mid 165.102649 -152.84323)
				(end 165.196012 -152.549606)
			)
			(xy 165.21938 -152.516586)
			(arc
				(start 165.21938 -151.713184)
				(mid 165.120375 -151.554012)
				(end 165.085776 -151.369776)
			)
			(xy 165.085776 -150.109682) (xy 165.21938 -149.975824) (xy 165.21938 -149.007322) (xy 165.154102 -148.942044)
			(xy 165.091618 -148.923756)
			(arc
				(start 165.059614 -148.930868)
				(mid 165.005082 -148.939957)
				(end 164.949886 -148.94306)
			)
			(xy 164.035232 -148.94306) (xy 164.01923 -148.947124)
			(arc
				(start 164.018722 -148.947124)
				(mid 163.823693 -148.959371)
				(end 163.638484 -148.897086)
			)
			(xy 163.60902 -148.880322) (xy 163.122356 -148.880322)
			(arc
				(start 163.090352 -148.901912)
				(mid 162.88502 -148.982503)
				(end 162.664902 -148.96846)
			)
			(xy 162.66414 -148.968206) (xy 162.646614 -148.96338)
			(arc
				(start 161.76498 -148.96338)
				(mid 161.635182 -148.946401)
				(end 161.514028 -148.896832)
			)
			(xy 161.484818 -148.880322) (xy 160.952942 -148.880322)
			(arc
				(start 160.923986 -148.896832)
				(mid 160.734311 -148.959498)
				(end 160.535112 -148.94433)
			)
			(xy 160.518094 -148.939504) (xy 158.795212 -148.939504) (xy 158.73603 -148.880322) (xy 158.56458 -148.880322)
			(arc
				(start 158.085028 -148.40077)
				(mid 158.043906 -148.3732)
				(end 157.995366 -148.363432)
			)
			(arc
				(start 157.203394 -148.363432)
				(mid 157.154847 -148.373182)
				(end 157.113732 -148.40077)
			)
			(arc
				(start 156.975302 -148.5392)
				(mid 156.944235 -148.589762)
				(end 156.939488 -148.648928)
			)
			(arc
				(start 156.939488 -148.648928)
				(mid 156.944419 -148.76428)
				(end 156.923232 -148.877782)
			)
			(xy 156.917644 -148.89607) (xy 156.917644 -149.628352)
			(arc
				(start 156.921454 -149.643846)
				(mid 156.937312 -149.76983)
				(end 156.921454 -149.895814)
			)
			(xy 156.917644 -149.911308) (xy 156.917644 -151.709628)
			(arc
				(start 156.923232 -151.727916)
				(mid 156.945742 -151.877522)
				(end 156.923232 -152.027128)
			)
			(xy 156.917644 -152.045416) (xy 156.917644 -153.462228)
			(arc
				(start 156.923232 -153.480516)
				(mid 156.945742 -153.630122)
				(end 156.923232 -153.779728)
			)
			(xy 156.917644 -153.798016) (xy 156.917644 -154.505152)
			(arc
				(start 156.921454 -154.520646)
				(mid 156.937312 -154.64663)
				(end 156.921454 -154.772614)
			)
			(xy 156.917644 -154.788108) (xy 156.917644 -155.749752)
			(arc
				(start 156.921454 -155.765246)
				(mid 156.937312 -155.89123)
				(end 156.921454 -156.017214)
			)
			(xy 156.917644 -156.032708) (xy 156.917644 -156.789628)
			(arc
				(start 156.923232 -156.807916)
				(mid 156.945742 -156.957522)
				(end 156.923232 -157.107128)
			)
			(xy 156.917644 -157.125416) (xy 156.917644 -157.215332)
			(arc
				(start 157.282896 -157.580584)
				(mid 157.324018 -157.608154)
				(end 157.372558 -157.617922)
			)
			(xy 164.76218 -157.617922)
		)
		(stroke
			(width 0)
			(type solid)
		)
		(fill yes)
		(layer "B.Cu")
		(net "GND")
	)
	(gr_poly
		(pts
			(xy 31.190184 -118.303802) (xy 31.206928 -118.303296) (xy 31.239261 -118.294581) (xy 31.26821 -118.277748)
			(xy 31.280354 -118.26621) (xy 31.280608 -118.265956) (xy 31.843472 -118.265956) (xy 31.876746 -118.24208)
			(xy 31.898153 -118.22712) (xy 31.944251 -118.202572) (xy 31.99327 -118.184553) (xy 32.044292 -118.173402)
			(xy 32.070294 -118.17096) (xy 32.11703 -118.167404) (xy 33.200086 -117.084602) (xy 33.200086 -111.549942)
			(xy 37.592508 -107.15752) (xy 37.592508 -105.013252) (xy 37.487606 -104.90835) (xy 28.277312 -104.90835)
			(xy 27.366722 -103.99776) (xy 24.69388 -103.99776) (xy 24.17826 -104.51338) (xy 24.17826 -108.100622)
			(xy 32.391094 -108.100622) (xy 32.395165 -108.045) (xy 32.407291 -107.990563) (xy 32.427214 -107.938472)
			(xy 32.45451 -107.889837) (xy 32.488596 -107.845694) (xy 32.528745 -107.806985) (xy 32.574103 -107.774534)
			(xy 32.623703 -107.749033) (xy 32.676487 -107.731026) (xy 32.73133 -107.720896) (xy 32.787064 -107.718859)
			(xy 32.842501 -107.724959) (xy 32.896458 -107.739065) (xy 32.947787 -107.760877) (xy 32.995393 -107.789931)
			(xy 33.038261 -107.825606) (xy 33.075478 -107.867143) (xy 33.106251 -107.913656) (xy 33.129923 -107.964153)
			(xy 33.138534 -107.992776) (xy 35.024777 -107.992776) (xy 35.025824 -107.9382) (xy 35.034639 -107.884331)
			(xy 35.05104 -107.832267) (xy 35.074694 -107.783073) (xy 35.105117 -107.737752) (xy 35.141688 -107.697228)
			(xy 35.183662 -107.662331) (xy 35.23018 -107.633771) (xy 35.280293 -107.612132) (xy 35.332979 -107.597856)
			(xy 35.387161 -107.591234) (xy 35.414458 -107.591352) (xy 35.438156 -107.591313) (xy 35.48489 -107.583479)
			(xy 35.529364 -107.567124) (xy 35.570038 -107.542813) (xy 35.605504 -107.511388) (xy 35.634536 -107.473937)
			(xy 35.656127 -107.431756) (xy 35.669531 -107.386306) (xy 35.674283 -107.339159) (xy 35.672776 -107.315508)
			(xy 35.670654 -107.285125) (xy 35.67349 -107.224285) (xy 35.68437 -107.164359) (xy 35.703101 -107.106406)
			(xy 35.729353 -107.051448) (xy 35.762661 -107.000457) (xy 35.802437 -106.954334) (xy 35.847979 -106.913893)
			(xy 35.898482 -106.87985) (xy 35.953053 -106.852804) (xy 36.01073 -106.833235) (xy 36.070492 -106.821488)
			(xy 36.131284 -106.817769) (xy 36.192032 -106.822146) (xy 36.251663 -106.834541) (xy 36.309124 -106.854734)
			(xy 36.363399 -106.88237) (xy 36.413529 -106.916959) (xy 36.45863 -106.957891) (xy 36.497904 -107.004442)
			(xy 36.530658 -107.055791) (xy 36.556312 -107.11103) (xy 36.574414 -107.169183) (xy 36.584644 -107.229224)
			(xy 36.586821 -107.290091) (xy 36.580906 -107.350708) (xy 36.567005 -107.410006) (xy 36.545363 -107.466937)
			(xy 36.516361 -107.520495) (xy 36.480513 -107.569733) (xy 36.438452 -107.613782) (xy 36.390921 -107.651865)
			(xy 36.338759 -107.683307) (xy 36.282887 -107.707554) (xy 36.224294 -107.724177) (xy 36.164014 -107.732882)
			(xy 36.103112 -107.733517) (xy 36.072826 -107.73029) (xy 36.049244 -107.72785) (xy 36.001932 -107.730847)
			(xy 35.955998 -107.742571) (xy 35.913038 -107.762615) (xy 35.874543 -107.790283) (xy 35.841851 -107.824614)
			(xy 35.816096 -107.864415) (xy 35.798175 -107.908303) (xy 35.788709 -107.954755) (xy 35.787838 -107.978448)
			(xy 35.786924 -108.00573) (xy 35.778346 -108.059638) (xy 35.762173 -108.111772) (xy 35.738735 -108.16107)
			(xy 35.708511 -108.206525) (xy 35.672118 -108.247208) (xy 35.630298 -108.282289) (xy 35.583906 -108.311053)
			(xy 35.533888 -108.332911) (xy 35.481265 -108.347419) (xy 35.427113 -108.354278) (xy 35.372535 -108.353351)
			(xy 35.318646 -108.344654) (xy 35.266547 -108.328367) (xy 35.217301 -108.304821) (xy 35.171913 -108.274498)
			(xy 35.13131 -108.238015) (xy 35.09632 -108.196119) (xy 35.067658 -108.149664) (xy 35.04591 -108.099598)
			(xy 35.031518 -108.046943) (xy 35.024777 -107.992776) (xy 33.138534 -107.992776) (xy 33.145991 -108.01756)
			(xy 33.154111 -108.072736) (xy 33.15462 -108.100622) (xy 33.154111 -108.128508) (xy 33.145991 -108.183684)
			(xy 33.129923 -108.237091) (xy 33.106251 -108.287588) (xy 33.075478 -108.334101) (xy 33.038261 -108.375638)
			(xy 32.995393 -108.411313) (xy 32.947787 -108.440367) (xy 32.896458 -108.462179) (xy 32.842501 -108.476285)
			(xy 32.787064 -108.482385) (xy 32.73133 -108.480348) (xy 32.676487 -108.470218) (xy 32.623703 -108.452211)
			(xy 32.574103 -108.42671) (xy 32.528745 -108.394259) (xy 32.488596 -108.35555) (xy 32.45451 -108.311407)
			(xy 32.427214 -108.262772) (xy 32.407291 -108.210681) (xy 32.395165 -108.156244) (xy 32.391094 -108.100622)
			(xy 24.17826 -108.100622) (xy 24.17826 -113.559844) (xy 24.33955 -113.721134) (xy 27.836368 -113.721134)
			(xy 28.321 -114.205766) (xy 28.321 -117.554502) (xy 29.0703 -118.303802)
		)
		(stroke
			(width 0)
			(type solid)
		)
		(fill yes)
		(layer "B.Cu")
		(net "GND")
	)
	(gr_poly
		(pts
			(xy 68.241418 -82.941668) (xy 68.241418 -82.362802) (xy 68.317618 -82.286602) (xy 71.0946 -82.286602)
			(xy 71.306944 -82.074258) (xy 71.308468 -82.072734) (xy 71.322692 -82.05851) (xy 71.324216 -82.056986)
			(xy 71.404734 -81.976468) (xy 71.518272 -81.976468) (xy 71.521574 -81.976214) (xy 71.531226 -81.97596)
			(xy 71.628 -81.97596) (xy 71.882254 -81.721706) (xy 71.882254 -81.533746) (xy 72.13473 -81.28127)
			(xy 72.466962 -81.28127) (xy 72.468232 -81.28) (xy 72.778874 -81.28) (xy 73.725278 -82.226404) (xy 76.526644 -82.226404)
			(xy 76.836778 -82.536284) (xy 78.738984 -82.536284) (xy 78.98257 -82.292698) (xy 78.986888 -82.292698)
			(xy 79.205074 -82.074512) (xy 81.33461 -82.074512) (xy 81.538318 -82.27822)
			(arc
				(start 81.795366 -82.27822)
				(mid 81.885169 -82.241023)
				(end 81.922366 -82.15122)
			)
			(xy 81.922366 -81.509108) (xy 81.556098 -81.14284) (xy 76.36891 -81.14284) (xy 75.901296 -80.675226)
			(xy 75.829922 -80.675226) (xy 75.814936 -80.66024) (xy 72.420226 -80.66024) (xy 72.419718 -80.659732)
			(xy 71.691754 -80.659732) (xy 71.691246 -80.66024) (xy 64.99479 -80.66024) (xy 64.9859 -80.65135)
			(xy 64.755268 -80.65135) (xy 64.68999 -80.716628) (xy 64.125602 -80.716628) (xy 64.060324 -80.65135)
			(xy 63.316104 -80.65135) (xy 63.1063 -80.441546)
			(arc
				(start 63.1063 -80.151478)
				(mid 63.069103 -80.061675)
				(end 62.9793 -80.024478)
			)
			(xy 61.375544 -80.024478) (xy 61.359288 -80.008476) (xy 58.491628 -80.008476) (xy 58.45048 -80.049624)
			(xy 58.45048 -80.648556)
			(arc
				(start 58.499248 -80.697578)
				(mid 58.540605 -80.725245)
				(end 58.589418 -80.734916)
			)
			(xy 60.164472 -80.734916) (xy 60.278772 -80.849216) (xy 60.278772 -80.855312) (xy 60.291472 -80.867758)
			(xy 60.291472 -82.457544) (xy 60.360814 -82.527394) (xy 60.407804 -82.546698) (xy 60.635388 -82.546698)
			(xy 60.844176 -82.337656) (xy 60.844176 -82.33537) (xy 61.129926 -82.04962) (xy 61.13018 -82.04962)
			(xy 61.189362 -81.990438) (xy 62.495684 -81.990438) (xy 62.562486 -81.941924)
			(arc
				(start 62.575186 -81.9023)
				(mid 62.921892 -81.637948)
				(end 63.290196 -81.871312)
			)
			(xy 63.303912 -81.903824) (xy 63.42253 -81.990438) (xy 64.639952 -81.990438) (xy 64.710564 -81.93151)
			(arc
				(start 64.718692 -81.886044)
				(mid 65.121565 -81.573363)
				(end 65.475358 -81.940654)
			)
			(arc
				(start 65.475358 -81.940654)
				(mid 65.555322 -82.109205)
				(end 65.72885 -82.177636)
			)
			(arc
				(start 66.31686 -82.177636)
				(mid 66.372417 -82.197921)
				(end 66.43116 -82.204814)
			)
			(xy 66.768472 -82.204814) (xy 66.771774 -82.201512) (xy 67.399662 -82.201512) (xy 67.581018 -82.382868)
			(xy 67.581018 -82.420206) (xy 67.607434 -82.473546)
			(arc
				(start 67.63131 -82.49158)
				(mid 67.733581 -82.613954)
				(end 67.77228 -82.768694)
			)
			(arc
				(start 67.77228 -82.768694)
				(mid 67.848357 -82.945204)
				(end 68.02628 -83.017868)
			)
			(xy 68.165218 -83.017868)
		)
		(stroke
			(width 0)
			(type solid)
		)
		(fill yes)
		(layer "B.Cu")
		(net "GND")
	)
	(gr_poly
		(pts
			(xy 55.4482 -102.320852) (xy 55.4482 -99.86645) (xy 55.339234 -99.742752) (xy 55.29834 -99.733862)
			(xy 55.268794 -99.726954) (xy 55.21171 -99.706385) (xy 55.157841 -99.678461) (xy 55.108128 -99.64367)
			(xy 55.063443 -99.602622) (xy 55.024568 -99.556035) (xy 54.992182 -99.504724) (xy 54.966852 -99.449587)
			(xy 54.949022 -99.391589) (xy 54.943502 -99.361752) (xy 54.939322 -99.339527) (xy 54.924154 -99.296928)
			(xy 54.901682 -99.257689) (xy 54.872615 -99.22305) (xy 54.837874 -99.194106) (xy 54.798556 -99.171772)
			(xy 54.755904 -99.156754) (xy 54.711267 -99.149528) (xy 54.666055 -99.15032) (xy 54.643782 -99.154234)
			(xy 54.614809 -99.159459) (xy 54.556062 -99.163302) (xy 54.497307 -99.159578) (xy 54.439515 -99.148349)
			(xy 54.38364 -99.129802) (xy 54.330605 -99.104242) (xy 54.281286 -99.072091) (xy 54.236498 -99.03388)
			(xy 54.19698 -98.990241) (xy 54.163385 -98.941895) (xy 54.136268 -98.889639) (xy 54.116076 -98.834336)
			(xy 54.103144 -98.776901) (xy 54.097685 -98.718282) (xy 54.099789 -98.659447) (xy 54.109421 -98.601367)
			(xy 54.126422 -98.545002) (xy 54.138068 -98.517964) (xy 54.146344 -98.498477) (xy 54.15702 -98.45751)
			(xy 54.16075 -98.415339) (xy 54.157431 -98.373134) (xy 54.147155 -98.332065) (xy 54.130207 -98.29327)
			(xy 54.107056 -98.257825) (xy 54.078345 -98.226713) (xy 54.061868 -98.213418) (xy 54.049964 -98.204078)
			(xy 54.027214 -98.184124) (xy 54.016402 -98.17354) (xy 53.539644 -97.696528) (xy 53.539644 -97.096834)
			(xy 53.53983 -97.081101) (xy 53.541991 -97.049707) (xy 53.543962 -97.034096) (xy 53.544978 -97.025714)
			(xy 53.544978 -97.014792) (xy 53.544482 -96.998139) (xy 53.53586 -96.965968) (xy 53.519204 -96.937126)
			(xy 53.49565 -96.913578) (xy 53.466804 -96.896929) (xy 53.434631 -96.888314) (xy 53.417978 -96.887792)
			(xy 52.81422 -96.887792) (xy 52.64658 -97.055432) (xy 52.64658 -97.493328) (xy 52.473352 -97.666556)
			(xy 52.473352 -97.85604) (xy 52.128928 -98.200718) (xy 52.106035 -98.222899) (xy 52.055429 -98.261657)
			(xy 52.000158 -98.293411) (xy 51.941185 -98.317607) (xy 51.910488 -98.326194) (xy 51.897534 -98.329496)
			(xy 51.870864 -98.342704) (xy 51.855359 -98.351111) (xy 51.82936 -98.374925) (xy 51.810863 -98.404939)
			(xy 51.801276 -98.438867) (xy 51.80076 -98.456496) (xy 51.80076 -100.470576) (xy 54.0009 -100.470576)
			(xy 54.004516 -100.409329) (xy 54.016283 -100.349113) (xy 54.035988 -100.29101) (xy 54.06328 -100.23606)
			(xy 54.097668 -100.185248) (xy 54.138536 -100.139486) (xy 54.185151 -100.099595) (xy 54.236678 -100.066289)
			(xy 54.292193 -100.040165) (xy 54.3507 -100.021692) (xy 54.411151 -100.011201) (xy 54.472461 -100.00888)
			(xy 54.533532 -100.014771) (xy 54.593268 -100.028768) (xy 54.650599 -100.05062) (xy 54.704497 -100.079936)
			(xy 54.753995 -100.116189) (xy 54.798205 -100.15873) (xy 54.836336 -100.206797) (xy 54.867704 -100.259526)
			(xy 54.891746 -100.315974) (xy 54.908031 -100.375128) (xy 54.916267 -100.435926) (xy 54.916307 -100.497281)
			(xy 54.908149 -100.55809) (xy 54.891941 -100.617265) (xy 54.867972 -100.673744) (xy 54.836673 -100.726514)
			(xy 54.818026 -100.750878) (xy 54.803749 -100.769849) (xy 54.781767 -100.811927) (xy 54.767976 -100.857354)
			(xy 54.762855 -100.904551) (xy 54.766584 -100.951879) (xy 54.779032 -100.997692) (xy 54.799766 -101.040398)
			(xy 54.828067 -101.078515) (xy 54.86295 -101.110716) (xy 54.882796 -101.12375) (xy 54.908599 -101.140355)
			(xy 54.955861 -101.179491) (xy 54.99747 -101.224591) (xy 55.032682 -101.274845) (xy 55.060864 -101.329353)
			(xy 55.081511 -101.387138) (xy 55.094253 -101.447163) (xy 55.098862 -101.508352) (xy 55.095254 -101.569608)
			(xy 55.083496 -101.629833) (xy 55.063797 -101.687948) (xy 55.03651 -101.742909) (xy 55.002126 -101.793733)
			(xy 54.961259 -101.839507) (xy 54.914644 -101.879412) (xy 54.863115 -101.91273) (xy 54.807598 -101.938867)
			(xy 54.749086 -101.957351) (xy 54.688629 -101.967853) (xy 54.62731 -101.970184) (xy 54.566231 -101.964302)
			(xy 54.506484 -101.950313) (xy 54.449142 -101.928467) (xy 54.395233 -101.899157) (xy 54.345723 -101.862906)
			(xy 54.301499 -101.820367) (xy 54.263355 -101.7723) (xy 54.231975 -101.719569) (xy 54.207921 -101.663118)
			(xy 54.191624 -101.603959) (xy 54.183376 -101.543153) (xy 54.183326 -101.481791) (xy 54.191475 -101.420972)
			(xy 54.207675 -101.361787) (xy 54.231638 -101.305297) (xy 54.262932 -101.252514) (xy 54.281578 -101.228144)
			(xy 54.295829 -101.209154) (xy 54.317813 -101.16708) (xy 54.331605 -101.121657) (xy 54.336728 -101.074463)
			(xy 54.333002 -101.027139) (xy 54.320558 -100.981328) (xy 54.299827 -100.938623) (xy 54.271531 -100.900507)
			(xy 54.236652 -100.868306) (xy 54.216808 -100.855272) (xy 54.19108 -100.838554) (xy 54.143831 -100.799415)
			(xy 54.102234 -100.754315) (xy 54.067035 -100.704062) (xy 54.038865 -100.649557) (xy 54.01823 -100.591777)
			(xy 54.005498 -100.531758) (xy 54.0009 -100.470576) (xy 51.80076 -100.470576) (xy 51.80076 -102.096316)
			(xy 52.23764 -102.533196) (xy 55.235856 -102.533196)
		)
		(stroke
			(width 0)
			(type solid)
		)
		(fill yes)
		(layer "B.Cu")
		(net "P1V8_NODE1")
	)
	(gr_poly
		(pts
			(xy 64.30518 -83.88731) (xy 64.389762 -83.802728) (xy 64.387337 -83.773729) (xy 64.390262 -83.715612)
			(xy 64.401987 -83.658615) (xy 64.42224 -83.604063) (xy 64.45055 -83.553224) (xy 64.467994 -83.529932)
			(xy 64.476719 -83.518021) (xy 64.488992 -83.491175) (xy 64.494755 -83.462225) (xy 64.493699 -83.432726)
			(xy 64.485881 -83.404262) (xy 64.471721 -83.378362) (xy 64.462152 -83.367118) (xy 64.444071 -83.346277)
			(xy 64.413483 -83.300359) (xy 64.389832 -83.250511) (xy 64.373613 -83.197776) (xy 64.365164 -83.143253)
			(xy 64.364662 -83.088082) (xy 64.372117 -83.033414) (xy 64.387373 -82.980392) (xy 64.410112 -82.930122)
			(xy 64.42456 -82.906616) (xy 64.433349 -82.891751) (xy 64.443422 -82.858734) (xy 64.444289 -82.824226)
			(xy 64.435887 -82.790746) (xy 64.418829 -82.760736) (xy 64.407034 -82.74812) (xy 64.387719 -82.728205)
			(xy 64.354471 -82.683796) (xy 64.32801 -82.635037) (xy 64.308895 -82.582958) (xy 64.297529 -82.528658)
			(xy 64.294153 -82.473284) (xy 64.296036 -82.445606) (xy 64.29696 -82.427213) (xy 64.289455 -82.391175)
			(xy 64.271996 -82.358768) (xy 64.25946 -82.345276) (xy 64.218312 -82.304128) (xy 63.195454 -82.304128)
			(xy 63.161926 -82.328258) (xy 63.140146 -82.343442) (xy 63.093224 -82.368285) (xy 63.043311 -82.386381)
			(xy 62.99137 -82.39738) (xy 62.938406 -82.40107) (xy 62.885442 -82.39738) (xy 62.833501 -82.386381)
			(xy 62.783588 -82.368285) (xy 62.736666 -82.343442) (xy 62.714886 -82.328258) (xy 62.681358 -82.304128)
			(xy 61.235336 -82.304128) (xy 61.098684 -82.44078) (xy 61.098684 -82.443066) (xy 60.862972 -82.678778)
			(xy 60.862972 -82.686652) (xy 60.863497 -82.703577) (xy 60.87239 -82.736237) (xy 60.889562 -82.765406)
			(xy 60.901326 -82.777584) (xy 60.921972 -82.798433) (xy 60.958165 -82.844617) (xy 60.987973 -82.895158)
			(xy 61.01088 -82.949178) (xy 61.026489 -83.005741) (xy 61.034528 -83.063864) (xy 61.034857 -83.122539)
			(xy 61.027473 -83.180749) (xy 61.012501 -83.237483) (xy 60.990203 -83.291758) (xy 60.960964 -83.34263)
			(xy 60.925293 -83.389219) (xy 60.904882 -83.410298) (xy 60.862972 -83.452462) (xy 60.862972 -83.928195)
			(xy 62.362879 -83.928195) (xy 62.370391 -83.871642) (xy 62.386239 -83.816837) (xy 62.410069 -83.765002)
			(xy 62.441351 -83.717293) (xy 62.479386 -83.674772) (xy 62.501018 -83.65617) (xy 62.513474 -83.64516)
			(xy 62.532661 -83.618024) (xy 62.544196 -83.586856) (xy 62.547297 -83.553766) (xy 62.541753 -83.520998)
			(xy 62.52794 -83.49077) (xy 62.517782 -83.477608) (xy 62.500826 -83.456269) (xy 62.472401 -83.409768)
			(xy 62.450883 -83.359696) (xy 62.43671 -83.307071) (xy 62.430171 -83.252964) (xy 62.431398 -83.198478)
			(xy 62.440367 -83.144721) (xy 62.456894 -83.092787) (xy 62.480645 -83.043734) (xy 62.511134 -82.99856)
			(xy 62.547742 -82.958186) (xy 62.589723 -82.923431) (xy 62.636223 -82.895005) (xy 62.686295 -82.873486)
			(xy 62.73892 -82.859312) (xy 62.793026 -82.852771) (xy 62.847513 -82.853997) (xy 62.90127 -82.862964)
			(xy 62.953204 -82.879491) (xy 63.002258 -82.90324) (xy 63.047432 -82.933728) (xy 63.087808 -82.970335)
			(xy 63.122563 -83.012316) (xy 63.15099 -83.058815) (xy 63.172511 -83.108886) (xy 63.186686 -83.161511)
			(xy 63.193228 -83.215617) (xy 63.192004 -83.270103) (xy 63.183038 -83.323861) (xy 63.166513 -83.375795)
			(xy 63.142765 -83.424849) (xy 63.112278 -83.470025) (xy 63.075672 -83.510401) (xy 63.054992 -83.528154)
			(xy 63.042606 -83.539237) (xy 63.023414 -83.566353) (xy 63.011871 -83.597503) (xy 63.008757 -83.630578)
			(xy 63.014285 -83.663335) (xy 63.028079 -83.693556) (xy 63.038228 -83.706716) (xy 63.055478 -83.728347)
			(xy 63.084252 -83.775601) (xy 63.105898 -83.826516) (xy 63.119961 -83.880023) (xy 63.126146 -83.935001)
			(xy 63.124323 -83.990296) (xy 63.114531 -84.044748) (xy 63.096976 -84.097213) (xy 63.072024 -84.146592)
			(xy 63.056516 -84.169504) (xy 63.046897 -84.184145) (xy 63.035292 -84.217183) (xy 63.033117 -84.252133)
			(xy 63.040535 -84.286355) (xy 63.056987 -84.317267) (xy 63.068708 -84.330286) (xy 63.087658 -84.350673)
			(xy 63.119957 -84.396005) (xy 63.145328 -84.445548) (xy 63.163232 -84.498252) (xy 63.173291 -84.552997)
			(xy 63.17529 -84.608623) (xy 63.169188 -84.663949) (xy 63.155113 -84.717801) (xy 63.133365 -84.769038)
			(xy 63.104404 -84.816572) (xy 63.068846 -84.859395) (xy 63.027444 -84.896598) (xy 62.981076 -84.927392)
			(xy 62.930727 -84.951124) (xy 62.877465 -84.96729) (xy 62.82242 -84.975548) (xy 62.766758 -84.975722)
			(xy 62.711662 -84.967808) (xy 62.6583 -84.951974) (xy 62.607804 -84.928557) (xy 62.561246 -84.898052)
			(xy 62.519612 -84.861108) (xy 62.483787 -84.818508) (xy 62.454531 -84.771156) (xy 62.432463 -84.720056)
			(xy 62.418053 -84.666292) (xy 62.411605 -84.611005) (xy 62.413257 -84.555368) (xy 62.422974 -84.500561)
			(xy 62.44055 -84.447747) (xy 62.465611 -84.398046) (xy 62.481206 -84.37499) (xy 62.490828 -84.360351)
			(xy 62.502429 -84.327312) (xy 62.504603 -84.292362) (xy 62.497184 -84.25814) (xy 62.480733 -84.227228)
			(xy 62.469014 -84.214208) (xy 62.449616 -84.193288) (xy 62.416697 -84.146694) (xy 62.391082 -84.095717)
			(xy 62.373341 -84.041496) (xy 62.363869 -83.985237) (xy 62.362879 -83.928195) (xy 60.862972 -83.928195)
			(xy 60.862972 -84.201508) (xy 61.674248 -85.012784) (xy 61.738256 -85.030564) (xy 61.770768 -85.02269)
			(xy 61.799952 -85.015984) (xy 61.859487 -85.009551) (xy 61.919347 -85.011155) (xy 61.978452 -85.02077)
			(xy 62.035734 -85.03822) (xy 62.090161 -85.063191) (xy 62.1157 -85.078824) (xy 62.146688 -85.098636)
			(xy 62.258956 -85.098636) (xy 62.258956 -85.22335) (xy 62.272926 -85.250782) (xy 62.278006 -85.260733)
			(xy 62.287283 -85.281062) (xy 62.291468 -85.291422) (xy 62.297546 -85.305683) (xy 62.315509 -85.330938)
			(xy 62.339037 -85.35111) (xy 62.366739 -85.365006) (xy 62.396976 -85.371803) (xy 62.427959 -85.371101)
			(xy 62.457857 -85.36294) (xy 62.471554 -85.355684) (xy 62.495717 -85.342693) (xy 62.546924 -85.323014)
			(xy 62.600422 -85.310872) (xy 62.655108 -85.306519) (xy 62.709854 -85.310044) (xy 62.76353 -85.321374)
			(xy 62.815029 -85.340276) (xy 62.86329 -85.36636) (xy 62.907317 -85.399088) (xy 62.946201 -85.437785)
			(xy 62.979142 -85.481653) (xy 63.00546 -85.529787) (xy 63.024611 -85.581194) (xy 63.030862 -85.607906)
			(xy 63.035078 -85.624671) (xy 63.051178 -85.655245) (xy 63.074897 -85.680374) (xy 63.104492 -85.69821)
			(xy 63.13779 -85.707445) (xy 63.155068 -85.707982) (xy 64.30518 -85.707982)
		)
		(stroke
			(width 0)
			(type solid)
		)
		(fill yes)
		(layer "B.Cu")
		(net "P1V8_SUS_NODE1")
	)
	(gr_poly
		(pts
			(xy 13.83792 -95.274892) (xy 13.83792 -79.836772) (xy 13.196824 -79.195676) (xy 13.184697 -79.184274)
			(xy 13.155916 -79.167578) (xy 13.123797 -79.158887) (xy 13.107162 -79.158338) (xy 2.878074 -79.158338)
			(xy 1.840484 -80.195928) (xy 1.840484 -81.774992) (xy 10.396718 -81.774992) (xy 10.396718 -81.68112)
			(xy 10.404679 -81.587586) (xy 10.420543 -81.495064) (xy 10.444197 -81.404221) (xy 10.475469 -81.315712)
			(xy 10.514135 -81.230173) (xy 10.559916 -81.148221) (xy 10.612482 -81.070447) (xy 10.671455 -80.997412)
			(xy 10.736408 -80.92964) (xy 10.806875 -80.867621) (xy 10.882348 -80.811802) (xy 10.962283 -80.762584)
			(xy 11.046104 -80.720322) (xy 11.133207 -80.685322) (xy 11.222964 -80.657834) (xy 11.314729 -80.638057)
			(xy 11.407841 -80.626134) (xy 11.501628 -80.62215) (xy 11.595415 -80.626134) (xy 11.688527 -80.638057)
			(xy 11.780292 -80.657834) (xy 11.870049 -80.685322) (xy 11.957152 -80.720322) (xy 12.040973 -80.762584)
			(xy 12.120908 -80.811802) (xy 12.196381 -80.867621) (xy 12.266848 -80.92964) (xy 12.331801 -80.997412)
			(xy 12.390774 -81.070447) (xy 12.44334 -81.148221) (xy 12.489121 -81.230173) (xy 12.527787 -81.315712)
			(xy 12.559059 -81.404221) (xy 12.582713 -81.495064) (xy 12.598577 -81.587586) (xy 12.606538 -81.68112)
			(xy 12.607036 -81.728056) (xy 12.606538 -81.774992) (xy 12.598577 -81.868526) (xy 12.582713 -81.961048)
			(xy 12.559059 -82.051891) (xy 12.527787 -82.1404) (xy 12.489121 -82.225939) (xy 12.44334 -82.307891)
			(xy 12.390774 -82.385665) (xy 12.331801 -82.4587) (xy 12.266848 -82.526472) (xy 12.196381 -82.588491)
			(xy 12.120908 -82.64431) (xy 12.040973 -82.693528) (xy 11.957152 -82.73579) (xy 11.870049 -82.77079)
			(xy 11.780292 -82.798278) (xy 11.688527 -82.818055) (xy 11.595415 -82.829978) (xy 11.501628 -82.833963)
			(xy 11.407841 -82.829978) (xy 11.314729 -82.818055) (xy 11.222964 -82.798278) (xy 11.133207 -82.77079)
			(xy 11.046104 -82.73579) (xy 10.962283 -82.693528) (xy 10.882348 -82.64431) (xy 10.806875 -82.588491)
			(xy 10.736408 -82.526472) (xy 10.671455 -82.4587) (xy 10.612482 -82.385665) (xy 10.559916 -82.307891)
			(xy 10.514135 -82.225939) (xy 10.475469 -82.1404) (xy 10.444197 -82.051891) (xy 10.420543 -81.961048)
			(xy 10.404679 -81.868526) (xy 10.396718 -81.774992) (xy 1.840484 -81.774992) (xy 1.840484 -84.822792)
			(xy 10.39622 -84.822792) (xy 12.607036 -84.822792) (xy 12.607036 -87.033608) (xy 10.39622 -87.033608)
			(xy 10.39622 -84.822792) (xy 1.840484 -84.822792) (xy 1.840484 -90.697241) (xy 4.534904 -90.697241)
			(xy 4.534904 -90.573415) (xy 4.542837 -90.449844) (xy 4.558672 -90.327036) (xy 4.582342 -90.205494)
			(xy 4.613751 -90.085718) (xy 4.652769 -89.968201) (xy 4.699237 -89.853425) (xy 4.752963 -89.741862)
			(xy 4.813726 -89.633971) (xy 4.881277 -89.530194) (xy 4.955339 -89.430959) (xy 5.035606 -89.336672)
			(xy 5.121749 -89.247722) (xy 5.213414 -89.164474) (xy 5.310225 -89.087271) (xy 5.411783 -89.016428)
			(xy 5.517671 -88.952238) (xy 5.627455 -88.894964) (xy 5.740682 -88.844841) (xy 5.856889 -88.802076)
			(xy 5.975596 -88.766845) (xy 6.096317 -88.739291) (xy 6.218555 -88.719528) (xy 6.341808 -88.707638)
			(xy 6.46557 -88.70367) (xy 6.589332 -88.707638) (xy 6.712585 -88.719528) (xy 6.834823 -88.739291)
			(xy 6.955544 -88.766845) (xy 7.074251 -88.802076) (xy 7.190458 -88.844841) (xy 7.303685 -88.894964)
			(xy 7.413469 -88.952238) (xy 7.519357 -89.016428) (xy 7.620915 -89.087271) (xy 7.717726 -89.164474)
			(xy 7.809391 -89.247722) (xy 7.895534 -89.336672) (xy 7.975801 -89.430959) (xy 8.049863 -89.530194)
			(xy 8.117414 -89.633971) (xy 8.178177 -89.741862) (xy 8.231903 -89.853425) (xy 8.278371 -89.968201)
			(xy 8.317389 -90.085718) (xy 8.348798 -90.205494) (xy 8.372468 -90.327036) (xy 8.388303 -90.449844)
			(xy 8.396236 -90.573415) (xy 8.396732 -90.635328) (xy 8.396236 -90.697241) (xy 8.388303 -90.820812)
			(xy 8.372468 -90.94362) (xy 8.348798 -91.065162) (xy 8.317389 -91.184938) (xy 8.278371 -91.302455)
			(xy 8.231903 -91.417231) (xy 8.178177 -91.528794) (xy 8.177831 -91.529408) (xy 12.125958 -91.529408)
			(xy 12.130029 -91.473786) (xy 12.142155 -91.419349) (xy 12.162078 -91.367258) (xy 12.189374 -91.318623)
			(xy 12.22346 -91.27448) (xy 12.263609 -91.235771) (xy 12.308967 -91.20332) (xy 12.358567 -91.177819)
			(xy 12.411351 -91.159812) (xy 12.466194 -91.149682) (xy 12.521928 -91.147645) (xy 12.577365 -91.153745)
			(xy 12.631322 -91.167851) (xy 12.682651 -91.189663) (xy 12.730257 -91.218717) (xy 12.773125 -91.254392)
			(xy 12.810342 -91.295929) (xy 12.841115 -91.342442) (xy 12.864787 -91.392939) (xy 12.880855 -91.446346)
			(xy 12.888975 -91.501522) (xy 12.889484 -91.529408) (xy 12.888975 -91.557294) (xy 12.880855 -91.61247)
			(xy 12.864787 -91.665877) (xy 12.841115 -91.716374) (xy 12.810342 -91.762887) (xy 12.773125 -91.804424)
			(xy 12.730257 -91.840099) (xy 12.682651 -91.869153) (xy 12.631322 -91.890965) (xy 12.577365 -91.905071)
			(xy 12.521928 -91.911171) (xy 12.466194 -91.909134) (xy 12.411351 -91.899004) (xy 12.358567 -91.880997)
			(xy 12.308967 -91.855496) (xy 12.263609 -91.823045) (xy 12.22346 -91.784336) (xy 12.189374 -91.740193)
			(xy 12.162078 -91.691558) (xy 12.142155 -91.639467) (xy 12.130029 -91.58503) (xy 12.125958 -91.529408)
			(xy 8.177831 -91.529408) (xy 8.117414 -91.636685) (xy 8.049863 -91.740462) (xy 7.975801 -91.839697)
			(xy 7.895534 -91.933984) (xy 7.809391 -92.022934) (xy 7.717726 -92.106182) (xy 7.620915 -92.183385)
			(xy 7.519357 -92.254228) (xy 7.413469 -92.318418) (xy 7.303685 -92.375692) (xy 7.190458 -92.425815)
			(xy 7.074251 -92.46858) (xy 6.955544 -92.503811) (xy 6.834823 -92.531365) (xy 6.712585 -92.551128)
			(xy 6.589332 -92.563018) (xy 6.46557 -92.566987) (xy 6.341808 -92.563018) (xy 6.218555 -92.551128)
			(xy 6.096317 -92.531365) (xy 5.975596 -92.503811) (xy 5.856889 -92.46858) (xy 5.740682 -92.425815)
			(xy 5.627455 -92.375692) (xy 5.517671 -92.318418) (xy 5.411783 -92.254228) (xy 5.310225 -92.183385)
			(xy 5.213414 -92.106182) (xy 5.121749 -92.022934) (xy 5.035606 -91.933984) (xy 4.955339 -91.839697)
			(xy 4.881277 -91.740462) (xy 4.813726 -91.636685) (xy 4.752963 -91.528794) (xy 4.699237 -91.417231)
			(xy 4.652769 -91.302455) (xy 4.613751 -91.184938) (xy 4.582342 -91.065162) (xy 4.558672 -90.94362)
			(xy 4.542837 -90.820812) (xy 4.534904 -90.697241) (xy 1.840484 -90.697241) (xy 1.840484 -95.52813)
			(xy 2.60858 -96.296226) (xy 12.816586 -96.296226)
		)
		(stroke
			(width 0)
			(type solid)
		)
		(fill yes)
		(layer "B.Cu")
		(net "P12V_DBG")
	)
	(gr_poly
		(pts
			(arc
				(start 60.1218 -134.635748)
				(mid 60.159119 -134.545832)
				(end 60.1218 -134.455916)
			)
			(xy 60.095892 -134.430008)
			(arc
				(start 60.059824 -134.42188)
				(mid 59.933346 -134.367573)
				(end 59.835288 -134.271004)
			)
			(arc
				(start 59.835288 -134.271004)
				(mid 59.741054 -134.252883)
				(end 59.64682 -134.271004)
			)
			(arc
				(start 59.64682 -134.271004)
				(mid 59.341004 -134.43075)
				(end 59.035188 -134.271004)
			)
			(arc
				(start 59.035188 -134.271004)
				(mid 58.940954 -134.252883)
				(end 58.84672 -134.271004)
			)
			(arc
				(start 58.84672 -134.271004)
				(mid 58.277511 -134.321692)
				(end 58.327798 -133.752336)
			)
			(arc
				(start 58.327798 -133.752336)
				(mid 58.345843 -133.658238)
				(end 58.327798 -133.564122)
			)
			(arc
				(start 58.327798 -133.564122)
				(mid 58.168161 -133.258202)
				(end 58.328052 -132.95249)
			)
			(arc
				(start 58.328052 -132.95249)
				(mid 58.346173 -132.858256)
				(end 58.328052 -132.764022)
			)
			(arc
				(start 58.328052 -132.764022)
				(mid 58.168306 -132.458206)
				(end 58.328052 -132.15239)
			)
			(arc
				(start 58.328052 -132.15239)
				(mid 58.346173 -132.058156)
				(end 58.328052 -131.963922)
			)
			(arc
				(start 58.328052 -131.963922)
				(mid 58.216851 -131.842006)
				(end 58.169302 -131.684014)
			)
			(arc
				(start 58.169302 -131.684014)
				(mid 58.12928 -131.599816)
				(end 58.042556 -131.56565)
			)
			(xy 57.869328 -131.56565) (xy 57.85739 -131.553712) (xy 57.842404 -131.53898) (xy 57.711594 -131.40817)
			(xy 57.287922 -131.40817)
			(arc
				(start 57.26049 -131.42214)
				(mid 57.057036 -131.471405)
				(end 56.853582 -131.42214)
			)
			(xy 56.82615 -131.40817) (xy 56.700928 -131.40817) (xy 56.700928 -131.407662)
			(arc
				(start 55.71617 -131.407662)
				(mid 55.663202 -131.419235)
				(end 55.619904 -131.451858)
			)
			(arc
				(start 55.619904 -131.451858)
				(mid 55.29613 -131.610752)
				(end 54.957726 -131.485894)
			)
			(xy 54.940962 -131.470146) (xy 54.851046 -131.431792) (xy 54.766718 -131.464558)
			(arc
				(start 54.751224 -131.477258)
				(mid 54.651129 -131.535854)
				(end 54.537864 -131.560824)
			)
			(xy 54.489604 -131.563872) (xy 54.272434 -131.781042) (xy 54.272434 -132.617718) (xy 54.374034 -132.719318)
			(xy 55.37454 -132.719318)
			(arc
				(start 55.39867 -132.708904)
				(mid 55.48371 -132.681072)
				(end 55.572406 -132.66928)
			)
			(arc
				(start 55.572406 -132.66928)
				(mid 55.618627 -132.669641)
				(end 55.664608 -132.67436)
			)
			(arc
				(start 55.664608 -132.67436)
				(mid 55.804624 -132.717662)
				(end 55.925466 -132.800598)
			)
			(xy 55.973472 -132.800598) (xy 55.973472 -132.852668)
			(arc
				(start 55.99303 -132.87883)
				(mid 56.149572 -132.902464)
				(end 56.289702 -132.828792)
			)
			(arc
				(start 56.289702 -132.828792)
				(mid 56.314578 -132.748619)
				(end 56.35371 -132.67436)
			)
			(arc
				(start 56.35371 -132.67436)
				(mid 57.178233 -132.800214)
				(end 56.539384 -133.336284)
			)
			(arc
				(start 56.539384 -133.336284)
				(mid 56.378532 -133.419534)
				(end 56.314086 -133.58876)
			)
			(xy 56.314086 -134.074662) (xy 56.949086 -134.709662) (xy 60.047886 -134.709662)
		)
		(stroke
			(width 0)
			(type solid)
		)
		(fill yes)
		(layer "B.Cu")
		(net "P0V75_BMC_VTTREF_NODE1")
	)
	(gr_poly
		(pts
			(xy 134.655052 -143.72971) (xy 134.655052 -137.593832) (xy 134.5819 -137.480294) (xy 134.553198 -137.4648)
			(xy 134.522416 -137.447567) (xy 134.465799 -137.405485) (xy 134.440422 -137.38098) (xy 134.273544 -137.214102)
			(xy 134.273544 -136.271) (xy 134.274306 -136.245092) (xy 134.275034 -136.222174) (xy 134.269216 -136.176697)
			(xy 134.255333 -136.133001) (xy 134.233836 -136.092505) (xy 134.205423 -136.056522) (xy 134.171014 -136.026222)
			(xy 134.131728 -136.002586) (xy 134.088839 -135.986382) (xy 134.043738 -135.978136) (xy 134.020814 -135.97763)
			(xy 133.51129 -135.97763) (xy 133.489441 -135.978078) (xy 133.446386 -135.985545) (xy 133.405245 -136.000275)
			(xy 133.367234 -136.021831) (xy 133.333476 -136.049577) (xy 133.304967 -136.082695) (xy 133.28255 -136.120204)
			(xy 133.274308 -136.140444) (xy 133.28195 -136.171569) (xy 133.290365 -136.235107) (xy 133.290844 -136.299197)
			(xy 133.283378 -136.362853) (xy 133.268083 -136.425093) (xy 133.245195 -136.484959) (xy 133.215067 -136.541528)
			(xy 133.178161 -136.593929) (xy 133.15696 -136.617964) (xy 133.15696 -136.627108) (xy 133.148578 -136.627108)
			(xy 133.140196 -136.635744) (xy 133.12521 -136.650476) (xy 133.113722 -136.662643) (xy 133.096982 -136.691605)
			(xy 133.088335 -136.72392) (xy 133.087872 -136.740646) (xy 133.087872 -137.24255) (xy 133.087288 -137.278683)
			(xy 133.077239 -137.350247) (xy 133.05729 -137.419704) (xy 133.027831 -137.485693) (xy 133.009132 -137.516616)
			(xy 133.009132 -137.707878) (xy 133.020054 -137.732516) (xy 133.033153 -137.763484) (xy 133.051622 -137.828137)
			(xy 133.060944 -137.894726) (xy 133.060937 -137.961965) (xy 133.051603 -138.028553) (xy 133.033122 -138.093202)
			(xy 133.020054 -138.124184) (xy 133.009132 -138.148822) (xy 133.009132 -138.51255) (xy 131.528312 -139.99337)
			(xy 128.159764 -139.99337) (xy 128.125474 -140.019532) (xy 128.101456 -140.037246) (xy 128.049704 -140.066965)
			(xy 127.994528 -140.089708) (xy 127.936864 -140.105087) (xy 127.877692 -140.112843) (xy 127.818012 -140.112843)
			(xy 127.75884 -140.105087) (xy 127.701176 -140.089708) (xy 127.646 -140.066965) (xy 127.594248 -140.037246)
			(xy 127.57023 -140.019532) (xy 127.53594 -139.99337) (xy 127.459994 -139.99337) (xy 127.442703 -139.993914)
			(xy 127.409376 -140.003141) (xy 127.379762 -140.020995) (xy 127.356043 -140.04616) (xy 127.347472 -140.061188)
			(xy 127.347472 -140.061442) (xy 127.333883 -140.086224) (xy 127.300516 -140.131839) (xy 127.260784 -140.172033)
			(xy 127.215557 -140.205925) (xy 127.165825 -140.232774) (xy 127.112675 -140.251992) (xy 127.057273 -140.263159)
			(xy 127.000829 -140.266029) (xy 126.944579 -140.260541) (xy 126.889754 -140.246814) (xy 126.837555 -140.225149)
			(xy 126.789123 -140.19602) (xy 126.745518 -140.160065) (xy 126.707695 -140.11807) (xy 126.676482 -140.070954)
			(xy 126.652561 -140.019749) (xy 126.636457 -139.965575) (xy 126.628521 -139.909618) (xy 126.628144 -139.881356)
			(xy 126.628398 -139.855956) (xy 126.609094 -139.808712) (xy 126.590552 -139.79017) (xy 126.590552 -139.14247)
			(xy 126.146052 -138.69797) (xy 124.406152 -138.69797) (xy 124.129292 -138.97483) (xy 124.129292 -139.82573)
			(xy 124.981208 -140.677646) (xy 126.059946 -140.677646) (xy 126.069852 -140.677392) (xy 127.165354 -140.677392)
			(xy 127.188976 -140.701268) (xy 127.351282 -140.86332) (xy 127.364951 -140.87727) (xy 127.390255 -140.907024)
			(xy 127.401828 -140.922756) (xy 127.419608 -140.947648) (xy 127.474218 -140.975842) (xy 128.68656 -140.975842)
			(xy 128.68656 -141.011402) (xy 128.760728 -141.08557) (xy 129.017776 -141.08557) (xy 129.127504 -140.975842)
			(xy 130.514852 -140.975842) (xy 130.546483 -140.976334) (xy 130.609204 -140.984586) (xy 130.670312 -141.000954)
			(xy 130.72876 -141.025159) (xy 130.783548 -141.056786) (xy 130.833739 -141.095294) (xy 130.878474 -141.140025)
			(xy 130.916987 -141.190212) (xy 130.94862 -141.244997) (xy 130.972831 -141.303443) (xy 130.989205 -141.364549)
			(xy 130.997463 -141.427269) (xy 130.997463 -141.490531) (xy 130.989205 -141.553251) (xy 130.972831 -141.614357)
			(xy 130.94862 -141.672803) (xy 130.916987 -141.727588) (xy 130.878474 -141.777775) (xy 130.833739 -141.822506)
			(xy 130.783548 -141.861014) (xy 130.72876 -141.892641) (xy 130.670312 -141.916846) (xy 130.609204 -141.933214)
			(xy 130.546483 -141.941466) (xy 130.514852 -141.942058) (xy 129.091944 -141.942058) (xy 129.091944 -141.916658)
			(xy 129.017776 -141.84249) (xy 128.760728 -141.84249) (xy 128.66116 -141.942058) (xy 128.586484 -141.942058)
			(xy 128.180592 -142.34795) (xy 127.97409 -142.34795) (xy 127.927354 -142.367508) (xy 127.921004 -142.373858)
			(xy 127.847344 -142.373858) (xy 127.518414 -142.702788) (xy 127.507896 -142.713927) (xy 127.492004 -142.74011)
			(xy 127.482825 -142.769329) (xy 127.48089 -142.799896) (xy 127.483108 -142.815056) (xy 127.487426 -142.838424)
			(xy 127.490728 -142.847822) (xy 127.500499 -142.876997) (xy 127.513417 -142.937153) (xy 127.518592 -142.998463)
			(xy 127.51594 -143.059933) (xy 127.505505 -143.120569) (xy 127.487456 -143.17939) (xy 127.462084 -143.235442)
			(xy 127.4298 -143.287819) (xy 127.408098 -143.314674) (xy 128.947672 -143.314674) (xy 128.947672 -142.40637)
			(xy 129.14122 -142.213076) (xy 131.53009 -142.213076) (xy 131.813808 -142.49654) (xy 131.813808 -143.310102)
			(xy 131.599178 -143.524732) (xy 129.15773 -143.524732) (xy 128.947672 -143.314674) (xy 127.408098 -143.314674)
			(xy 127.391127 -143.335674) (xy 127.34669 -143.37823) (xy 127.29721 -143.4148) (xy 127.243487 -143.444792)
			(xy 127.186391 -143.467719) (xy 127.126846 -143.483211) (xy 127.065816 -143.491017) (xy 127.035052 -143.491458)
			(xy 126.729744 -143.491458) (xy 126.628652 -143.59255) (xy 126.349252 -143.59255) (xy 126.069852 -143.87195)
			(xy 126.069852 -144.48155) (xy 126.35103 -144.762728) (xy 126.38786 -144.770602) (xy 126.421887 -144.778578)
			(xy 126.487196 -144.803452) (xy 126.517908 -144.820132) (xy 126.547118 -144.836642) (xy 127.136652 -144.836642)
			(xy 127.173772 -144.837365) (xy 127.247034 -144.849372) (xy 127.282448 -144.860518) (xy 127.300648 -144.86688)
			(xy 127.336001 -144.882269) (xy 127.35306 -144.891252) (xy 127.381 -144.906238) (xy 127.540004 -144.906238)
			(xy 127.540004 -144.878552) (xy 127.595122 -144.878552) (xy 127.617441 -144.858683) (xy 127.666123 -144.824028)
			(xy 127.718709 -144.795647) (xy 127.774397 -144.773973) (xy 127.832334 -144.759337) (xy 127.891634 -144.751963)
			(xy 127.921512 -144.751552) (xy 129.306574 -144.751552) (xy 129.340102 -144.727168) (xy 129.371294 -144.705137)
			(xy 129.439181 -144.670172) (xy 129.47523 -144.657572) (xy 129.504212 -144.648556) (xy 129.563799 -144.636995)
			(xy 129.624364 -144.632992) (xy 129.684953 -144.63661) (xy 129.744612 -144.647792) (xy 129.802399 -144.666362)
			(xy 129.857403 -144.692027) (xy 129.908757 -144.724382) (xy 129.955653 -144.762918) (xy 129.997349 -144.807027)
			(xy 130.033189 -144.856013) (xy 130.048254 -144.882362) (xy 130.056932 -144.896885) (xy 130.080554 -144.921088)
			(xy 130.109707 -144.938231) (xy 130.142342 -144.947107) (xy 130.159252 -144.94764) (xy 133.437122 -144.94764)
		)
		(stroke
			(width 0)
			(type solid)
		)
		(fill yes)
		(layer "B.Cu")
		(net "P1V0_PCI_SW_A")
	)
	(gr_poly
		(pts
			(xy 48.3616 -99.927664) (xy 48.3616 -97.221548) (xy 48.209962 -97.06991) (xy 47.120048 -97.06991)
			(xy 47.1043 -97.073974) (xy 47.07296 -97.081383) (xy 47.008796 -97.086805) (xy 46.944632 -97.081383)
			(xy 46.913292 -97.073974) (xy 46.897544 -97.06991) (xy 45.762926 -97.06991) (xy 44.959778 -97.873058)
			(xy 44.946062 -97.952052) (xy 44.963334 -97.988628) (xy 44.974232 -98.012742) (xy 44.990017 -98.06325)
			(xy 44.998672 -98.115454) (xy 45.000032 -98.168353) (xy 44.994071 -98.220933) (xy 44.980902 -98.272186)
			(xy 44.960778 -98.321127) (xy 44.934086 -98.366818) (xy 44.901337 -98.408384) (xy 44.882562 -98.427032)
			(xy 44.867072 -98.442496) (xy 44.841117 -98.477734) (xy 44.821592 -98.516903) (xy 44.809075 -98.55884)
			(xy 44.803937 -98.602303) (xy 44.806331 -98.646002) (xy 44.816186 -98.688644) (xy 44.833209 -98.728963)
			(xy 44.844716 -98.74758) (xy 44.859328 -98.771259) (xy 44.882283 -98.821943) (xy 44.897632 -98.875424)
			(xy 44.90505 -98.930566) (xy 44.904381 -98.986202) (xy 44.895638 -99.041151) (xy 44.879006 -99.094247)
			(xy 44.854839 -99.144364) (xy 44.823649 -99.19044) (xy 44.786098 -99.231496) (xy 44.742981 -99.266664)
			(xy 44.695214 -99.295195) (xy 44.643809 -99.316487) (xy 44.589857 -99.330086) (xy 44.534501 -99.335705)
			(xy 44.478917 -99.333224) (xy 44.424282 -99.322695) (xy 44.371756 -99.304344) (xy 44.322453 -99.278557)
			(xy 44.277417 -99.245883) (xy 44.237605 -99.207014) (xy 44.203861 -99.162775) (xy 44.1769 -99.114104)
			(xy 44.157294 -99.062033) (xy 44.145459 -99.007666) (xy 44.141646 -98.952157) (xy 44.145936 -98.896683)
			(xy 44.158238 -98.842421) (xy 44.178291 -98.79052) (xy 44.205669 -98.742082) (xy 44.239793 -98.698135)
			(xy 44.2595 -98.678492) (xy 44.274986 -98.663029) (xy 44.300932 -98.627792) (xy 44.320448 -98.588627)
			(xy 44.332956 -98.546694) (xy 44.338083 -98.503236) (xy 44.335679 -98.459544) (xy 44.325814 -98.416911)
			(xy 44.308781 -98.376604) (xy 44.297346 -98.357944) (xy 44.283188 -98.335051) (xy 44.260749 -98.286125)
			(xy 44.245413 -98.23453) (xy 44.237484 -98.181291) (xy 44.23712 -98.127467) (xy 44.244327 -98.074125)
			(xy 44.258963 -98.022327) (xy 44.269406 -97.997518) (xy 44.274896 -97.985335) (xy 44.287354 -97.961691)
			(xy 44.294298 -97.950274) (xy 44.313348 -97.919794) (xy 44.313094 -97.868994) (xy 44.312579 -97.852498)
			(xy 44.304121 -97.820611) (xy 44.28775 -97.791969) (xy 44.264565 -97.768499) (xy 44.236126 -97.751778)
			(xy 44.220384 -97.74682) (xy 44.195027 -97.739279) (xy 44.146526 -97.718159) (xy 44.10141 -97.690536)
			(xy 44.060546 -97.656941) (xy 44.02472 -97.618018) (xy 43.99462 -97.574516) (xy 43.970822 -97.52727)
			(xy 43.953786 -97.477188) (xy 43.943838 -97.425231) (xy 43.941168 -97.372398) (xy 43.943016 -97.346008)
			(xy 43.944521 -97.322638) (xy 43.939984 -97.276034) (xy 43.926991 -97.231049) (xy 43.905979 -97.189204)
			(xy 43.877661 -97.151914) (xy 43.842992 -97.12044) (xy 43.803147 -97.095847) (xy 43.759472 -97.078965)
			(xy 43.713444 -97.070367) (xy 43.690032 -97.06991) (xy 41.415462 -97.06991) (xy 41.39316 -97.070353)
			(xy 41.349235 -97.078098) (xy 41.307338 -97.093394) (xy 41.268756 -97.115773) (xy 41.234676 -97.144546)
			(xy 41.206144 -97.178829) (xy 41.184038 -97.217568) (xy 41.169038 -97.259572) (xy 41.161604 -97.303551)
			(xy 41.161965 -97.348152) (xy 41.17011 -97.392004) (xy 41.177464 -97.413064) (xy 41.186583 -97.438637)
			(xy 41.19832 -97.491644) (xy 41.202423 -97.545781) (xy 41.198808 -97.599952) (xy 41.187548 -97.653063)
			(xy 41.168872 -97.704041) (xy 41.143156 -97.751856) (xy 41.110919 -97.795542) (xy 41.072815 -97.834215)
			(xy 41.029611 -97.867094) (xy 40.982183 -97.893516) (xy 40.931487 -97.912945) (xy 40.878548 -97.92499)
			(xy 40.824436 -97.929407) (xy 40.770245 -97.926106) (xy 40.717069 -97.915155) (xy 40.665984 -97.896775)
			(xy 40.61802 -97.871337) (xy 40.574149 -97.839355) (xy 40.535255 -97.801475) (xy 40.502125 -97.758463)
			(xy 40.475429 -97.711189) (xy 40.455705 -97.660606) (xy 40.448992 -97.634298) (xy 40.44061 -97.598992)
			(xy 39.911528 -97.06991) (xy 39.431722 -97.06991) (xy 39.31793 -97.183702) (xy 39.309548 -97.219008)
			(xy 39.309548 -97.219262) (xy 39.302889 -97.245483) (xy 39.283179 -97.295864) (xy 39.256557 -97.342959)
			(xy 39.223556 -97.385827) (xy 39.184835 -97.423608) (xy 39.141171 -97.455547) (xy 39.117524 -97.46869)
			(xy 39.102284 -97.47631) (xy 39.077348 -97.487659) (xy 39.025024 -97.503903) (xy 38.970918 -97.51251)
			(xy 38.943534 -97.513394) (xy 38.914627 -97.51326) (xy 38.857367 -97.505341) (xy 38.801951 -97.488892)
			(xy 38.749643 -97.464289) (xy 38.725348 -97.448624) (xy 38.710616 -97.438718) (xy 38.63721 -97.414842)
			(xy 38.53815 -97.464118) (xy 38.521386 -97.483422) (xy 38.50318 -97.503715) (xy 38.46197 -97.539406)
			(xy 38.416098 -97.568867) (xy 38.366501 -97.5915) (xy 38.314186 -97.606842) (xy 38.260221 -97.614583)
			(xy 38.205704 -97.614563) (xy 38.151744 -97.606784) (xy 38.099441 -97.591403) (xy 38.04986 -97.568735)
			(xy 38.00401 -97.539241) (xy 37.962825 -97.50352) (xy 37.927143 -97.462301) (xy 37.897692 -97.416423)
			(xy 37.87507 -97.366821) (xy 37.859739 -97.314503) (xy 37.855398 -97.287588) (xy 37.851672 -97.265226)
			(xy 37.837347 -97.222219) (xy 37.815617 -97.182437) (xy 37.787172 -97.147143) (xy 37.752914 -97.117458)
			(xy 37.713933 -97.094323) (xy 37.671464 -97.078474) (xy 37.626857 -97.070413) (xy 37.604192 -97.06991)
			(xy 37.385752 -97.06991) (xy 37.25926 -97.196402) (xy 37.25926 -97.581212) (xy 38.629336 -98.983038)
			(xy 39.611441 -99.844094) (xy 45.372002 -99.844094) (xy 45.372002 -99.784158) (xy 45.379825 -99.724736)
			(xy 45.395338 -99.666843) (xy 45.418274 -99.61147) (xy 45.448241 -99.559564) (xy 45.484728 -99.512014)
			(xy 45.527108 -99.469634) (xy 45.574658 -99.433147) (xy 45.626564 -99.40318) (xy 45.681937 -99.380244)
			(xy 45.73983 -99.364731) (xy 45.799252 -99.356908) (xy 45.859188 -99.356908) (xy 45.91861 -99.364731)
			(xy 45.976503 -99.380244) (xy 46.031876 -99.40318) (xy 46.083782 -99.433147) (xy 46.131332 -99.469634)
			(xy 46.173712 -99.512014) (xy 46.210199 -99.559564) (xy 46.240166 -99.61147) (xy 46.263102 -99.666843)
			(xy 46.278615 -99.724736) (xy 46.286438 -99.784158) (xy 46.286928 -99.814126) (xy 46.286438 -99.844094)
			(xy 46.278615 -99.903516) (xy 46.263102 -99.961409) (xy 46.240166 -100.016782) (xy 46.210199 -100.068688)
			(xy 46.173712 -100.116238) (xy 46.131332 -100.158618) (xy 46.083782 -100.195105) (xy 46.031876 -100.225072)
			(xy 45.976503 -100.248008) (xy 45.91861 -100.263521) (xy 45.859188 -100.271344) (xy 45.799252 -100.271344)
			(xy 45.73983 -100.263521) (xy 45.681937 -100.248008) (xy 45.626564 -100.225072) (xy 45.574658 -100.195105)
			(xy 45.527108 -100.158618) (xy 45.484728 -100.116238) (xy 45.448241 -100.068688) (xy 45.418274 -100.016782)
			(xy 45.395338 -99.961409) (xy 45.379825 -99.903516) (xy 45.372002 -99.844094) (xy 39.611441 -99.844094)
			(xy 40.43045 -100.562156) (xy 40.635174 -100.58527) (xy 47.703994 -100.58527)
		)
		(stroke
			(width 0)
			(type solid)
		)
		(fill yes)
		(layer "B.Cu")
		(net "P3V3_NODE1")
	)
	(gr_poly
		(pts
			(xy 81.619852 -88.251284) (xy 81.619852 -87.729568) (xy 81.619353 -87.712918) (xy 81.610726 -87.680756)
			(xy 81.594068 -87.651922) (xy 81.570514 -87.628383) (xy 81.54167 -87.611743) (xy 81.509502 -87.603136)
			(xy 81.492852 -87.602568) (xy 81.045812 -87.602568) (xy 81.045812 -87.37346) (xy 80.82788 -87.155274)
			(xy 80.82788 -86.754462) (xy 81.045812 -86.536276) (xy 81.045812 -86.36635) (xy 81.002378 -86.301834)
			(xy 80.966056 -86.287356) (xy 80.941103 -86.276834) (xy 80.8942 -86.249768) (xy 80.851593 -86.216345)
			(xy 80.814138 -86.177235) (xy 80.782586 -86.133225) (xy 80.75757 -86.085197) (xy 80.739594 -86.034115)
			(xy 80.729017 -85.981006) (xy 80.726053 -85.926935) (xy 80.73076 -85.872987) (xy 80.743044 -85.820247)
			(xy 80.752442 -85.79485) (xy 80.759946 -85.774242) (xy 80.768561 -85.731243) (xy 80.769672 -85.687403)
			(xy 80.763244 -85.644023) (xy 80.749468 -85.60239) (xy 80.728753 -85.563737) (xy 80.701714 -85.529211)
			(xy 80.669152 -85.499837) (xy 80.650842 -85.487764) (xy 80.625728 -85.47145) (xy 80.579562 -85.433303)
			(xy 80.538766 -85.38946) (xy 80.504036 -85.340672) (xy 80.475965 -85.287771) (xy 80.455033 -85.231661)
			(xy 80.441597 -85.173301) (xy 80.435888 -85.113686) (xy 80.438001 -85.053836) (xy 80.447903 -84.994773)
			(xy 80.465422 -84.937506) (xy 80.49026 -84.883012) (xy 80.521993 -84.832223) (xy 80.560079 -84.786007)
			(xy 80.603867 -84.745152) (xy 80.652608 -84.710357) (xy 80.705472 -84.682216) (xy 80.761554 -84.661209)
			(xy 80.819897 -84.647695) (xy 80.879503 -84.641906) (xy 80.939356 -84.64394) (xy 80.998432 -84.653763)
			(xy 81.055723 -84.671206) (xy 81.11025 -84.695972) (xy 81.161081 -84.727637) (xy 81.207348 -84.765661)
			(xy 81.248261 -84.809394) (xy 81.283121 -84.85809) (xy 81.311333 -84.910916) (xy 81.332414 -84.96697)
			(xy 81.33969 -84.99602) (xy 81.345194 -85.017621) (xy 81.362719 -85.058603) (xy 81.387129 -85.095896)
			(xy 81.417675 -85.128355) (xy 81.453419 -85.154983) (xy 81.493263 -85.174962) (xy 81.535982 -85.187677)
			(xy 81.580266 -85.19274) (xy 81.624753 -85.189994) (xy 81.668078 -85.179523) (xy 81.688686 -85.171026)
			(xy 81.707202 -85.16324) (xy 81.745509 -85.15115) (xy 81.76514 -85.146896) (xy 81.782112 -85.142884)
			(xy 81.813115 -85.126939) (xy 81.838645 -85.103198) (xy 81.856797 -85.073434) (xy 81.866216 -85.039868)
			(xy 81.86674 -85.022436) (xy 81.86674 -83.653122) (xy 81.830926 -83.593178) (xy 81.800446 -83.576414)
			(xy 81.777045 -83.563191) (xy 81.733871 -83.531176) (xy 81.695616 -83.49342) (xy 81.663036 -83.45067)
			(xy 81.636778 -83.403772) (xy 81.617359 -83.353653) (xy 81.605165 -83.301305) (xy 81.600436 -83.247765)
			(xy 81.603267 -83.19409) (xy 81.6136 -83.141344) (xy 81.631232 -83.090569) (xy 81.655814 -83.04277)
			(xy 81.68686 -82.998894) (xy 81.704942 -82.979006) (xy 81.715794 -82.966769) (xy 81.731452 -82.938066)
			(xy 81.739303 -82.906327) (xy 81.738833 -82.873634) (xy 81.730073 -82.842134) (xy 81.713597 -82.813893)
			(xy 81.702402 -82.801968) (xy 81.2292 -82.328766) (xy 80.765904 -82.328766) (xy 80.749254 -82.329309)
			(xy 80.717087 -82.337925) (xy 80.688246 -82.354572) (xy 80.664696 -82.378116) (xy 80.64804 -82.406952)
			(xy 80.639414 -82.439116) (xy 80.638904 -82.455766) (xy 80.638904 -83.283552) (xy 79.927196 -83.283552)
			(xy 79.927196 -83.28152) (xy 79.853028 -83.207352) (xy 79.293466 -83.207352) (xy 79.280004 -83.210146)
			(xy 79.2496 -83.21628) (xy 79.187774 -83.221254) (xy 79.125843 -83.217838) (xy 79.06494 -83.206095)
			(xy 79.006179 -83.186239) (xy 78.950636 -83.158633) (xy 78.899327 -83.123784) (xy 78.87589 -83.103466)
			(xy 78.859657 -83.089455) (xy 78.82342 -83.066532) (xy 78.783846 -83.050025) (xy 78.742062 -83.040403)
			(xy 78.699254 -83.037939) (xy 78.656641 -83.042704) (xy 78.615435 -83.054562) (xy 78.576808 -83.073175)
			(xy 78.541857 -83.098015) (xy 78.526386 -83.112864) (xy 78.23962 -83.39963) (xy 78.23962 -84.232496)
			(xy 78.254348 -84.247224) (xy 79.438482 -84.247224) (xy 79.438482 -84.187288) (xy 79.446305 -84.127866)
			(xy 79.461818 -84.069973) (xy 79.484754 -84.0146) (xy 79.514721 -83.962694) (xy 79.551208 -83.915144)
			(xy 79.593588 -83.872764) (xy 79.641138 -83.836277) (xy 79.693044 -83.80631) (xy 79.748417 -83.783374)
			(xy 79.80631 -83.767861) (xy 79.865732 -83.760038) (xy 79.925668 -83.760038) (xy 79.98509 -83.767861)
			(xy 80.042983 -83.783374) (xy 80.098356 -83.80631) (xy 80.150262 -83.836277) (xy 80.197812 -83.872764)
			(xy 80.240192 -83.915144) (xy 80.276679 -83.962694) (xy 80.306646 -84.0146) (xy 80.329582 -84.069973)
			(xy 80.345095 -84.127866) (xy 80.352918 -84.187288) (xy 80.353408 -84.217256) (xy 80.352918 -84.247224)
			(xy 80.345095 -84.306646) (xy 80.329582 -84.364539) (xy 80.306646 -84.419912) (xy 80.276679 -84.471818)
			(xy 80.240192 -84.519368) (xy 80.197812 -84.561748) (xy 80.150262 -84.598235) (xy 80.098356 -84.628202)
			(xy 80.042983 -84.651138) (xy 79.98509 -84.666651) (xy 79.925668 -84.674474) (xy 79.865732 -84.674474)
			(xy 79.80631 -84.666651) (xy 79.748417 -84.651138) (xy 79.693044 -84.628202) (xy 79.641138 -84.598235)
			(xy 79.593588 -84.561748) (xy 79.551208 -84.519368) (xy 79.514721 -84.471818) (xy 79.484754 -84.419912)
			(xy 79.461818 -84.364539) (xy 79.446305 -84.306646) (xy 79.438482 -84.247224) (xy 78.254348 -84.247224)
			(xy 78.479396 -84.472272) (xy 78.496922 -84.481416) (xy 78.515353 -84.491244) (xy 78.550704 -84.513496)
			(xy 78.567534 -84.525866) (xy 78.601316 -84.551012) (xy 78.618588 -84.551012) (xy 78.618588 -84.566506)
			(xy 78.648814 -84.60232) (xy 78.667356 -84.624585) (xy 78.69982 -84.672581) (xy 78.713584 -84.698078)
			(xy 78.722728 -84.715604) (xy 79.21498 -85.207856) (xy 79.21498 -85.549232) (xy 79.314802 -85.649308)
			(xy 79.55026 -85.649308) (xy 79.583929 -85.649851) (xy 79.650679 -85.658736) (xy 79.715672 -85.676355)
			(xy 79.77777 -85.702399) (xy 79.835886 -85.736414) (xy 79.889003 -85.777803) (xy 79.912972 -85.801454)
			(xy 79.931768 -85.801454) (xy 79.931768 -85.81898) (xy 79.957168 -85.852762) (xy 79.97637 -85.879235)
			(xy 80.008549 -85.936171) (xy 80.03316 -85.996763) (xy 80.049799 -86.06001) (xy 80.058189 -86.12487)
			(xy 80.058193 -86.190269) (xy 80.04981 -86.25513) (xy 80.03318 -86.31838) (xy 80.008575 -86.378975)
			(xy 79.976403 -86.435914) (xy 79.957168 -86.462362) (xy 79.931768 -86.496144) (xy 79.931768 -86.61908)
			(xy 79.957168 -86.652862) (xy 79.97637 -86.679335) (xy 80.008549 -86.736271) (xy 80.03316 -86.796863)
			(xy 80.049799 -86.86011) (xy 80.058189 -86.92497) (xy 80.058193 -86.990369) (xy 80.04981 -87.05523)
			(xy 80.03318 -87.11848) (xy 80.008575 -87.179075) (xy 79.976403 -87.236014) (xy 79.957168 -87.262462)
			(xy 79.931768 -87.296244) (xy 79.931768 -87.31377) (xy 79.912972 -87.31377) (xy 79.894016 -87.332656)
			(xy 79.852781 -87.366762) (xy 79.830676 -87.381842) (xy 79.81216 -87.394661) (xy 79.779559 -87.425723)
			(xy 79.752943 -87.462044) (xy 79.733146 -87.502489) (xy 79.720788 -87.545789) (xy 79.716256 -87.590591)
			(xy 79.719692 -87.635489) (xy 79.730988 -87.679079) (xy 79.749791 -87.719995) (xy 79.775511 -87.756956)
			(xy 79.791052 -87.773256) (xy 80.32496 -88.307164) (xy 81.563972 -88.307164)
		)
		(stroke
			(width 0)
			(type solid)
		)
		(fill yes)
		(layer "B.Cu")
		(net "P3V3_NODE1")
	)
	(gr_poly
		(pts
			(xy 100.000054 -95.79991) (xy 100.000548 -95.899331) (xy 100.008453 -96.098015) (xy 100.024251 -96.296227)
			(xy 100.047917 -96.493655) (xy 100.079413 -96.689986) (xy 100.118689 -96.884909) (xy 100.165684 -97.078117)
			(xy 100.220324 -97.269304) (xy 100.28252 -97.458167) (xy 100.352177 -97.644408) (xy 100.429182 -97.827733)
			(xy 100.513415 -98.007851) (xy 100.604742 -98.184479) (xy 100.703019 -98.357335) (xy 100.808091 -98.526148)
			(xy 100.919791 -98.69065) (xy 101.037942 -98.850581) (xy 101.162359 -99.005689) (xy 101.292843 -99.155727)
			(xy 101.42919 -99.30046) (xy 101.571183 -99.439657) (xy 101.718597 -99.573099) (xy 101.8712 -99.700574)
			(xy 102.028751 -99.821883) (xy 102.191 -99.936831) (xy 102.35769 -100.045238) (xy 102.528559 -100.146933)
			(xy 102.703335 -100.241753) (xy 102.881743 -100.329551) (xy 103.0635 -100.410186) (xy 103.24832 -100.483531)
			(xy 103.435909 -100.549471) (xy 103.625972 -100.6079) (xy 103.818207 -100.658727) (xy 104.012311 -100.701872)
			(xy 104.207977 -100.737265) (xy 104.404895 -100.764851) (xy 104.602755 -100.784587) (xy 104.801242 -100.796441)
			(xy 105.000044 -100.800395) (xy 105.198846 -100.796441) (xy 105.397333 -100.784587) (xy 105.595193 -100.764851)
			(xy 105.792111 -100.737265) (xy 105.987777 -100.701872) (xy 106.181881 -100.658727) (xy 106.374116 -100.6079)
			(xy 106.564179 -100.549471) (xy 106.751768 -100.483531) (xy 106.936588 -100.410186) (xy 107.118345 -100.329551)
			(xy 107.296753 -100.241753) (xy 107.471529 -100.146933) (xy 107.642398 -100.045238) (xy 107.809088 -99.936831)
			(xy 107.971337 -99.821883) (xy 108.128888 -99.700574) (xy 108.281491 -99.573099) (xy 108.428905 -99.439657)
			(xy 108.570898 -99.30046) (xy 108.707245 -99.155727) (xy 108.837729 -99.005689) (xy 108.962146 -98.850581)
			(xy 109.080297 -98.69065) (xy 109.191997 -98.526148) (xy 109.297069 -98.357335) (xy 109.395346 -98.184479)
			(xy 109.486673 -98.007851) (xy 109.570906 -97.827733) (xy 109.647911 -97.644408) (xy 109.717568 -97.458167)
			(xy 109.779764 -97.269304) (xy 109.834404 -97.078117) (xy 109.881399 -96.884909) (xy 109.920675 -96.689986)
			(xy 109.952171 -96.493655) (xy 109.975837 -96.296227) (xy 109.991635 -96.098015) (xy 109.99954 -95.899331)
			(xy 110.000034 -95.79991) (xy 110.000034 -90.79992) (xy 109.99954 -90.700499) (xy 109.991635 -90.501815)
			(xy 109.975837 -90.303603) (xy 109.952171 -90.106175) (xy 109.920675 -89.909844) (xy 109.881399 -89.714921)
			(xy 109.834404 -89.521713) (xy 109.779764 -89.330526) (xy 109.717568 -89.141663) (xy 109.647911 -88.955422)
			(xy 109.570906 -88.772097) (xy 109.486673 -88.591979) (xy 109.395346 -88.415351) (xy 109.297069 -88.242495)
			(xy 109.191997 -88.073682) (xy 109.080297 -87.90918) (xy 108.962146 -87.749249) (xy 108.837729 -87.594141)
			(xy 108.707245 -87.444103) (xy 108.570898 -87.29937) (xy 108.428905 -87.160173) (xy 108.281491 -87.026731)
			(xy 108.128888 -86.899256) (xy 107.971337 -86.777947) (xy 107.809088 -86.662999) (xy 107.642398 -86.554592)
			(xy 107.471529 -86.452897) (xy 107.296753 -86.358077) (xy 107.118345 -86.270279) (xy 106.936588 -86.189644)
			(xy 106.751768 -86.116299) (xy 106.564179 -86.050359) (xy 106.374116 -85.99193) (xy 106.181881 -85.941103)
			(xy 105.987777 -85.897958) (xy 105.792111 -85.862565) (xy 105.595193 -85.834979) (xy 105.397333 -85.815243)
			(xy 105.198846 -85.803389) (xy 105.000044 -85.799436) (xy 104.801242 -85.803389) (xy 104.602755 -85.815243)
			(xy 104.404895 -85.834979) (xy 104.207977 -85.862565) (xy 104.012311 -85.897958) (xy 103.818207 -85.941103)
			(xy 103.625972 -85.99193) (xy 103.435909 -86.050359) (xy 103.24832 -86.116299) (xy 103.0635 -86.189644)
			(xy 102.881743 -86.270279) (xy 102.703335 -86.358077) (xy 102.528559 -86.452897) (xy 102.35769 -86.554592)
			(xy 102.191 -86.662999) (xy 102.028751 -86.777947) (xy 101.8712 -86.899256) (xy 101.718597 -87.026731)
			(xy 101.571183 -87.160173) (xy 101.42919 -87.29937) (xy 101.292843 -87.444103) (xy 101.162359 -87.594141)
			(xy 101.037942 -87.749249) (xy 100.919791 -87.90918) (xy 100.808091 -88.073682) (xy 100.703019 -88.242495)
			(xy 100.604742 -88.415351) (xy 100.513415 -88.591979) (xy 100.429182 -88.772097) (xy 100.352177 -88.955422)
			(xy 100.28252 -89.141663) (xy 100.220324 -89.330526) (xy 100.165684 -89.521713) (xy 100.118689 -89.714921)
			(xy 100.079413 -89.909844) (xy 100.047917 -90.106175) (xy 100.024251 -90.303603) (xy 100.008453 -90.501815)
			(xy 100.000548 -90.700499) (xy 100.000054 -90.79992) (xy 100.000054 -95.764319) (xy 102.485192 -95.764319)
			(xy 102.491234 -95.622098) (xy 102.505312 -95.480447) (xy 102.527381 -95.339819) (xy 102.557371 -95.200665)
			(xy 102.595186 -95.06343) (xy 102.640704 -94.928555) (xy 102.69378 -94.796471) (xy 102.754243 -94.667601)
			(xy 102.8219 -94.542358) (xy 102.896535 -94.421144) (xy 102.977908 -94.304346) (xy 103.065758 -94.192339)
			(xy 103.159805 -94.085481) (xy 103.259746 -93.984116) (xy 103.365262 -93.888567) (xy 103.476015 -93.79914)
			(xy 103.591649 -93.716122) (xy 103.711796 -93.63978) (xy 103.836068 -93.570357) (xy 103.96407 -93.508076)
			(xy 104.09539 -93.453136) (xy 104.229607 -93.405714) (xy 104.366293 -93.365961) (xy 104.505009 -93.334005)
			(xy 104.64531 -93.309948) (xy 104.786748 -93.293867) (xy 104.928869 -93.285814) (xy 105.000044 -93.28531)
			(xy 105.071219 -93.285814) (xy 105.21334 -93.293867) (xy 105.354778 -93.309948) (xy 105.495079 -93.334005)
			(xy 105.633795 -93.365961) (xy 105.770481 -93.405714) (xy 105.904698 -93.453136) (xy 106.036018 -93.508076)
			(xy 106.16402 -93.570357) (xy 106.288292 -93.63978) (xy 106.408439 -93.716122) (xy 106.524073 -93.79914)
			(xy 106.634826 -93.888567) (xy 106.740342 -93.984116) (xy 106.840283 -94.085481) (xy 106.93433 -94.192339)
			(xy 107.02218 -94.304346) (xy 107.103553 -94.421144) (xy 107.178188 -94.542358) (xy 107.245845 -94.667601)
			(xy 107.306308 -94.796471) (xy 107.359384 -94.928555) (xy 107.404902 -95.06343) (xy 107.442717 -95.200665)
			(xy 107.472707 -95.339819) (xy 107.494776 -95.480447) (xy 107.508854 -95.622098) (xy 107.514896 -95.764319)
			(xy 107.512881 -95.906654) (xy 107.502818 -96.048647) (xy 107.484737 -96.189843) (xy 107.458697 -96.32979)
			(xy 107.424781 -96.46804) (xy 107.383098 -96.604149) (xy 107.333781 -96.737683) (xy 107.276989 -96.868212)
			(xy 107.212902 -96.995319) (xy 107.141728 -97.118597) (xy 107.063693 -97.237651) (xy 106.979047 -97.352099)
			(xy 106.888063 -97.461575) (xy 106.79103 -97.565729) (xy 106.68826 -97.664226) (xy 106.580082 -97.75675)
			(xy 106.466843 -97.843007) (xy 106.348906 -97.922719) (xy 106.226647 -97.995631) (xy 106.10046 -98.061509)
			(xy 105.970747 -98.120143) (xy 105.837925 -98.171344) (xy 105.702419 -98.214949) (xy 105.564663 -98.250818)
			(xy 105.425099 -98.278836) (xy 105.284172 -98.298913) (xy 105.142336 -98.310985) (xy 105.000044 -98.315014)
			(xy 104.857752 -98.310985) (xy 104.715916 -98.298913) (xy 104.574989 -98.278836) (xy 104.435425 -98.250818)
			(xy 104.297669 -98.214949) (xy 104.162163 -98.171344) (xy 104.029341 -98.120143) (xy 103.899628 -98.061509)
			(xy 103.773441 -97.995631) (xy 103.651182 -97.922719) (xy 103.533245 -97.843007) (xy 103.420006 -97.75675)
			(xy 103.311828 -97.664226) (xy 103.209058 -97.565729) (xy 103.112025 -97.461575) (xy 103.021041 -97.352099)
			(xy 102.936395 -97.237651) (xy 102.85836 -97.118597) (xy 102.787186 -96.995319) (xy 102.723099 -96.868212)
			(xy 102.666307 -96.737683) (xy 102.61699 -96.604149) (xy 102.575307 -96.46804) (xy 102.541391 -96.32979)
			(xy 102.515351 -96.189843) (xy 102.49727 -96.048647) (xy 102.487207 -95.906654) (xy 102.485192 -95.764319)
			(xy 100.000054 -95.764319)
		)
		(stroke
			(width 0)
			(type solid)
		)
		(fill yes)
		(layer "B.Cu")
		(net "GND")
	)
	(gr_poly
		(pts
			(xy 95.6818 -78.032864) (xy 95.6818 -71.933562) (xy 94.615762 -70.867524) (xy 91.79052 -70.867524)
			(xy 91.6559 -71.002144) (xy 91.6559 -75.391947) (xy 92.129918 -75.391947) (xy 92.133171 -75.335902)
			(xy 92.144602 -75.280939) (xy 92.163965 -75.228244) (xy 92.190842 -75.178956) (xy 92.224652 -75.134139)
			(xy 92.264664 -75.094761) (xy 92.310016 -75.061672) (xy 92.359728 -75.035587) (xy 92.412725 -75.017069)
			(xy 92.467864 -75.006518) (xy 92.523954 -75.004162) (xy 92.579784 -75.010052) (xy 92.634148 -75.02406)
			(xy 92.685872 -75.045883) (xy 92.733839 -75.075052) (xy 92.777013 -75.110936) (xy 92.814462 -75.152759)
			(xy 92.845378 -75.199619) (xy 92.869092 -75.250504) (xy 92.885093 -75.304315) (xy 92.893035 -75.35989)
			(xy 92.893388 -75.387962) (xy 92.893771 -75.411016) (xy 92.901872 -75.456403) (xy 92.918032 -75.499581)
			(xy 92.94172 -75.539134) (xy 92.972159 -75.573761) (xy 93.008348 -75.602325) (xy 93.049099 -75.623888)
			(xy 93.070934 -75.631294) (xy 93.096458 -75.639807) (xy 93.145005 -75.663005) (xy 93.189812 -75.692793)
			(xy 93.229991 -75.728579) (xy 93.264744 -75.769654) (xy 93.293383 -75.815204) (xy 93.315339 -75.864325)
			(xy 93.330178 -75.916044) (xy 93.337605 -75.969334) (xy 93.337473 -76.023138) (xy 93.329785 -76.076391)
			(xy 93.314692 -76.128036) (xy 93.292494 -76.177049) (xy 93.278452 -76.2) (xy 93.266488 -76.219844)
			(xy 93.249165 -76.262814) (xy 93.239918 -76.308213) (xy 93.239054 -76.354536) (xy 93.246602 -76.400247)
			(xy 93.262311 -76.443834) (xy 93.285662 -76.48385) (xy 93.295967 -76.495827) (xy 94.52323 -76.495827)
			(xy 94.524063 -76.440346) (xy 94.532923 -76.385571) (xy 94.549626 -76.332658) (xy 94.573818 -76.282722)
			(xy 94.604988 -76.236817) (xy 94.64248 -76.195913) (xy 94.685503 -76.160871) (xy 94.733148 -76.132432)
			(xy 94.78441 -76.111195) (xy 94.838208 -76.097609) (xy 94.893407 -76.091959) (xy 94.948842 -76.094365)
			(xy 95.003343 -76.104777) (xy 95.055762 -76.122975) (xy 95.104991 -76.148575) (xy 95.149992 -76.181036)
			(xy 95.189816 -76.219674) (xy 95.223622 -76.263674) (xy 95.250697 -76.312107) (xy 95.27047 -76.363951)
			(xy 95.282524 -76.418113) (xy 95.286605 -76.47345) (xy 95.282626 -76.528795) (xy 95.270671 -76.582979)
			(xy 95.250993 -76.634859) (xy 95.224006 -76.683342) (xy 95.19028 -76.727403) (xy 95.170752 -76.747116)
			(xy 95.154619 -76.763391) (xy 95.128045 -76.800724) (xy 95.108593 -76.842216) (xy 95.096894 -76.886523)
			(xy 95.093328 -76.932209) (xy 95.098009 -76.977794) (xy 95.110786 -77.021802) (xy 95.131245 -77.062807)
			(xy 95.158724 -77.099479) (xy 95.192331 -77.130632) (xy 95.211392 -77.143356) (xy 95.234487 -77.158732)
			(xy 95.276431 -77.195047) (xy 95.312672 -77.237055) (xy 95.342445 -77.283871) (xy 95.365122 -77.334505)
			(xy 95.380225 -77.387891) (xy 95.387434 -77.442901) (xy 95.386599 -77.498375) (xy 95.377735 -77.553143)
			(xy 95.361032 -77.60605) (xy 95.33684 -77.655978) (xy 95.30567 -77.701875) (xy 95.268181 -77.742773)
			(xy 95.225162 -77.777808) (xy 95.177521 -77.806242) (xy 95.126264 -77.827475) (xy 95.072472 -77.841058)
			(xy 95.01728 -77.846705) (xy 94.961851 -77.844297) (xy 94.907356 -77.833884) (xy 94.854945 -77.815687)
			(xy 94.805722 -77.79009) (xy 94.760727 -77.757632) (xy 94.720909 -77.718998) (xy 94.687107 -77.675003)
			(xy 94.660035 -77.626575) (xy 94.640265 -77.574737) (xy 94.628212 -77.520581) (xy 94.624132 -77.465251)
			(xy 94.62811 -77.409913) (xy 94.640063 -77.355735) (xy 94.659739 -77.303861) (xy 94.686721 -77.255384)
			(xy 94.720442 -77.211327) (xy 94.739968 -77.191616) (xy 94.756062 -77.175305) (xy 94.782635 -77.137978)
			(xy 94.802087 -77.096492) (xy 94.813787 -77.052191) (xy 94.817356 -77.006511) (xy 94.81268 -76.960931)
			(xy 94.799908 -76.916927) (xy 94.779456 -76.875925) (xy 94.751985 -76.839254) (xy 94.718385 -76.808101)
			(xy 94.699328 -76.795376) (xy 94.676218 -76.780018) (xy 94.634265 -76.743702) (xy 94.598017 -76.701692)
			(xy 94.568236 -76.654873) (xy 94.545553 -76.604234) (xy 94.530445 -76.550844) (xy 94.52323 -76.495827)
			(xy 93.295967 -76.495827) (xy 93.315879 -76.51897) (xy 93.351963 -76.548031) (xy 93.392717 -76.570068)
			(xy 93.414596 -76.577698) (xy 93.443408 -76.587564) (xy 93.49836 -76.613812) (xy 93.549347 -76.647115)
			(xy 93.595468 -76.686884) (xy 93.635909 -76.732417) (xy 93.669955 -76.782911) (xy 93.697005 -76.837473)
			(xy 93.716582 -76.89514) (xy 93.72834 -76.954894) (xy 93.732071 -77.015679) (xy 93.727709 -77.076422)
			(xy 93.715332 -77.13605) (xy 93.695157 -77.193511) (xy 93.667542 -77.247789) (xy 93.632974 -77.297926)
			(xy 93.592062 -77.343038) (xy 93.545531 -77.382326) (xy 93.494201 -77.415097) (xy 93.438979 -77.440774)
			(xy 93.38084 -77.458901) (xy 93.320811 -77.469159) (xy 93.259952 -77.471368) (xy 93.199337 -77.465487)
			(xy 93.140037 -77.451621) (xy 93.083099 -77.430015) (xy 93.029529 -77.401049) (xy 92.980273 -77.365237)
			(xy 92.9362 -77.32321) (xy 92.898088 -77.275709) (xy 92.866612 -77.223575) (xy 92.842326 -77.167728)
			(xy 92.825659 -77.109153) (xy 92.816907 -77.048886) (xy 92.816222 -76.987991) (xy 92.823618 -76.927542)
			(xy 92.838964 -76.868608) (xy 92.861989 -76.812229) (xy 92.892286 -76.759401) (xy 92.910406 -76.734924)
			(xy 92.924153 -76.716248) (xy 92.945206 -76.674929) (xy 92.958413 -76.630477) (xy 92.963338 -76.584367)
			(xy 92.959816 -76.538129) (xy 92.947965 -76.493296) (xy 92.928178 -76.451357) (xy 92.901111 -76.413704)
			(xy 92.867663 -76.381585) (xy 92.828943 -76.356067) (xy 92.80779 -76.346558) (xy 92.782123 -76.335223)
			(xy 92.734193 -76.306052) (xy 92.691056 -76.270171) (xy 92.653645 -76.228355) (xy 92.622766 -76.181507)
			(xy 92.599088 -76.130639) (xy 92.583121 -76.07685) (xy 92.575211 -76.021301) (xy 92.574872 -75.993244)
			(xy 92.574442 -75.970192) (xy 92.566345 -75.924811) (xy 92.55019 -75.881636) (xy 92.526509 -75.842085)
			(xy 92.496079 -75.807458) (xy 92.459899 -75.778891) (xy 92.419157 -75.757322) (xy 92.397326 -75.749912)
			(xy 92.37071 -75.74098) (xy 92.320211 -75.716455) (xy 92.273851 -75.684794) (xy 92.232632 -75.646681)
			(xy 92.197443 -75.602938) (xy 92.169045 -75.554511) (xy 92.148051 -75.502445) (xy 92.134914 -75.447864)
			(xy 92.129918 -75.391947) (xy 91.6559 -75.391947) (xy 91.6559 -76.325984) (xy 91.13647 -76.845414)
			(xy 90.459052 -76.845414) (xy 89.808558 -77.495908) (xy 88.994996 -77.495908) (xy 88.903556 -77.587348)
			(xy 88.903556 -77.898244) (xy 88.904104 -77.914891) (xy 88.912729 -77.947048) (xy 88.929379 -77.975879)
			(xy 88.952921 -77.999421) (xy 88.981752 -78.016071) (xy 89.013909 -78.024696) (xy 89.030556 -78.025244)
			(xy 89.761822 -78.025244) (xy 89.792302 -78.013306) (xy 89.802716 -78.00975) (xy 89.833043 -77.999907)
			(xy 89.895558 -77.987368) (xy 89.95918 -77.983164) (xy 90.022802 -77.987368) (xy 90.085317 -77.999907)
			(xy 90.115644 -78.00975) (xy 90.13571 -78.016608) (xy 90.367866 -78.016608) (xy 90.427556 -77.981048)
			(xy 90.44432 -77.950314) (xy 90.457943 -77.926258) (xy 90.49106 -77.881995) (xy 90.53022 -77.842974)
			(xy 90.5746 -77.810014) (xy 90.623273 -77.783803) (xy 90.675219 -77.764892) (xy 90.729351 -77.753675)
			(xy 90.784535 -77.750388) (xy 90.839615 -77.755099) (xy 90.893439 -77.76771) (xy 90.944879 -77.787958)
			(xy 90.992859 -77.815417) (xy 91.036373 -77.849513) (xy 91.074511 -77.889532) (xy 91.106475 -77.934636)
			(xy 91.131594 -77.983881) (xy 91.149343 -78.036236) (xy 91.154758 -78.063344) (xy 91.157824 -78.077754)
			(xy 91.16964 -78.104733) (xy 91.187337 -78.128277) (xy 91.20997 -78.147125) (xy 91.236327 -78.160269)
			(xy 91.264999 -78.167007) (xy 91.279726 -78.167484) (xy 95.54718 -78.167484)
		)
		(stroke
			(width 0)
			(type solid)
		)
		(fill yes)
		(layer "B.Cu")
		(net "P1V05_SUS_NODE1")
	)
	(gr_poly
		(pts
			(arc
				(start 39.47541 -161.518854)
				(mid 39.689143 -161.402092)
				(end 39.706296 -161.15919)
			)
			(arc
				(start 39.706296 -161.15919)
				(mid 39.752763 -160.698838)
				(end 40.176958 -160.514284)
			)
			(arc
				(start 40.176958 -160.514284)
				(mid 40.544563 -160.791522)
				(end 40.48506 -161.24809)
			)
			(xy 40.464232 -161.275014) (xy 40.455088 -161.341816) (xy 40.467788 -161.373058)
			(arc
				(start 40.494204 -161.439098)
				(mid 40.540915 -161.497022)
				(end 40.61206 -161.518854)
			)
			(xy 40.79621 -161.518854) (xy 40.857424 -161.481008)
			(arc
				(start 40.87368 -161.449004)
				(mid 41.28262 -161.196826)
				(end 41.69156 -161.449004)
			)
			(xy 41.707816 -161.481008) (xy 41.76903 -161.518854)
			(arc
				(start 42.458894 -161.518854)
				(mid 42.624186 -161.457713)
				(end 42.709846 -161.303716)
			)
			(arc
				(start 42.709846 -161.303716)
				(mid 42.748554 -161.177602)
				(end 42.821606 -161.06775)
			)
			(arc
				(start 42.821606 -161.06775)
				(mid 43.140754 -160.916313)
				(end 43.472608 -161.03727)
			)
			(arc
				(start 43.472608 -161.03727)
				(mid 43.561229 -161.070861)
				(end 43.648376 -161.033714)
			)
			(xy 43.75277 -160.92932) (xy 43.75277 -160.11398) (xy 44.108624 -159.758126) (xy 44.108624 -159.35833)
			(xy 44.021502 -159.271208) (xy 40.26662 -159.271208) (xy 40.113712 -159.1183)
			(arc
				(start 40.113712 -154.339544)
				(mid 40.075158 -154.248405)
				(end 39.982902 -154.212544)
			)
			(xy 39.96817 -154.212798) (xy 39.28999 -154.212798) (xy 38.982904 -153.905458) (xy 38.608762 -153.531316)
			(xy 38.518338 -153.493724) (xy 38.449758 -153.514552)
			(arc
				(start 38.435788 -153.522934)
				(mid 37.932294 -153.506482)
				(end 37.748972 -153.037286)
			)
			(arc
				(start 37.748972 -153.037286)
				(mid 37.931737 -152.759358)
				(end 38.254432 -152.678638)
			)
			(arc
				(start 38.254432 -152.678638)
				(mid 38.377712 -152.712416)
				(end 38.486842 -152.778968)
			)
			(arc
				(start 38.486842 -152.778968)
				(mid 38.567181 -152.807735)
				(end 38.647624 -152.779222)
			)
			(arc
				(start 38.647624 -152.779222)
				(mid 38.994724 -152.66523)
				(end 39.328598 -152.813512)
			)
			(xy 39.538402 -153.023062) (xy 39.711122 -153.195782) (xy 39.96817 -153.195782)
			(arc
				(start 39.982902 -153.196036)
				(mid 40.075198 -153.160216)
				(end 40.113712 -153.069036)
			)
			(xy 40.113712 -150.782782) (xy 39.70782 -150.37689) (xy 38.896798 -150.37689)
			(arc
				(start 38.864794 -150.398226)
				(mid 38.5826 -150.483732)
				(end 38.300406 -150.398226)
			)
			(xy 38.268402 -150.37689) (xy 38.13302 -150.37689) (xy 38.03142 -150.47849)
			(arc
				(start 38.03142 -151.705056)
				(mid 37.995823 -152.21818)
				(end 37.562282 -152.494996)
			)
			(xy 37.17417 -152.883108) (xy 37.17417 -154.176476)
			(arc
				(start 37.329872 -154.332178)
				(mid 37.370994 -154.359748)
				(end 37.419534 -154.369516)
			)
			(xy 37.45357 -154.369516) (xy 37.738812 -154.654758)
			(arc
				(start 37.7571 -154.663902)
				(mid 37.796779 -154.686047)
				(end 37.834316 -154.711654)
			)
			(xy 37.885116 -154.750008) (xy 37.885116 -154.752548)
			(arc
				(start 37.915596 -154.788108)
				(mid 37.952597 -154.837108)
				(end 37.983414 -154.890216)
			)
			(xy 37.992558 -154.908504) (xy 38.009068 -154.92476) (xy 38.009068 -154.949144)
			(arc
				(start 38.014656 -154.967432)
				(mid 38.035963 -155.077305)
				(end 38.03269 -155.189174)
			)
			(xy 38.03142 -155.198064) (xy 38.03142 -156.34462) (xy 38.03777 -156.364178)
			(arc
				(start 38.03777 -156.364432)
				(mid 38.063369 -156.52369)
				(end 38.03777 -156.682948)
			)
			(xy 38.03777 -156.683202) (xy 38.03142 -156.70276) (xy 38.03142 -157.155134)
			(arc
				(start 38.03269 -157.164024)
				(mid 38.03634 -157.199373)
				(end 38.037516 -157.23489)
			)
			(xy 38.037516 -157.454854)
			(arc
				(start 38.04285 -157.47238)
				(mid 38.058296 -157.543397)
				(end 38.063424 -157.61589)
			)
			(arc
				(start 38.063424 -159.15894)
				(mid 38.058265 -159.231429)
				(end 38.04285 -159.30245)
			)
			(xy 38.037516 -159.319976)
			(arc
				(start 38.037516 -159.399478)
				(mid 38.036345 -159.434996)
				(end 38.03269 -159.470344)
			)
			(xy 38.03142 -159.479234) (xy 38.03142 -160.647888) (xy 38.902386 -161.518854)
		)
		(stroke
			(width 0)
			(type solid)
		)
		(fill yes)
		(layer "B.Cu")
		(net "P1V9_LAN1")
	)
	(gr_poly
		(pts
			(arc
				(start 56.609742 -76.487782)
				(mid 56.658426 -76.47808)
				(end 56.699658 -76.450444)
			)
			(xy 56.793384 -76.356464) (xy 56.793384 -76.020168) (xy 57.016142 -75.797664) (xy 57.409588 -75.797664)
			(xy 57.58561 -75.973686)
			(arc
				(start 57.58561 -76.252578)
				(mid 57.595312 -76.301262)
				(end 57.622948 -76.342494)
			)
			(xy 57.692544 -76.411836) (xy 57.693814 -76.411836) (xy 57.708038 -76.426314) (xy 58.203592 -76.426314)
			(xy 58.203592 -76.454762) (xy 58.910982 -76.454762) (xy 59.087004 -76.27874) (xy 59.095132 -76.242926)
			(xy 59.104784 -76.20762) (xy 59.110626 -76.189078) (xy 59.110626 -75.878436) (xy 59.237626 -75.751436)
			(xy 60.21959 -75.751436)
			(arc
				(start 60.240164 -75.74407)
				(mid 60.299532 -75.727257)
				(end 60.36056 -75.718162)
			)
			(arc
				(start 60.36056 -75.718162)
				(mid 60.443349 -75.677576)
				(end 60.476892 -75.59167)
			)
			(xy 60.476892 -74.814684) (xy 60.57646 -74.714862) (xy 60.57646 -74.478134) (xy 60.435998 -74.337672)
			(xy 59.109102 -74.337672) (xy 59.06262 -74.29119) (xy 59.06262 -73.643744) (xy 59.01055 -73.591674)
			(xy 58.62574 -73.591674) (xy 58.520584 -73.69683) (xy 58.520584 -74.368152) (xy 58.393838 -74.494898)
			(xy 57.695592 -74.494898) (xy 57.49036 -74.289666) (xy 57.49036 -73.62825) (xy 57.394602 -73.532492)
			(xy 57.027572 -73.532492) (xy 57.026048 -73.531222) (xy 57.026048 -73.528174) (xy 56.960262 -73.462388)
			(xy 56.945022 -73.453752) (xy 56.907938 -73.430892) (xy 56.84901 -73.391014) (xy 56.810402 -73.352152)
			(xy 56.771032 -73.293478) (xy 56.749442 -73.258426) (xy 56.740806 -73.242932) (xy 56.646572 -73.148698)
			(xy 56.646572 -72.869298) (xy 56.814466 -72.701404) (xy 56.911748 -72.603614) (xy 58.842656 -72.603614)
			(xy 59.034172 -72.412098) (xy 59.034172 -71.176134) (xy 58.950606 -71.092568) (xy 58.359802 -71.092568)
			(xy 58.344308 -71.108062) (xy 58.344308 -71.851266) (xy 58.250074 -71.9455) (xy 57.006236 -71.9455)
			(xy 56.933084 -71.872348) (xy 56.268366 -71.872348) (xy 56.138572 -72.002142)
			(arc
				(start 56.138572 -73.189084)
				(mid 56.185442 -73.336098)
				(end 56.308752 -73.42886)
			)
			(arc
				(start 56.308752 -73.42886)
				(mid 56.455754 -73.421707)
				(end 56.594502 -73.47077)
			)
			(xy 56.600598 -73.474326) (xy 56.686958 -73.513442) (xy 56.726328 -73.600564)
			(arc
				(start 56.729884 -73.606406)
				(mid 56.726693 -73.997326)
				(end 56.381142 -74.180446)
			)
			(xy 56.375808 -74.179938)
			(arc
				(start 56.374284 -74.179938)
				(mid 56.153069 -74.089806)
				(end 56.028844 -73.885806)
			)
			(arc
				(start 56.028844 -73.885806)
				(mid 55.926246 -73.734563)
				(end 55.748682 -73.691496)
			)
			(arc
				(start 55.748682 -73.691496)
				(mid 55.452418 -73.638415)
				(end 55.253128 -73.412858)
			)
			(xy 55.243476 -73.38949) (xy 55.18785 -73.333864) (xy 55.072788 -73.333864)
			(arc
				(start 55.051706 -73.33742)
				(mid 54.995829 -73.339332)
				(end 54.941724 -73.353422)
			)
			(arc
				(start 54.941724 -73.353422)
				(mid 54.887075 -73.370574)
				(end 54.830472 -73.37933)
			)
			(arc
				(start 54.830472 -73.37933)
				(mid 54.689004 -73.363948)
				(end 54.56301 -73.297796)
			)
			(xy 54.52872 -73.270618)
			(arc
				(start 54.501542 -73.236328)
				(mid 54.489015 -73.219638)
				(end 54.477412 -73.202292)
			)
			(arc
				(start 54.477412 -73.202292)
				(mid 54.459169 -73.170081)
				(end 54.444138 -73.136252)
			)
			(arc
				(start 54.444138 -73.136252)
				(mid 54.506964 -72.755003)
				(end 54.870604 -72.624188)
			)
			(arc
				(start 54.870604 -72.624188)
				(mid 54.953116 -72.649537)
				(end 55.02783 -72.692768)
			)
			(arc
				(start 55.02783 -72.692768)
				(mid 55.071753 -72.730926)
				(end 55.109364 -72.775318)
			)
			(arc
				(start 55.109364 -72.775318)
				(mid 55.26323 -72.875055)
				(end 55.444136 -72.845168)
			)
			(arc
				(start 55.45455 -72.837548)
				(mid 55.49395 -72.79225)
				(end 55.508144 -72.733916)
			)
			(xy 55.508144 -71.996808) (xy 55.26024 -71.748904) (xy 54.953916 -71.748904)
			(arc
				(start 54.93258 -71.756778)
				(mid 54.742927 -71.776003)
				(end 54.567582 -71.701152)
			)
			(xy 54.529482 -71.671942) (xy 54.434232 -71.678038) (xy 54.335172 -71.777098) (xy 54.335172 -72.513698)
			(xy 54.131972 -72.716898) (xy 52.506372 -72.716898) (xy 52.404772 -72.615298) (xy 52.404772 -72.031098)
			(xy 52.353972 -71.980298) (xy 51.889914 -71.980298) (xy 51.236372 -72.63384) (xy 51.236372 -73.148698)
			(xy 51.414172 -73.326498) (xy 52.709572 -73.326498) (xy 52.836572 -73.453498) (xy 52.836572 -73.713086)
			(arc
				(start 52.83835 -73.723754)
				(mid 52.844793 -73.799192)
				(end 52.83835 -73.87463)
			)
			(xy 52.836572 -73.885298) (xy 52.836572 -74.513186) (xy 52.83835 -74.523854) (xy 52.84216 -74.55154)
			(xy 52.846986 -74.596498) (xy 52.9717 -74.719688)
			(arc
				(start 53.299868 -74.719688)
				(mid 53.389671 -74.682491)
				(end 53.426868 -74.592688)
			)
			(xy 53.426868 -73.526142) (xy 53.66766 -73.28535) (xy 54.187598 -73.28535) (xy 54.31663 -73.414382)
			(xy 54.321456 -73.414382) (xy 54.589172 -73.682098) (xy 54.589172 -73.687178) (xy 54.605936 -73.703688)
			(xy 54.605936 -74.003662) (xy 54.665372 -74.063098) (xy 54.843172 -74.063098) (xy 54.872128 -74.092054)
			(xy 54.94782 -74.10704) (xy 55.053992 -74.062844) (xy 55.179214 -74.062844)
			(arc
				(start 55.206646 -74.048874)
				(mid 55.4101 -73.999609)
				(end 55.613554 -74.048874)
			)
			(xy 55.640986 -74.062844) (xy 55.766208 -74.062844) (xy 55.766208 -74.175112)
			(arc
				(start 55.78602 -74.206354)
				(mid 55.832274 -74.304072)
				(end 55.853584 -74.410062)
			)
			(xy 55.857394 -74.459846) (xy 55.930546 -74.52741) (xy 55.960772 -74.52741) (xy 55.960772 -74.901298)
			(xy 55.955184 -74.906886) (xy 55.955184 -75.649836)
			(arc
				(start 55.900828 -75.703938)
				(mid 55.873161 -75.745295)
				(end 55.86349 -75.794108)
			)
			(xy 55.86349 -75.85583) (xy 56.011826 -76.004166) (xy 56.011826 -76.363322) (xy 56.136286 -76.487782)
		)
		(stroke
			(width 0)
			(type solid)
		)
		(fill yes)
		(layer "B.Cu")
		(net "P1V05_NODE1")
	)
	(gr_poly
		(pts
			(xy 184.75198 -60.791598) (xy 184.75198 -57.383172) (xy 184.722674 -57.327673) (xy 184.670561 -57.213484)
			(xy 184.626078 -57.096113) (xy 184.589417 -56.976068) (xy 184.560736 -56.853871) (xy 184.540161 -56.730051)
			(xy 184.52778 -56.605145) (xy 184.523647 -56.479695) (xy 184.527781 -56.354245) (xy 184.540162 -56.229339)
			(xy 184.560738 -56.105519) (xy 184.589419 -55.983321) (xy 184.626082 -55.863277) (xy 184.670566 -55.745906)
			(xy 184.722678 -55.631717) (xy 184.75198 -55.576216) (xy 184.75198 -51.130708) (xy 183.94172 -50.320448)
			(xy 182.596536 -50.320448) (xy 182.581897 -50.320863) (xy 182.553391 -50.327542) (xy 182.527152 -50.340533)
			(xy 182.50456 -50.359156) (xy 182.486799 -50.382432) (xy 182.480458 -50.395632) (xy 182.455205 -50.451115)
			(xy 182.398569 -50.559075) (xy 182.335145 -50.663194) (xy 182.265195 -50.763044) (xy 182.189003 -50.858218)
			(xy 182.106882 -50.948325) (xy 182.019168 -51.032998) (xy 181.92622 -51.111889) (xy 181.828419 -51.184677)
			(xy 181.726163 -51.251062) (xy 181.619872 -51.310773) (xy 181.509981 -51.363567) (xy 181.39694 -51.409226)
			(xy 181.28121 -51.447565) (xy 181.163266 -51.478426) (xy 181.04359 -51.501683) (xy 180.922673 -51.51724)
			(xy 180.801007 -51.525035) (xy 180.679093 -51.525035) (xy 180.557427 -51.51724) (xy 180.43651 -51.501683)
			(xy 180.316834 -51.478426) (xy 180.19889 -51.447565) (xy 180.08316 -51.409226) (xy 179.970119 -51.363567)
			(xy 179.860228 -51.310773) (xy 179.753937 -51.251062) (xy 179.651681 -51.184677) (xy 179.55388 -51.111889)
			(xy 179.460932 -51.032998) (xy 179.373218 -50.948325) (xy 179.291097 -50.858218) (xy 179.214905 -50.763044)
			(xy 179.144955 -50.663194) (xy 179.081531 -50.559075) (xy 179.024895 -50.451115) (xy 178.999642 -50.395632)
			(xy 178.993304 -50.382425) (xy 178.97558 -50.35911) (xy 178.952991 -50.340469) (xy 178.926736 -50.327492)
			(xy 178.898209 -50.320866) (xy 178.883564 -50.320448) (xy 171.983654 -50.320448) (xy 171.74464 -50.559462)
			(xy 171.74464 -53.881528) (xy 177.84648 -53.881528) (xy 177.850551 -53.825906) (xy 177.862677 -53.771469)
			(xy 177.8826 -53.719378) (xy 177.909896 -53.670743) (xy 177.943982 -53.6266) (xy 177.984131 -53.587891)
			(xy 178.029489 -53.55544) (xy 178.079089 -53.529939) (xy 178.131873 -53.511932) (xy 178.186716 -53.501802)
			(xy 178.24245 -53.499765) (xy 178.297887 -53.505865) (xy 178.351844 -53.519971) (xy 178.403173 -53.541783)
			(xy 178.450779 -53.570837) (xy 178.493647 -53.606512) (xy 178.530864 -53.648049) (xy 178.561637 -53.694562)
			(xy 178.585309 -53.745059) (xy 178.601377 -53.798466) (xy 178.609497 -53.853642) (xy 178.610006 -53.881528)
			(xy 178.609497 -53.909414) (xy 178.601377 -53.96459) (xy 178.585309 -54.017997) (xy 178.561637 -54.068494)
			(xy 178.530864 -54.115007) (xy 178.493647 -54.156544) (xy 178.450779 -54.192219) (xy 178.403173 -54.221273)
			(xy 178.351844 -54.243085) (xy 178.297887 -54.257191) (xy 178.24245 -54.263291) (xy 178.186716 -54.261254)
			(xy 178.131873 -54.251124) (xy 178.079089 -54.233117) (xy 178.029489 -54.207616) (xy 177.984131 -54.175165)
			(xy 177.943982 -54.136456) (xy 177.909896 -54.092313) (xy 177.8826 -54.043678) (xy 177.862677 -53.991587)
			(xy 177.850551 -53.93715) (xy 177.84648 -53.881528) (xy 171.74464 -53.881528) (xy 171.74464 -55.084472)
			(xy 177.65852 -55.084472) (xy 177.662591 -55.02885) (xy 177.674717 -54.974413) (xy 177.69464 -54.922322)
			(xy 177.721936 -54.873687) (xy 177.756022 -54.829544) (xy 177.796171 -54.790835) (xy 177.841529 -54.758384)
			(xy 177.891129 -54.732883) (xy 177.943913 -54.714876) (xy 177.998756 -54.704746) (xy 178.05449 -54.702709)
			(xy 178.109927 -54.708809) (xy 178.163884 -54.722915) (xy 178.215213 -54.744727) (xy 178.262819 -54.773781)
			(xy 178.305687 -54.809456) (xy 178.342904 -54.850993) (xy 178.373677 -54.897506) (xy 178.397349 -54.948003)
			(xy 178.413417 -55.00141) (xy 178.421537 -55.056586) (xy 178.422046 -55.084472) (xy 178.421537 -55.112358)
			(xy 178.413417 -55.167534) (xy 178.397349 -55.220941) (xy 178.373677 -55.271438) (xy 178.342904 -55.317951)
			(xy 178.305687 -55.359488) (xy 178.262819 -55.395163) (xy 178.215213 -55.424217) (xy 178.163884 -55.446029)
			(xy 178.109927 -55.460135) (xy 178.05449 -55.466235) (xy 177.998756 -55.464198) (xy 177.943913 -55.454068)
			(xy 177.891129 -55.436061) (xy 177.841529 -55.41056) (xy 177.796171 -55.378109) (xy 177.756022 -55.3394)
			(xy 177.721936 -55.295257) (xy 177.69464 -55.246622) (xy 177.674717 -55.194531) (xy 177.662591 -55.140094)
			(xy 177.65852 -55.084472) (xy 171.74464 -55.084472) (xy 171.74464 -56.227472) (xy 177.670458 -56.227472)
			(xy 177.674529 -56.17185) (xy 177.686655 -56.117413) (xy 177.706578 -56.065322) (xy 177.733874 -56.016687)
			(xy 177.76796 -55.972544) (xy 177.808109 -55.933835) (xy 177.853467 -55.901384) (xy 177.903067 -55.875883)
			(xy 177.955851 -55.857876) (xy 178.010694 -55.847746) (xy 178.066428 -55.845709) (xy 178.121865 -55.851809)
			(xy 178.175822 -55.865915) (xy 178.227151 -55.887727) (xy 178.274757 -55.916781) (xy 178.317625 -55.952456)
			(xy 178.354842 -55.993993) (xy 178.385615 -56.040506) (xy 178.409287 -56.091003) (xy 178.425355 -56.14441)
			(xy 178.433475 -56.199586) (xy 178.433984 -56.227472) (xy 178.433475 -56.255358) (xy 178.425355 -56.310534)
			(xy 178.409287 -56.363941) (xy 178.385615 -56.414438) (xy 178.354842 -56.460951) (xy 178.338048 -56.479694)
			(xy 178.834042 -56.479694) (xy 178.838039 -56.356318) (xy 178.850014 -56.23346) (xy 178.869917 -56.111635)
			(xy 178.897663 -55.991354) (xy 178.933137 -55.87312) (xy 178.97619 -55.757431) (xy 179.026641 -55.644772)
			(xy 179.084278 -55.535614) (xy 179.148861 -55.430416) (xy 179.220118 -55.329619) (xy 179.297749 -55.233646)
			(xy 179.381431 -55.142899) (xy 179.47081 -55.05776) (xy 179.565514 -54.978584) (xy 179.665143 -54.905705)
			(xy 179.769282 -54.839427) (xy 179.877492 -54.780029) (xy 179.98932 -54.727761) (xy 180.104296 -54.68284)
			(xy 180.22194 -54.645456) (xy 180.341756 -54.615766) (xy 180.463243 -54.593893) (xy 180.585891 -54.57993)
			(xy 180.709186 -54.573936) (xy 180.83261 -54.575935) (xy 180.955646 -54.585919) (xy 181.077777 -54.603846)
			(xy 181.198492 -54.629641) (xy 181.317285 -54.663196) (xy 181.433656 -54.704369) (xy 181.547118 -54.752989)
			(xy 181.657194 -54.808852) (xy 181.763424 -54.871723) (xy 181.865362 -54.941338) (xy 181.962579 -55.017405)
			(xy 182.054669 -55.099606) (xy 182.141245 -55.187595) (xy 182.221944 -55.281004) (xy 182.296427 -55.379441)
			(xy 182.364382 -55.482492) (xy 182.425524 -55.589726) (xy 182.479597 -55.700693) (xy 182.526373 -55.814927)
			(xy 182.565657 -55.93195) (xy 182.597284 -56.05127) (xy 182.621121 -56.172387) (xy 182.637068 -56.294792)
			(xy 182.645058 -56.417974) (xy 182.645558 -56.479694) (xy 182.645058 -56.541414) (xy 182.637068 -56.664596)
			(xy 182.621121 -56.787001) (xy 182.597284 -56.908118) (xy 182.565657 -57.027438) (xy 182.526373 -57.144461)
			(xy 182.479597 -57.258695) (xy 182.425524 -57.369662) (xy 182.364382 -57.476896) (xy 182.296427 -57.579947)
			(xy 182.221944 -57.678384) (xy 182.141245 -57.771793) (xy 182.054669 -57.859782) (xy 181.962579 -57.941983)
			(xy 181.865362 -58.01805) (xy 181.763424 -58.087665) (xy 181.657194 -58.150536) (xy 181.547118 -58.206399)
			(xy 181.433656 -58.255019) (xy 181.317285 -58.296192) (xy 181.198492 -58.329747) (xy 181.077777 -58.355542)
			(xy 180.955646 -58.373469) (xy 180.83261 -58.383453) (xy 180.709186 -58.385452) (xy 180.585891 -58.379458)
			(xy 180.463243 -58.365495) (xy 180.341756 -58.343622) (xy 180.22194 -58.313932) (xy 180.104296 -58.276548)
			(xy 179.98932 -58.231627) (xy 179.877492 -58.179359) (xy 179.769282 -58.119961) (xy 179.665143 -58.053683)
			(xy 179.565514 -57.980804) (xy 179.47081 -57.901628) (xy 179.381431 -57.816489) (xy 179.297749 -57.725742)
			(xy 179.220118 -57.629769) (xy 179.148861 -57.528972) (xy 179.084278 -57.423774) (xy 179.026641 -57.314616)
			(xy 178.97619 -57.201957) (xy 178.933137 -57.086268) (xy 178.897663 -56.968034) (xy 178.869917 -56.847753)
			(xy 178.850014 -56.725928) (xy 178.838039 -56.60307) (xy 178.834042 -56.479694) (xy 178.338048 -56.479694)
			(xy 178.317625 -56.502488) (xy 178.274757 -56.538163) (xy 178.227151 -56.567217) (xy 178.175822 -56.589029)
			(xy 178.121865 -56.603135) (xy 178.066428 -56.609235) (xy 178.010694 -56.607198) (xy 177.955851 -56.597068)
			(xy 177.903067 -56.579061) (xy 177.853467 -56.55356) (xy 177.808109 -56.521109) (xy 177.76796 -56.4824)
			(xy 177.733874 -56.438257) (xy 177.706578 -56.389622) (xy 177.686655 -56.337531) (xy 177.674529 -56.283094)
			(xy 177.670458 -56.227472) (xy 171.74464 -56.227472) (xy 171.74464 -60.570364) (xy 172.301154 -61.126878)
			(xy 184.4167 -61.126878)
		)
		(stroke
			(width 0)
			(type solid)
		)
		(fill yes)
		(layer "B.Cu")
		(net "USBPWR_P1")
	)
	(gr_poly
		(pts
			(xy 79.175864 -141.218158)
			(arc
				(start 79.19085 -141.188948)
				(mid 79.213498 -141.15106)
				(end 79.24038 -141.11605)
			)
			(xy 79.254096 -141.100048) (xy 79.288894 -141.013688) (xy 79.252318 -140.92555)
			(arc
				(start 79.23784 -140.909294)
				(mid 79.196329 -140.854035)
				(end 79.16545 -140.7922)
			)
			(arc
				(start 79.16545 -140.7922)
				(mid 79.143515 -140.598261)
				(end 79.220314 -140.41882)
			)
			(arc
				(start 79.220314 -140.41882)
				(mid 79.268769 -140.276125)
				(end 79.227934 -140.131038)
			)
			(arc
				(start 79.227934 -140.131038)
				(mid 79.199852 -139.731574)
				(end 79.544164 -139.527026)
			)
			(arc
				(start 79.544164 -139.527026)
				(mid 79.882366 -139.744082)
				(end 79.83855 -140.143484)
			)
			(arc
				(start 79.83855 -140.143484)
				(mid 79.790095 -140.286179)
				(end 79.83093 -140.431266)
			)
			(arc
				(start 79.83093 -140.431266)
				(mid 79.869426 -140.498311)
				(end 79.893668 -140.571728)
			)
			(arc
				(start 79.893668 -140.571728)
				(mid 79.900711 -140.615917)
				(end 79.902558 -140.660628)
			)
			(arc
				(start 79.902558 -140.660628)
				(mid 79.877523 -140.789867)
				(end 79.810102 -140.902944)
			)
			(xy 79.796386 -140.918946) (xy 79.761588 -141.005306) (xy 79.798164 -141.093444)
			(arc
				(start 79.812642 -141.1097)
				(mid 79.830724 -141.131165)
				(end 79.847186 -141.153896)
			)
			(arc
				(start 79.847186 -141.153896)
				(mid 79.858078 -141.171267)
				(end 79.868014 -141.189202)
			)
			(xy 79.883 -141.218412) (xy 79.997808 -141.294358) (xy 81.637124 -141.294358) (xy 81.70418 -141.244828)
			(arc
				(start 81.716626 -141.204696)
				(mid 81.743998 -141.138708)
				(end 81.783174 -141.078966)
			)
			(arc
				(start 81.783174 -141.078966)
				(mid 81.810917 -140.999718)
				(end 81.783174 -140.92047)
			)
			(arc
				(start 81.783174 -140.92047)
				(mid 82.081116 -140.30073)
				(end 82.379058 -140.92047)
			)
			(arc
				(start 82.379058 -140.92047)
				(mid 82.351315 -140.999718)
				(end 82.379058 -141.078966)
			)
			(arc
				(start 82.379058 -141.078966)
				(mid 82.418256 -141.138697)
				(end 82.445606 -141.204696)
			)
			(arc
				(start 82.445606 -141.204696)
				(mid 82.491546 -141.269529)
				(end 82.567018 -141.294358)
			)
			(xy 83.274662 -141.294358) (xy 83.906106 -140.662914) (xy 83.906106 -137.37336) (xy 83.677252 -137.14476)
			(arc
				(start 82.285078 -137.14476)
				(mid 82.203067 -137.181695)
				(end 82.165952 -137.263632)
			)
			(xy 82.165952 -137.313416) (xy 81.923128 -137.313416)
			(arc
				(start 81.903824 -137.319512)
				(mid 81.784698 -137.338599)
				(end 81.665572 -137.319512)
			)
			(xy 81.646268 -137.313416) (xy 81.403444 -137.313416) (xy 81.403444 -137.296144) (xy 81.292192 -137.185146)
			(xy 81.28254 -137.185146) (xy 81.18094 -137.083546) (xy 80.79994 -137.083546) (xy 79.90586 -136.189466)
			(xy 79.90586 -135.458454) (xy 78.12786 -133.680454) (xy 78.12786 -133.566916) (xy 75.689968 -131.129024)
			(xy 75.617832 -131.113276)
			(arc
				(start 75.58278 -131.125976)
				(mid 75.31307 -131.144652)
				(end 75.075542 -131.015486)
			)
			(xy 72.023478 -131.015486) (xy 71.360792 -131.678172) (xy 71.360792 -131.89585) (xy 71.122794 -132.133594)
			(arc
				(start 70.553072 -132.133594)
				(mid 70.504388 -132.143296)
				(end 70.463156 -132.170932)
			)
			(xy 70.40499 -132.229352) (xy 70.255384 -132.229352) (xy 70.25386 -132.229352) (xy 70.247256 -132.229606)
			(xy 69.677026 -132.229606) (xy 69.394324 -132.512562) (xy 69.394324 -133.465316) (xy 69.398388 -133.469634)
			(xy 70.61581 -133.469634) (xy 70.619366 -133.47319) (xy 70.876414 -133.47319) (xy 71.667116 -134.263892)
			(xy 72.433434 -134.263892) (xy 72.938132 -134.768844) (xy 73.23582 -135.066532)
			(arc
				(start 73.23582 -135.085836)
				(mid 73.351055 -135.298581)
				(end 73.592182 -135.318246)
			)
			(arc
				(start 73.592182 -135.318246)
				(mid 73.793812 -135.290394)
				(end 73.98004 -135.372602)
			)
			(arc
				(start 73.98004 -135.372602)
				(mid 74.142092 -135.431015)
				(end 74.304144 -135.372602)
			)
			(arc
				(start 74.304144 -135.372602)
				(mid 74.912218 -135.703202)
				(end 74.243692 -135.882634)
			)
			(arc
				(start 74.243692 -135.882634)
				(mid 74.142092 -135.831732)
				(end 74.040492 -135.882634)
			)
			(arc
				(start 74.016616 -135.911336)
				(mid 73.949786 -136.088429)
				(end 74.023982 -136.262618)
			)
			(xy 74.669904 -136.90854)
			(arc
				(start 74.691748 -136.917938)
				(mid 74.805694 -136.995762)
				(end 74.883518 -137.109708)
			)
			(xy 74.892916 -137.131552) (xy 77.24648 -139.485116)
			(arc
				(start 77.24648 -141.167358)
				(mid 77.283677 -141.257161)
				(end 77.37348 -141.294358)
			)
			(xy 79.061056 -141.294358)
		)
		(stroke
			(width 0)
			(type solid)
		)
		(fill yes)
		(layer "B.Cu")
		(net "P1V26_BMC_NODE1")
	)
	(gr_poly
		(pts
			(xy 194.4624 -38.599618) (xy 194.4624 -30.862524) (xy 193.69532 -30.095444) (xy 183.325262 -30.095444)
			(xy 179.845716 -33.57499) (xy 172.978318 -33.57499) (xy 171.82592 -34.727388) (xy 171.82592 -35.59556)
			(xy 175.169574 -35.59556) (xy 175.173645 -35.539938) (xy 175.185771 -35.485501) (xy 175.205694 -35.43341)
			(xy 175.23299 -35.384775) (xy 175.267076 -35.340632) (xy 175.307225 -35.301923) (xy 175.352583 -35.269472)
			(xy 175.402183 -35.243971) (xy 175.454967 -35.225964) (xy 175.50981 -35.215834) (xy 175.565544 -35.213797)
			(xy 175.620981 -35.219897) (xy 175.674938 -35.234003) (xy 175.726267 -35.255815) (xy 175.773873 -35.284869)
			(xy 175.816741 -35.320544) (xy 175.853958 -35.362081) (xy 175.884731 -35.408594) (xy 175.908403 -35.459091)
			(xy 175.924471 -35.512498) (xy 175.932591 -35.567674) (xy 175.9331 -35.59556) (xy 175.932591 -35.623446)
			(xy 175.924471 -35.678622) (xy 175.908403 -35.732029) (xy 175.884731 -35.782526) (xy 175.853958 -35.829039)
			(xy 175.816741 -35.870576) (xy 175.773873 -35.906251) (xy 175.726267 -35.935305) (xy 175.674938 -35.957117)
			(xy 175.620981 -35.971223) (xy 175.565544 -35.977323) (xy 175.50981 -35.975286) (xy 175.454967 -35.965156)
			(xy 175.402183 -35.947149) (xy 175.352583 -35.921648) (xy 175.307225 -35.889197) (xy 175.267076 -35.850488)
			(xy 175.23299 -35.806345) (xy 175.205694 -35.75771) (xy 175.185771 -35.705619) (xy 175.173645 -35.651182)
			(xy 175.169574 -35.59556) (xy 171.82592 -35.59556) (xy 171.82592 -36.46297) (xy 178.834042 -36.46297)
			(xy 178.838039 -36.339594) (xy 178.850014 -36.216736) (xy 178.869917 -36.094911) (xy 178.897663 -35.97463)
			(xy 178.933137 -35.856396) (xy 178.97619 -35.740707) (xy 179.026641 -35.628048) (xy 179.084278 -35.51889)
			(xy 179.148861 -35.413692) (xy 179.220118 -35.312895) (xy 179.297749 -35.216922) (xy 179.381431 -35.126175)
			(xy 179.47081 -35.041036) (xy 179.565514 -34.96186) (xy 179.665143 -34.888981) (xy 179.769282 -34.822703)
			(xy 179.877492 -34.763305) (xy 179.98932 -34.711037) (xy 180.104296 -34.666116) (xy 180.22194 -34.628732)
			(xy 180.341756 -34.599042) (xy 180.463243 -34.577169) (xy 180.585891 -34.563206) (xy 180.709186 -34.557212)
			(xy 180.83261 -34.559211) (xy 180.955646 -34.569195) (xy 181.077777 -34.587122) (xy 181.198492 -34.612917)
			(xy 181.317285 -34.646472) (xy 181.433656 -34.687645) (xy 181.547118 -34.736265) (xy 181.657194 -34.792128)
			(xy 181.763424 -34.854999) (xy 181.865362 -34.924614) (xy 181.962579 -35.000681) (xy 182.054669 -35.082882)
			(xy 182.141245 -35.170871) (xy 182.221944 -35.26428) (xy 182.296427 -35.362717) (xy 182.364382 -35.465768)
			(xy 182.425524 -35.573002) (xy 182.479597 -35.683969) (xy 182.526373 -35.798203) (xy 182.565657 -35.915226)
			(xy 182.597284 -36.034546) (xy 182.621121 -36.155663) (xy 182.637068 -36.278068) (xy 182.645058 -36.40125)
			(xy 182.645558 -36.46297) (xy 184.523642 -36.46297) (xy 184.527639 -36.339594) (xy 184.539614 -36.216736)
			(xy 184.559517 -36.094911) (xy 184.587263 -35.97463) (xy 184.622737 -35.856396) (xy 184.66579 -35.740707)
			(xy 184.716241 -35.628048) (xy 184.773878 -35.51889) (xy 184.838461 -35.413692) (xy 184.909718 -35.312895)
			(xy 184.987349 -35.216922) (xy 185.071031 -35.126175) (xy 185.16041 -35.041036) (xy 185.255114 -34.96186)
			(xy 185.354743 -34.888981) (xy 185.458882 -34.822703) (xy 185.567092 -34.763305) (xy 185.67892 -34.711037)
			(xy 185.793896 -34.666116) (xy 185.91154 -34.628732) (xy 186.031356 -34.599042) (xy 186.152843 -34.577169)
			(xy 186.275491 -34.563206) (xy 186.398786 -34.557212) (xy 186.52221 -34.559211) (xy 186.645246 -34.569195)
			(xy 186.767377 -34.587122) (xy 186.888092 -34.612917) (xy 187.006885 -34.646472) (xy 187.123256 -34.687645)
			(xy 187.236718 -34.736265) (xy 187.346794 -34.792128) (xy 187.453024 -34.854999) (xy 187.554962 -34.924614)
			(xy 187.652179 -35.000681) (xy 187.744269 -35.082882) (xy 187.830845 -35.170871) (xy 187.911544 -35.26428)
			(xy 187.986027 -35.362717) (xy 188.053982 -35.465768) (xy 188.115124 -35.573002) (xy 188.169197 -35.683969)
			(xy 188.215973 -35.798203) (xy 188.255257 -35.915226) (xy 188.286884 -36.034546) (xy 188.310721 -36.155663)
			(xy 188.326668 -36.278068) (xy 188.334658 -36.40125) (xy 188.335158 -36.46297) (xy 188.334658 -36.52469)
			(xy 188.326668 -36.647872) (xy 188.310721 -36.770277) (xy 188.286884 -36.891394) (xy 188.255257 -37.010714)
			(xy 188.215973 -37.127737) (xy 188.169197 -37.241971) (xy 188.115124 -37.352938) (xy 188.053982 -37.460172)
			(xy 187.986027 -37.563223) (xy 187.911544 -37.66166) (xy 187.830845 -37.755069) (xy 187.744269 -37.843058)
			(xy 187.652179 -37.925259) (xy 187.554962 -38.001326) (xy 187.453024 -38.070941) (xy 187.346794 -38.133812)
			(xy 187.236718 -38.189675) (xy 187.123256 -38.238295) (xy 187.006885 -38.279468) (xy 186.888092 -38.313023)
			(xy 186.767377 -38.338818) (xy 186.645246 -38.356745) (xy 186.52221 -38.366729) (xy 186.398786 -38.368728)
			(xy 186.275491 -38.362734) (xy 186.152843 -38.348771) (xy 186.031356 -38.326898) (xy 185.91154 -38.297208)
			(xy 185.793896 -38.259824) (xy 185.67892 -38.214903) (xy 185.567092 -38.162635) (xy 185.458882 -38.103237)
			(xy 185.354743 -38.036959) (xy 185.255114 -37.96408) (xy 185.16041 -37.884904) (xy 185.071031 -37.799765)
			(xy 184.987349 -37.709018) (xy 184.909718 -37.613045) (xy 184.838461 -37.512248) (xy 184.773878 -37.40705)
			(xy 184.716241 -37.297892) (xy 184.66579 -37.185233) (xy 184.622737 -37.069544) (xy 184.587263 -36.95131)
			(xy 184.559517 -36.831029) (xy 184.539614 -36.709204) (xy 184.527639 -36.586346) (xy 184.523642 -36.46297)
			(xy 182.645558 -36.46297) (xy 182.645058 -36.52469) (xy 182.637068 -36.647872) (xy 182.621121 -36.770277)
			(xy 182.597284 -36.891394) (xy 182.565657 -37.010714) (xy 182.526373 -37.127737) (xy 182.479597 -37.241971)
			(xy 182.425524 -37.352938) (xy 182.364382 -37.460172) (xy 182.296427 -37.563223) (xy 182.221944 -37.66166)
			(xy 182.141245 -37.755069) (xy 182.054669 -37.843058) (xy 181.962579 -37.925259) (xy 181.865362 -38.001326)
			(xy 181.763424 -38.070941) (xy 181.657194 -38.133812) (xy 181.547118 -38.189675) (xy 181.433656 -38.238295)
			(xy 181.317285 -38.279468) (xy 181.198492 -38.313023) (xy 181.077777 -38.338818) (xy 180.955646 -38.356745)
			(xy 180.83261 -38.366729) (xy 180.709186 -38.368728) (xy 180.585891 -38.362734) (xy 180.463243 -38.348771)
			(xy 180.341756 -38.326898) (xy 180.22194 -38.297208) (xy 180.104296 -38.259824) (xy 179.98932 -38.214903)
			(xy 179.877492 -38.162635) (xy 179.769282 -38.103237) (xy 179.665143 -38.036959) (xy 179.565514 -37.96408)
			(xy 179.47081 -37.884904) (xy 179.381431 -37.799765) (xy 179.297749 -37.709018) (xy 179.220118 -37.613045)
			(xy 179.148861 -37.512248) (xy 179.084278 -37.40705) (xy 179.026641 -37.297892) (xy 178.97619 -37.185233)
			(xy 178.933137 -37.069544) (xy 178.897663 -36.95131) (xy 178.869917 -36.831029) (xy 178.850014 -36.709204)
			(xy 178.838039 -36.586346) (xy 178.834042 -36.46297) (xy 171.82592 -36.46297) (xy 171.82592 -36.848034)
			(xy 175.211738 -36.848034) (xy 175.215809 -36.792412) (xy 175.227935 -36.737975) (xy 175.247858 -36.685884)
			(xy 175.275154 -36.637249) (xy 175.30924 -36.593106) (xy 175.349389 -36.554397) (xy 175.394747 -36.521946)
			(xy 175.444347 -36.496445) (xy 175.497131 -36.478438) (xy 175.551974 -36.468308) (xy 175.607708 -36.466271)
			(xy 175.663145 -36.472371) (xy 175.717102 -36.486477) (xy 175.768431 -36.508289) (xy 175.816037 -36.537343)
			(xy 175.858905 -36.573018) (xy 175.896122 -36.614555) (xy 175.926895 -36.661068) (xy 175.950567 -36.711565)
			(xy 175.966635 -36.764972) (xy 175.974755 -36.820148) (xy 175.975264 -36.848034) (xy 175.974755 -36.87592)
			(xy 175.966635 -36.931096) (xy 175.950567 -36.984503) (xy 175.926895 -37.035) (xy 175.896122 -37.081513)
			(xy 175.858905 -37.12305) (xy 175.816037 -37.158725) (xy 175.768431 -37.187779) (xy 175.717102 -37.209591)
			(xy 175.663145 -37.223697) (xy 175.607708 -37.229797) (xy 175.551974 -37.22776) (xy 175.497131 -37.21763)
			(xy 175.444347 -37.199623) (xy 175.394747 -37.174122) (xy 175.349389 -37.141671) (xy 175.30924 -37.102962)
			(xy 175.275154 -37.058819) (xy 175.247858 -37.010184) (xy 175.227935 -36.958093) (xy 175.215809 -36.903656)
			(xy 175.211738 -36.848034) (xy 171.82592 -36.848034) (xy 171.82592 -37.991034) (xy 175.203102 -37.991034)
			(xy 175.207173 -37.935412) (xy 175.219299 -37.880975) (xy 175.239222 -37.828884) (xy 175.266518 -37.780249)
			(xy 175.300604 -37.736106) (xy 175.340753 -37.697397) (xy 175.386111 -37.664946) (xy 175.435711 -37.639445)
			(xy 175.488495 -37.621438) (xy 175.543338 -37.611308) (xy 175.599072 -37.609271) (xy 175.654509 -37.615371)
			(xy 175.708466 -37.629477) (xy 175.759795 -37.651289) (xy 175.807401 -37.680343) (xy 175.850269 -37.716018)
			(xy 175.887486 -37.757555) (xy 175.918259 -37.804068) (xy 175.941931 -37.854565) (xy 175.957999 -37.907972)
			(xy 175.966119 -37.963148) (xy 175.966628 -37.991034) (xy 175.966119 -38.01892) (xy 175.957999 -38.074096)
			(xy 175.941931 -38.127503) (xy 175.918259 -38.178) (xy 175.887486 -38.224513) (xy 175.850269 -38.26605)
			(xy 175.807401 -38.301725) (xy 175.759795 -38.330779) (xy 175.708466 -38.352591) (xy 175.654509 -38.366697)
			(xy 175.599072 -38.372797) (xy 175.543338 -38.37076) (xy 175.488495 -38.36063) (xy 175.435711 -38.342623)
			(xy 175.386111 -38.317122) (xy 175.340753 -38.284671) (xy 175.300604 -38.245962) (xy 175.266518 -38.201819)
			(xy 175.239222 -38.153184) (xy 175.219299 -38.101093) (xy 175.207173 -38.046656) (xy 175.203102 -37.991034)
			(xy 171.82592 -37.991034) (xy 171.82592 -38.91788) (xy 173.42612 -40.51808) (xy 192.543938 -40.51808)
		)
		(stroke
			(width 0)
			(type solid)
		)
		(fill yes)
		(layer "B.Cu")
		(net "USBPWR_P0")
	)
	(gr_poly
		(pts
			(xy 92.97924 -178.612546) (xy 92.97924 -178.505104) (xy 92.953332 -178.462686)
			(arc
				(start 92.945712 -178.448208)
				(mid 92.892638 -178.23434)
				(end 92.945712 -178.020472)
			)
			(xy 92.953332 -178.005994) (xy 92.97924 -177.963576)
			(arc
				(start 92.97924 -177.851308)
				(mid 92.942043 -177.761505)
				(end 92.85224 -177.724308)
			)
			(xy 92.828872 -177.724308)
			(arc
				(start 92.806774 -177.73269)
				(mid 92.658252 -177.757709)
				(end 92.511626 -177.723292)
			)
			(arc
				(start 92.511626 -177.723292)
				(mid 92.342037 -177.708456)
				(end 92.201238 -177.804064)
			)
			(arc
				(start 92.201238 -177.804064)
				(mid 91.627876 -177.852109)
				(end 91.659202 -177.277522)
			)
			(arc
				(start 91.659202 -177.277522)
				(mid 91.757148 -177.072774)
				(end 91.652344 -176.871376)
			)
			(arc
				(start 91.652344 -176.871376)
				(mid 91.505308 -176.473229)
				(end 91.817444 -176.185576)
			)
			(arc
				(start 91.817444 -176.185576)
				(mid 91.961206 -176.111077)
				(end 92.030804 -175.96485)
			)
			(arc
				(start 92.030804 -175.96485)
				(mid 92.257071 -175.622699)
				(end 92.666566 -175.599344)
			)
			(xy 92.677742 -175.60417)
			(arc
				(start 92.701872 -175.609504)
				(mid 92.815616 -175.578422)
				(end 92.85478 -175.467264)
			)
			(xy 92.853256 -175.456088) (xy 92.850716 -175.445674) (xy 92.850462 -175.444658) (xy 92.8497 -175.441864)
			(arc
				(start 92.842842 -175.409098)
				(mid 92.764023 -175.264649)
				(end 92.613226 -175.198786)
			)
			(arc
				(start 92.613226 -175.198786)
				(mid 92.548168 -175.188785)
				(end 92.48521 -175.169576)
			)
			(arc
				(start 92.48521 -175.169576)
				(mid 92.314472 -175.164877)
				(end 92.179394 -175.269398)
			)
			(arc
				(start 92.179394 -175.269398)
				(mid 91.504657 -175.207278)
				(end 91.94546 -174.692564)
			)
			(arc
				(start 91.94546 -174.692564)
				(mid 92.115151 -174.673511)
				(end 92.234512 -174.55134)
			)
			(arc
				(start 92.234512 -174.55134)
				(mid 92.284466 -174.467475)
				(end 92.351098 -174.396146)
			)
			(arc
				(start 92.351098 -174.396146)
				(mid 92.43883 -174.20952)
				(end 92.359226 -174.01921)
			)
			(arc
				(start 92.359226 -174.01921)
				(mid 92.239879 -173.761165)
				(end 92.332048 -173.49216)
			)
			(arc
				(start 92.332048 -173.49216)
				(mid 92.392816 -173.302958)
				(end 92.298774 -173.127924)
			)
			(arc
				(start 92.298774 -173.127924)
				(mid 92.155831 -172.829879)
				(end 92.299282 -172.53204)
			)
			(arc
				(start 92.299282 -172.53204)
				(mid 92.391873 -172.37252)
				(end 92.352114 -172.192442)
			)
			(arc
				(start 92.352114 -172.192442)
				(mid 92.30952 -172.112416)
				(end 92.283534 -172.025564)
			)
			(arc
				(start 92.283534 -172.025564)
				(mid 92.174074 -171.861804)
				(end 91.980512 -171.825666)
			)
			(arc
				(start 91.980512 -171.825666)
				(mid 91.519129 -171.426467)
				(end 92.031058 -171.094654)
			)
			(arc
				(start 92.031058 -171.094654)
				(mid 92.252873 -171.071661)
				(end 92.371164 -170.882564)
			)
			(arc
				(start 92.371164 -170.882564)
				(mid 92.437179 -170.70467)
				(end 92.580714 -170.580558)
			)
			(xy 92.61094 -170.565572)
			(arc
				(start 92.642436 -170.51909)
				(mid 92.664176 -170.449451)
				(end 92.64396 -170.37939)
			)
			(xy 92.616274 -170.336464)
			(arc
				(start 92.587572 -170.32097)
				(mid 92.545114 -170.294632)
				(end 92.505784 -170.26382)
			)
			(arc
				(start 92.505784 -170.26382)
				(mid 92.466829 -170.240654)
				(end 92.422218 -170.232578)
			)
			(xy 91.934538 -170.232578)
			(arc
				(start 91.92768 -170.23334)
				(mid 91.88704 -170.23551)
				(end 91.8464 -170.23334)
			)
			(xy 91.839542 -170.232578) (xy 91.672156 -170.232578) (xy 91.583002 -170.273218) (xy 91.568524 -170.289474)
			(xy 91.568524 -170.34002) (xy 91.516708 -170.34002) (xy 91.484704 -170.36161)
			(arc
				(start 91.463622 -170.374818)
				(mid 91.264253 -170.441862)
				(end 91.05519 -170.418506)
			)
			(xy 91.020646 -170.406568) (xy 90.950034 -170.423078) (xy 90.879168 -170.493944) (xy 90.879168 -178.758088)
			(xy 91.1098 -178.98872) (xy 92.603066 -178.98872)
		)
		(stroke
			(width 0)
			(type solid)
		)
		(fill yes)
		(layer "B.Cu")
		(net "P5V_NODE1")
	)
	(gr_poly
		(pts
			(xy 19.000216 -182.799736) (xy 19.000706 -182.909332) (xy 19.008702 -183.128379) (xy 19.024693 -183.346988)
			(xy 19.048658 -183.564866) (xy 19.080564 -183.781724) (xy 19.12037 -183.997272) (xy 19.168021 -184.211223)
			(xy 19.223455 -184.42329) (xy 19.286597 -184.633191) (xy 19.357363 -184.840646) (xy 19.435659 -185.045378)
			(xy 19.52138 -185.247114) (xy 19.614411 -185.445585) (xy 19.71463 -185.640525) (xy 19.821901 -185.831675)
			(xy 19.936082 -186.018779) (xy 20.057021 -186.201589) (xy 20.184555 -186.379859) (xy 20.318516 -186.553353)
			(xy 20.458724 -186.721838) (xy 20.604991 -186.88509) (xy 20.757124 -187.042891) (xy 20.914918 -187.19503)
			(xy 21.078164 -187.341304) (xy 21.246643 -187.481519) (xy 21.420131 -187.615487) (xy 21.598396 -187.743029)
			(xy 21.7812 -187.863976) (xy 21.9683 -187.978165) (xy 22.159445 -188.085444) (xy 22.354381 -188.185671)
			(xy 22.552848 -188.278711) (xy 22.75458 -188.36444) (xy 22.959309 -188.442745) (xy 23.166761 -188.51352)
			(xy 23.376659 -188.57667) (xy 23.588724 -188.632113) (xy 23.802673 -188.679773) (xy 24.018219 -188.719588)
			(xy 24.235076 -188.751504) (xy 24.452953 -188.775478) (xy 24.671561 -188.791478) (xy 24.890608 -188.799484)
			(xy 25.1098 -188.799484) (xy 25.328847 -188.791478) (xy 25.547455 -188.775478) (xy 25.765332 -188.751504)
			(xy 25.982189 -188.719588) (xy 26.197735 -188.679773) (xy 26.411684 -188.632113) (xy 26.623749 -188.57667)
			(xy 26.833647 -188.51352) (xy 27.041099 -188.442745) (xy 27.245828 -188.36444) (xy 27.44756 -188.278711)
			(xy 27.646027 -188.185671) (xy 27.840963 -188.085444) (xy 28.032108 -187.978165) (xy 28.219208 -187.863976)
			(xy 28.402012 -187.743029) (xy 28.580277 -187.615487) (xy 28.753765 -187.481519) (xy 28.922244 -187.341304)
			(xy 29.08549 -187.19503) (xy 29.243284 -187.042891) (xy 29.395417 -186.88509) (xy 29.541684 -186.721838)
			(xy 29.681892 -186.553353) (xy 29.815853 -186.379859) (xy 29.943387 -186.201589) (xy 30.064326 -186.018779)
			(xy 30.178507 -185.831675) (xy 30.285778 -185.640525) (xy 30.385997 -185.445585) (xy 30.479028 -185.247114)
			(xy 30.564749 -185.045378) (xy 30.643045 -184.840646) (xy 30.713811 -184.633191) (xy 30.776953 -184.42329)
			(xy 30.832387 -184.211223) (xy 30.880038 -183.997272) (xy 30.919844 -183.781724) (xy 30.95175 -183.564866)
			(xy 30.975715 -183.346988) (xy 30.991706 -183.128379) (xy 30.999702 -182.909332) (xy 31.000192 -182.799736)
			(xy 30.999938 -177.749962) (xy 30.998539 -177.640959) (xy 30.988802 -177.423155) (xy 30.971159 -177.205849)
			(xy 30.945633 -176.989327) (xy 30.912258 -176.773876) (xy 30.871079 -176.559779) (xy 30.822148 -176.347319)
			(xy 30.765532 -176.136777) (xy 30.701305 -175.928431) (xy 30.629551 -175.722556) (xy 30.550365 -175.519423)
			(xy 30.463852 -175.319301) (xy 30.370126 -175.122454) (xy 30.269311 -174.929142) (xy 30.16154 -174.73962)
			(xy 30.046955 -174.554138) (xy 29.925707 -174.372941) (xy 29.797957 -174.196268) (xy 29.663873 -174.024353)
			(xy 29.523632 -173.857423) (xy 29.37742 -173.695697) (xy 29.225428 -173.53939) (xy 29.067859 -173.388708)
			(xy 28.90492 -173.243849) (xy 28.736826 -173.105005) (xy 28.563798 -172.972359) (xy 28.386067 -172.846087)
			(xy 28.203865 -172.726355) (xy 28.017434 -172.613321) (xy 27.827019 -172.507134) (xy 27.632873 -172.407934)
			(xy 27.435251 -172.315854) (xy 27.234415 -172.231013) (xy 27.030629 -172.153524) (xy 26.824162 -172.083489)
			(xy 26.615288 -172.021002) (xy 26.404281 -171.966143) (xy 26.191421 -171.918986) (xy 25.976988 -171.879594)
			(xy 25.761265 -171.848017) (xy 25.544538 -171.824298) (xy 25.327092 -171.808467) (xy 25.109215 -171.800547)
			(xy 24.891193 -171.800547) (xy 24.673316 -171.808467) (xy 24.45587 -171.824298) (xy 24.239143 -171.848017)
			(xy 24.02342 -171.879594) (xy 23.808987 -171.918986) (xy 23.596127 -171.966143) (xy 23.38512 -172.021002)
			(xy 23.176246 -172.083489) (xy 22.969779 -172.153524) (xy 22.765993 -172.231013) (xy 22.565157 -172.315854)
			(xy 22.367535 -172.407934) (xy 22.173389 -172.507134) (xy 21.982974 -172.613321) (xy 21.796543 -172.726355)
			(xy 21.614341 -172.846087) (xy 21.43661 -172.972359) (xy 21.263582 -173.105005) (xy 21.095488 -173.243849)
			(xy 20.932549 -173.388708) (xy 20.77498 -173.53939) (xy 20.622988 -173.695697) (xy 20.476776 -173.857423)
			(xy 20.336535 -174.024353) (xy 20.202451 -174.196268) (xy 20.074701 -174.372941) (xy 19.953453 -174.554138)
			(xy 19.838868 -174.73962) (xy 19.731097 -174.929142) (xy 19.630282 -175.122454) (xy 19.536556 -175.319301)
			(xy 19.450043 -175.519423) (xy 19.370857 -175.722556) (xy 19.299103 -175.928431) (xy 19.234876 -176.136777)
			(xy 19.17826 -176.347319) (xy 19.129329 -176.559779) (xy 19.08815 -176.773876) (xy 19.054775 -176.989327)
			(xy 19.029249 -177.205849) (xy 19.011606 -177.423155) (xy 19.001869 -177.640959) (xy 19.000504 -177.747317)
			(xy 20.989385 -177.747317) (xy 20.9957 -177.568929) (xy 21.009946 -177.390997) (xy 21.032093 -177.213876)
			(xy 21.062099 -177.037915) (xy 21.099904 -176.863464) (xy 21.145432 -176.690867) (xy 21.198594 -176.520467)
			(xy 21.259285 -176.3526) (xy 21.327384 -176.1876) (xy 21.402756 -176.025793) (xy 21.485252 -175.8675)
			(xy 21.57471 -175.713033) (xy 21.67095 -175.5627) (xy 21.773784 -175.416797) (xy 21.883008 -175.275613)
			(xy 21.998404 -175.139429) (xy 22.119745 -175.008513) (xy 22.24679 -174.883126) (xy 22.379288 -174.763515)
			(xy 22.516976 -174.649917) (xy 22.659582 -174.542558) (xy 22.806823 -174.441649) (xy 22.958408 -174.347391)
			(xy 23.114036 -174.25997) (xy 23.273399 -174.17956) (xy 23.436182 -174.106319) (xy 23.602062 -174.040393)
			(xy 23.770711 -173.981913) (xy 23.941795 -173.930993) (xy 24.114975 -173.887736) (xy 24.289908 -173.852226)
			(xy 24.466247 -173.824534) (xy 24.643644 -173.804714) (xy 24.821748 -173.792807) (xy 25.000204 -173.788835)
			(xy 25.17866 -173.792807) (xy 25.356764 -173.804714) (xy 25.534161 -173.824534) (xy 25.7105 -173.852226)
			(xy 25.885433 -173.887736) (xy 26.058613 -173.930993) (xy 26.229697 -173.981913) (xy 26.398346 -174.040393)
			(xy 26.564226 -174.106319) (xy 26.727009 -174.17956) (xy 26.886372 -174.25997) (xy 27.042 -174.347391)
			(xy 27.193585 -174.441649) (xy 27.340826 -174.542558) (xy 27.483432 -174.649917) (xy 27.62112 -174.763515)
			(xy 27.753618 -174.883126) (xy 27.880663 -175.008513) (xy 28.002004 -175.139429) (xy 28.1174 -175.275613)
			(xy 28.226624 -175.416797) (xy 28.329458 -175.5627) (xy 28.425698 -175.713033) (xy 28.515156 -175.8675)
			(xy 28.597652 -176.025793) (xy 28.673024 -176.1876) (xy 28.741123 -176.3526) (xy 28.801814 -176.520467)
			(xy 28.854976 -176.690867) (xy 28.900504 -176.863464) (xy 28.938309 -177.037915) (xy 28.968315 -177.213876)
			(xy 28.990462 -177.390997) (xy 29.004708 -177.568929) (xy 29.011023 -177.747317) (xy 29.009395 -177.925811)
			(xy 28.999828 -178.104055) (xy 28.982341 -178.281697) (xy 28.956967 -178.458385) (xy 28.923758 -178.633769)
			(xy 28.882778 -178.807502) (xy 28.83411 -178.97924) (xy 28.77785 -179.148643) (xy 28.714108 -179.315374)
			(xy 28.643012 -179.479105) (xy 28.564701 -179.639511) (xy 28.479332 -179.796274) (xy 28.387073 -179.949083)
			(xy 28.288107 -180.097637) (xy 28.18263 -180.241641) (xy 28.07085 -180.380809) (xy 27.95299 -180.514866)
			(xy 27.829282 -180.643547) (xy 27.699971 -180.766597) (xy 27.565314 -180.883772) (xy 27.495754 -180.939694)
			(xy 27.471441 -180.959638) (xy 27.427607 -181.004729) (xy 27.389918 -181.055068) (xy 27.358994 -181.109824)
			(xy 27.335348 -181.168094) (xy 27.319368 -181.228915) (xy 27.311321 -181.291283) (xy 27.310842 -181.322726)
			(xy 27.310842 -182.79999) (xy 27.310335 -182.868477) (xy 27.30222 -183.00521) (xy 27.28602 -183.141223)
			(xy 27.26179 -183.276037) (xy 27.229617 -183.409178) (xy 27.189613 -183.54018) (xy 27.141919 -183.668582)
			(xy 27.086701 -183.793933) (xy 27.024155 -183.915793) (xy 26.954499 -184.033733) (xy 26.877979 -184.14734)
			(xy 26.794864 -184.256215) (xy 26.705444 -184.359974) (xy 26.610035 -184.458254) (xy 26.508971 -184.550709)
			(xy 26.402607 -184.637014) (xy 26.291318 -184.716867) (xy 26.175493 -184.789987) (xy 26.055541 -184.856117)
			(xy 25.931881 -184.915025) (xy 25.804949 -184.966503) (xy 25.67519 -185.010372) (xy 25.54306 -185.046476)
			(xy 25.409023 -185.07469) (xy 25.273551 -185.094914) (xy 25.137118 -185.107077) (xy 25.000204 -185.111136)
			(xy 24.86329 -185.107077) (xy 24.726857 -185.094914) (xy 24.591385 -185.07469) (xy 24.457348 -185.046476)
			(xy 24.325218 -185.010372) (xy 24.195459 -184.966503) (xy 24.068527 -184.915025) (xy 23.944867 -184.856117)
			(xy 23.824915 -184.789987) (xy 23.70909 -184.716867) (xy 23.597801 -184.637014) (xy 23.491437 -184.550709)
			(xy 23.390373 -184.458254) (xy 23.294964 -184.359974) (xy 23.205544 -184.256215) (xy 23.122429 -184.14734)
			(xy 23.045909 -184.033733) (xy 22.976253 -183.915793) (xy 22.913707 -183.793933) (xy 22.858489 -183.668582)
			(xy 22.810795 -183.54018) (xy 22.770791 -183.409178) (xy 22.738618 -183.276037) (xy 22.714388 -183.141223)
			(xy 22.698188 -183.00521) (xy 22.690073 -182.868477) (xy 22.689566 -182.79999) (xy 22.689566 -181.322726)
			(xy 22.689088 -181.291287) (xy 22.680995 -181.228931) (xy 22.66499 -181.168123) (xy 22.641336 -181.109863)
			(xy 22.610422 -181.055108) (xy 22.572757 -181.004759) (xy 22.528959 -180.959643) (xy 22.504654 -180.939694)
			(xy 22.435094 -180.883772) (xy 22.300437 -180.766597) (xy 22.171126 -180.643547) (xy 22.047418 -180.514866)
			(xy 21.929558 -180.380809) (xy 21.817778 -180.241641) (xy 21.712301 -180.097637) (xy 21.613335 -179.949083)
			(xy 21.521076 -179.796274) (xy 21.435707 -179.639511) (xy 21.357396 -179.479105) (xy 21.2863 -179.315374)
			(xy 21.222558 -179.148643) (xy 21.166298 -178.97924) (xy 21.11763 -178.807502) (xy 21.07665 -178.633769)
			(xy 21.043441 -178.458385) (xy 21.018067 -178.281697) (xy 21.00058 -178.104055) (xy 20.991013 -177.925811)
			(xy 20.989385 -177.747317) (xy 19.000504 -177.747317) (xy 19.00047 -177.749962)
		)
		(stroke
			(width 0)
			(type solid)
		)
		(fill yes)
		(layer "B.Cu")
		(net "GND")
	)
	(gr_poly
		(pts
			(xy 19.000216 -26.799794) (xy 19.000706 -26.90939) (xy 19.008702 -27.128437) (xy 19.024693 -27.347046)
			(xy 19.048658 -27.564924) (xy 19.080564 -27.781782) (xy 19.12037 -27.99733) (xy 19.168021 -28.211281)
			(xy 19.223455 -28.423348) (xy 19.286597 -28.633249) (xy 19.357363 -28.840704) (xy 19.435659 -29.045436)
			(xy 19.52138 -29.247172) (xy 19.614411 -29.445643) (xy 19.71463 -29.640583) (xy 19.821901 -29.831733)
			(xy 19.936082 -30.018837) (xy 20.057021 -30.201647) (xy 20.184555 -30.379917) (xy 20.318516 -30.553411)
			(xy 20.458724 -30.721896) (xy 20.604991 -30.885148) (xy 20.757124 -31.042949) (xy 20.914918 -31.195088)
			(xy 21.078164 -31.341362) (xy 21.246643 -31.481577) (xy 21.420131 -31.615545) (xy 21.598396 -31.743087)
			(xy 21.7812 -31.864034) (xy 21.9683 -31.978223) (xy 22.159445 -32.085502) (xy 22.354381 -32.185729)
			(xy 22.552848 -32.278769) (xy 22.75458 -32.364498) (xy 22.959309 -32.442803) (xy 23.166761 -32.513578)
			(xy 23.376659 -32.576728) (xy 23.588724 -32.632171) (xy 23.802673 -32.679831) (xy 24.018219 -32.719646)
			(xy 24.235076 -32.751562) (xy 24.452953 -32.775536) (xy 24.671561 -32.791536) (xy 24.890608 -32.799542)
			(xy 25.1098 -32.799542) (xy 25.328847 -32.791536) (xy 25.547455 -32.775536) (xy 25.765332 -32.751562)
			(xy 25.982189 -32.719646) (xy 26.197735 -32.679831) (xy 26.411684 -32.632171) (xy 26.623749 -32.576728)
			(xy 26.833647 -32.513578) (xy 27.041099 -32.442803) (xy 27.245828 -32.364498) (xy 27.44756 -32.278769)
			(xy 27.646027 -32.185729) (xy 27.840963 -32.085502) (xy 28.032108 -31.978223) (xy 28.219208 -31.864034)
			(xy 28.402012 -31.743087) (xy 28.580277 -31.615545) (xy 28.753765 -31.481577) (xy 28.922244 -31.341362)
			(xy 29.08549 -31.195088) (xy 29.243284 -31.042949) (xy 29.395417 -30.885148) (xy 29.541684 -30.721896)
			(xy 29.681892 -30.553411) (xy 29.815853 -30.379917) (xy 29.943387 -30.201647) (xy 30.064326 -30.018837)
			(xy 30.178507 -29.831733) (xy 30.285778 -29.640583) (xy 30.385997 -29.445643) (xy 30.479028 -29.247172)
			(xy 30.564749 -29.045436) (xy 30.643045 -28.840704) (xy 30.713811 -28.633249) (xy 30.776953 -28.423348)
			(xy 30.832387 -28.211281) (xy 30.880038 -27.99733) (xy 30.919844 -27.781782) (xy 30.95175 -27.564924)
			(xy 30.975715 -27.347046) (xy 30.991706 -27.128437) (xy 30.999702 -26.90939) (xy 31.000192 -26.799794)
			(xy 30.999938 -21.75002) (xy 30.998539 -21.641017) (xy 30.988802 -21.423213) (xy 30.971159 -21.205907)
			(xy 30.945633 -20.989385) (xy 30.912258 -20.773934) (xy 30.871079 -20.559837) (xy 30.822148 -20.347377)
			(xy 30.765532 -20.136835) (xy 30.701305 -19.928489) (xy 30.629551 -19.722614) (xy 30.550365 -19.519481)
			(xy 30.463852 -19.319359) (xy 30.370126 -19.122512) (xy 30.269311 -18.9292) (xy 30.16154 -18.739678)
			(xy 30.046955 -18.554196) (xy 29.925707 -18.372999) (xy 29.797957 -18.196326) (xy 29.663873 -18.024411)
			(xy 29.523632 -17.857481) (xy 29.37742 -17.695755) (xy 29.225428 -17.539448) (xy 29.067859 -17.388766)
			(xy 28.90492 -17.243907) (xy 28.736826 -17.105063) (xy 28.563798 -16.972417) (xy 28.386067 -16.846145)
			(xy 28.203865 -16.726413) (xy 28.017434 -16.613379) (xy 27.827019 -16.507192) (xy 27.632873 -16.407992)
			(xy 27.435251 -16.315912) (xy 27.234415 -16.231071) (xy 27.030629 -16.153582) (xy 26.824162 -16.083547)
			(xy 26.615288 -16.02106) (xy 26.404281 -15.966201) (xy 26.191421 -15.919044) (xy 25.976988 -15.879652)
			(xy 25.761265 -15.848075) (xy 25.544538 -15.824356) (xy 25.327092 -15.808525) (xy 25.109215 -15.800605)
			(xy 24.891193 -15.800605) (xy 24.673316 -15.808525) (xy 24.45587 -15.824356) (xy 24.239143 -15.848075)
			(xy 24.02342 -15.879652) (xy 23.808987 -15.919044) (xy 23.596127 -15.966201) (xy 23.38512 -16.02106)
			(xy 23.176246 -16.083547) (xy 22.969779 -16.153582) (xy 22.765993 -16.231071) (xy 22.565157 -16.315912)
			(xy 22.367535 -16.407992) (xy 22.173389 -16.507192) (xy 21.982974 -16.613379) (xy 21.796543 -16.726413)
			(xy 21.614341 -16.846145) (xy 21.43661 -16.972417) (xy 21.263582 -17.105063) (xy 21.095488 -17.243907)
			(xy 20.932549 -17.388766) (xy 20.77498 -17.539448) (xy 20.622988 -17.695755) (xy 20.476776 -17.857481)
			(xy 20.336535 -18.024411) (xy 20.202451 -18.196326) (xy 20.074701 -18.372999) (xy 19.953453 -18.554196)
			(xy 19.838868 -18.739678) (xy 19.731097 -18.9292) (xy 19.630282 -19.122512) (xy 19.536556 -19.319359)
			(xy 19.450043 -19.519481) (xy 19.370857 -19.722614) (xy 19.299103 -19.928489) (xy 19.234876 -20.136835)
			(xy 19.17826 -20.347377) (xy 19.129329 -20.559837) (xy 19.08815 -20.773934) (xy 19.054775 -20.989385)
			(xy 19.029249 -21.205907) (xy 19.011606 -21.423213) (xy 19.001869 -21.641017) (xy 19.000504 -21.747375)
			(xy 20.989385 -21.747375) (xy 20.9957 -21.568987) (xy 21.009946 -21.391055) (xy 21.032093 -21.213934)
			(xy 21.062099 -21.037973) (xy 21.099904 -20.863522) (xy 21.145432 -20.690925) (xy 21.198594 -20.520525)
			(xy 21.259285 -20.352658) (xy 21.327384 -20.187658) (xy 21.402756 -20.025851) (xy 21.485252 -19.867558)
			(xy 21.57471 -19.713091) (xy 21.67095 -19.562758) (xy 21.773784 -19.416855) (xy 21.883008 -19.275671)
			(xy 21.998404 -19.139487) (xy 22.119745 -19.008571) (xy 22.24679 -18.883184) (xy 22.379288 -18.763573)
			(xy 22.516976 -18.649975) (xy 22.659582 -18.542616) (xy 22.806823 -18.441707) (xy 22.958408 -18.347449)
			(xy 23.114036 -18.260028) (xy 23.273399 -18.179618) (xy 23.436182 -18.106377) (xy 23.602062 -18.040451)
			(xy 23.770711 -17.981971) (xy 23.941795 -17.931051) (xy 24.114975 -17.887794) (xy 24.289908 -17.852284)
			(xy 24.466247 -17.824592) (xy 24.643644 -17.804772) (xy 24.821748 -17.792865) (xy 25.000204 -17.788893)
			(xy 25.17866 -17.792865) (xy 25.356764 -17.804772) (xy 25.534161 -17.824592) (xy 25.7105 -17.852284)
			(xy 25.885433 -17.887794) (xy 26.058613 -17.931051) (xy 26.229697 -17.981971) (xy 26.398346 -18.040451)
			(xy 26.564226 -18.106377) (xy 26.727009 -18.179618) (xy 26.886372 -18.260028) (xy 27.042 -18.347449)
			(xy 27.193585 -18.441707) (xy 27.340826 -18.542616) (xy 27.483432 -18.649975) (xy 27.62112 -18.763573)
			(xy 27.753618 -18.883184) (xy 27.880663 -19.008571) (xy 28.002004 -19.139487) (xy 28.1174 -19.275671)
			(xy 28.226624 -19.416855) (xy 28.329458 -19.562758) (xy 28.425698 -19.713091) (xy 28.515156 -19.867558)
			(xy 28.597652 -20.025851) (xy 28.673024 -20.187658) (xy 28.741123 -20.352658) (xy 28.801814 -20.520525)
			(xy 28.854976 -20.690925) (xy 28.900504 -20.863522) (xy 28.938309 -21.037973) (xy 28.968315 -21.213934)
			(xy 28.990462 -21.391055) (xy 29.004708 -21.568987) (xy 29.011023 -21.747375) (xy 29.009395 -21.925869)
			(xy 28.999828 -22.104113) (xy 28.982341 -22.281755) (xy 28.956967 -22.458443) (xy 28.923758 -22.633827)
			(xy 28.882778 -22.80756) (xy 28.83411 -22.979298) (xy 28.77785 -23.148701) (xy 28.714108 -23.315432)
			(xy 28.643012 -23.479163) (xy 28.564701 -23.639569) (xy 28.479332 -23.796332) (xy 28.387073 -23.949141)
			(xy 28.288107 -24.097695) (xy 28.18263 -24.241699) (xy 28.07085 -24.380867) (xy 27.95299 -24.514924)
			(xy 27.829282 -24.643605) (xy 27.699971 -24.766655) (xy 27.565314 -24.88383) (xy 27.495754 -24.939752)
			(xy 27.471461 -24.95972) (xy 27.427626 -25.004806) (xy 27.389935 -25.055141) (xy 27.359009 -25.109894)
			(xy 27.335359 -25.16816) (xy 27.319376 -25.228977) (xy 27.311323 -25.291342) (xy 27.310842 -25.322784)
			(xy 27.310842 -26.800048) (xy 27.310335 -26.868535) (xy 27.30222 -27.005268) (xy 27.28602 -27.141281)
			(xy 27.26179 -27.276095) (xy 27.229617 -27.409236) (xy 27.189613 -27.540238) (xy 27.141919 -27.66864)
			(xy 27.086701 -27.793991) (xy 27.024155 -27.915851) (xy 26.954499 -28.033791) (xy 26.877979 -28.147398)
			(xy 26.794864 -28.256273) (xy 26.705444 -28.360032) (xy 26.610035 -28.458312) (xy 26.508971 -28.550767)
			(xy 26.402607 -28.637072) (xy 26.291318 -28.716925) (xy 26.175493 -28.790045) (xy 26.055541 -28.856175)
			(xy 25.931881 -28.915083) (xy 25.804949 -28.966561) (xy 25.67519 -29.01043) (xy 25.54306 -29.046534)
			(xy 25.409023 -29.074748) (xy 25.273551 -29.094972) (xy 25.137118 -29.107135) (xy 25.000204 -29.111194)
			(xy 24.86329 -29.107135) (xy 24.726857 -29.094972) (xy 24.591385 -29.074748) (xy 24.457348 -29.046534)
			(xy 24.325218 -29.01043) (xy 24.195459 -28.966561) (xy 24.068527 -28.915083) (xy 23.944867 -28.856175)
			(xy 23.824915 -28.790045) (xy 23.70909 -28.716925) (xy 23.597801 -28.637072) (xy 23.491437 -28.550767)
			(xy 23.390373 -28.458312) (xy 23.294964 -28.360032) (xy 23.205544 -28.256273) (xy 23.122429 -28.147398)
			(xy 23.045909 -28.033791) (xy 22.976253 -27.915851) (xy 22.913707 -27.793991) (xy 22.858489 -27.66864)
			(xy 22.810795 -27.540238) (xy 22.770791 -27.409236) (xy 22.738618 -27.276095) (xy 22.714388 -27.141281)
			(xy 22.698188 -27.005268) (xy 22.690073 -26.868535) (xy 22.689566 -26.800048) (xy 22.689566 -25.322784)
			(xy 22.689046 -25.291346) (xy 22.68096 -25.228992) (xy 22.664962 -25.168185) (xy 22.641316 -25.109925)
			(xy 22.610408 -25.05517) (xy 22.572749 -25.00482) (xy 22.528956 -24.959702) (xy 22.504654 -24.939752)
			(xy 22.435094 -24.88383) (xy 22.300437 -24.766655) (xy 22.171126 -24.643605) (xy 22.047418 -24.514924)
			(xy 21.929558 -24.380867) (xy 21.817778 -24.241699) (xy 21.712301 -24.097695) (xy 21.613335 -23.949141)
			(xy 21.521076 -23.796332) (xy 21.435707 -23.639569) (xy 21.357396 -23.479163) (xy 21.2863 -23.315432)
			(xy 21.222558 -23.148701) (xy 21.166298 -22.979298) (xy 21.11763 -22.80756) (xy 21.07665 -22.633827)
			(xy 21.043441 -22.458443) (xy 21.018067 -22.281755) (xy 21.00058 -22.104113) (xy 20.991013 -21.925869)
			(xy 20.989385 -21.747375) (xy 19.000504 -21.747375) (xy 19.00047 -21.75002)
		)
		(stroke
			(width 0)
			(type solid)
		)
		(fill yes)
		(layer "B.Cu")
		(net "GND")
	)
	(gr_poly
		(pts
			(xy 169.00017 -182.749952) (xy 169.00067 -182.859545) (xy 169.008676 -183.078586) (xy 169.024675 -183.297187)
			(xy 169.048648 -183.515059) (xy 169.080562 -183.73191) (xy 169.120374 -183.94745) (xy 169.168032 -184.161393)
			(xy 169.223471 -184.373452) (xy 169.286619 -184.583346) (xy 169.35739 -184.790792) (xy 169.43569 -184.995516)
			(xy 169.521415 -185.197244) (xy 169.61445 -185.395706) (xy 169.714671 -185.590638) (xy 169.821945 -185.781779)
			(xy 169.936128 -185.968875) (xy 170.057068 -186.151676) (xy 170.184604 -186.329938) (xy 170.318565 -186.503424)
			(xy 170.458773 -186.671901) (xy 170.60504 -186.835145) (xy 170.757172 -186.992938) (xy 170.914965 -187.14507)
			(xy 171.078209 -187.291337) (xy 171.246686 -187.431545) (xy 171.420172 -187.565506) (xy 171.598434 -187.693042)
			(xy 171.781235 -187.813982) (xy 171.968331 -187.928165) (xy 172.159472 -188.035439) (xy 172.354404 -188.13566)
			(xy 172.552866 -188.228695) (xy 172.754594 -188.31442) (xy 172.959318 -188.39272) (xy 173.166764 -188.463491)
			(xy 173.376658 -188.526639) (xy 173.588717 -188.582078) (xy 173.80266 -188.629736) (xy 174.0182 -188.669548)
			(xy 174.235051 -188.701462) (xy 174.452923 -188.725435) (xy 174.671524 -188.741434) (xy 174.890565 -188.74944)
			(xy 175.109751 -188.74944) (xy 175.328792 -188.741434) (xy 175.547393 -188.725435) (xy 175.765265 -188.701462)
			(xy 175.982116 -188.669548) (xy 176.197656 -188.629736) (xy 176.411599 -188.582078) (xy 176.623658 -188.526639)
			(xy 176.833552 -188.463491) (xy 177.040998 -188.39272) (xy 177.245722 -188.31442) (xy 177.44745 -188.228695)
			(xy 177.645912 -188.13566) (xy 177.840844 -188.035439) (xy 178.031985 -187.928165) (xy 178.219081 -187.813982)
			(xy 178.401882 -187.693042) (xy 178.580144 -187.565506) (xy 178.75363 -187.431545) (xy 178.922107 -187.291337)
			(xy 179.085351 -187.14507) (xy 179.243144 -186.992938) (xy 179.395276 -186.835145) (xy 179.541543 -186.671901)
			(xy 179.681751 -186.503424) (xy 179.815712 -186.329938) (xy 179.943248 -186.151676) (xy 180.064188 -185.968875)
			(xy 180.178371 -185.781779) (xy 180.285645 -185.590638) (xy 180.385866 -185.395706) (xy 180.478901 -185.197244)
			(xy 180.564626 -184.995516) (xy 180.642926 -184.790792) (xy 180.713697 -184.583346) (xy 180.776845 -184.373452)
			(xy 180.832284 -184.161393) (xy 180.879942 -183.94745) (xy 180.919754 -183.73191) (xy 180.951668 -183.515059)
			(xy 180.975641 -183.297187) (xy 180.99164 -183.078586) (xy 180.999646 -182.859545) (xy 181.000146 -182.749952)
			(xy 181.000146 -177.749962) (xy 180.999646 -177.640369) (xy 180.99164 -177.421328) (xy 180.975641 -177.202727)
			(xy 180.951668 -176.984855) (xy 180.919754 -176.768004) (xy 180.879942 -176.552464) (xy 180.832284 -176.338521)
			(xy 180.776845 -176.126462) (xy 180.713697 -175.916568) (xy 180.642926 -175.709122) (xy 180.564626 -175.504398)
			(xy 180.478901 -175.30267) (xy 180.385866 -175.104208) (xy 180.285645 -174.909276) (xy 180.178371 -174.718135)
			(xy 180.064188 -174.531039) (xy 179.943248 -174.348238) (xy 179.815712 -174.169976) (xy 179.681751 -173.99649)
			(xy 179.541543 -173.828013) (xy 179.395276 -173.664769) (xy 179.243144 -173.506976) (xy 179.085351 -173.354844)
			(xy 178.922107 -173.208577) (xy 178.75363 -173.068369) (xy 178.580144 -172.934408) (xy 178.401882 -172.806872)
			(xy 178.219081 -172.685932) (xy 178.031985 -172.571749) (xy 177.840844 -172.464475) (xy 177.645912 -172.364254)
			(xy 177.44745 -172.271219) (xy 177.245722 -172.185494) (xy 177.040998 -172.107194) (xy 176.833552 -172.036423)
			(xy 176.623658 -171.973275) (xy 176.411599 -171.917836) (xy 176.197656 -171.870178) (xy 175.982116 -171.830366)
			(xy 175.765265 -171.798452) (xy 175.547393 -171.774479) (xy 175.328792 -171.75848) (xy 175.109751 -171.750474)
			(xy 174.890565 -171.750474) (xy 174.671524 -171.75848) (xy 174.452923 -171.774479) (xy 174.235051 -171.798452)
			(xy 174.0182 -171.830366) (xy 173.80266 -171.870178) (xy 173.588717 -171.917836) (xy 173.376658 -171.973275)
			(xy 173.166764 -172.036423) (xy 172.959318 -172.107194) (xy 172.754594 -172.185494) (xy 172.552866 -172.271219)
			(xy 172.354404 -172.364254) (xy 172.159472 -172.464475) (xy 171.968331 -172.571749) (xy 171.781235 -172.685932)
			(xy 171.598434 -172.806872) (xy 171.420172 -172.934408) (xy 171.246686 -173.068369) (xy 171.078209 -173.208577)
			(xy 170.914965 -173.354844) (xy 170.757172 -173.506976) (xy 170.60504 -173.664769) (xy 170.458773 -173.828013)
			(xy 170.318565 -173.99649) (xy 170.184604 -174.169976) (xy 170.057068 -174.348238) (xy 169.936128 -174.531039)
			(xy 169.821945 -174.718135) (xy 169.714671 -174.909276) (xy 169.61445 -175.104208) (xy 169.521415 -175.30267)
			(xy 169.43569 -175.504398) (xy 169.35739 -175.709122) (xy 169.286619 -175.916568) (xy 169.223471 -176.126462)
			(xy 169.168032 -176.338521) (xy 169.120374 -176.552464) (xy 169.080562 -176.768004) (xy 169.048648 -176.984855)
			(xy 169.024675 -177.202727) (xy 169.008676 -177.421328) (xy 169.00067 -177.640369) (xy 169.000224 -177.738164)
			(xy 170.98885 -177.738164) (xy 170.993402 -177.558564) (xy 171.005992 -177.379348) (xy 171.026595 -177.200876)
			(xy 171.055168 -177.023506) (xy 171.091656 -176.847593) (xy 171.135984 -176.67349) (xy 171.188064 -176.501547)
			(xy 171.247792 -176.332108) (xy 171.315046 -176.165514) (xy 171.389694 -176.002099) (xy 171.471584 -175.84219)
			(xy 171.560552 -175.686108) (xy 171.656421 -175.534168) (xy 171.758997 -175.386672) (xy 171.868075 -175.243918)
			(xy 171.983436 -175.106191) (xy 172.104849 -174.973769) (xy 172.232069 -174.846916) (xy 172.364843 -174.725887)
			(xy 172.502903 -174.610925) (xy 172.645972 -174.502261) (xy 172.793764 -174.400112) (xy 172.945981 -174.304683)
			(xy 173.102319 -174.216167) (xy 173.262464 -174.13474) (xy 173.426095 -174.060566) (xy 173.592883 -173.993794)
			(xy 173.762494 -173.934557) (xy 173.934587 -173.882975) (xy 174.108817 -173.839151) (xy 174.284835 -173.803172)
			(xy 174.462288 -173.775112) (xy 174.640819 -173.755026) (xy 174.820071 -173.742955) (xy 174.999683 -173.738923)
			(xy 175.179295 -173.742937) (xy 175.358548 -173.754991) (xy 175.537081 -173.775059) (xy 175.714536 -173.803102)
			(xy 175.890558 -173.839063) (xy 176.064792 -173.88287) (xy 176.236891 -173.934435) (xy 176.406507 -173.993655)
			(xy 176.573302 -174.060411) (xy 176.73694 -174.134569) (xy 176.897093 -174.21598) (xy 177.05344 -174.304481)
			(xy 177.205667 -174.399895) (xy 177.353469 -174.502029) (xy 177.496549 -174.610679) (xy 177.63462 -174.725628)
			(xy 177.767405 -174.846643) (xy 177.894638 -174.973484) (xy 178.016064 -175.105895) (xy 178.131439 -175.24361)
			(xy 178.240531 -175.386353) (xy 178.343121 -175.533839) (xy 178.439005 -175.68577) (xy 178.527989 -175.841843)
			(xy 178.609894 -176.001743) (xy 178.684558 -176.165151) (xy 178.751829 -176.331739) (xy 178.811573 -176.501171)
			(xy 178.86367 -176.67311) (xy 178.908015 -176.847208) (xy 178.94452 -177.023118) (xy 178.973111 -177.200485)
			(xy 178.993731 -177.378955) (xy 179.006339 -177.55817) (xy 179.010909 -177.737769) (xy 179.007432 -177.917393)
			(xy 178.995915 -178.096681) (xy 178.976381 -178.275273) (xy 178.948869 -178.452812) (xy 178.913435 -178.62894)
			(xy 178.870149 -178.803305) (xy 178.8191 -178.975557) (xy 178.760387 -179.14535) (xy 178.694131 -179.312343)
			(xy 178.620463 -179.476203) (xy 178.539532 -179.636599) (xy 178.451499 -179.79321) (xy 178.356541 -179.945721)
			(xy 178.25485 -180.093828) (xy 178.146628 -180.237233) (xy 178.032094 -180.375647) (xy 177.911476 -180.508794)
			(xy 177.785016 -180.636406) (xy 177.65297 -180.758228) (xy 177.584608 -180.816504) (xy 177.561635 -180.8365)
			(xy 177.520284 -180.881217) (xy 177.484805 -180.930722) (xy 177.455747 -180.98425) (xy 177.433561 -181.040971)
			(xy 177.418589 -181.100008) (xy 177.411064 -181.160447) (xy 177.410618 -181.1909) (xy 177.410618 -182.749952)
			(xy 177.410126 -182.818799) (xy 177.402265 -182.956269) (xy 177.386569 -183.093066) (xy 177.36309 -183.228744)
			(xy 177.331902 -183.36286) (xy 177.293109 -183.494977) (xy 177.246837 -183.624664) (xy 177.193237 -183.751497)
			(xy 177.132483 -183.875064) (xy 177.064774 -183.994961) (xy 176.990331 -184.110797) (xy 176.909396 -184.222194)
			(xy 176.822234 -184.328789) (xy 176.729128 -184.430235) (xy 176.630383 -184.526199) (xy 176.52632 -184.61637)
			(xy 176.41728 -184.700453) (xy 176.303617 -184.778173) (xy 176.185702 -184.849279) (xy 176.063921 -184.913536)
			(xy 175.938669 -184.970736) (xy 175.810357 -185.020693) (xy 175.679402 -185.063243) (xy 175.546231 -185.098247)
			(xy 175.411279 -185.125592) (xy 175.274986 -185.145188) (xy 175.137796 -185.156971) (xy 175.000158 -185.160904)
			(xy 174.86252 -185.156971) (xy 174.72533 -185.145188) (xy 174.589037 -185.125592) (xy 174.454085 -185.098247)
			(xy 174.320914 -185.063243) (xy 174.189959 -185.020693) (xy 174.061647 -184.970736) (xy 173.936395 -184.913536)
			(xy 173.814614 -184.849279) (xy 173.696699 -184.778173) (xy 173.583036 -184.700453) (xy 173.473996 -184.61637)
			(xy 173.369933 -184.526199) (xy 173.271188 -184.430235) (xy 173.178082 -184.328789) (xy 173.09092 -184.222194)
			(xy 173.009985 -184.110797) (xy 172.935542 -183.994961) (xy 172.867833 -183.875064) (xy 172.807079 -183.751497)
			(xy 172.753479 -183.624664) (xy 172.707207 -183.494977) (xy 172.668414 -183.36286) (xy 172.637226 -183.228744)
			(xy 172.613747 -183.093066) (xy 172.598051 -182.956269) (xy 172.59019 -182.818799) (xy 172.589698 -182.749952)
			(xy 172.589698 -181.1909) (xy 172.589235 -181.160458) (xy 172.581636 -181.100048) (xy 172.566606 -181.041047)
			(xy 172.544377 -180.984365) (xy 172.515291 -180.930876) (xy 172.479797 -180.881406) (xy 172.438444 -180.836719)
			(xy 172.415454 -180.816758) (xy 172.347086 -180.758489) (xy 172.215028 -180.63668) (xy 172.088556 -180.509081)
			(xy 171.967925 -180.375946) (xy 171.853377 -180.237542) (xy 171.745141 -180.094149) (xy 171.643435 -179.946052)
			(xy 171.548462 -179.793549) (xy 171.460414 -179.636947) (xy 171.379467 -179.476559) (xy 171.305783 -179.312707)
			(xy 171.23951 -179.14572) (xy 171.180781 -178.975933) (xy 171.129714 -178.803686) (xy 171.086412 -178.629325)
			(xy 171.05096 -178.4532) (xy 171.023431 -178.275664) (xy 171.00388 -178.097074) (xy 170.992345 -177.917787)
			(xy 170.98885 -177.738164) (xy 169.000224 -177.738164) (xy 169.00017 -177.749962)
		)
		(stroke
			(width 0)
			(type solid)
		)
		(fill yes)
		(layer "B.Cu")
		(net "GND")
	)
	(gr_poly
		(pts
			(xy 169.00017 -26.75001) (xy 169.00067 -26.859603) (xy 169.008676 -27.078644) (xy 169.024675 -27.297245)
			(xy 169.048648 -27.515117) (xy 169.080562 -27.731968) (xy 169.120374 -27.947508) (xy 169.168032 -28.161451)
			(xy 169.223471 -28.37351) (xy 169.286619 -28.583404) (xy 169.35739 -28.79085) (xy 169.43569 -28.995574)
			(xy 169.521415 -29.197302) (xy 169.61445 -29.395764) (xy 169.714671 -29.590696) (xy 169.821945 -29.781837)
			(xy 169.936128 -29.968933) (xy 170.057068 -30.151734) (xy 170.184604 -30.329996) (xy 170.318565 -30.503482)
			(xy 170.458773 -30.671959) (xy 170.60504 -30.835203) (xy 170.757172 -30.992996) (xy 170.914965 -31.145128)
			(xy 171.078209 -31.291395) (xy 171.246686 -31.431603) (xy 171.420172 -31.565564) (xy 171.598434 -31.6931)
			(xy 171.781235 -31.81404) (xy 171.968331 -31.928223) (xy 172.159472 -32.035497) (xy 172.354404 -32.135718)
			(xy 172.552866 -32.228753) (xy 172.754594 -32.314478) (xy 172.959318 -32.392778) (xy 173.166764 -32.463549)
			(xy 173.376658 -32.526697) (xy 173.588717 -32.582136) (xy 173.80266 -32.629794) (xy 174.0182 -32.669606)
			(xy 174.235051 -32.70152) (xy 174.452923 -32.725493) (xy 174.671524 -32.741492) (xy 174.890565 -32.749498)
			(xy 175.109751 -32.749498) (xy 175.328792 -32.741492) (xy 175.547393 -32.725493) (xy 175.765265 -32.70152)
			(xy 175.982116 -32.669606) (xy 176.197656 -32.629794) (xy 176.411599 -32.582136) (xy 176.623658 -32.526697)
			(xy 176.833552 -32.463549) (xy 177.040998 -32.392778) (xy 177.245722 -32.314478) (xy 177.44745 -32.228753)
			(xy 177.645912 -32.135718) (xy 177.840844 -32.035497) (xy 178.031985 -31.928223) (xy 178.219081 -31.81404)
			(xy 178.401882 -31.6931) (xy 178.580144 -31.565564) (xy 178.75363 -31.431603) (xy 178.922107 -31.291395)
			(xy 179.085351 -31.145128) (xy 179.243144 -30.992996) (xy 179.395276 -30.835203) (xy 179.541543 -30.671959)
			(xy 179.681751 -30.503482) (xy 179.815712 -30.329996) (xy 179.943248 -30.151734) (xy 180.064188 -29.968933)
			(xy 180.178371 -29.781837) (xy 180.285645 -29.590696) (xy 180.385866 -29.395764) (xy 180.478901 -29.197302)
			(xy 180.564626 -28.995574) (xy 180.642926 -28.79085) (xy 180.713697 -28.583404) (xy 180.776845 -28.37351)
			(xy 180.832284 -28.161451) (xy 180.879942 -27.947508) (xy 180.919754 -27.731968) (xy 180.951668 -27.515117)
			(xy 180.975641 -27.297245) (xy 180.99164 -27.078644) (xy 180.999646 -26.859603) (xy 181.000146 -26.75001)
			(xy 181.000146 -21.75002) (xy 180.999646 -21.640427) (xy 180.99164 -21.421386) (xy 180.975641 -21.202785)
			(xy 180.951668 -20.984913) (xy 180.919754 -20.768062) (xy 180.879942 -20.552522) (xy 180.832284 -20.338579)
			(xy 180.776845 -20.12652) (xy 180.713697 -19.916626) (xy 180.642926 -19.70918) (xy 180.564626 -19.504456)
			(xy 180.478901 -19.302728) (xy 180.385866 -19.104266) (xy 180.285645 -18.909334) (xy 180.178371 -18.718193)
			(xy 180.064188 -18.531097) (xy 179.943248 -18.348296) (xy 179.815712 -18.170034) (xy 179.681751 -17.996548)
			(xy 179.541543 -17.828071) (xy 179.395276 -17.664827) (xy 179.243144 -17.507034) (xy 179.085351 -17.354902)
			(xy 178.922107 -17.208635) (xy 178.75363 -17.068427) (xy 178.580144 -16.934466) (xy 178.401882 -16.80693)
			(xy 178.219081 -16.68599) (xy 178.031985 -16.571807) (xy 177.840844 -16.464533) (xy 177.645912 -16.364312)
			(xy 177.44745 -16.271277) (xy 177.245722 -16.185552) (xy 177.040998 -16.107252) (xy 176.833552 -16.036481)
			(xy 176.623658 -15.973333) (xy 176.411599 -15.917894) (xy 176.197656 -15.870236) (xy 175.982116 -15.830424)
			(xy 175.765265 -15.79851) (xy 175.547393 -15.774537) (xy 175.328792 -15.758538) (xy 175.109751 -15.750532)
			(xy 174.890565 -15.750532) (xy 174.671524 -15.758538) (xy 174.452923 -15.774537) (xy 174.235051 -15.79851)
			(xy 174.0182 -15.830424) (xy 173.80266 -15.870236) (xy 173.588717 -15.917894) (xy 173.376658 -15.973333)
			(xy 173.166764 -16.036481) (xy 172.959318 -16.107252) (xy 172.754594 -16.185552) (xy 172.552866 -16.271277)
			(xy 172.354404 -16.364312) (xy 172.159472 -16.464533) (xy 171.968331 -16.571807) (xy 171.781235 -16.68599)
			(xy 171.598434 -16.80693) (xy 171.420172 -16.934466) (xy 171.246686 -17.068427) (xy 171.078209 -17.208635)
			(xy 170.914965 -17.354902) (xy 170.757172 -17.507034) (xy 170.60504 -17.664827) (xy 170.458773 -17.828071)
			(xy 170.318565 -17.996548) (xy 170.184604 -18.170034) (xy 170.057068 -18.348296) (xy 169.936128 -18.531097)
			(xy 169.821945 -18.718193) (xy 169.714671 -18.909334) (xy 169.61445 -19.104266) (xy 169.521415 -19.302728)
			(xy 169.43569 -19.504456) (xy 169.35739 -19.70918) (xy 169.286619 -19.916626) (xy 169.223471 -20.12652)
			(xy 169.168032 -20.338579) (xy 169.120374 -20.552522) (xy 169.080562 -20.768062) (xy 169.048648 -20.984913)
			(xy 169.024675 -21.202785) (xy 169.008676 -21.421386) (xy 169.00067 -21.640427) (xy 169.000224 -21.738223)
			(xy 170.988852 -21.738223) (xy 170.993404 -21.558623) (xy 171.005994 -21.379408) (xy 171.026596 -21.200936)
			(xy 171.05517 -21.023565) (xy 171.091658 -20.847652) (xy 171.135986 -20.673549) (xy 171.188066 -20.501606)
			(xy 171.247793 -20.332168) (xy 171.315048 -20.165574) (xy 171.389695 -20.002159) (xy 171.471585 -19.84225)
			(xy 171.560554 -19.686169) (xy 171.656422 -19.534228) (xy 171.758998 -19.386733) (xy 171.868076 -19.243979)
			(xy 171.983437 -19.106252) (xy 172.10485 -18.97383) (xy 172.232071 -18.846977) (xy 172.364844 -18.725948)
			(xy 172.502904 -18.610986) (xy 172.645973 -18.502322) (xy 172.793765 -18.400173) (xy 172.945982 -18.304744)
			(xy 173.10232 -18.216228) (xy 173.262465 -18.134801) (xy 173.426096 -18.060627) (xy 173.592884 -17.993855)
			(xy 173.762495 -17.934618) (xy 173.934588 -17.883036) (xy 174.108818 -17.839212) (xy 174.284836 -17.803234)
			(xy 174.462288 -17.775174) (xy 174.640819 -17.755088) (xy 174.820071 -17.743017) (xy 174.999683 -17.738984)
			(xy 175.179295 -17.742999) (xy 175.358548 -17.755052) (xy 175.537081 -17.775121) (xy 175.714536 -17.803163)
			(xy 175.890557 -17.839124) (xy 176.064792 -17.882931) (xy 176.23689 -17.934497) (xy 176.406507 -17.993717)
			(xy 176.573301 -18.060472) (xy 176.736939 -18.13463) (xy 176.897092 -18.216041) (xy 177.053439 -18.304542)
			(xy 177.205666 -18.399956) (xy 177.353467 -18.50209) (xy 177.496547 -18.61074) (xy 177.634618 -18.725689)
			(xy 177.767404 -18.846704) (xy 177.894637 -18.973545) (xy 178.016063 -19.105955) (xy 178.131437 -19.24367)
			(xy 178.240529 -19.386414) (xy 178.34312 -19.533899) (xy 178.439003 -19.68583) (xy 178.527987 -19.841903)
			(xy 178.609893 -20.001803) (xy 178.684556 -20.165211) (xy 178.751827 -20.331799) (xy 178.811571 -20.501231)
			(xy 178.863668 -20.673169) (xy 178.908014 -20.847268) (xy 178.944519 -21.023177) (xy 178.97311 -21.200545)
			(xy 178.99373 -21.379015) (xy 179.006337 -21.558229) (xy 179.010907 -21.737828) (xy 179.00743 -21.917452)
			(xy 178.995913 -22.09674) (xy 178.976379 -22.275332) (xy 178.948868 -22.45287) (xy 178.913434 -22.628999)
			(xy 178.870148 -22.803364) (xy 178.819098 -22.975615) (xy 178.760386 -23.145408) (xy 178.69413 -23.312402)
			(xy 178.620462 -23.476261) (xy 178.539531 -23.636657) (xy 178.451498 -23.793268) (xy 178.356541 -23.94578)
			(xy 178.254849 -24.093886) (xy 178.146628 -24.237291) (xy 178.032093 -24.375705) (xy 177.911475 -24.508852)
			(xy 177.785016 -24.636464) (xy 177.65297 -24.758286) (xy 177.584608 -24.816562) (xy 177.561607 -24.836527)
			(xy 177.520257 -24.88125) (xy 177.484781 -24.93076) (xy 177.455727 -24.984293) (xy 177.433545 -25.041019)
			(xy 177.418579 -25.10006) (xy 177.41106 -25.160503) (xy 177.410618 -25.190958) (xy 177.410618 -26.75001)
			(xy 177.410126 -26.818857) (xy 177.402265 -26.956327) (xy 177.386569 -27.093124) (xy 177.36309 -27.228802)
			(xy 177.331902 -27.362918) (xy 177.293109 -27.495035) (xy 177.246837 -27.624722) (xy 177.193237 -27.751555)
			(xy 177.132483 -27.875122) (xy 177.064774 -27.995019) (xy 176.990331 -28.110855) (xy 176.909396 -28.222252)
			(xy 176.822234 -28.328847) (xy 176.729128 -28.430293) (xy 176.630383 -28.526257) (xy 176.52632 -28.616428)
			(xy 176.41728 -28.700511) (xy 176.303617 -28.778231) (xy 176.185702 -28.849337) (xy 176.063921 -28.913594)
			(xy 175.938669 -28.970794) (xy 175.810357 -29.020751) (xy 175.679402 -29.063301) (xy 175.546231 -29.098305)
			(xy 175.411279 -29.12565) (xy 175.274986 -29.145246) (xy 175.137796 -29.157029) (xy 175.000158 -29.160962)
			(xy 174.86252 -29.157029) (xy 174.72533 -29.145246) (xy 174.589037 -29.12565) (xy 174.454085 -29.098305)
			(xy 174.320914 -29.063301) (xy 174.189959 -29.020751) (xy 174.061647 -28.970794) (xy 173.936395 -28.913594)
			(xy 173.814614 -28.849337) (xy 173.696699 -28.778231) (xy 173.583036 -28.700511) (xy 173.473996 -28.616428)
			(xy 173.369933 -28.526257) (xy 173.271188 -28.430293) (xy 173.178082 -28.328847) (xy 173.09092 -28.222252)
			(xy 173.009985 -28.110855) (xy 172.935542 -27.995019) (xy 172.867833 -27.875122) (xy 172.807079 -27.751555)
			(xy 172.753479 -27.624722) (xy 172.707207 -27.495035) (xy 172.668414 -27.362918) (xy 172.637226 -27.228802)
			(xy 172.613747 -27.093124) (xy 172.598051 -26.956327) (xy 172.59019 -26.818857) (xy 172.589698 -26.75001)
			(xy 172.589698 -25.190958) (xy 172.589194 -25.160517) (xy 172.581603 -25.100109) (xy 172.56658 -25.041109)
			(xy 172.544357 -24.984427) (xy 172.515277 -24.930937) (xy 172.479789 -24.881467) (xy 172.438441 -24.836778)
			(xy 172.415454 -24.816816) (xy 172.347086 -24.758547) (xy 172.215028 -24.636738) (xy 172.088556 -24.509139)
			(xy 171.967925 -24.376004) (xy 171.853377 -24.237601) (xy 171.745141 -24.094207) (xy 171.643435 -23.94611)
			(xy 171.548463 -23.793607) (xy 171.460415 -23.637005) (xy 171.379468 -23.476617) (xy 171.305784 -23.312765)
			(xy 171.239511 -23.145778) (xy 171.180782 -22.975991) (xy 171.129715 -22.803744) (xy 171.086413 -22.629384)
			(xy 171.050962 -22.453259) (xy 171.023432 -22.275723) (xy 171.003881 -22.097133) (xy 170.992346 -21.917846)
			(xy 170.988852 -21.738223) (xy 169.000224 -21.738223) (xy 169.00017 -21.75002)
		)
		(stroke
			(width 0)
			(type solid)
		)
		(fill yes)
		(layer "B.Cu")
		(net "GND")
	)
	(gr_poly
		(pts
			(arc
				(start 66.29654 -69.454014)
				(mid 66.495259 -69.358532)
				(end 66.544444 -69.143626)
			)
			(arc
				(start 66.544444 -69.143626)
				(mid 66.428493 -68.85005)
				(end 66.5734 -68.569586)
			)
			(arc
				(start 66.5734 -68.569586)
				(mid 66.586762 -68.488306)
				(end 66.5734 -68.407026)
			)
			(arc
				(start 66.5734 -68.407026)
				(mid 66.427906 -68.107306)
				(end 66.5734 -67.807586)
			)
			(arc
				(start 66.5734 -67.807586)
				(mid 66.586762 -67.726306)
				(end 66.5734 -67.645026)
			)
			(arc
				(start 66.5734 -67.645026)
				(mid 66.427906 -67.345306)
				(end 66.5734 -67.045586)
			)
			(arc
				(start 66.5734 -67.045586)
				(mid 66.586842 -66.963369)
				(end 66.572892 -66.881248)
			)
			(arc
				(start 66.552064 -66.8528)
				(mid 66.45349 -66.7961)
				(end 66.349118 -66.841116)
			)
			(arc
				(start 66.349118 -66.841116)
				(mid 66.060785 -66.976929)
				(end 65.769998 -66.84645)
			)
			(arc
				(start 65.769998 -66.84645)
				(mid 65.687309 -66.837576)
				(end 65.606168 -66.855848)
			)
			(arc
				(start 65.606168 -66.855848)
				(mid 65.246686 -67.084146)
				(end 64.899794 -66.837306)
			)
			(arc
				(start 64.899794 -66.837306)
				(mid 64.853165 -66.777704)
				(end 64.780922 -66.755264)
			)
			(arc
				(start 64.643762 -66.755264)
				(mid 64.579134 -66.772938)
				(end 64.53251 -66.82105)
			)
			(xy 64.511936 -66.855086) (xy 64.4906 -66.88709) (xy 64.4906 -66.94424)
			(arc
				(start 64.435736 -66.94424)
				(mid 64.209455 -67.060579)
				(end 63.955422 -67.04584)
			)
			(arc
				(start 63.955422 -67.04584)
				(mid 63.83194 -67.039859)
				(end 63.720218 -67.09283)
			)
			(arc
				(start 63.720218 -67.09283)
				(mid 63.340732 -67.36033)
				(end 62.983872 -67.063366)
			)
			(arc
				(start 62.983872 -67.063366)
				(mid 62.937075 -66.990351)
				(end 62.854332 -66.964306)
			)
			(arc
				(start 62.854332 -66.964306)
				(mid 62.826237 -66.964581)
				(end 62.798198 -66.962782)
			)
			(arc
				(start 62.798198 -66.962782)
				(mid 62.619337 -67.012884)
				(end 62.522354 -67.171316)
			)
			(arc
				(start 61.750956 -67.171316)
				(mid 61.641933 -67.007845)
				(end 61.44895 -66.971164)
			)
			(arc
				(start 61.44895 -66.971164)
				(mid 61.402844 -66.978075)
				(end 61.35624 -66.979292)
			)
			(xy 61.311536 -66.977768) (xy 61.226446 -67.041014)
			(arc
				(start 61.214 -67.079876)
				(mid 61.18594 -67.146099)
				(end 61.145928 -67.20586)
			)
			(xy 61.117226 -67.240912) (xy 61.117226 -67.4497)
			(arc
				(start 61.145928 -67.484752)
				(mid 61.190616 -67.553414)
				(end 61.219588 -67.63004)
			)
			(xy 61.23051 -67.671188) (xy 61.318902 -67.741292)
			(arc
				(start 61.364114 -67.74053)
				(mid 61.625113 -67.838586)
				(end 61.749686 -68.088002)
			)
			(arc
				(start 61.749686 -68.088002)
				(mid 61.831249 -68.252818)
				(end 62.00267 -68.319396)
			)
			(arc
				(start 62.202568 -68.319396)
				(mid 62.376146 -68.250832)
				(end 62.45606 -68.08216)
			)
			(arc
				(start 62.45606 -68.08216)
				(mid 62.876979 -67.727851)
				(end 63.21425 -68.162424)
			)
			(xy 63.209932 -68.192142) (xy 63.228728 -68.249038) (xy 63.3349 -68.355464) (xy 63.638938 -68.355464)
			(xy 63.923418 -68.63969) (xy 64.811148 -68.63969) (xy 64.851788 -68.68033) (xy 64.989964 -68.68033)
			(arc
				(start 65.031874 -68.662296)
				(mid 65.058897 -68.628666)
				(end 65.089532 -68.598288)
			)
			(arc
				(start 65.089532 -68.598288)
				(mid 65.132505 -68.503038)
				(end 65.089532 -68.407788)
			)
			(arc
				(start 65.089532 -68.407788)
				(mid 65.010086 -68.309614)
				(end 64.967104 -68.190872)
			)
			(arc
				(start 64.967104 -68.190872)
				(mid 64.925324 -68.117714)
				(end 64.846962 -68.086732)
			)
			(arc
				(start 64.846962 -68.086732)
				(mid 64.572682 -67.455834)
				(end 65.236344 -67.636644)
			)
			(arc
				(start 65.236344 -67.636644)
				(mid 65.278124 -67.709802)
				(end 65.356486 -67.740784)
			)
			(arc
				(start 65.356486 -67.740784)
				(mid 65.70503 -68.0039)
				(end 65.578228 -68.421758)
			)
			(arc
				(start 65.578228 -68.421758)
				(mid 65.564866 -68.503038)
				(end 65.578228 -68.584318)
			)
			(arc
				(start 65.578228 -68.584318)
				(mid 65.72337 -68.867647)
				(end 65.60312 -69.162422)
			)
			(arc
				(start 65.60312 -69.162422)
				(mid 65.562958 -69.252976)
				(end 65.600072 -69.344794)
			)
			(xy 65.709292 -69.454014)
		)
		(stroke
			(width 0)
			(type solid)
		)
		(fill yes)
		(layer "B.Cu")
		(net "PV_VDDR_NODE1")
	)
	(gr_poly
		(pts
			(xy 84.764372 -93.857826) (xy 84.775607 -93.84589) (xy 84.792129 -93.817593) (xy 84.800892 -93.786019)
			(xy 84.801316 -93.753254) (xy 84.793374 -93.721463) (xy 84.777589 -93.692748) (xy 84.766658 -93.680534)
			(xy 84.74832 -93.660475) (xy 84.716923 -93.616114) (xy 84.69214 -93.567745) (xy 84.674473 -93.516349)
			(xy 84.66428 -93.462965) (xy 84.661766 -93.408676) (xy 84.666983 -93.354579) (xy 84.679826 -93.30177)
			(xy 84.700033 -93.251318) (xy 84.727196 -93.204246) (xy 84.760766 -93.161505) (xy 84.800061 -93.123961)
			(xy 84.844288 -93.092374) (xy 84.89255 -93.067384) (xy 84.94387 -93.049497) (xy 84.997209 -93.039075)
			(xy 85.051488 -93.036329) (xy 85.105606 -93.041314) (xy 85.15847 -93.05393) (xy 85.209007 -93.073921)
			(xy 85.256196 -93.100882) (xy 85.27796 -93.117162) (xy 85.29184 -93.12729) (xy 85.323564 -93.140455)
			(xy 85.357648 -93.144687) (xy 85.391628 -93.139683) (xy 85.423045 -93.125802) (xy 85.43671 -93.115384)
			(xy 85.452204 -93.103192) (xy 85.476588 -93.085158) (xy 85.50402 -93.030802) (xy 85.50402 -90.18905)
			(xy 85.269578 -89.954354) (xy 85.248012 -89.93214) (xy 85.209871 -89.883367) (xy 85.177936 -89.830323)
			(xy 85.152681 -89.773792) (xy 85.134479 -89.714613) (xy 85.123599 -89.653661) (xy 85.120204 -89.591839)
			(xy 85.124343 -89.530062) (xy 85.135955 -89.469245) (xy 85.154868 -89.410289) (xy 85.180801 -89.354067)
			(xy 85.213372 -89.301411) (xy 85.252097 -89.2531) (xy 85.296404 -89.209852) (xy 85.345635 -89.172305)
			(xy 85.399062 -89.141015) (xy 85.427312 -89.128346) (xy 85.462364 -89.113106) (xy 85.50402 -89.049606)
			(xy 85.50402 -87.971884) (xy 84.696808 -87.164672) (xy 83.42249 -87.164672) (xy 83.123532 -86.865714)
			(xy 83.123532 -86.803738) (xy 83.123042 -86.787078) (xy 83.114428 -86.754892) (xy 83.097777 -86.726033)
			(xy 83.074223 -86.702466) (xy 83.045373 -86.685799) (xy 83.013191 -86.677167) (xy 82.996532 -86.676738)
			(xy 81.42732 -86.676738) (xy 81.410665 -86.67723) (xy 81.37849 -86.685849) (xy 81.349644 -86.702503)
			(xy 81.326092 -86.726058) (xy 81.309442 -86.754907) (xy 81.300828 -86.787083) (xy 81.30032 -86.803738)
			(xy 81.30032 -87.221314) (xy 81.300816 -87.237967) (xy 81.30944 -87.270136) (xy 81.326096 -87.298977)
			(xy 81.34965 -87.322524) (xy 81.378496 -87.339173) (xy 81.410667 -87.347788) (xy 81.42732 -87.348314)
			(xy 81.770474 -87.348314) (xy 81.87436 -87.4522) (xy 81.87436 -88.491314) (xy 81.79435 -88.571324)
			(xy 81.790286 -88.571324) (xy 81.767256 -88.571825) (xy 81.721951 -88.580129) (xy 81.678884 -88.596462)
			(xy 81.639466 -88.620289) (xy 81.604987 -88.65083) (xy 81.576578 -88.687085) (xy 81.555168 -88.727867)
			(xy 81.541458 -88.771839) (xy 81.535898 -88.817563) (xy 81.538669 -88.863539) (xy 81.543652 -88.88603)
			(xy 81.5504 -88.915448) (xy 81.557005 -88.975442) (xy 81.555671 -89.035784) (xy 81.546419 -89.095427)
			(xy 81.52941 -89.153337) (xy 81.50494 -89.208511) (xy 81.473432 -89.25999) (xy 81.435433 -89.306884)
			(xy 81.413858 -89.32799) (xy 81.398338 -89.343309) (xy 81.372265 -89.378258) (xy 81.352545 -89.417147)
			(xy 81.339758 -89.458833) (xy 81.334279 -89.502091) (xy 81.33627 -89.545649) (xy 81.345672 -89.588226)
			(xy 81.362209 -89.628572) (xy 81.385395 -89.6655) (xy 81.414547 -89.697925) (xy 81.431384 -89.711784)
			(xy 81.439244 -89.718099) (xy 81.454366 -89.73144) (xy 81.46161 -89.738454) (xy 81.478805 -89.754518)
			(xy 81.517957 -89.780615) (xy 81.561247 -89.79905) (xy 81.607193 -89.809194) (xy 81.654221 -89.810698)
			(xy 81.700721 -89.803511) (xy 81.745101 -89.787879) (xy 81.78584 -89.764338) (xy 81.804002 -89.749376)
			(xy 81.825511 -89.731602) (xy 81.872733 -89.701877) (xy 81.92378 -89.679348) (xy 81.977565 -89.664495)
			(xy 82.032939 -89.657635) (xy 82.088722 -89.658913) (xy 82.143724 -89.668304) (xy 82.196772 -89.685605)
			(xy 82.246734 -89.71045) (xy 82.292544 -89.742306) (xy 82.333225 -89.780496) (xy 82.367909 -89.824203)
			(xy 82.395858 -89.872497) (xy 82.416473 -89.924347) (xy 82.429317 -89.978646) (xy 82.434114 -90.034238)
			(xy 82.430762 -90.089935) (xy 82.419334 -90.14455) (xy 82.400072 -90.196917) (xy 82.373387 -90.245921)
			(xy 82.33985 -90.290515) (xy 82.300174 -90.329748) (xy 82.255207 -90.362784) (xy 82.205908 -90.388917)
			(xy 82.153328 -90.407591) (xy 82.126074 -90.413586) (xy 82.104995 -90.418205) (xy 82.064677 -90.433577)
			(xy 82.027534 -90.455537) (xy 81.994634 -90.483455) (xy 81.966922 -90.516528) (xy 81.945193 -90.553807)
			(xy 81.930072 -90.59422) (xy 81.921994 -90.636606) (xy 81.921191 -90.679747) (xy 81.927685 -90.722405)
			(xy 81.93405 -90.743024) (xy 81.942232 -90.769114) (xy 81.951902 -90.82293) (xy 81.953789 -90.877576)
			(xy 81.947854 -90.931931) (xy 81.934219 -90.984881) (xy 81.913162 -91.035342) (xy 81.899939 -91.057472)
			(xy 82.615514 -91.057472) (xy 82.615514 -90.997536) (xy 82.623337 -90.938114) (xy 82.63885 -90.880221)
			(xy 82.661786 -90.824848) (xy 82.691753 -90.772942) (xy 82.72824 -90.725392) (xy 82.77062 -90.683012)
			(xy 82.81817 -90.646525) (xy 82.870076 -90.616558) (xy 82.925449 -90.593622) (xy 82.983342 -90.578109)
			(xy 83.042764 -90.570286) (xy 83.1027 -90.570286) (xy 83.162122 -90.578109) (xy 83.220015 -90.593622)
			(xy 83.275388 -90.616558) (xy 83.327294 -90.646525) (xy 83.374844 -90.683012) (xy 83.417224 -90.725392)
			(xy 83.453711 -90.772942) (xy 83.483678 -90.824848) (xy 83.506614 -90.880221) (xy 83.522127 -90.938114)
			(xy 83.52995 -90.997536) (xy 83.53044 -91.027504) (xy 83.52995 -91.057472) (xy 83.522127 -91.116894)
			(xy 83.506614 -91.174787) (xy 83.483678 -91.23016) (xy 83.453711 -91.282066) (xy 83.417224 -91.329616)
			(xy 83.374844 -91.371996) (xy 83.327294 -91.408483) (xy 83.275388 -91.43845) (xy 83.220015 -91.461386)
			(xy 83.162122 -91.476899) (xy 83.1027 -91.484722) (xy 83.042764 -91.484722) (xy 82.983342 -91.476899)
			(xy 82.925449 -91.461386) (xy 82.870076 -91.43845) (xy 82.81817 -91.408483) (xy 82.77062 -91.371996)
			(xy 82.72824 -91.329616) (xy 82.691753 -91.282066) (xy 82.661786 -91.23016) (xy 82.63885 -91.174787)
			(xy 82.623337 -91.116894) (xy 82.615514 -91.057472) (xy 81.899939 -91.057472) (xy 81.885116 -91.08228)
			(xy 81.850656 -91.124731) (xy 81.810487 -91.161828) (xy 81.765433 -91.192808) (xy 81.716417 -91.217039)
			(xy 81.664443 -91.234022) (xy 81.610577 -91.243409) (xy 81.555922 -91.245009) (xy 81.501599 -91.238789)
			(xy 81.448721 -91.224876) (xy 81.398371 -91.203556) (xy 81.351581 -91.175264) (xy 81.309311 -91.140581)
			(xy 81.272426 -91.100218) (xy 81.241682 -91.055002) (xy 81.217709 -91.00586) (xy 81.200999 -90.953797)
			(xy 81.191894 -90.899883) (xy 81.190581 -90.845221) (xy 81.197086 -90.790931) (xy 81.211276 -90.738126)
			(xy 81.22158 -90.712798) (xy 81.230272 -90.691244) (xy 81.240545 -90.645925) (xy 81.242416 -90.599494)
			(xy 81.23582 -90.553496) (xy 81.220979 -90.50946) (xy 81.198386 -90.468854) (xy 81.168792 -90.433027)
			(xy 81.133183 -90.403172) (xy 81.092743 -90.380282) (xy 81.070958 -90.372184) (xy 81.044003 -90.362352)
			(xy 80.993165 -90.335752) (xy 80.946885 -90.30184) (xy 80.906204 -90.261379) (xy 80.872042 -90.215282)
			(xy 80.845169 -90.164588) (xy 80.82619 -90.110442) (xy 80.815534 -90.054065) (xy 80.813442 -89.996727)
			(xy 80.819959 -89.939723) (xy 80.83494 -89.884338) (xy 80.858046 -89.83182) (xy 80.888756 -89.783355)
			(xy 80.907128 -89.761314) (xy 80.921105 -89.744549) (xy 80.943691 -89.707204) (xy 80.959561 -89.666548)
			(xy 80.96825 -89.623777) (xy 80.969501 -89.580151) (xy 80.963277 -89.536953) (xy 80.949761 -89.495455)
			(xy 80.929352 -89.456877) (xy 80.90265 -89.422355) (xy 80.87044 -89.392904) (xy 80.852264 -89.380822)
			(xy 80.825945 -89.363318) (xy 80.777931 -89.322211) (xy 80.736025 -89.274894) (xy 80.701022 -89.222264)
			(xy 80.673587 -89.165321) (xy 80.654242 -89.105147) (xy 80.643354 -89.042885) (xy 80.64113 -88.979717)
			(xy 80.647612 -88.916843) (xy 80.654652 -88.88603) (xy 80.659673 -88.863545) (xy 80.662445 -88.817561)
			(xy 80.656884 -88.771831) (xy 80.643172 -88.727851) (xy 80.621758 -88.687064) (xy 80.593345 -88.650803)
			(xy 80.558861 -88.620256) (xy 80.519437 -88.596425) (xy 80.476364 -88.580089) (xy 80.431052 -88.571783)
			(xy 80.408018 -88.571324) (xy 79.677768 -88.571324) (xy 78.998572 -89.25052) (xy 77.96022 -89.25052)
			(xy 77.51064 -89.7001) (xy 77.51064 -90.794586) (xy 77.511049 -90.81013) (xy 77.518505 -90.840308)
			(xy 77.53305 -90.867782) (xy 77.553816 -90.890914) (xy 77.579567 -90.908326) (xy 77.60877 -90.918982)
			(xy 77.624178 -90.921078) (xy 77.651888 -90.924555) (xy 77.705946 -90.938573) (xy 77.757382 -90.960323)
			(xy 77.805097 -90.989342) (xy 77.84807 -91.025008) (xy 77.885383 -91.066559) (xy 77.916238 -91.113107)
			(xy 77.939976 -91.163657) (xy 77.956088 -91.217128) (xy 77.964232 -91.272377) (xy 77.964232 -91.328223)
			(xy 77.956088 -91.383472) (xy 77.939976 -91.436943) (xy 77.916238 -91.487493) (xy 77.885383 -91.534041)
			(xy 77.84807 -91.575592) (xy 77.805097 -91.611258) (xy 77.757382 -91.640277) (xy 77.705946 -91.662027)
			(xy 77.651888 -91.676045) (xy 77.624178 -91.679522) (xy 77.608778 -91.681619) (xy 77.5796 -91.692302)
			(xy 77.553872 -91.709725) (xy 77.533123 -91.732854) (xy 77.518585 -91.760315) (xy 77.51112 -91.790477)
			(xy 77.51064 -91.806014) (xy 77.51064 -91.936062) (xy 79.118968 -93.54439) (xy 79.27721 -93.54439)
			(xy 79.28737 -93.533976) (xy 79.350362 -93.533976) (xy 79.35849 -93.533468) (xy 79.358998 -93.533468)
			(xy 79.3623 -93.533214) (xy 79.373538 -93.532713) (xy 79.396034 -93.532967) (xy 79.407258 -93.533722)
			(xy 79.41183 -93.533976) (xy 79.466186 -93.533976) (xy 79.482841 -93.533483) (xy 79.515016 -93.524864)
			(xy 79.543863 -93.508209) (xy 79.567415 -93.484655) (xy 79.584068 -93.455807) (xy 79.592684 -93.423631)
			(xy 79.593186 -93.406976) (xy 79.593186 -93.389704) (xy 79.593286 -93.362415) (xy 79.600337 -93.308302)
			(xy 79.615026 -93.255746) (xy 79.637052 -93.205818) (xy 79.665967 -93.159538) (xy 79.701181 -93.117849)
			(xy 79.741974 -93.081603) (xy 79.787515 -93.051537) (xy 79.836875 -93.028267) (xy 79.889047 -93.012266)
			(xy 79.942966 -93.003862) (xy 79.997533 -93.003224) (xy 80.051634 -93.010367) (xy 80.104165 -93.025145)
			(xy 80.154055 -93.047257) (xy 80.200286 -93.07625) (xy 80.241915 -93.111534) (xy 80.278092 -93.152389)
			(xy 80.30808 -93.197981) (xy 80.331267 -93.247381) (xy 80.347179 -93.29958) (xy 80.355492 -93.353513)
			(xy 80.356036 -93.408081) (xy 80.348801 -93.46217) (xy 80.333934 -93.514676) (xy 80.311738 -93.564528)
			(xy 80.297528 -93.587824) (xy 80.273906 -93.625416) (xy 80.283812 -93.713808) (xy 80.703928 -94.133924)
			(xy 80.703928 -94.787974) (xy 80.705165 -94.804113) (xy 80.714749 -94.835019) (xy 80.731784 -94.86253)
			(xy 80.75518 -94.884883) (xy 80.783439 -94.900647) (xy 80.81475 -94.908812) (xy 80.830928 -94.909386)
			(xy 83.712812 -94.909386)
		)
		(stroke
			(width 0)
			(type solid)
		)
		(fill yes)
		(layer "B.Cu")
		(net "P3V3_SUS_NODE1")
	)
	(gr_poly
		(pts
			(xy 108.52658 -139.99972) (xy 108.52658 -139.677902) (xy 108.496608 -139.621768) (xy 108.469684 -139.603988)
			(xy 108.444818 -139.586986) (xy 108.399348 -139.547475) (xy 108.359455 -139.502339) (xy 108.325831 -139.452358)
			(xy 108.299055 -139.398398) (xy 108.279591 -139.341391) (xy 108.267775 -139.282322) (xy 108.263813 -139.222214)
			(xy 108.267772 -139.162106) (xy 108.279583 -139.103037) (xy 108.299044 -139.046029) (xy 108.325816 -138.992067)
			(xy 108.359438 -138.942084) (xy 108.399327 -138.896945) (xy 108.444795 -138.857431) (xy 108.469684 -138.840464)
			(xy 108.496608 -138.822684) (xy 108.52658 -138.76655) (xy 108.52658 -138.637518) (xy 108.314744 -138.425682)
			(xy 108.314744 -136.93013) (xy 108.274612 -136.889998) (xy 105.590848 -136.889998) (xy 105.377488 -136.676638)
			(xy 105.377488 -132.957316) (xy 105.795064 -132.53974) (xy 105.795064 -129.305304) (xy 105.377488 -128.887728)
			(xy 105.377488 -128.074166) (xy 105.349802 -128.04648) (xy 103.480616 -128.04648) (xy 103.297482 -128.229614)
			(xy 103.297482 -128.427226) (xy 103.30815 -128.45161) (xy 103.318231 -128.475783) (xy 103.332426 -128.526198)
			(xy 103.339592 -128.57808) (xy 103.339597 -128.630454) (xy 103.332439 -128.682338) (xy 103.318254 -128.732755)
			(xy 103.30815 -128.756918) (xy 103.297482 -128.781302) (xy 103.297482 -129.141474) (xy 103.754172 -129.141474)
			(xy 103.758243 -129.085852) (xy 103.770369 -129.031415) (xy 103.790292 -128.979324) (xy 103.817588 -128.930689)
			(xy 103.851674 -128.886546) (xy 103.891823 -128.847837) (xy 103.937181 -128.815386) (xy 103.986781 -128.789885)
			(xy 104.039565 -128.771878) (xy 104.094408 -128.761748) (xy 104.150142 -128.759711) (xy 104.205579 -128.765811)
			(xy 104.259536 -128.779917) (xy 104.310865 -128.801729) (xy 104.358471 -128.830783) (xy 104.401339 -128.866458)
			(xy 104.438556 -128.907995) (xy 104.469329 -128.954508) (xy 104.493001 -129.005005) (xy 104.509069 -129.058412)
			(xy 104.517189 -129.113588) (xy 104.517698 -129.141474) (xy 104.517189 -129.16936) (xy 104.509069 -129.224536)
			(xy 104.493001 -129.277943) (xy 104.469329 -129.32844) (xy 104.438556 -129.374953) (xy 104.401339 -129.41649)
			(xy 104.358471 -129.452165) (xy 104.310865 -129.481219) (xy 104.259536 -129.503031) (xy 104.205579 -129.517137)
			(xy 104.150142 -129.523237) (xy 104.094408 -129.5212) (xy 104.039565 -129.51107) (xy 103.986781 -129.493063)
			(xy 103.937181 -129.467562) (xy 103.891823 -129.435111) (xy 103.851674 -129.396402) (xy 103.817588 -129.352259)
			(xy 103.790292 -129.303624) (xy 103.770369 -129.251533) (xy 103.758243 -129.197096) (xy 103.754172 -129.141474)
			(xy 103.297482 -129.141474) (xy 103.297482 -130.513074) (xy 103.297974 -130.535949) (xy 103.306173 -130.580959)
			(xy 103.322293 -130.623775) (xy 103.345813 -130.663016) (xy 103.375975 -130.697415) (xy 103.411806 -130.725863)
			(xy 103.452148 -130.74744) (xy 103.4957 -130.761452) (xy 103.541056 -130.767444) (xy 103.563928 -130.76682)
			(xy 103.59574 -130.765025) (xy 103.659318 -130.769194) (xy 103.721705 -130.782134) (xy 103.781696 -130.803597)
			(xy 103.838133 -130.833167) (xy 103.889927 -130.870274) (xy 103.936078 -130.914202) (xy 103.956358 -130.938778)
			(xy 103.971593 -130.956556) (xy 104.00737 -130.98675) (xy 104.048069 -131.009883) (xy 104.092317 -131.025173)
			(xy 104.138615 -131.032104) (xy 104.1854 -131.030441) (xy 104.23109 -131.02024) (xy 104.27414 -131.001846)
			(xy 104.293924 -130.989324) (xy 104.317533 -130.974181) (xy 104.368255 -130.950239) (xy 104.421936 -130.933984)
			(xy 104.477419 -130.925765) (xy 104.533507 -130.925759) (xy 104.588991 -130.933967) (xy 104.642675 -130.950213)
			(xy 104.693402 -130.974144) (xy 104.740077 -131.005247) (xy 104.781694 -131.042849) (xy 104.817355 -131.08614)
			(xy 104.846293 -131.134187) (xy 104.867882 -131.185954) (xy 104.881658 -131.240324) (xy 104.887323 -131.296125)
			(xy 104.884755 -131.352155) (xy 104.87401 -131.407204) (xy 104.86517 -131.433824) (xy 104.856055 -131.458337)
			(xy 104.832066 -131.504808) (xy 104.801957 -131.547568) (xy 104.766291 -131.585817) (xy 104.725737 -131.618838)
			(xy 104.681054 -131.646013) (xy 104.63308 -131.666832) (xy 104.582711 -131.680906) (xy 104.530893 -131.687971)
			(xy 104.504744 -131.688332) (xy 104.47538 -131.687734) (xy 104.417361 -131.678619) (xy 104.361424 -131.660721)
			(xy 104.30889 -131.634462) (xy 104.261001 -131.600463) (xy 104.239568 -131.580382) (xy 104.222529 -131.564533)
			(xy 104.183832 -131.5387) (xy 104.141079 -131.520339) (xy 104.0957 -131.510065) (xy 104.049208 -131.50822)
			(xy 104.003157 -131.514866) (xy 103.959084 -131.529781) (xy 103.918461 -131.552467) (xy 103.900224 -131.56692)
			(xy 103.877095 -131.586599) (xy 103.82659 -131.620318) (xy 103.772071 -131.647065) (xy 103.714494 -131.666369)
			(xy 103.65487 -131.677892) (xy 103.594246 -131.681432) (xy 103.563928 -131.679696) (xy 103.541054 -131.679062)
			(xy 103.495691 -131.685041) (xy 103.452132 -131.699044) (xy 103.411783 -131.720619) (xy 103.375948 -131.749068)
			(xy 103.345785 -131.783473) (xy 103.322268 -131.822722) (xy 103.306158 -131.865547) (xy 103.297974 -131.910564)
			(xy 103.297482 -131.933442) (xy 103.297482 -133.255004) (xy 103.297969 -133.277637) (xy 103.305977 -133.322188)
			(xy 103.321755 -133.364615) (xy 103.344805 -133.403572) (xy 103.374395 -133.437826) (xy 103.409589 -133.466293)
			(xy 103.449272 -133.488069) (xy 103.492187 -133.502466) (xy 103.536974 -133.509027) (xy 103.55961 -133.50875)
			(xy 103.590225 -133.508202) (xy 103.651151 -133.514308) (xy 103.710719 -133.528481) (xy 103.767866 -133.55047)
			(xy 103.821571 -133.579881) (xy 103.870876 -133.61619) (xy 103.9149 -133.658748) (xy 103.952856 -133.706796)
			(xy 103.984068 -133.759475) (xy 104.007979 -133.815845) (xy 104.02416 -133.874899) (xy 104.032323 -133.935584)
			(xy 104.032323 -133.996816) (xy 104.02416 -134.0575) (xy 104.007979 -134.116555) (xy 103.984069 -134.172925)
			(xy 103.952857 -134.225604) (xy 103.9149 -134.273652) (xy 103.870876 -134.31621) (xy 103.821572 -134.352519)
			(xy 103.767867 -134.38193) (xy 103.71072 -134.403919) (xy 103.651151 -134.418092) (xy 103.590225 -134.424198)
			(xy 103.55961 -134.423658) (xy 103.536984 -134.423438) (xy 103.492225 -134.430039) (xy 103.449341 -134.444458)
			(xy 103.409687 -134.466241) (xy 103.374514 -134.4947) (xy 103.344935 -134.528934) (xy 103.321883 -134.567864)
			(xy 103.306086 -134.61026) (xy 103.298043 -134.654783) (xy 103.297482 -134.677404) (xy 103.297482 -134.761224)
			(xy 103.298022 -134.777211) (xy 103.306043 -134.808164) (xy 103.321501 -134.836156) (xy 103.343428 -134.85943)
			(xy 103.356664 -134.868412) (xy 103.382413 -134.885257) (xy 103.429575 -134.924777) (xy 103.471018 -134.970259)
			(xy 103.505994 -135.020882) (xy 103.533875 -135.075734) (xy 103.554156 -135.133826) (xy 103.566472 -135.194112)
			(xy 103.570602 -135.255504) (xy 103.566471 -135.316896) (xy 103.554153 -135.377182) (xy 103.533871 -135.435274)
			(xy 103.50599 -135.490126) (xy 103.471012 -135.540748) (xy 103.429569 -135.586229) (xy 103.382406 -135.625748)
			(xy 103.356664 -135.642604) (xy 103.343375 -135.651527) (xy 103.321412 -135.674799) (xy 103.305942 -135.70281)
			(xy 103.297941 -135.733793) (xy 103.297482 -135.749792) (xy 103.297482 -135.800846) (xy 103.298011 -135.824509)
			(xy 103.306779 -135.871016) (xy 103.324003 -135.915097) (xy 103.349088 -135.955228) (xy 103.381167 -135.990023)
			(xy 103.419132 -136.01828) (xy 103.461671 -136.039022) (xy 103.507314 -136.051532) (xy 103.554483 -136.055378)
			(xy 103.60155 -136.050427) (xy 103.62438 -136.044178) (xy 103.653677 -136.035944) (xy 103.713779 -136.026402)
			(xy 103.774617 -136.024911) (xy 103.835115 -136.031496) (xy 103.894206 -136.046043) (xy 103.950847 -136.068294)
			(xy 104.00404 -136.097857) (xy 104.052844 -136.13421) (xy 104.096399 -136.176711) (xy 104.133937 -136.22461)
			(xy 104.164794 -136.277062) (xy 104.188426 -136.333142) (xy 104.204416 -136.391859) (xy 104.212481 -136.452177)
			(xy 104.212481 -136.513033) (xy 104.204414 -136.573351) (xy 104.188422 -136.632068) (xy 104.164789 -136.688147)
			(xy 104.133931 -136.740599) (xy 104.096393 -136.788497) (xy 104.052836 -136.830997) (xy 104.004031 -136.867349)
			(xy 103.950838 -136.89691) (xy 103.894196 -136.91916) (xy 103.835104 -136.933705) (xy 103.774606 -136.94029)
			(xy 103.713769 -136.938797) (xy 103.653667 -136.929253) (xy 103.62438 -136.920986) (xy 103.601559 -136.914698)
			(xy 103.554489 -136.909746) (xy 103.507316 -136.913592) (xy 103.461669 -136.926104) (xy 103.419128 -136.94685)
			(xy 103.381162 -136.975112) (xy 103.349085 -137.009914) (xy 103.324004 -137.050053) (xy 103.306787 -137.09414)
			(xy 103.298029 -137.140653) (xy 103.297482 -137.164318) (xy 103.297482 -139.090908) (xy 105.412792 -139.090908)
			(xy 105.416863 -139.035286) (xy 105.428989 -138.980849) (xy 105.448912 -138.928758) (xy 105.476208 -138.880123)
			(xy 105.510294 -138.83598) (xy 105.550443 -138.797271) (xy 105.595801 -138.76482) (xy 105.645401 -138.739319)
			(xy 105.698185 -138.721312) (xy 105.753028 -138.711182) (xy 105.808762 -138.709145) (xy 105.864199 -138.715245)
			(xy 105.918156 -138.729351) (xy 105.969485 -138.751163) (xy 106.017091 -138.780217) (xy 106.059959 -138.815892)
			(xy 106.097176 -138.857429) (xy 106.127949 -138.903942) (xy 106.151621 -138.954439) (xy 106.167689 -139.007846)
			(xy 106.175809 -139.063022) (xy 106.176318 -139.090908) (xy 106.175809 -139.118794) (xy 106.171727 -139.14653)
			(xy 106.593876 -139.14653) (xy 106.593876 -139.086594) (xy 106.601699 -139.027172) (xy 106.617212 -138.969279)
			(xy 106.640148 -138.913906) (xy 106.670115 -138.862) (xy 106.706602 -138.81445) (xy 106.748982 -138.77207)
			(xy 106.796532 -138.735583) (xy 106.848438 -138.705616) (xy 106.903811 -138.68268) (xy 106.961704 -138.667167)
			(xy 107.021126 -138.659344) (xy 107.081062 -138.659344) (xy 107.140484 -138.667167) (xy 107.198377 -138.68268)
			(xy 107.25375 -138.705616) (xy 107.305656 -138.735583) (xy 107.353206 -138.77207) (xy 107.395586 -138.81445)
			(xy 107.432073 -138.862) (xy 107.46204 -138.913906) (xy 107.484976 -138.969279) (xy 107.500489 -139.027172)
			(xy 107.508312 -139.086594) (xy 107.508802 -139.116562) (xy 107.508312 -139.14653) (xy 107.500489 -139.205952)
			(xy 107.484976 -139.263845) (xy 107.46204 -139.319218) (xy 107.432073 -139.371124) (xy 107.395586 -139.418674)
			(xy 107.353206 -139.461054) (xy 107.305656 -139.497541) (xy 107.25375 -139.527508) (xy 107.198377 -139.550444)
			(xy 107.140484 -139.565957) (xy 107.081062 -139.57378) (xy 107.021126 -139.57378) (xy 106.961704 -139.565957)
			(xy 106.903811 -139.550444) (xy 106.848438 -139.527508) (xy 106.796532 -139.497541) (xy 106.748982 -139.461054)
			(xy 106.706602 -139.418674) (xy 106.670115 -139.371124) (xy 106.640148 -139.319218) (xy 106.617212 -139.263845)
			(xy 106.601699 -139.205952) (xy 106.593876 -139.14653) (xy 106.171727 -139.14653) (xy 106.167689 -139.17397)
			(xy 106.151621 -139.227377) (xy 106.127949 -139.277874) (xy 106.097176 -139.324387) (xy 106.059959 -139.365924)
			(xy 106.017091 -139.401599) (xy 105.969485 -139.430653) (xy 105.918156 -139.452465) (xy 105.864199 -139.466571)
			(xy 105.808762 -139.472671) (xy 105.753028 -139.470634) (xy 105.698185 -139.460504) (xy 105.645401 -139.442497)
			(xy 105.595801 -139.416996) (xy 105.550443 -139.384545) (xy 105.510294 -139.345836) (xy 105.476208 -139.301693)
			(xy 105.448912 -139.253058) (xy 105.428989 -139.200967) (xy 105.416863 -139.14653) (xy 105.412792 -139.090908)
			(xy 103.297482 -139.090908) (xy 103.297482 -139.298426) (xy 103.543354 -139.544298) (xy 104.743758 -139.544298)
			(xy 105.45064 -140.25118) (xy 108.27512 -140.25118)
		)
		(stroke
			(width 0)
			(type solid)
		)
		(fill yes)
		(layer "B.Cu")
		(net "P5V_STB_NODE1")
	)
	(gr_poly
		(pts
			(arc
				(start 68.068952 -15.951454)
				(mid 68.136635 -15.931915)
				(end 68.183506 -15.879318)
			)
			(arc
				(start 68.183506 -15.879318)
				(mid 68.527422 -15.662926)
				(end 68.871338 -15.879318)
			)
			(arc
				(start 68.871338 -15.879318)
				(mid 68.918201 -15.931928)
				(end 68.985892 -15.951454)
			)
			(arc
				(start 69.105272 -15.951454)
				(mid 69.172955 -15.931915)
				(end 69.219826 -15.879318)
			)
			(arc
				(start 69.219826 -15.879318)
				(mid 69.563742 -15.662926)
				(end 69.907658 -15.879318)
			)
			(arc
				(start 69.907658 -15.879318)
				(mid 69.954521 -15.931928)
				(end 70.022212 -15.951454)
			)
			(arc
				(start 70.116192 -15.951454)
				(mid 70.183875 -15.931915)
				(end 70.230746 -15.879318)
			)
			(arc
				(start 70.230746 -15.879318)
				(mid 70.574662 -15.662926)
				(end 70.918578 -15.879318)
			)
			(arc
				(start 70.918578 -15.879318)
				(mid 70.965441 -15.931928)
				(end 71.033132 -15.951454)
			)
			(arc
				(start 71.175372 -15.951454)
				(mid 71.243055 -15.931915)
				(end 71.289926 -15.879318)
			)
			(arc
				(start 71.289926 -15.879318)
				(mid 71.633842 -15.662926)
				(end 71.977758 -15.879318)
			)
			(arc
				(start 71.977758 -15.879318)
				(mid 72.024621 -15.931928)
				(end 72.092312 -15.951454)
			)
			(arc
				(start 73.410572 -15.951454)
				(mid 73.478255 -15.931915)
				(end 73.525126 -15.879318)
			)
			(arc
				(start 73.525126 -15.879318)
				(mid 73.869042 -15.662926)
				(end 74.212958 -15.879318)
			)
			(arc
				(start 74.212958 -15.879318)
				(mid 74.259821 -15.931928)
				(end 74.327512 -15.951454)
			)
			(arc
				(start 74.446892 -15.951454)
				(mid 74.514575 -15.931915)
				(end 74.561446 -15.879318)
			)
			(arc
				(start 74.561446 -15.879318)
				(mid 74.905362 -15.662926)
				(end 75.249278 -15.879318)
			)
			(arc
				(start 75.249278 -15.879318)
				(mid 75.296141 -15.931928)
				(end 75.363832 -15.951454)
			)
			(xy 75.494642 -15.951454) (xy 75.556364 -15.912592)
			(arc
				(start 75.572366 -15.879318)
				(mid 75.916282 -15.662926)
				(end 76.260198 -15.879318)
			)
			(arc
				(start 76.260198 -15.879318)
				(mid 76.307061 -15.931928)
				(end 76.374752 -15.951454)
			)
			(xy 76.553822 -15.951454) (xy 76.615544 -15.912592)
			(arc
				(start 76.631546 -15.879318)
				(mid 76.975462 -15.662926)
				(end 77.319378 -15.879318)
			)
			(arc
				(start 77.319378 -15.879318)
				(mid 77.366241 -15.931928)
				(end 77.433932 -15.951454)
			)
			(arc
				(start 77.441552 -15.951454)
				(mid 77.509235 -15.931915)
				(end 77.556106 -15.879318)
			)
			(arc
				(start 77.556106 -15.879318)
				(mid 77.900022 -15.662926)
				(end 78.243938 -15.879318)
			)
			(arc
				(start 78.243938 -15.879318)
				(mid 78.290801 -15.931928)
				(end 78.358492 -15.951454)
			)
			(xy 78.441042 -15.951454) (xy 78.502764 -15.912592)
			(arc
				(start 78.518766 -15.879318)
				(mid 78.862682 -15.662926)
				(end 79.206598 -15.879318)
			)
			(arc
				(start 79.206598 -15.879318)
				(mid 79.253461 -15.931928)
				(end 79.321152 -15.951454)
			)
			(xy 79.49692 -15.951454) (xy 79.558642 -15.912592)
			(arc
				(start 79.574644 -15.879318)
				(mid 79.91856 -15.662926)
				(end 80.262476 -15.879318)
			)
			(arc
				(start 80.262476 -15.879318)
				(mid 80.309339 -15.931928)
				(end 80.37703 -15.951454)
			)
			(xy 80.488282 -15.951454) (xy 80.550004 -15.912592)
			(arc
				(start 80.566006 -15.879318)
				(mid 80.909922 -15.662926)
				(end 81.253838 -15.879318)
			)
			(arc
				(start 81.253838 -15.879318)
				(mid 81.300701 -15.931928)
				(end 81.368392 -15.951454)
			)
			(arc
				(start 81.510632 -15.951454)
				(mid 81.578315 -15.931915)
				(end 81.625186 -15.879318)
			)
			(arc
				(start 81.625186 -15.879318)
				(mid 81.969102 -15.662926)
				(end 82.313018 -15.879318)
			)
			(arc
				(start 82.313018 -15.879318)
				(mid 82.359881 -15.931928)
				(end 82.427572 -15.951454)
			)
			(arc
				(start 82.435192 -15.951454)
				(mid 82.502875 -15.931915)
				(end 82.549746 -15.879318)
			)
			(arc
				(start 82.549746 -15.879318)
				(mid 82.893662 -15.662926)
				(end 83.237578 -15.879318)
			)
			(arc
				(start 83.237578 -15.879318)
				(mid 83.284441 -15.931928)
				(end 83.352132 -15.951454)
			)
			(xy 86.650576 -15.951454) (xy 90.009472 -12.592558) (xy 94.99092 -12.592558) (xy 95.92564 -11.657838)
			(xy 95.92564 -3.826764) (xy 95.738188 -3.639312) (xy 93.783912 -3.639312) (xy 93.64472 -3.77825)
			(xy 93.64472 -9.59485) (xy 92.71889 -10.52068) (xy 90.512392 -10.52068) (xy 90.438224 -10.594848)
			(arc
				(start 90.438224 -10.627106)
				(mid 90.007546 -10.733261)
				(end 89.576148 -10.630154)
			)
			(xy 89.576148 -10.594848) (xy 89.50198 -10.52068) (xy 88.665304 -10.52068) (xy 84.760308 -14.425676)
			(xy 69.250052 -14.425676) (xy 68.095368 -13.270992) (xy 67.04584 -13.270992) (xy 66.902838 -13.12799)
			(xy 65.4558 -13.12799) (xy 65.217548 -13.366496) (xy 65.217548 -14.849348) (xy 65.200784 -14.865858)
			(xy 65.200784 -15.467838) (xy 65.6844 -15.951454)
		)
		(stroke
			(width 0)
			(type solid)
		)
		(fill yes)
		(layer "B.Cu")
		(net "P5V_NODE1")
	)
	(gr_poly
		(pts
			(xy 15.20698 -166.186866) (xy 15.20698 -166.14521) (xy 15.198448 -166.113864) (xy 15.189284 -166.04955)
			(xy 15.189289 -165.984587) (xy 15.198462 -165.920274) (xy 15.20698 -165.888924) (xy 15.20698 -163.806632)
			(xy 15.206454 -163.790087) (xy 15.197949 -163.75811) (xy 15.181504 -163.729396) (xy 15.158224 -163.705881)
			(xy 15.129679 -163.689146) (xy 15.097789 -163.680319) (xy 15.08125 -163.679632) (xy 15.054176 -163.678888)
			(xy 15.00064 -163.670694) (xy 14.9488 -163.655011) (xy 14.899699 -163.632155) (xy 14.854324 -163.602585)
			(xy 14.813587 -163.566896) (xy 14.778306 -163.525804) (xy 14.74919 -163.480136) (xy 14.726826 -163.430809)
			(xy 14.711662 -163.378816) (xy 14.704002 -163.3252) (xy 14.704002 -163.27104) (xy 14.711662 -163.217425)
			(xy 14.726826 -163.165431) (xy 14.74919 -163.116104) (xy 14.778306 -163.070436) (xy 14.813587 -163.029344)
			(xy 14.854324 -162.993655) (xy 14.899699 -162.964085) (xy 14.9488 -162.941229) (xy 15.00064 -162.925546)
			(xy 15.054176 -162.917352) (xy 15.08125 -162.916616) (xy 15.09779 -162.915924) (xy 15.129684 -162.907097)
			(xy 15.158234 -162.890365) (xy 15.18152 -162.866852) (xy 15.197975 -162.83814) (xy 15.20649 -162.806162)
			(xy 15.20698 -162.789616) (xy 15.20698 -160.9598) (xy 15.206535 -160.943985) (xy 15.19881 -160.913316)
			(xy 15.183762 -160.885499) (xy 15.16232 -160.86225) (xy 15.135808 -160.845005) (xy 15.105863 -160.83483)
			(xy 15.09014 -160.833054) (xy 15.060796 -160.830148) (xy 15.003444 -160.816447) (xy 14.94888 -160.794091)
			(xy 14.898403 -160.763612) (xy 14.853212 -160.725734) (xy 14.814382 -160.681358) (xy 14.782837 -160.63154)
			(xy 14.770608 -160.604708) (xy 14.76161 -160.585169) (xy 14.738044 -160.549185) (xy 14.708754 -160.517685)
			(xy 14.674578 -160.491567) (xy 14.636491 -160.471579) (xy 14.595581 -160.45829) (xy 14.553018 -160.452082)
			(xy 14.510017 -160.453131) (xy 14.467807 -160.461407) (xy 14.44752 -160.468564) (xy 14.419008 -160.478871)
			(xy 14.359986 -160.492734) (xy 14.29965 -160.498685) (xy 14.239058 -160.49662) (xy 14.179267 -160.486575)
			(xy 14.121326 -160.468726) (xy 14.066248 -160.443386) (xy 14.014996 -160.410997) (xy 13.968468 -160.372127)
			(xy 13.927478 -160.327455) (xy 13.892742 -160.277764) (xy 13.864869 -160.223923) (xy 13.844347 -160.166874)
			(xy 13.831535 -160.107615) (xy 13.826656 -160.047184) (xy 13.829797 -159.986637) (xy 13.840902 -159.927034)
			(xy 13.859777 -159.869419) (xy 13.886091 -159.8148) (xy 13.919385 -159.764131) (xy 13.959075 -159.718301)
			(xy 14.004468 -159.67811) (xy 14.054768 -159.644262) (xy 14.109095 -159.61735) (xy 14.1665 -159.597844)
			(xy 14.225977 -159.586086) (xy 14.286486 -159.582282) (xy 14.346967 -159.586497) (xy 14.406363 -159.598658)
			(xy 14.463634 -159.618553) (xy 14.517777 -159.645834) (xy 14.567847 -159.680022) (xy 14.612965 -159.72052)
			(xy 14.652343 -159.766619) (xy 14.685292 -159.817512) (xy 14.711236 -159.872309) (xy 14.729719 -159.930051)
			(xy 14.735556 -159.959802) (xy 14.738449 -159.973708) (xy 14.749513 -159.999862) (xy 14.766068 -160.022935)
			(xy 14.7873 -160.041792) (xy 14.799564 -160.048956) (xy 14.931898 -160.121346) (xy 14.957806 -160.107884)
			(xy 14.976789 -160.098438) (xy 15.011578 -160.074203) (xy 15.041861 -160.044529) (xy 15.066798 -160.01024)
			(xy 15.085698 -159.972287) (xy 15.098035 -159.931724) (xy 15.103468 -159.889675) (xy 15.101845 -159.847308)
			(xy 15.098014 -159.826452) (xy 15.091939 -159.794453) (xy 15.08784 -159.729451) (xy 15.093002 -159.664525)
			(xy 15.10732 -159.600988) (xy 15.130504 -159.540123) (xy 15.162085 -159.483161) (xy 15.181326 -159.456882)
			(xy 15.20698 -159.422846) (xy 15.20698 -158.773114) (xy 15.181326 -158.739332) (xy 15.163779 -158.715389)
			(xy 15.134354 -158.663833) (xy 15.111841 -158.608906) (xy 15.096621 -158.551529) (xy 15.088947 -158.492665)
			(xy 15.088949 -158.433303) (xy 15.096627 -158.37444) (xy 15.111852 -158.317064) (xy 15.134368 -158.262138)
			(xy 15.163797 -158.210585) (xy 15.181326 -158.186628) (xy 15.20698 -158.152846) (xy 15.20698 -156.061918)
			(xy 14.7828 -155.637738) (xy 11.378946 -155.637738) (xy 11.35888 -155.657804) (xy 11.352305 -155.689252)
			(xy 11.331515 -155.750043) (xy 11.302429 -155.807329) (xy 11.265619 -155.859986) (xy 11.221807 -155.906978)
			(xy 11.171855 -155.947382) (xy 11.116743 -155.980404) (xy 11.057556 -156.005395) (xy 11.026648 -156.014166)
			(xy 10.993628 -156.023056) (xy 10.822432 -156.194252) (xy 10.822432 -156.70936) (xy 11.602702 -156.70936)
			(xy 11.602702 -156.649424) (xy 11.610525 -156.590002) (xy 11.626038 -156.532109) (xy 11.648974 -156.476736)
			(xy 11.678941 -156.42483) (xy 11.715428 -156.37728) (xy 11.757808 -156.3349) (xy 11.805358 -156.298413)
			(xy 11.857264 -156.268446) (xy 11.912637 -156.24551) (xy 11.97053 -156.229997) (xy 12.029952 -156.222174)
			(xy 12.089888 -156.222174) (xy 12.14931 -156.229997) (xy 12.207203 -156.24551) (xy 12.262576 -156.268446)
			(xy 12.314482 -156.298413) (xy 12.362032 -156.3349) (xy 12.404412 -156.37728) (xy 12.440899 -156.42483)
			(xy 12.470866 -156.476736) (xy 12.493802 -156.532109) (xy 12.509315 -156.590002) (xy 12.517138 -156.649424)
			(xy 12.517628 -156.679392) (xy 12.517138 -156.70936) (xy 12.509315 -156.768782) (xy 12.493802 -156.826675)
			(xy 12.470866 -156.882048) (xy 12.440899 -156.933954) (xy 12.404412 -156.981504) (xy 12.362032 -157.023884)
			(xy 12.314482 -157.060371) (xy 12.262576 -157.090338) (xy 12.207203 -157.113274) (xy 12.14931 -157.128787)
			(xy 12.089888 -157.13661) (xy 12.029952 -157.13661) (xy 11.97053 -157.128787) (xy 11.912637 -157.113274)
			(xy 11.857264 -157.090338) (xy 11.805358 -157.060371) (xy 11.757808 -157.023884) (xy 11.715428 -156.981504)
			(xy 11.678941 -156.933954) (xy 11.648974 -156.882048) (xy 11.626038 -156.826675) (xy 11.610525 -156.768782)
			(xy 11.602702 -156.70936) (xy 10.822432 -156.70936) (xy 10.822432 -158.754368) (xy 11.871238 -158.754368)
			(xy 11.873097 -158.693786) (xy 11.882937 -158.63398) (xy 11.900586 -158.575997) (xy 11.925733 -158.52085)
			(xy 11.957941 -158.469506) (xy 11.996644 -158.422862) (xy 12.041165 -158.381736) (xy 12.090726 -158.346846)
			(xy 12.144458 -158.318804) (xy 12.201422 -158.2981) (xy 12.26062 -158.285096) (xy 12.321017 -158.280021)
			(xy 12.381556 -158.282962) (xy 12.441176 -158.293869) (xy 12.498835 -158.312551) (xy 12.553523 -158.33868)
			(xy 12.604284 -158.3718) (xy 12.650228 -158.41133) (xy 12.690553 -158.456579) (xy 12.724551 -158.506756)
			(xy 12.751629 -158.560981) (xy 12.771312 -158.618305) (xy 12.783255 -158.677727) (xy 12.787251 -158.738205)
			(xy 12.783228 -158.798681) (xy 12.777724 -158.828486) (xy 12.773959 -158.849631) (xy 12.772672 -158.892554)
			(xy 12.778614 -158.935084) (xy 12.791617 -158.976012) (xy 12.811311 -159.014173) (xy 12.837136 -159.048483)
			(xy 12.868358 -159.077967) (xy 12.904089 -159.101786) (xy 12.92352 -159.110934) (xy 12.948632 -159.12258)
			(xy 12.995431 -159.152142) (xy 13.037464 -159.18816) (xy 13.07385 -159.229875) (xy 13.103823 -159.276412)
			(xy 13.126755 -159.326793) (xy 13.142162 -159.37996) (xy 13.149722 -159.434795) (xy 13.149276 -159.490148)
			(xy 13.140832 -159.544854) (xy 13.12457 -159.597765) (xy 13.100829 -159.64777) (xy 13.070109 -159.693818)
			(xy 13.033055 -159.734941) (xy 12.990446 -159.770276) (xy 12.943177 -159.79908) (xy 12.89224 -159.820748)
			(xy 12.838706 -159.834826) (xy 12.783699 -159.841017) (xy 12.728375 -159.839191) (xy 12.673896 -159.829387)
			(xy 12.621406 -159.811811) (xy 12.572009 -159.786831) (xy 12.526741 -159.754973) (xy 12.486554 -159.716906)
			(xy 12.452292 -159.67343) (xy 12.424675 -159.625457) (xy 12.404283 -159.573996) (xy 12.391544 -159.520127)
			(xy 12.386725 -159.464983) (xy 12.387834 -159.437324) (xy 12.388571 -159.415854) (xy 12.383842 -159.373161)
			(xy 12.371994 -159.331874) (xy 12.353365 -159.293171) (xy 12.328486 -159.258156) (xy 12.298069 -159.227828)
			(xy 12.26298 -159.203054) (xy 12.224222 -159.18454) (xy 12.203684 -159.178244) (xy 12.174681 -159.169443)
			(xy 12.119094 -159.145285) (xy 12.067182 -159.114) (xy 12.019854 -159.076137) (xy 11.977938 -159.032358)
			(xy 11.942168 -158.983428) (xy 11.91317 -158.930206) (xy 11.891452 -158.873621) (xy 11.877392 -158.814664)
			(xy 11.871238 -158.754368) (xy 10.822432 -158.754368) (xy 10.822432 -160.955224) (xy 11.452842 -160.955224)
			(xy 11.452842 -160.895288) (xy 11.460665 -160.835866) (xy 11.476178 -160.777973) (xy 11.499114 -160.7226)
			(xy 11.529081 -160.670694) (xy 11.565568 -160.623144) (xy 11.607948 -160.580764) (xy 11.655498 -160.544277)
			(xy 11.707404 -160.51431) (xy 11.762777 -160.491374) (xy 11.82067 -160.475861) (xy 11.880092 -160.468038)
			(xy 11.940028 -160.468038) (xy 11.99945 -160.475861) (xy 12.057343 -160.491374) (xy 12.112716 -160.51431)
			(xy 12.164622 -160.544277) (xy 12.212172 -160.580764) (xy 12.254552 -160.623144) (xy 12.291039 -160.670694)
			(xy 12.321006 -160.7226) (xy 12.343942 -160.777973) (xy 12.359455 -160.835866) (xy 12.367278 -160.895288)
			(xy 12.367768 -160.925256) (xy 12.367278 -160.955224) (xy 12.359455 -161.014646) (xy 12.343942 -161.072539)
			(xy 12.321006 -161.127912) (xy 12.291039 -161.179818) (xy 12.254552 -161.227368) (xy 12.212172 -161.269748)
			(xy 12.164622 -161.306235) (xy 12.112716 -161.336202) (xy 12.057343 -161.359138) (xy 11.99945 -161.374651)
			(xy 11.940028 -161.382474) (xy 11.880092 -161.382474) (xy 11.82067 -161.374651) (xy 11.762777 -161.359138)
			(xy 11.707404 -161.336202) (xy 11.655498 -161.306235) (xy 11.607948 -161.269748) (xy 11.565568 -161.227368)
			(xy 11.529081 -161.179818) (xy 11.499114 -161.127912) (xy 11.476178 -161.072539) (xy 11.460665 -161.014646)
			(xy 11.452842 -160.955224) (xy 10.822432 -160.955224) (xy 10.822432 -161.77133) (xy 12.361162 -161.77133)
			(xy 12.365233 -161.715708) (xy 12.377359 -161.661271) (xy 12.397282 -161.60918) (xy 12.424578 -161.560545)
			(xy 12.458664 -161.516402) (xy 12.498813 -161.477693) (xy 12.544171 -161.445242) (xy 12.593771 -161.419741)
			(xy 12.646555 -161.401734) (xy 12.701398 -161.391604) (xy 12.757132 -161.389567) (xy 12.812569 -161.395667)
			(xy 12.866526 -161.409773) (xy 12.917855 -161.431585) (xy 12.965461 -161.460639) (xy 13.008329 -161.496314)
			(xy 13.045546 -161.537851) (xy 13.076319 -161.584364) (xy 13.099991 -161.634861) (xy 13.116059 -161.688268)
			(xy 13.124179 -161.743444) (xy 13.124688 -161.77133) (xy 13.124179 -161.799216) (xy 13.116059 -161.854392)
			(xy 13.099991 -161.907799) (xy 13.076319 -161.958296) (xy 13.045546 -162.004809) (xy 13.008329 -162.046346)
			(xy 12.965461 -162.082021) (xy 12.917855 -162.111075) (xy 12.866526 -162.132887) (xy 12.812569 -162.146993)
			(xy 12.757132 -162.153093) (xy 12.701398 -162.151056) (xy 12.646555 -162.140926) (xy 12.593771 -162.122919)
			(xy 12.544171 -162.097418) (xy 12.498813 -162.064967) (xy 12.458664 -162.026258) (xy 12.424578 -161.982115)
			(xy 12.397282 -161.93348) (xy 12.377359 -161.881389) (xy 12.365233 -161.826952) (xy 12.361162 -161.77133)
			(xy 10.822432 -161.77133) (xy 10.822432 -164.699696) (xy 10.822915 -164.722201) (xy 10.830841 -164.766508)
			(xy 10.846446 -164.808727) (xy 10.869242 -164.847538) (xy 10.898517 -164.881727) (xy 10.933356 -164.910227)
			(xy 10.972669 -164.932145) (xy 11.015228 -164.946798) (xy 11.059702 -164.953727) (xy 11.104701 -164.952715)
			(xy 11.148818 -164.943794) (xy 11.169904 -164.935916) (xy 11.198682 -164.925045) (xy 11.25839 -164.91024)
			(xy 11.319544 -164.903567) (xy 11.381041 -164.905145) (xy 11.441772 -164.914948) (xy 11.500642 -164.932797)
			(xy 11.556591 -164.958371) (xy 11.60861 -164.99121) (xy 11.655761 -165.030721) (xy 11.697195 -165.076192)
			(xy 11.732164 -165.126803) (xy 11.760038 -165.181642) (xy 11.780315 -165.239721) (xy 11.792629 -165.299993)
			(xy 11.796758 -165.361371) (xy 11.792628 -165.42275) (xy 11.780314 -165.483021) (xy 11.760037 -165.5411)
			(xy 11.732162 -165.59594) (xy 11.697193 -165.646551) (xy 11.655759 -165.692021) (xy 11.608608 -165.731532)
			(xy 11.556589 -165.76437) (xy 11.50064 -165.789944) (xy 11.441769 -165.807793) (xy 11.381038 -165.817595)
			(xy 11.319541 -165.819173) (xy 11.258388 -165.8125) (xy 11.198679 -165.797694) (xy 11.169904 -165.786816)
			(xy 11.148799 -165.778981) (xy 11.104681 -165.770043) (xy 11.059678 -165.769017) (xy 11.015199 -165.775934)
			(xy 10.972633 -165.790579) (xy 10.933313 -165.812493) (xy 10.898468 -165.840991) (xy 10.869189 -165.875181)
			(xy 10.84639 -165.913995) (xy 10.830784 -165.956217) (xy 10.822861 -166.000529) (xy 10.822432 -166.023036)
			(xy 10.822432 -166.386764) (xy 11.178794 -166.743126) (xy 14.65072 -166.743126)
		)
		(stroke
			(width 0)
			(type solid)
		)
		(fill yes)
		(layer "B.Cu")
		(net "N54065132")
	)
	(gr_poly
		(pts
			(xy 88.69172 -131.191) (xy 88.69426 -131.1402) (xy 88.696271 -131.111062) (xy 88.708039 -131.053855)
			(xy 88.728391 -130.999112) (xy 88.756851 -130.948111) (xy 88.792754 -130.902045) (xy 88.81364 -130.881628)
			(xy 88.830035 -130.865509) (xy 88.857292 -130.82849) (xy 88.877451 -130.787174) (xy 88.889855 -130.742908)
			(xy 88.894099 -130.697132) (xy 88.890046 -130.65134) (xy 88.877828 -130.607021) (xy 88.857841 -130.565622)
			(xy 88.830739 -130.528489) (xy 88.814402 -130.512312) (xy 88.792925 -130.491315) (xy 88.755098 -130.444658)
			(xy 88.7237 -130.393453) (xy 88.699271 -130.33858) (xy 88.682232 -130.280983) (xy 88.672874 -130.221652)
			(xy 88.671359 -130.161606) (xy 88.677713 -130.101879) (xy 88.691827 -130.043496) (xy 88.713457 -129.987461)
			(xy 88.742233 -129.934738) (xy 88.777659 -129.886233) (xy 88.819127 -129.84278) (xy 88.865923 -129.805125)
			(xy 88.917243 -129.773916) (xy 88.972206 -129.74969) (xy 89.029865 -129.732863) (xy 89.08923 -129.723724)
			(xy 89.149281 -129.722431) (xy 89.208985 -129.729005) (xy 89.267315 -129.743333) (xy 89.32327 -129.76517)
			(xy 89.375886 -129.79414) (xy 89.40038 -129.811526) (xy 89.418509 -129.824245) (xy 89.4582 -129.843875)
			(xy 89.500693 -129.856332) (xy 89.544701 -129.861238) (xy 89.588893 -129.858445) (xy 89.631933 -129.848038)
			(xy 89.67252 -129.830332) (xy 89.709424 -129.805861) (xy 89.741531 -129.775367) (xy 89.767869 -129.739771)
			(xy 89.787642 -129.70015) (xy 89.800251 -129.657702) (xy 89.803224 -129.635758) (xy 90.05189 -127.475488)
			(xy 90.202004 -126.321312) (xy 90.051128 -124.652786) (xy 90.089482 -124.090684) (xy 90.090081 -124.076244)
			(xy 90.085508 -124.047714) (xy 90.074619 -124.020951) (xy 90.057976 -123.997331) (xy 90.036436 -123.978073)
			(xy 90.02395 -123.970796) (xy 90.00045 -123.95731) (xy 89.957167 -123.924718) (xy 89.918927 -123.886333)
			(xy 89.886501 -123.842926) (xy 89.86054 -123.795369) (xy 89.841565 -123.744619) (xy 89.829959 -123.691695)
			(xy 89.825953 -123.637662) (xy 89.82963 -123.583605) (xy 89.840915 -123.530612) (xy 89.859581 -123.479747)
			(xy 89.885252 -123.432033) (xy 89.917414 -123.388429) (xy 89.955419 -123.349813) (xy 89.998503 -123.316959)
			(xy 90.045801 -123.290528) (xy 90.07094 -123.280424) (xy 90.084278 -123.274894) (xy 90.108218 -123.258761)
			(xy 90.127918 -123.237659) (xy 90.142369 -123.212668) (xy 90.150833 -123.185068) (xy 90.15222 -123.170696)
			(xy 90.159586 -123.062238) (xy 90.145108 -122.822462) (xy 90.115644 -122.344434) (xy 88.396572 -115.309904)
			(xy 88.361266 -115.185444) (xy 88.35623 -115.169554) (xy 88.339125 -115.140957) (xy 88.3152 -115.117763)
			(xy 88.286085 -115.101554) (xy 88.253766 -115.093435) (xy 88.220448 -115.09396) (xy 88.204294 -115.098068)
			(xy 88.1761 -115.105942) (xy 88.13292 -115.144804) (xy 88.121744 -115.171728) (xy 88.109656 -115.199731)
			(xy 88.079127 -115.252534) (xy 88.041855 -115.300814) (xy 87.998501 -115.343716) (xy 87.949833 -115.38048)
			(xy 87.896713 -115.410454) (xy 87.840082 -115.433107) (xy 87.780945 -115.448037) (xy 87.720348 -115.454981)
			(xy 87.659366 -115.453815) (xy 87.599079 -115.444559) (xy 87.540556 -115.427378) (xy 87.484833 -115.402576)
			(xy 87.432898 -115.370593) (xy 87.385672 -115.331995) (xy 87.34399 -115.287466) (xy 87.308592 -115.237796)
			(xy 87.280104 -115.183864) (xy 87.259033 -115.126627) (xy 87.24575 -115.067098) (xy 87.240492 -115.006331)
			(xy 87.243351 -114.945405) (xy 87.254277 -114.885399) (xy 87.273076 -114.827375) (xy 87.299416 -114.772363)
			(xy 87.332829 -114.721336) (xy 87.372723 -114.675199) (xy 87.418392 -114.63477) (xy 87.469026 -114.600764)
			(xy 87.523728 -114.573785) (xy 87.581529 -114.554311) (xy 87.641404 -114.542686) (xy 87.702292 -114.539117)
			(xy 87.763116 -114.543667) (xy 87.793068 -114.549428) (xy 87.81447 -114.553492) (xy 87.858002 -114.5551)
			(xy 87.90117 -114.549264) (xy 87.942711 -114.536155) (xy 87.98141 -114.516156) (xy 88.016133 -114.489853)
			(xy 88.045864 -114.458016) (xy 88.069733 -114.421577) (xy 88.08704 -114.381602) (xy 88.097281 -114.339262)
			(xy 88.100153 -114.295796) (xy 88.095575 -114.252477) (xy 88.089994 -114.23142) (xy 87.879936 -113.492788)
			(xy 86.485476 -112.098328) (xy 84.686394 -112.098328) (xy 84.632038 -112.043972) (xy 83.142582 -112.043972)
			(xy 83.015582 -112.170972) (xy 82.571844 -112.170972) (xy 82.238088 -112.504728) (xy 82.248248 -112.514634)
			(xy 82.248248 -113.658396) (xy 84.035646 -115.445794) (xy 84.984334 -115.445794) (xy 84.988405 -115.390172)
			(xy 85.000531 -115.335735) (xy 85.020454 -115.283644) (xy 85.04775 -115.235009) (xy 85.081836 -115.190866)
			(xy 85.121985 -115.152157) (xy 85.167343 -115.119706) (xy 85.216943 -115.094205) (xy 85.269727 -115.076198)
			(xy 85.32457 -115.066068) (xy 85.380304 -115.064031) (xy 85.435741 -115.070131) (xy 85.489698 -115.084237)
			(xy 85.541027 -115.106049) (xy 85.588633 -115.135103) (xy 85.631501 -115.170778) (xy 85.668718 -115.212315)
			(xy 85.699491 -115.258828) (xy 85.723163 -115.309325) (xy 85.739231 -115.362732) (xy 85.747351 -115.417908)
			(xy 85.74786 -115.445794) (xy 85.747351 -115.47368) (xy 85.739231 -115.528856) (xy 85.723163 -115.582263)
			(xy 85.699491 -115.63276) (xy 85.668718 -115.679273) (xy 85.631501 -115.72081) (xy 85.588633 -115.756485)
			(xy 85.541027 -115.785539) (xy 85.489698 -115.807351) (xy 85.435741 -115.821457) (xy 85.380304 -115.827557)
			(xy 85.32457 -115.82552) (xy 85.269727 -115.81539) (xy 85.216943 -115.797383) (xy 85.167343 -115.771882)
			(xy 85.121985 -115.739431) (xy 85.081836 -115.700722) (xy 85.04775 -115.656579) (xy 85.020454 -115.607944)
			(xy 85.000531 -115.555853) (xy 84.988405 -115.501416) (xy 84.984334 -115.445794) (xy 84.035646 -115.445794)
			(xy 84.795868 -116.206016) (xy 84.795868 -116.40058) (xy 85.4075 -117.012466) (xy 85.4075 -118.499128)
			(xy 87.692482 -118.499128) (xy 87.696553 -118.443506) (xy 87.708679 -118.389069) (xy 87.728602 -118.336978)
			(xy 87.755898 -118.288343) (xy 87.789984 -118.2442) (xy 87.830133 -118.205491) (xy 87.875491 -118.17304)
			(xy 87.925091 -118.147539) (xy 87.977875 -118.129532) (xy 88.032718 -118.119402) (xy 88.088452 -118.117365)
			(xy 88.143889 -118.123465) (xy 88.197846 -118.137571) (xy 88.249175 -118.159383) (xy 88.296781 -118.188437)
			(xy 88.339649 -118.224112) (xy 88.376866 -118.265649) (xy 88.407639 -118.312162) (xy 88.431311 -118.362659)
			(xy 88.447379 -118.416066) (xy 88.455499 -118.471242) (xy 88.456008 -118.499128) (xy 88.455499 -118.527014)
			(xy 88.447379 -118.58219) (xy 88.431311 -118.635597) (xy 88.407639 -118.686094) (xy 88.376866 -118.732607)
			(xy 88.339649 -118.774144) (xy 88.296781 -118.809819) (xy 88.249175 -118.838873) (xy 88.197846 -118.860685)
			(xy 88.143889 -118.874791) (xy 88.088452 -118.880891) (xy 88.032718 -118.878854) (xy 87.977875 -118.868724)
			(xy 87.925091 -118.850717) (xy 87.875491 -118.825216) (xy 87.830133 -118.792765) (xy 87.789984 -118.754056)
			(xy 87.755898 -118.709913) (xy 87.728602 -118.661278) (xy 87.708679 -118.609187) (xy 87.696553 -118.55475)
			(xy 87.692482 -118.499128) (xy 85.4075 -118.499128) (xy 85.4075 -121.838805) (xy 85.663611 -121.838805)
			(xy 85.665973 -121.783735) (xy 85.676235 -121.729579) (xy 85.694183 -121.677462) (xy 85.719444 -121.628471)
			(xy 85.751491 -121.583625) (xy 85.789659 -121.543857) (xy 85.833151 -121.509995) (xy 85.881064 -121.482744)
			(xy 85.932399 -121.462671) (xy 85.986089 -121.450194) (xy 86.041015 -121.445573) (xy 86.096034 -121.448903)
			(xy 86.150002 -121.460116) (xy 86.201794 -121.478978) (xy 86.250333 -121.505097) (xy 86.294609 -121.537929)
			(xy 86.333699 -121.576789) (xy 86.366791 -121.620871) (xy 86.393195 -121.669255) (xy 86.412362 -121.720936)
			(xy 86.423892 -121.774837) (xy 86.427547 -121.829835) (xy 86.423249 -121.884788) (xy 86.411089 -121.93855)
			(xy 86.401656 -121.96445) (xy 86.39447 -121.984404) (xy 86.385988 -122.025954) (xy 86.384524 -122.068336)
			(xy 86.390118 -122.110373) (xy 86.402616 -122.150896) (xy 86.421669 -122.188782) (xy 86.446749 -122.222978)
			(xy 86.47716 -122.252534) (xy 86.494366 -122.264932) (xy 86.518992 -122.282453) (xy 86.563797 -122.323019)
			(xy 86.602873 -122.369128) (xy 86.635541 -122.419979) (xy 86.661232 -122.474686) (xy 86.679501 -122.532299)
			(xy 86.690028 -122.591816) (xy 86.692631 -122.652199) (xy 86.687264 -122.712401) (xy 86.674022 -122.771372)
			(xy 86.653133 -122.828088) (xy 86.624962 -122.881561) (xy 86.589999 -122.930862) (xy 86.548851 -122.975132)
			(xy 86.502236 -123.013603) (xy 86.450962 -123.045604) (xy 86.395924 -123.070578) (xy 86.338077 -123.088092)
			(xy 86.278428 -123.097841) (xy 86.218015 -123.099654) (xy 86.157889 -123.093502) (xy 86.099096 -123.07949)
			(xy 86.042658 -123.057862) (xy 85.989558 -123.028995) (xy 85.940718 -122.99339) (xy 85.896989 -122.951668)
			(xy 85.859131 -122.904553) (xy 85.827803 -122.852866) (xy 85.803549 -122.797506) (xy 85.786793 -122.739435)
			(xy 85.777824 -122.679664) (xy 85.7768 -122.619233) (xy 85.783738 -122.559193) (xy 85.798517 -122.500587)
			(xy 85.82088 -122.444437) (xy 85.835236 -122.41784) (xy 85.845238 -122.399149) (xy 85.859554 -122.35925)
			(xy 85.867036 -122.317527) (xy 85.867477 -122.27514) (xy 85.860864 -122.23327) (xy 85.847382 -122.193082)
			(xy 85.827405 -122.155695) (xy 85.80149 -122.12215) (xy 85.786214 -122.107452) (xy 85.766301 -122.088393)
			(xy 85.73168 -122.045503) (xy 85.70359 -121.998077) (xy 85.682617 -121.947103) (xy 85.669198 -121.893641)
			(xy 85.663611 -121.838805) (xy 85.4075 -121.838805) (xy 85.4075 -123.186698) (xy 85.40804 -123.203315)
			(xy 85.416632 -123.23542) (xy 85.433233 -123.264212) (xy 85.444584 -123.27636) (xy 85.76517 -123.596904)
			(xy 87.990662 -123.596904) (xy 87.990662 -123.536968) (xy 87.998485 -123.477546) (xy 88.013998 -123.419653)
			(xy 88.036934 -123.36428) (xy 88.066901 -123.312374) (xy 88.103388 -123.264824) (xy 88.145768 -123.222444)
			(xy 88.193318 -123.185957) (xy 88.245224 -123.15599) (xy 88.300597 -123.133054) (xy 88.35849 -123.117541)
			(xy 88.417912 -123.109718) (xy 88.477848 -123.109718) (xy 88.53727 -123.117541) (xy 88.595163 -123.133054)
			(xy 88.650536 -123.15599) (xy 88.702442 -123.185957) (xy 88.749992 -123.222444) (xy 88.792372 -123.264824)
			(xy 88.828859 -123.312374) (xy 88.858826 -123.36428) (xy 88.881762 -123.419653) (xy 88.897275 -123.477546)
			(xy 88.905098 -123.536968) (xy 88.905588 -123.566936) (xy 88.905098 -123.596904) (xy 88.897275 -123.656326)
			(xy 88.881762 -123.714219) (xy 88.858826 -123.769592) (xy 88.828859 -123.821498) (xy 88.792372 -123.869048)
			(xy 88.749992 -123.911428) (xy 88.702442 -123.947915) (xy 88.650536 -123.977882) (xy 88.595163 -124.000818)
			(xy 88.53727 -124.016331) (xy 88.477848 -124.024154) (xy 88.417912 -124.024154) (xy 88.35849 -124.016331)
			(xy 88.300597 -124.000818) (xy 88.245224 -123.977882) (xy 88.193318 -123.947915) (xy 88.145768 -123.911428)
			(xy 88.103388 -123.869048) (xy 88.066901 -123.821498) (xy 88.036934 -123.769592) (xy 88.013998 -123.714219)
			(xy 87.998485 -123.656326) (xy 87.990662 -123.596904) (xy 85.76517 -123.596904) (xy 87.40648 -125.238002)
			(xy 87.40648 -126.017782) (xy 87.438738 -126.07544) (xy 87.467186 -126.092712) (xy 87.493558 -126.109431)
			(xy 87.541936 -126.148906) (xy 87.584499 -126.194592) (xy 87.620456 -126.24564) (xy 87.64914 -126.301102)
			(xy 87.670019 -126.359948) (xy 87.682704 -126.421086) (xy 87.686961 -126.483381) (xy 87.682709 -126.545677)
			(xy 87.670029 -126.606816) (xy 87.649155 -126.665664) (xy 87.620476 -126.721128) (xy 87.584523 -126.772179)
			(xy 87.541963 -126.817868) (xy 87.493588 -126.857348) (xy 87.467186 -126.874016) (xy 87.438738 -126.891288)
			(xy 87.40648 -126.948946) (xy 87.40648 -127.429002) (xy 88.155762 -127.429002) (xy 88.155762 -127.369066)
			(xy 88.163585 -127.309644) (xy 88.179098 -127.251751) (xy 88.202034 -127.196378) (xy 88.232001 -127.144472)
			(xy 88.268488 -127.096922) (xy 88.310868 -127.054542) (xy 88.358418 -127.018055) (xy 88.410324 -126.988088)
			(xy 88.465697 -126.965152) (xy 88.52359 -126.949639) (xy 88.583012 -126.941816) (xy 88.642948 -126.941816)
			(xy 88.70237 -126.949639) (xy 88.760263 -126.965152) (xy 88.815636 -126.988088) (xy 88.867542 -127.018055)
			(xy 88.915092 -127.054542) (xy 88.957472 -127.096922) (xy 88.993959 -127.144472) (xy 89.023926 -127.196378)
			(xy 89.046862 -127.251751) (xy 89.062375 -127.309644) (xy 89.070198 -127.369066) (xy 89.070688 -127.399034)
			(xy 89.070198 -127.429002) (xy 89.062375 -127.488424) (xy 89.046862 -127.546317) (xy 89.023926 -127.60169)
			(xy 88.993959 -127.653596) (xy 88.957472 -127.701146) (xy 88.915092 -127.743526) (xy 88.867542 -127.780013)
			(xy 88.815636 -127.80998) (xy 88.760263 -127.832916) (xy 88.70237 -127.848429) (xy 88.642948 -127.856252)
			(xy 88.583012 -127.856252) (xy 88.52359 -127.848429) (xy 88.465697 -127.832916) (xy 88.410324 -127.80998)
			(xy 88.358418 -127.780013) (xy 88.310868 -127.743526) (xy 88.268488 -127.701146) (xy 88.232001 -127.653596)
			(xy 88.202034 -127.60169) (xy 88.179098 -127.546317) (xy 88.163585 -127.488424) (xy 88.155762 -127.429002)
			(xy 87.40648 -127.429002) (xy 87.40648 -130.722878) (xy 87.663274 -130.979672) (xy 87.742014 -130.993388)
			(xy 87.77859 -130.97637) (xy 87.805642 -130.964205) (xy 87.862149 -130.946174) (xy 87.920511 -130.935593)
			(xy 87.979752 -130.932639) (xy 88.038878 -130.937363) (xy 88.096898 -130.949685) (xy 88.152841 -130.969398)
			(xy 88.205768 -130.996173) (xy 88.254793 -131.02956) (xy 88.299095 -131.069) (xy 88.337931 -131.113833)
			(xy 88.37065 -131.163307) (xy 88.384126 -131.18973) (xy 88.400128 -131.222496) (xy 88.461596 -131.26085)
			(xy 88.618314 -131.26085)
		)
		(stroke
			(width 0)
			(type solid)
		)
		(fill yes)
		(layer "B.Cu")
		(net "P1V8_NODE1")
	)
	(gr_poly
		(pts
			(xy 171.482512 -124.645928) (xy 171.482512 -120.175528) (xy 172.498512 -119.159528) (xy 172.498512 -118.345458)
			(xy 172.498 -118.329091) (xy 172.489658 -118.297436) (xy 172.473535 -118.268947) (xy 172.450692 -118.245499)
			(xy 172.422634 -118.228637) (xy 172.407072 -118.223538) (xy 172.406818 -118.223538) (xy 172.381312 -118.215671)
			(xy 172.332689 -118.193652) (xy 172.287706 -118.16492) (xy 172.247284 -118.130062) (xy 172.212251 -118.089792)
			(xy 172.183323 -118.044934) (xy 172.161093 -117.996407) (xy 172.146016 -117.945205) (xy 172.1384 -117.892375)
			(xy 172.138402 -117.838999) (xy 172.146022 -117.786169) (xy 172.161102 -117.734968) (xy 172.183336 -117.686442)
			(xy 172.212267 -117.641587) (xy 172.247303 -117.601319) (xy 172.287727 -117.566464) (xy 172.332712 -117.537735)
			(xy 172.381337 -117.515719) (xy 172.406818 -117.507766) (xy 172.407072 -117.507766) (xy 172.422647 -117.502696)
			(xy 172.450713 -117.48583) (xy 172.473562 -117.462376) (xy 172.48969 -117.43388) (xy 172.498035 -117.402218)
			(xy 172.498512 -117.385846) (xy 172.498512 -116.467128) (xy 172.981112 -115.984528) (xy 175.5648 -115.984528)
			(xy 176.438052 -115.111276) (xy 178.83886 -115.111276) (xy 180.397912 -116.670328) (xy 181.362094 -116.670328)
			(xy 181.366165 -116.614706) (xy 181.378291 -116.560269) (xy 181.398214 -116.508178) (xy 181.42551 -116.459543)
			(xy 181.459596 -116.4154) (xy 181.499745 -116.376691) (xy 181.545103 -116.34424) (xy 181.594703 -116.318739)
			(xy 181.647487 -116.300732) (xy 181.70233 -116.290602) (xy 181.758064 -116.288565) (xy 181.813501 -116.294665)
			(xy 181.867458 -116.308771) (xy 181.918787 -116.330583) (xy 181.966393 -116.359637) (xy 182.009261 -116.395312)
			(xy 182.046478 -116.436849) (xy 182.077251 -116.483362) (xy 182.100923 -116.533859) (xy 182.116991 -116.587266)
			(xy 182.125111 -116.642442) (xy 182.12562 -116.670328) (xy 182.125111 -116.698214) (xy 182.116991 -116.75339)
			(xy 182.100923 -116.806797) (xy 182.077251 -116.857294) (xy 182.046478 -116.903807) (xy 182.009261 -116.945344)
			(xy 181.966393 -116.981019) (xy 181.918787 -117.010073) (xy 181.867458 -117.031885) (xy 181.813501 -117.045991)
			(xy 181.758064 -117.052091) (xy 181.70233 -117.050054) (xy 181.647487 -117.039924) (xy 181.594703 -117.021917)
			(xy 181.545103 -116.996416) (xy 181.499745 -116.963965) (xy 181.459596 -116.925256) (xy 181.42551 -116.881113)
			(xy 181.398214 -116.832478) (xy 181.378291 -116.780387) (xy 181.366165 -116.72595) (xy 181.362094 -116.670328)
			(xy 180.397912 -116.670328) (xy 180.474112 -116.746528) (xy 180.474112 -119.374412) (xy 180.474542 -119.389116)
			(xy 180.481299 -119.417739) (xy 180.494429 -119.444054) (xy 180.513234 -119.466666) (xy 180.536715 -119.484372)
			(xy 180.563627 -119.496234) (xy 180.577998 -119.49938) (xy 180.605366 -119.504926) (xy 180.658159 -119.523119)
			(xy 180.707647 -119.548985) (xy 180.752723 -119.581945) (xy 180.792376 -119.621261) (xy 180.825719 -119.666053)
			(xy 180.852007 -119.715318) (xy 180.870651 -119.767954) (xy 180.881233 -119.822783) (xy 180.882798 -119.850662)
			(xy 180.883958 -119.866844) (xy 180.893438 -119.89786) (xy 180.910439 -119.92548) (xy 180.93386 -119.947914)
			(xy 180.962186 -119.963711) (xy 180.993581 -119.971848) (xy 181.009798 -119.972328) (xy 182.277004 -119.972328)
			(xy 182.343552 -119.923306) (xy 182.356252 -119.883682) (xy 182.364817 -119.85814) (xy 182.388129 -119.809573)
			(xy 182.418044 -119.76477) (xy 182.453965 -119.724621) (xy 182.495178 -119.689927) (xy 182.540863 -119.661378)
			(xy 182.590111 -119.639541) (xy 182.641941 -119.624851) (xy 182.695323 -119.617601) (xy 182.749194 -119.617934)
			(xy 182.802482 -119.625845) (xy 182.854127 -119.641175) (xy 182.903101 -119.66362) (xy 182.948429 -119.692734)
			(xy 182.969154 -119.709946) (xy 182.987512 -119.725068) (xy 183.028678 -119.748881) (xy 183.073554 -119.764622)
			(xy 183.120575 -119.771741) (xy 183.1681 -119.769989) (xy 183.214469 -119.759427) (xy 183.258065 -119.740424)
			(xy 183.297364 -119.713644) (xy 183.314594 -119.697246) (xy 183.598312 -119.413528) (xy 183.598312 -114.384328)
			(xy 182.556912 -113.342928) (xy 173.712886 -113.342928) (xy 173.680374 -113.365026) (xy 173.654905 -113.381833)
			(xy 173.600407 -113.40928) (xy 173.542744 -113.429241) (xy 173.48294 -113.441361) (xy 173.422056 -113.445425)
			(xy 173.361172 -113.441361) (xy 173.301368 -113.429241) (xy 173.243705 -113.40928) (xy 173.189207 -113.381833)
			(xy 173.163738 -113.365026) (xy 173.131226 -113.342928) (xy 172.263054 -113.342928) (xy 172.230796 -113.364518)
			(xy 172.205562 -113.38087) (xy 172.151669 -113.407537) (xy 172.094748 -113.42692) (xy 172.035781 -113.438684)
			(xy 171.97578 -113.442628) (xy 171.915779 -113.438684) (xy 171.856812 -113.42692) (xy 171.799891 -113.407537)
			(xy 171.745998 -113.38087) (xy 171.720764 -113.364518) (xy 171.688506 -113.342928) (xy 170.035474 -113.342928)
			(xy 170.019847 -113.34338) (xy 169.989535 -113.350991) (xy 169.961997 -113.36577) (xy 169.95013 -113.375948)
			(xy 169.926394 -113.396773) (xy 169.874242 -113.432375) (xy 169.81769 -113.460465) (xy 169.757811 -113.48051)
			(xy 169.695745 -113.49213) (xy 169.63267 -113.495102) (xy 169.569786 -113.489371) (xy 169.508288 -113.475045)
			(xy 169.449345 -113.452397) (xy 169.394077 -113.421857) (xy 169.36847 -113.40338) (xy 169.277792 -113.414048)
			(xy 168.390574 -114.301266) (xy 170.672742 -114.301266) (xy 170.672742 -114.24133) (xy 170.680565 -114.181908)
			(xy 170.696078 -114.124015) (xy 170.719014 -114.068642) (xy 170.748981 -114.016736) (xy 170.785468 -113.969186)
			(xy 170.827848 -113.926806) (xy 170.875398 -113.890319) (xy 170.927304 -113.860352) (xy 170.982677 -113.837416)
			(xy 171.04057 -113.821903) (xy 171.099992 -113.81408) (xy 171.159928 -113.81408) (xy 171.21935 -113.821903)
			(xy 171.277243 -113.837416) (xy 171.332616 -113.860352) (xy 171.384522 -113.890319) (xy 171.432072 -113.926806)
			(xy 171.474452 -113.969186) (xy 171.510939 -114.016736) (xy 171.540906 -114.068642) (xy 171.563842 -114.124015)
			(xy 171.579355 -114.181908) (xy 171.587178 -114.24133) (xy 171.587668 -114.271298) (xy 171.587178 -114.301266)
			(xy 171.579355 -114.360688) (xy 171.563842 -114.418581) (xy 171.540906 -114.473954) (xy 171.510939 -114.52586)
			(xy 171.474452 -114.57341) (xy 171.432072 -114.61579) (xy 171.384522 -114.652277) (xy 171.332616 -114.682244)
			(xy 171.277243 -114.70518) (xy 171.21935 -114.720693) (xy 171.159928 -114.728516) (xy 171.099992 -114.728516)
			(xy 171.04057 -114.720693) (xy 170.982677 -114.70518) (xy 170.927304 -114.682244) (xy 170.875398 -114.652277)
			(xy 170.827848 -114.61579) (xy 170.785468 -114.57341) (xy 170.748981 -114.52586) (xy 170.719014 -114.473954)
			(xy 170.696078 -114.418581) (xy 170.680565 -114.360688) (xy 170.672742 -114.301266) (xy 168.390574 -114.301266)
			(xy 168.053512 -114.638328) (xy 168.053512 -116.132864) (xy 170.354242 -116.132864) (xy 170.358313 -116.077242)
			(xy 170.370439 -116.022805) (xy 170.390362 -115.970714) (xy 170.417658 -115.922079) (xy 170.451744 -115.877936)
			(xy 170.491893 -115.839227) (xy 170.537251 -115.806776) (xy 170.586851 -115.781275) (xy 170.639635 -115.763268)
			(xy 170.694478 -115.753138) (xy 170.750212 -115.751101) (xy 170.805649 -115.757201) (xy 170.859606 -115.771307)
			(xy 170.910935 -115.793119) (xy 170.958541 -115.822173) (xy 171.001409 -115.857848) (xy 171.038626 -115.899385)
			(xy 171.069399 -115.945898) (xy 171.093071 -115.996395) (xy 171.109139 -116.049802) (xy 171.117259 -116.104978)
			(xy 171.117768 -116.132864) (xy 171.117259 -116.16075) (xy 171.109139 -116.215926) (xy 171.093071 -116.269333)
			(xy 171.069399 -116.31983) (xy 171.038626 -116.366343) (xy 171.001409 -116.40788) (xy 170.958541 -116.443555)
			(xy 170.910935 -116.472609) (xy 170.859606 -116.494421) (xy 170.805649 -116.508527) (xy 170.750212 -116.514627)
			(xy 170.694478 -116.51259) (xy 170.639635 -116.50246) (xy 170.586851 -116.484453) (xy 170.537251 -116.458952)
			(xy 170.491893 -116.426501) (xy 170.451744 -116.387792) (xy 170.417658 -116.343649) (xy 170.390362 -116.295014)
			(xy 170.370439 -116.242923) (xy 170.358313 -116.188486) (xy 170.354242 -116.132864) (xy 168.053512 -116.132864)
			(xy 168.053512 -117.815868) (xy 170.912546 -117.815868) (xy 170.916522 -117.761542) (xy 170.928365 -117.708373)
			(xy 170.947824 -117.657496) (xy 170.974484 -117.609994) (xy 171.007775 -117.56688) (xy 171.046989 -117.529073)
			(xy 171.091291 -117.497378) (xy 171.139734 -117.472472) (xy 171.191288 -117.454884) (xy 171.244854 -117.44499)
			(xy 171.299289 -117.443) (xy 171.353434 -117.448958) (xy 171.406134 -117.462736) (xy 171.456267 -117.48404)
			(xy 171.502763 -117.512416) (xy 171.544633 -117.54726) (xy 171.580982 -117.587829) (xy 171.611038 -117.633258)
			(xy 171.634159 -117.682579) (xy 171.649852 -117.734741) (xy 171.657783 -117.788632) (xy 171.65828 -117.815868)
			(xy 171.657783 -117.843104) (xy 171.649852 -117.896995) (xy 171.634159 -117.949157) (xy 171.611038 -117.998478)
			(xy 171.580982 -118.043907) (xy 171.544633 -118.084476) (xy 171.502763 -118.11932) (xy 171.456267 -118.147696)
			(xy 171.406134 -118.169) (xy 171.353434 -118.182778) (xy 171.299289 -118.188736) (xy 171.244854 -118.186746)
			(xy 171.191288 -118.176852) (xy 171.139734 -118.159264) (xy 171.091291 -118.134358) (xy 171.046989 -118.102663)
			(xy 171.007775 -118.064856) (xy 170.974484 -118.021742) (xy 170.947824 -117.97424) (xy 170.928365 -117.923363)
			(xy 170.916522 -117.870194) (xy 170.912546 -117.815868) (xy 168.053512 -117.815868) (xy 168.053512 -118.134384)
			(xy 168.053512 -118.167912) (xy 168.053512 -119.214392) (xy 168.053979 -119.230477) (xy 168.062014 -119.261626)
			(xy 168.077576 -119.289781) (xy 168.08831 -119.301768) (xy 168.109665 -119.325054) (xy 168.146427 -119.37644)
			(xy 168.175771 -119.432395) (xy 168.197138 -119.491855) (xy 168.210121 -119.553688) (xy 168.214475 -119.61672)
			(xy 168.210116 -119.679752) (xy 168.197127 -119.741585) (xy 168.175755 -119.801042) (xy 168.146406 -119.856995)
			(xy 168.109639 -119.908377) (xy 168.08831 -119.931688) (xy 168.077578 -119.943682) (xy 168.061982 -119.971824)
			(xy 168.053936 -120.002976) (xy 168.053512 -120.019064) (xy 168.053512 -120.457214) (xy 168.054013 -120.480159)
			(xy 168.062267 -120.525302) (xy 168.078487 -120.568231) (xy 168.102146 -120.607553) (xy 168.132476 -120.641993)
			(xy 168.168494 -120.670431) (xy 168.209029 -120.691946) (xy 168.252767 -120.705839) (xy 168.298287 -120.711659)
			(xy 168.321228 -120.71096) (xy 168.352037 -120.709788) (xy 168.413494 -120.714733) (xy 168.473729 -120.727885)
			(xy 168.531654 -120.749006) (xy 168.586218 -120.777713) (xy 168.636433 -120.813487) (xy 168.681391 -120.855679)
			(xy 168.720276 -120.903525) (xy 168.752385 -120.956159) (xy 168.777137 -121.012627) (xy 168.794082 -121.071908)
			(xy 168.802914 -121.132927) (xy 168.803473 -121.194579) (xy 168.79575 -121.255749) (xy 168.779883 -121.315327)
			(xy 168.75616 -121.372235) (xy 168.725011 -121.425443) (xy 168.713663 -121.439936) (xy 169.157378 -121.439936)
			(xy 169.157378 -121.38) (xy 169.165201 -121.320578) (xy 169.180714 -121.262685) (xy 169.20365 -121.207312)
			(xy 169.233617 -121.155406) (xy 169.270104 -121.107856) (xy 169.312484 -121.065476) (xy 169.360034 -121.028989)
			(xy 169.41194 -120.999022) (xy 169.467313 -120.976086) (xy 169.525206 -120.960573) (xy 169.584628 -120.95275)
			(xy 169.644564 -120.95275) (xy 169.703986 -120.960573) (xy 169.761879 -120.976086) (xy 169.817252 -120.999022)
			(xy 169.869158 -121.028989) (xy 169.916708 -121.065476) (xy 169.959088 -121.107856) (xy 169.995575 -121.155406)
			(xy 170.025542 -121.207312) (xy 170.048478 -121.262685) (xy 170.063991 -121.320578) (xy 170.071814 -121.38)
			(xy 170.072304 -121.409968) (xy 170.071814 -121.439936) (xy 170.063991 -121.499358) (xy 170.048478 -121.557251)
			(xy 170.025542 -121.612624) (xy 169.995575 -121.66453) (xy 169.959088 -121.71208) (xy 169.916708 -121.75446)
			(xy 169.869158 -121.790947) (xy 169.817252 -121.820914) (xy 169.761879 -121.84385) (xy 169.703986 -121.859363)
			(xy 169.644564 -121.867186) (xy 169.584628 -121.867186) (xy 169.525206 -121.859363) (xy 169.467313 -121.84385)
			(xy 169.41194 -121.820914) (xy 169.360034 -121.790947) (xy 169.312484 -121.75446) (xy 169.270104 -121.71208)
			(xy 169.233617 -121.66453) (xy 169.20365 -121.612624) (xy 169.180714 -121.557251) (xy 169.165201 -121.499358)
			(xy 169.157378 -121.439936) (xy 168.713663 -121.439936) (xy 168.687 -121.473987) (xy 168.642815 -121.516988)
			(xy 168.593257 -121.553666) (xy 168.539223 -121.583358) (xy 168.481691 -121.605527) (xy 168.421704 -121.61977)
			(xy 168.391078 -121.623328) (xy 168.372028 -121.62536) (xy 168.296082 -121.65711) (xy 168.28135 -121.669556)
			(xy 168.259986 -121.686932) (xy 168.213851 -121.717001) (xy 168.164448 -121.741332) (xy 168.138602 -121.750836)
			(xy 168.138348 -121.750836) (xy 168.123707 -121.756474) (xy 168.097556 -121.77379) (xy 168.076431 -121.796972)
			(xy 168.061612 -121.824615) (xy 168.054 -121.855041) (xy 168.053512 -121.870724) (xy 168.053512 -122.8664)
			(xy 168.978562 -122.8664) (xy 168.978562 -122.806464) (xy 168.986385 -122.747042) (xy 169.001898 -122.689149)
			(xy 169.024834 -122.633776) (xy 169.054801 -122.58187) (xy 169.091288 -122.53432) (xy 169.133668 -122.49194)
			(xy 169.181218 -122.455453) (xy 169.233124 -122.425486) (xy 169.288497 -122.40255) (xy 169.34639 -122.387037)
			(xy 169.405812 -122.379214) (xy 169.465748 -122.379214) (xy 169.52517 -122.387037) (xy 169.583063 -122.40255)
			(xy 169.638436 -122.425486) (xy 169.690342 -122.455453) (xy 169.737892 -122.49194) (xy 169.780272 -122.53432)
			(xy 169.816759 -122.58187) (xy 169.846726 -122.633776) (xy 169.869662 -122.689149) (xy 169.885175 -122.747042)
			(xy 169.892998 -122.806464) (xy 169.893488 -122.836432) (xy 169.892998 -122.8664) (xy 169.885175 -122.925822)
			(xy 169.869662 -122.983715) (xy 169.846726 -123.039088) (xy 169.816759 -123.090994) (xy 169.780272 -123.138544)
			(xy 169.737892 -123.180924) (xy 169.690342 -123.217411) (xy 169.638436 -123.247378) (xy 169.583063 -123.270314)
			(xy 169.52517 -123.285827) (xy 169.465748 -123.29365) (xy 169.405812 -123.29365) (xy 169.34639 -123.285827)
			(xy 169.288497 -123.270314) (xy 169.233124 -123.247378) (xy 169.181218 -123.217411) (xy 169.133668 -123.180924)
			(xy 169.091288 -123.138544) (xy 169.054801 -123.090994) (xy 169.024834 -123.039088) (xy 169.001898 -122.983715)
			(xy 168.986385 -122.925822) (xy 168.978562 -122.8664) (xy 168.053512 -122.8664) (xy 168.053512 -122.952256)
			(xy 168.053865 -122.966714) (xy 168.060318 -122.994898) (xy 168.072967 -123.020898) (xy 168.091161 -123.04337)
			(xy 168.113959 -123.061153) (xy 168.126918 -123.067572) (xy 168.154444 -123.080923) (xy 168.205997 -123.113862)
			(xy 168.252702 -123.153376) (xy 168.293726 -123.198761) (xy 168.328338 -123.249206) (xy 168.355919 -123.303814)
			(xy 168.375979 -123.361609) (xy 168.38816 -123.421562) (xy 168.392244 -123.482603) (xy 168.388159 -123.543645)
			(xy 168.375977 -123.603597) (xy 168.355917 -123.661392) (xy 168.328334 -123.715999) (xy 168.293722 -123.766445)
			(xy 168.252698 -123.811829) (xy 168.205992 -123.851342) (xy 168.154438 -123.88428) (xy 168.126918 -123.897644)
			(xy 168.113988 -123.904105) (xy 168.09122 -123.921904) (xy 168.073041 -123.94437) (xy 168.060383 -123.970349)
			(xy 168.053894 -123.99851) (xy 168.053512 -124.01296) (xy 168.053512 -124.214128) (xy 168.637712 -124.798328)
			(xy 171.330112 -124.798328)
		)
		(stroke
			(width 0)
			(type solid)
		)
		(fill yes)
		(layer "B.Cu")
		(net "GND")
	)
	(gr_poly
		(pts
			(xy 163.854638 -106.652568) (xy 163.854638 -105.176574) (xy 162.943794 -104.26573) (xy 162.943794 -103.137208)
			(xy 162.955986 -103.125016) (xy 162.955986 -101.711506) (xy 162.84448 -101.6) (xy 162.84448 -101.469698)
			(xy 162.843985 -101.453044) (xy 162.835363 -101.420872) (xy 162.818708 -101.392028) (xy 162.795154 -101.368479)
			(xy 162.766307 -101.351828) (xy 162.734134 -101.343212) (xy 162.71748 -101.342698) (xy 162.212528 -101.342698)
			(xy 162.18535 -101.356414) (xy 162.157293 -101.370194) (xy 162.098549 -101.391563) (xy 162.037629 -101.405568)
			(xy 161.975451 -101.411998) (xy 161.912954 -101.410755) (xy 161.851081 -101.401859) (xy 161.790765 -101.385443)
			(xy 161.732918 -101.361755) (xy 161.678411 -101.331153) (xy 161.628069 -101.294098) (xy 161.582649 -101.251151)
			(xy 161.542838 -101.202958) (xy 161.509237 -101.150247) (xy 161.482353 -101.093815) (xy 161.462591 -101.034511)
			(xy 161.450249 -100.973232) (xy 161.445515 -100.910902) (xy 161.448458 -100.848462) (xy 161.459036 -100.786854)
			(xy 161.477088 -100.727008) (xy 161.502342 -100.669827) (xy 161.534417 -100.616174) (xy 161.572828 -100.566858)
			(xy 161.594546 -100.544376) (xy 161.824416 -100.314252) (xy 161.83578 -100.302089) (xy 161.852387 -100.273256)
			(xy 161.860979 -100.241111) (xy 161.860972 -100.207837) (xy 161.852367 -100.175695) (xy 161.835748 -100.146869)
			(xy 161.824416 -100.134674) (xy 161.626042 -99.936046) (xy 161.602049 -99.911258) (xy 161.56029 -99.856345)
			(xy 161.52634 -99.796291) (xy 161.500823 -99.732197) (xy 161.484206 -99.665241) (xy 161.476796 -99.596654)
			(xy 161.477198 -99.562158) (xy 161.477337 -99.538434) (xy 161.469853 -99.491591) (xy 161.453809 -99.44695)
			(xy 161.429761 -99.40606) (xy 161.398544 -99.370342) (xy 161.361243 -99.341036) (xy 161.319152 -99.319158)
			(xy 161.273734 -99.305469) (xy 161.226564 -99.300445) (xy 161.202878 -99.301808) (xy 161.172732 -99.303772)
			(xy 161.112399 -99.300702) (xy 161.052995 -99.289719) (xy 160.995552 -99.271016) (xy 160.941069 -99.244917)
			(xy 160.890494 -99.211876) (xy 160.844707 -99.172468) (xy 160.804503 -99.127378) (xy 160.770581 -99.077389)
			(xy 160.743531 -99.023372) (xy 160.723825 -98.966266) (xy 160.711804 -98.907063) (xy 160.707677 -98.846793)
			(xy 160.711516 -98.786504) (xy 160.723255 -98.727244) (xy 160.742689 -98.670044) (xy 160.76948 -98.615898)
			(xy 160.803163 -98.565749) (xy 160.843152 -98.520467) (xy 160.888751 -98.480841) (xy 160.939167 -98.44756)
			(xy 160.993525 -98.421201) (xy 161.050878 -98.402224) (xy 161.08045 -98.396044) (xy 161.101666 -98.391588)
			(xy 161.142277 -98.376426) (xy 161.179725 -98.35459) (xy 161.212923 -98.326715) (xy 161.240907 -98.293609)
			(xy 161.262866 -98.256233) (xy 161.278161 -98.215673) (xy 161.28635 -98.173104) (xy 161.287206 -98.151442)
			(xy 161.288321 -98.120202) (xy 161.29725 -98.058329) (xy 161.3137 -97.998019) (xy 161.337421 -97.940181)
			(xy 161.368057 -97.885689) (xy 161.405144 -97.835365) (xy 161.448123 -97.789969) (xy 161.496344 -97.750187)
			(xy 161.54908 -97.716619) (xy 161.605535 -97.689771) (xy 161.664856 -97.67005) (xy 161.726148 -97.657753)
			(xy 161.788486 -97.653064) (xy 161.850927 -97.656057) (xy 161.912531 -97.666684) (xy 161.972366 -97.684786)
			(xy 162.02953 -97.710089) (xy 162.083159 -97.742212) (xy 162.132444 -97.780668) (xy 162.15487 -97.802446)
			(xy 162.21456 -97.861882) (xy 162.728402 -97.861882) (xy 162.766651 -97.862596) (xy 162.842284 -97.874078)
			(xy 162.879024 -97.884742) (xy 162.895669 -97.889307) (xy 162.930155 -97.890316) (xy 162.963645 -97.882024)
			(xy 162.993675 -97.86504) (xy 163.006278 -97.853246) (xy 163.912042 -96.947482) (xy 164.098224 -96.947482)
			(xy 164.162994 -96.882712) (xy 166.101522 -96.882712) (xy 167.015668 -95.968566) (xy 167.015668 -95.779844)
			(xy 167.016174 -95.747544) (xy 167.024366 -95.683466) (xy 167.040609 -95.620943) (xy 167.064644 -95.560981)
			(xy 167.096081 -95.504547) (xy 167.134415 -95.452551) (xy 167.179028 -95.40583) (xy 167.2292 -95.365139)
			(xy 167.284124 -95.331131) (xy 167.342913 -95.304357) (xy 167.404621 -95.285246) (xy 167.468253 -95.274107)
			(xy 167.532783 -95.27112) (xy 167.597172 -95.276333) (xy 167.660381 -95.289661) (xy 167.721393 -95.31089)
			(xy 167.779223 -95.339678) (xy 167.80637 -95.357188) (xy 167.819427 -95.365361) (xy 167.848407 -95.37578)
			(xy 167.879039 -95.378958) (xy 167.90954 -95.374708) (xy 167.938137 -95.363279) (xy 167.950896 -95.354648)
			(xy 167.977636 -95.336112) (xy 168.034918 -95.305258) (xy 168.095671 -95.281968) (xy 168.158899 -95.266624)
			(xy 168.223569 -95.259476) (xy 168.288622 -95.260642) (xy 168.352994 -95.270102) (xy 168.415632 -95.287702)
			(xy 168.475511 -95.313154) (xy 168.531651 -95.346041) (xy 168.583134 -95.385825) (xy 168.60647 -95.408496)
			(xy 169.14876 -95.950532) (xy 169.14876 -95.952818) (xy 169.31005 -96.114108) (xy 169.31005 -96.721676)
			(xy 169.458894 -96.87052) (xy 170.675046 -96.87052) (xy 170.698015 -96.870003) (xy 170.743198 -96.861703)
			(xy 170.786154 -96.845417) (xy 170.825483 -96.821677) (xy 170.859905 -96.791254) (xy 170.888299 -96.75514)
			(xy 170.90974 -96.714511) (xy 170.923529 -96.67069) (xy 170.929219 -96.625105) (xy 170.926622 -96.579239)
			(xy 170.915825 -96.534587) (xy 170.906948 -96.513396) (xy 170.895763 -96.48697) (xy 170.880564 -96.431637)
			(xy 170.873824 -96.374653) (xy 170.875695 -96.317301) (xy 170.886135 -96.260877) (xy 170.90491 -96.206653)
			(xy 170.931594 -96.155852) (xy 170.965585 -96.109622) (xy 171.006118 -96.069004) (xy 171.052278 -96.034916)
			(xy 171.103023 -96.008126) (xy 171.157207 -95.989239) (xy 171.185332 -95.983552) (xy 171.206884 -95.979041)
			(xy 171.248116 -95.963601) (xy 171.28607 -95.941286) (xy 171.31961 -95.912763) (xy 171.347731 -95.878886)
			(xy 171.369592 -95.840668) (xy 171.384538 -95.799254) (xy 171.392122 -95.755884) (xy 171.392596 -95.73387)
			(xy 171.392596 -94.606618) (xy 171.392104 -94.589962) (xy 171.383485 -94.557784) (xy 171.366832 -94.528933)
			(xy 171.343278 -94.505377) (xy 171.314429 -94.48872) (xy 171.282252 -94.480098) (xy 171.265596 -94.479618)
			(xy 169.254932 -94.479618) (xy 168.731692 -93.956378) (xy 161.728912 -93.956378) (xy 160.959546 -94.725744)
			(xy 160.954212 -94.725744) (xy 160.787592 -94.892364) (xy 164.242732 -94.892364) (xy 164.242732 -94.832428)
			(xy 164.250555 -94.773006) (xy 164.266068 -94.715113) (xy 164.289004 -94.65974) (xy 164.318971 -94.607834)
			(xy 164.355458 -94.560284) (xy 164.397838 -94.517904) (xy 164.445388 -94.481417) (xy 164.497294 -94.45145)
			(xy 164.552667 -94.428514) (xy 164.61056 -94.413001) (xy 164.669982 -94.405178) (xy 164.729918 -94.405178)
			(xy 164.78934 -94.413001) (xy 164.847233 -94.428514) (xy 164.902606 -94.45145) (xy 164.954512 -94.481417)
			(xy 165.002062 -94.517904) (xy 165.044442 -94.560284) (xy 165.080929 -94.607834) (xy 165.110896 -94.65974)
			(xy 165.133832 -94.715113) (xy 165.149345 -94.773006) (xy 165.157168 -94.832428) (xy 165.157658 -94.862396)
			(xy 165.157168 -94.892364) (xy 165.149345 -94.951786) (xy 165.133832 -95.009679) (xy 165.110896 -95.065052)
			(xy 165.080929 -95.116958) (xy 165.044442 -95.164508) (xy 165.002062 -95.206888) (xy 164.954512 -95.243375)
			(xy 164.902606 -95.273342) (xy 164.847233 -95.296278) (xy 164.78934 -95.311791) (xy 164.729918 -95.319614)
			(xy 164.669982 -95.319614) (xy 164.61056 -95.311791) (xy 164.552667 -95.296278) (xy 164.497294 -95.273342)
			(xy 164.445388 -95.243375) (xy 164.397838 -95.206888) (xy 164.355458 -95.164508) (xy 164.318971 -95.116958)
			(xy 164.289004 -95.065052) (xy 164.266068 -95.009679) (xy 164.250555 -94.951786) (xy 164.242732 -94.892364)
			(xy 160.787592 -94.892364) (xy 160.086294 -95.593662) (xy 160.086294 -96.0059) (xy 163.432726 -96.0059)
			(xy 163.432726 -95.945964) (xy 163.440549 -95.886542) (xy 163.456062 -95.828649) (xy 163.478998 -95.773276)
			(xy 163.508965 -95.72137) (xy 163.545452 -95.67382) (xy 163.587832 -95.63144) (xy 163.635382 -95.594953)
			(xy 163.687288 -95.564986) (xy 163.742661 -95.54205) (xy 163.800554 -95.526537) (xy 163.859976 -95.518714)
			(xy 163.919912 -95.518714) (xy 163.979334 -95.526537) (xy 164.037227 -95.54205) (xy 164.0926 -95.564986)
			(xy 164.144506 -95.594953) (xy 164.192056 -95.63144) (xy 164.234436 -95.67382) (xy 164.270923 -95.72137)
			(xy 164.30089 -95.773276) (xy 164.320127 -95.819718) (xy 165.186088 -95.819718) (xy 165.186088 -95.759782)
			(xy 165.193911 -95.70036) (xy 165.209424 -95.642467) (xy 165.23236 -95.587094) (xy 165.262327 -95.535188)
			(xy 165.298814 -95.487638) (xy 165.341194 -95.445258) (xy 165.388744 -95.408771) (xy 165.44065 -95.378804)
			(xy 165.496023 -95.355868) (xy 165.553916 -95.340355) (xy 165.613338 -95.332532) (xy 165.673274 -95.332532)
			(xy 165.732696 -95.340355) (xy 165.790589 -95.355868) (xy 165.845962 -95.378804) (xy 165.897868 -95.408771)
			(xy 165.945418 -95.445258) (xy 165.987798 -95.487638) (xy 166.024285 -95.535188) (xy 166.054252 -95.587094)
			(xy 166.077188 -95.642467) (xy 166.092701 -95.70036) (xy 166.100524 -95.759782) (xy 166.101014 -95.78975)
			(xy 166.100524 -95.819718) (xy 166.092701 -95.87914) (xy 166.077188 -95.937033) (xy 166.054252 -95.992406)
			(xy 166.024285 -96.044312) (xy 165.987798 -96.091862) (xy 165.945418 -96.134242) (xy 165.897868 -96.170729)
			(xy 165.845962 -96.200696) (xy 165.790589 -96.223632) (xy 165.732696 -96.239145) (xy 165.673274 -96.246968)
			(xy 165.613338 -96.246968) (xy 165.553916 -96.239145) (xy 165.496023 -96.223632) (xy 165.44065 -96.200696)
			(xy 165.388744 -96.170729) (xy 165.341194 -96.134242) (xy 165.298814 -96.091862) (xy 165.262327 -96.044312)
			(xy 165.23236 -95.992406) (xy 165.209424 -95.937033) (xy 165.193911 -95.87914) (xy 165.186088 -95.819718)
			(xy 164.320127 -95.819718) (xy 164.323826 -95.828649) (xy 164.339339 -95.886542) (xy 164.347162 -95.945964)
			(xy 164.347652 -95.975932) (xy 164.347162 -96.0059) (xy 164.339339 -96.065322) (xy 164.323826 -96.123215)
			(xy 164.30089 -96.178588) (xy 164.270923 -96.230494) (xy 164.234436 -96.278044) (xy 164.192056 -96.320424)
			(xy 164.144506 -96.356911) (xy 164.0926 -96.386878) (xy 164.037227 -96.409814) (xy 163.979334 -96.425327)
			(xy 163.919912 -96.43315) (xy 163.859976 -96.43315) (xy 163.800554 -96.425327) (xy 163.742661 -96.409814)
			(xy 163.687288 -96.386878) (xy 163.635382 -96.356911) (xy 163.587832 -96.320424) (xy 163.545452 -96.278044)
			(xy 163.508965 -96.230494) (xy 163.478998 -96.178588) (xy 163.456062 -96.123215) (xy 163.440549 -96.065322)
			(xy 163.432726 -96.0059) (xy 160.086294 -96.0059) (xy 160.086294 -96.960432) (xy 162.416726 -96.960432)
			(xy 162.416726 -96.900496) (xy 162.424549 -96.841074) (xy 162.440062 -96.783181) (xy 162.462998 -96.727808)
			(xy 162.492965 -96.675902) (xy 162.529452 -96.628352) (xy 162.571832 -96.585972) (xy 162.619382 -96.549485)
			(xy 162.671288 -96.519518) (xy 162.726661 -96.496582) (xy 162.784554 -96.481069) (xy 162.843976 -96.473246)
			(xy 162.903912 -96.473246) (xy 162.963334 -96.481069) (xy 163.021227 -96.496582) (xy 163.0766 -96.519518)
			(xy 163.128506 -96.549485) (xy 163.176056 -96.585972) (xy 163.218436 -96.628352) (xy 163.254923 -96.675902)
			(xy 163.28489 -96.727808) (xy 163.307826 -96.783181) (xy 163.323339 -96.841074) (xy 163.331162 -96.900496)
			(xy 163.331652 -96.930464) (xy 163.331162 -96.960432) (xy 163.323339 -97.019854) (xy 163.307826 -97.077747)
			(xy 163.28489 -97.13312) (xy 163.254923 -97.185026) (xy 163.218436 -97.232576) (xy 163.176056 -97.274956)
			(xy 163.128506 -97.311443) (xy 163.0766 -97.34141) (xy 163.021227 -97.364346) (xy 162.963334 -97.379859)
			(xy 162.903912 -97.387682) (xy 162.843976 -97.387682) (xy 162.784554 -97.379859) (xy 162.726661 -97.364346)
			(xy 162.671288 -97.34141) (xy 162.619382 -97.311443) (xy 162.571832 -97.274956) (xy 162.529452 -97.232576)
			(xy 162.492965 -97.185026) (xy 162.462998 -97.13312) (xy 162.440062 -97.077747) (xy 162.424549 -97.019854)
			(xy 162.416726 -96.960432) (xy 160.086294 -96.960432) (xy 160.086294 -101.668072) (xy 160.63722 -102.218998)
			(xy 160.72104 -102.230682) (xy 160.758378 -102.210108) (xy 160.782854 -102.197157) (xy 160.834688 -102.17768)
			(xy 160.888794 -102.1659) (xy 160.944035 -102.162065) (xy 160.999249 -102.166257) (xy 161.053277 -102.178386)
			(xy 161.104985 -102.198198) (xy 161.153285 -102.225277) (xy 161.197164 -102.259054) (xy 161.235698 -102.29882)
			(xy 161.26808 -102.343738) (xy 161.293628 -102.392865) (xy 161.311805 -102.44517) (xy 161.32223 -102.499553)
			(xy 161.324685 -102.554872) (xy 161.319116 -102.609964) (xy 161.305642 -102.663673) (xy 161.284545 -102.71487)
			(xy 161.256269 -102.762479) (xy 161.221407 -102.805501) (xy 161.180692 -102.84303) (xy 161.134979 -102.87428)
			(xy 161.085229 -102.898594) (xy 161.032487 -102.91546) (xy 161.005266 -102.920546) (xy 160.983316 -102.924675)
			(xy 160.941223 -102.939594) (xy 160.902383 -102.961638) (xy 160.867993 -102.990129) (xy 160.839109 -103.024191)
			(xy 160.816621 -103.062775) (xy 160.801221 -103.104695) (xy 160.793381 -103.148661) (xy 160.792922 -103.17099)
			(xy 160.792922 -103.768144) (xy 160.793404 -103.79067) (xy 160.801344 -103.835017) (xy 160.816986 -103.877266)
			(xy 160.839838 -103.916092) (xy 160.869184 -103.950276) (xy 160.904101 -103.978745) (xy 160.943494 -104.000606)
			(xy 160.986126 -104.015171) (xy 161.008314 -104.019096) (xy 161.038579 -104.024382) (xy 161.09701 -104.04335)
			(xy 161.151643 -104.071446) (xy 161.176716 -104.0892) (xy 161.189707 -104.09819) (xy 161.218951 -104.110114)
			(xy 161.250229 -104.114485) (xy 161.281622 -104.111034) (xy 161.311204 -104.099972) (xy 161.337159 -104.081979)
			(xy 161.347912 -104.070404) (xy 161.368263 -104.047819) (xy 161.413933 -104.007689) (xy 161.464514 -103.97396)
			(xy 161.519116 -103.947227) (xy 161.576778 -103.92796) (xy 161.636483 -103.916498) (xy 161.69718 -103.913044)
			(xy 161.7578 -103.917658) (xy 161.817275 -103.930259) (xy 161.874558 -103.950626) (xy 161.928639 -103.978398)
			(xy 161.978566 -104.013088) (xy 162.023459 -104.054084) (xy 162.062528 -104.100664) (xy 162.095085 -104.152008)
			(xy 162.120556 -104.20721) (xy 162.138492 -104.2653) (xy 162.148577 -104.325253) (xy 162.150634 -104.386014)
			(xy 162.144627 -104.446512) (xy 162.130661 -104.505681) (xy 162.108983 -104.56248) (xy 162.079974 -104.615908)
			(xy 162.044145 -104.665024) (xy 162.002127 -104.708963) (xy 161.954661 -104.74695) (xy 161.902582 -104.778317)
			(xy 161.846809 -104.802512) (xy 161.788322 -104.819107) (xy 161.728153 -104.827811) (xy 161.667361 -104.82847)
			(xy 161.607017 -104.821073) (xy 161.548184 -104.80575) (xy 161.491899 -104.782771) (xy 161.439152 -104.752541)
			(xy 161.390873 -104.715592) (xy 161.368994 -104.694482) (xy 161.357506 -104.683657) (xy 161.330402 -104.6675)
			(xy 161.300159 -104.658497) (xy 161.26863 -104.6572) (xy 161.23775 -104.663691) (xy 161.209411 -104.677569)
			(xy 161.197036 -104.68737) (xy 161.176719 -104.704032) (xy 161.132364 -104.732203) (xy 161.084561 -104.754015)
			(xy 161.034215 -104.769055) (xy 161.008314 -104.773476) (xy 160.986128 -104.777384) (xy 160.943513 -104.791981)
			(xy 160.904137 -104.81386) (xy 160.869234 -104.842336) (xy 160.839895 -104.876517) (xy 160.817039 -104.915333)
			(xy 160.801382 -104.95757) (xy 160.793414 -105.001906) (xy 160.792922 -105.024428) (xy 160.792922 -106.665268)
			(xy 161.282126 -107.154472) (xy 163.352734 -107.154472)
		)
		(stroke
			(width 0)
			(type solid)
		)
		(fill yes)
		(layer "B.Cu")
		(net "P3V3_USB_NODE1")
	)
	(gr_poly
		(pts
			(xy 48.04156 -79.440532) (xy 48.058284 -79.440031) (xy 48.090582 -79.431338) (xy 48.119505 -79.41454)
			(xy 48.143061 -79.390795) (xy 48.151796 -79.376524) (xy 48.159416 -79.363316) (xy 48.159416 -79.346044)
			(xy 48.19142 -79.290418) (xy 48.19142 -78.61046) (xy 48.171862 -78.563724) (xy 48.159416 -78.551278)
			(xy 48.159416 -77.92212) (xy 48.19142 -77.888084) (xy 48.19142 -77.015594) (xy 48.420528 -77.015594)
			(xy 48.607472 -76.82865) (xy 48.759872 -76.823062) (xy 48.774561 -76.822014) (xy 48.802776 -76.813616)
			(xy 48.828064 -76.798545) (xy 48.848875 -76.777724) (xy 48.863936 -76.75243) (xy 48.872322 -76.724211)
			(xy 48.87341 -76.709524) (xy 48.878998 -76.557124) (xy 48.9077 -76.528422) (xy 48.9077 -76.463144)
			(xy 48.29556 -75.851004) (xy 48.29556 -75.373738) (xy 48.586644 -75.082654) (xy 48.608606 -75.077123)
			(xy 48.650262 -75.059364) (xy 48.688113 -75.034506) (xy 48.720961 -75.003334) (xy 48.747765 -74.966835)
			(xy 48.767679 -74.926165) (xy 48.780071 -74.882609) (xy 48.78455 -74.837547) (xy 48.78324 -74.814938)
			(xy 48.781548 -74.787686) (xy 48.785039 -74.733197) (xy 48.796264 -74.679762) (xy 48.814993 -74.628473)
			(xy 48.840843 -74.580379) (xy 48.873287 -74.536463) (xy 48.91166 -74.49762) (xy 48.95518 -74.464647)
			(xy 49.002957 -74.438215) (xy 49.054015 -74.418865) (xy 49.107309 -74.406993) (xy 49.161752 -74.402842)
			(xy 49.216231 -74.406495) (xy 49.269632 -74.417879) (xy 49.320865 -74.43676) (xy 49.368881 -74.462754)
			(xy 49.412701 -74.495328) (xy 49.451429 -74.533817) (xy 49.484273 -74.577436) (xy 49.510562 -74.625291)
			(xy 49.52976 -74.676406) (xy 49.541473 -74.729736) (xy 49.545462 -74.784191) (xy 49.541646 -74.838658)
			(xy 49.530103 -74.892025) (xy 49.52111 -74.917808) (xy 49.512982 -74.939144) (xy 49.512982 -74.962004)
			(xy 49.513526 -74.978653) (xy 49.522144 -75.010816) (xy 49.538792 -75.039653) (xy 49.562336 -75.0632)
			(xy 49.591171 -75.079851) (xy 49.623333 -75.088473) (xy 49.639982 -75.089004) (xy 49.844706 -75.089004)
			(xy 50.1142 -74.81951) (xy 50.1142 -74.150982) (xy 49.61128 -73.648062) (xy 49.61128 -71.941944)
			(xy 49.309782 -71.640446) (xy 49.242726 -71.623174) (xy 49.209706 -71.632572) (xy 49.179695 -71.640588)
			(xy 49.118203 -71.649383) (xy 49.056087 -71.649783) (xy 48.994487 -71.641781) (xy 48.934534 -71.625522)
			(xy 48.877331 -71.601307) (xy 48.823927 -71.569579) (xy 48.775304 -71.530922) (xy 48.732354 -71.486045)
			(xy 48.695867 -71.435773) (xy 48.666512 -71.381029) (xy 48.64483 -71.322818) (xy 48.631217 -71.26221)
			(xy 48.625924 -71.200319) (xy 48.62703 -71.169276) (xy 48.62767 -71.146545) (xy 48.621839 -71.101452)
			(xy 48.608076 -71.058116) (xy 48.58682 -71.017922) (xy 48.558751 -70.982152) (xy 48.524763 -70.951948)
			(xy 48.485943 -70.928276) (xy 48.443529 -70.91189) (xy 48.42129 -70.907148) (xy 48.394158 -70.901441)
			(xy 48.341791 -70.883232) (xy 48.292611 -70.857633) (xy 48.247655 -70.825184) (xy 48.207871 -70.78657)
			(xy 48.174095 -70.742602) (xy 48.14704 -70.694209) (xy 48.127276 -70.642408) (xy 48.115219 -70.588292)
			(xy 48.111122 -70.533001) (xy 48.11268 -70.50532) (xy 48.11268 -70.505066) (xy 48.113383 -70.486947)
			(xy 48.105657 -70.451533) (xy 48.088264 -70.419731) (xy 48.07585 -70.406514) (xy 47.9425 -70.273164)
			(xy 47.772574 -70.273164) (xy 47.749775 -70.273677) (xy 47.704911 -70.28182) (xy 47.66222 -70.297839)
			(xy 47.623074 -70.321221) (xy 47.588729 -70.351214) (xy 47.560289 -70.386856) (xy 47.538667 -70.427001)
			(xy 47.524558 -70.470361) (xy 47.518414 -70.515542) (xy 47.520432 -70.561095) (xy 47.530549 -70.605556)
			(xy 47.548438 -70.647498) (xy 47.560484 -70.666864) (xy 47.575241 -70.690213) (xy 47.5986 -70.740264)
			(xy 47.614498 -70.79316) (xy 47.622604 -70.847795) (xy 47.622747 -70.903028) (xy 47.614925 -70.957705)
			(xy 47.599301 -71.010683) (xy 47.576202 -71.060855) (xy 47.546111 -71.107171) (xy 47.509655 -71.148665)
			(xy 47.467598 -71.18447) (xy 47.420818 -71.213836) (xy 47.370293 -71.23615) (xy 47.317078 -71.250947)
			(xy 47.262286 -71.257916) (xy 47.207062 -71.256912) (xy 47.152559 -71.247956) (xy 47.099917 -71.231235)
			(xy 47.050236 -71.207099) (xy 47.004554 -71.176052) (xy 46.963826 -71.138743) (xy 46.928903 -71.095952)
			(xy 46.914308 -71.072502) (xy 46.805342 -71.010526) (xy 46.74616 -71.025258) (xy 46.720107 -71.038507)
			(xy 46.665375 -71.059021) (xy 46.608477 -71.072399) (xy 46.550338 -71.078422) (xy 46.491906 -71.076993)
			(xy 46.46295 -71.07301) (xy 46.448162 -71.07118) (xy 46.418474 -71.073666) (xy 46.39017 -71.082963)
			(xy 46.364791 -71.098566) (xy 46.353984 -71.108824) (xy 46.290992 -71.171816) (xy 46.290992 -71.940928)
			(xy 46.291449 -71.963191) (xy 46.299202 -72.007035) (xy 46.314482 -72.048856) (xy 46.336822 -72.087371)
			(xy 46.365537 -72.121399) (xy 46.399746 -72.149899) (xy 46.438402 -72.171995) (xy 46.480318 -72.187011)
			(xy 46.524211 -72.194486) (xy 46.568735 -72.194192) (xy 46.590712 -72.19061) (xy 46.618211 -72.186101)
			(xy 46.673901 -72.184164) (xy 46.72928 -72.190348) (xy 46.783171 -72.20452) (xy 46.834428 -72.22638)
			(xy 46.881961 -72.255462) (xy 46.924758 -72.291148) (xy 46.96191 -72.332679) (xy 46.992627 -72.379172)
			(xy 47.016255 -72.429638) (xy 47.032293 -72.483003) (xy 47.040398 -72.538134) (xy 47.040398 -72.593858)
			(xy 47.032294 -72.648989) (xy 47.016258 -72.702355) (xy 47.00172 -72.733408) (xy 47.32223 -72.733408)
			(xy 47.326301 -72.677786) (xy 47.338427 -72.623349) (xy 47.35835 -72.571258) (xy 47.385646 -72.522623)
			(xy 47.419732 -72.47848) (xy 47.459881 -72.439771) (xy 47.505239 -72.40732) (xy 47.554839 -72.381819)
			(xy 47.607623 -72.363812) (xy 47.662466 -72.353682) (xy 47.7182 -72.351645) (xy 47.773637 -72.357745)
			(xy 47.827594 -72.371851) (xy 47.878923 -72.393663) (xy 47.926529 -72.422717) (xy 47.969397 -72.458392)
			(xy 48.006614 -72.499929) (xy 48.037387 -72.546442) (xy 48.061059 -72.596939) (xy 48.077127 -72.650346)
			(xy 48.085247 -72.705522) (xy 48.085519 -72.72045) (xy 48.386474 -72.72045) (xy 48.386474 -72.660514)
			(xy 48.394297 -72.601092) (xy 48.40981 -72.543199) (xy 48.432746 -72.487826) (xy 48.462713 -72.43592)
			(xy 48.4992 -72.38837) (xy 48.54158 -72.34599) (xy 48.58913 -72.309503) (xy 48.641036 -72.279536)
			(xy 48.696409 -72.2566) (xy 48.754302 -72.241087) (xy 48.813724 -72.233264) (xy 48.87366 -72.233264)
			(xy 48.933082 -72.241087) (xy 48.990975 -72.2566) (xy 49.046348 -72.279536) (xy 49.098254 -72.309503)
			(xy 49.145804 -72.34599) (xy 49.188184 -72.38837) (xy 49.224671 -72.43592) (xy 49.254638 -72.487826)
			(xy 49.277574 -72.543199) (xy 49.293087 -72.601092) (xy 49.30091 -72.660514) (xy 49.3014 -72.690482)
			(xy 49.30091 -72.72045) (xy 49.293087 -72.779872) (xy 49.277574 -72.837765) (xy 49.254638 -72.893138)
			(xy 49.224671 -72.945044) (xy 49.188184 -72.992594) (xy 49.145804 -73.034974) (xy 49.098254 -73.071461)
			(xy 49.046348 -73.101428) (xy 48.990975 -73.124364) (xy 48.933082 -73.139877) (xy 48.87366 -73.1477)
			(xy 48.813724 -73.1477) (xy 48.754302 -73.139877) (xy 48.696409 -73.124364) (xy 48.641036 -73.101428)
			(xy 48.58913 -73.071461) (xy 48.54158 -73.034974) (xy 48.4992 -72.992594) (xy 48.462713 -72.945044)
			(xy 48.432746 -72.893138) (xy 48.40981 -72.837765) (xy 48.394297 -72.779872) (xy 48.386474 -72.72045)
			(xy 48.085519 -72.72045) (xy 48.085756 -72.733408) (xy 48.085247 -72.761294) (xy 48.077127 -72.81647)
			(xy 48.061059 -72.869877) (xy 48.037387 -72.920374) (xy 48.006614 -72.966887) (xy 47.969397 -73.008424)
			(xy 47.926529 -73.044099) (xy 47.878923 -73.073153) (xy 47.827594 -73.094965) (xy 47.773637 -73.109071)
			(xy 47.7182 -73.115171) (xy 47.662466 -73.113134) (xy 47.607623 -73.103004) (xy 47.554839 -73.084997)
			(xy 47.505239 -73.059496) (xy 47.459881 -73.027045) (xy 47.419732 -72.988336) (xy 47.385646 -72.944193)
			(xy 47.35835 -72.895558) (xy 47.338427 -72.843467) (xy 47.326301 -72.78903) (xy 47.32223 -72.733408)
			(xy 47.00172 -72.733408) (xy 46.992631 -72.752822) (xy 46.961915 -72.799315) (xy 46.924764 -72.840847)
			(xy 46.881967 -72.876534) (xy 46.834435 -72.905617) (xy 46.783179 -72.927477) (xy 46.729288 -72.941651)
			(xy 46.673909 -72.947836) (xy 46.618219 -72.9459) (xy 46.590712 -72.941434) (xy 46.568739 -72.937893)
			(xy 46.524236 -72.937649) (xy 46.480371 -72.945159) (xy 46.438483 -72.960191) (xy 46.399852 -72.982288)
			(xy 46.36566 -73.010774) (xy 46.336949 -73.044778) (xy 46.314599 -73.083262) (xy 46.29929 -73.12505)
			(xy 46.291492 -73.168865) (xy 46.290992 -73.191116) (xy 46.290992 -74.438836) (xy 46.560839 -74.438836)
			(xy 46.561639 -74.38354) (xy 46.570415 -74.328939) (xy 46.586982 -74.276178) (xy 46.610994 -74.226362)
			(xy 46.641947 -74.180534) (xy 46.679193 -74.139656) (xy 46.72195 -74.104584) (xy 46.769324 -74.076054)
			(xy 46.82032 -74.054662) (xy 46.873871 -74.040858) (xy 46.928854 -74.03493) (xy 46.984116 -74.037004)
			(xy 47.0385 -74.047035) (xy 47.090866 -74.064813) (xy 47.140116 -74.089966) (xy 47.185219 -74.121966)
			(xy 47.225228 -74.160143) (xy 47.259306 -74.203697) (xy 47.286738 -74.251715) (xy 47.306949 -74.303191)
			(xy 47.319516 -74.357045) (xy 47.324176 -74.41215) (xy 47.322994 -74.43978) (xy 47.322525 -74.456935)
			(xy 47.329688 -74.490484) (xy 47.345528 -74.520914) (xy 47.3689 -74.546026) (xy 47.398115 -74.564006)
			(xy 47.414434 -74.56932) (xy 47.44084 -74.577522) (xy 47.491182 -74.600383) (xy 47.537696 -74.630274)
			(xy 47.579407 -74.666567) (xy 47.61544 -74.708502) (xy 47.645042 -74.7552) (xy 47.667591 -74.805683)
			(xy 47.682615 -74.858892) (xy 47.689799 -74.913713) (xy 47.688993 -74.968997) (xy 47.680213 -75.023585)
			(xy 47.663644 -75.076334) (xy 47.639632 -75.126138) (xy 47.608681 -75.171953) (xy 47.57144 -75.212819)
			(xy 47.528688 -75.24788) (xy 47.481323 -75.276401) (xy 47.430335 -75.297785) (xy 47.376795 -75.311583)
			(xy 47.321823 -75.317506) (xy 47.266572 -75.31543) (xy 47.2122 -75.305399) (xy 47.159846 -75.287622)
			(xy 47.110607 -75.262473) (xy 47.065515 -75.230478) (xy 47.025514 -75.192308) (xy 46.991445 -75.148762)
			(xy 46.964019 -75.100754) (xy 46.943812 -75.049289) (xy 46.931248 -74.995445) (xy 46.926589 -74.940352)
			(xy 46.92777 -74.912728) (xy 46.928257 -74.895572) (xy 46.921094 -74.862019) (xy 46.905251 -74.831587)
			(xy 46.881874 -74.806475) (xy 46.852652 -74.788498) (xy 46.83633 -74.783188) (xy 46.809897 -74.77506)
			(xy 46.75954 -74.752202) (xy 46.713012 -74.722313) (xy 46.671287 -74.686018) (xy 46.63524 -74.64408)
			(xy 46.605626 -74.597376) (xy 46.583065 -74.546886) (xy 46.568031 -74.493667) (xy 46.560839 -74.438836)
			(xy 46.290992 -74.438836) (xy 46.290992 -75.159108) (xy 46.290738 -75.159108) (xy 46.290738 -75.256644)
			(xy 46.139354 -75.408028) (xy 46.041818 -75.408028) (xy 46.041818 -75.408282) (xy 44.045632 -75.408282)
			(xy 43.015662 -76.438252) (xy 41.76014 -76.438252) (xy 41.738508 -76.438684) (xy 41.695869 -76.446005)
			(xy 41.655085 -76.46044) (xy 41.617336 -76.481574) (xy 41.58371 -76.508796) (xy 41.555181 -76.541319)
			(xy 41.532572 -76.578204) (xy 41.516535 -76.618386) (xy 41.507536 -76.660702) (xy 41.505833 -76.703932)
			(xy 41.511476 -76.746825) (xy 41.524301 -76.788144) (xy 41.533826 -76.807568) (xy 41.546038 -76.832604)
			(xy 41.56388 -76.88537) (xy 41.570574 -76.922122) (xy 46.545498 -76.922122) (xy 46.549569 -76.8665)
			(xy 46.561695 -76.812063) (xy 46.581618 -76.759972) (xy 46.608914 -76.711337) (xy 46.643 -76.667194)
			(xy 46.683149 -76.628485) (xy 46.728507 -76.596034) (xy 46.778107 -76.570533) (xy 46.830891 -76.552526)
			(xy 46.885734 -76.542396) (xy 46.941468 -76.540359) (xy 46.996905 -76.546459) (xy 47.050862 -76.560565)
			(xy 47.102191 -76.582377) (xy 47.149797 -76.611431) (xy 47.192665 -76.647106) (xy 47.229882 -76.688643)
			(xy 47.260655 -76.735156) (xy 47.284327 -76.785653) (xy 47.300395 -76.83906) (xy 47.308515 -76.894236)
			(xy 47.309024 -76.922122) (xy 47.308515 -76.950008) (xy 47.300395 -77.005184) (xy 47.284327 -77.058591)
			(xy 47.260655 -77.109088) (xy 47.229882 -77.155601) (xy 47.192665 -77.197138) (xy 47.149797 -77.232813)
			(xy 47.102191 -77.261867) (xy 47.050862 -77.283679) (xy 46.996905 -77.297785) (xy 46.941468 -77.303885)
			(xy 46.885734 -77.301848) (xy 46.830891 -77.291718) (xy 46.778107 -77.273711) (xy 46.728507 -77.24821)
			(xy 46.683149 -77.215759) (xy 46.643 -77.17705) (xy 46.608914 -77.132907) (xy 46.581618 -77.084272)
			(xy 46.561695 -77.032181) (xy 46.549569 -76.977744) (xy 46.545498 -76.922122) (xy 41.570574 -76.922122)
			(xy 41.573861 -76.940169) (xy 41.575768 -76.995837) (xy 41.569561 -77.051191) (xy 41.555371 -77.105055)
			(xy 41.533501 -77.156282) (xy 41.504415 -77.203786) (xy 41.468732 -77.246556) (xy 41.427208 -77.283683)
			(xy 41.380728 -77.314379) (xy 41.330279 -77.33799) (xy 41.276934 -77.354015) (xy 41.221824 -77.362114)
			(xy 41.166124 -77.362114) (xy 41.111014 -77.354015) (xy 41.057669 -77.33799) (xy 41.00722 -77.314379)
			(xy 40.96074 -77.283683) (xy 40.919216 -77.246556) (xy 40.883533 -77.203786) (xy 40.854447 -77.156282)
			(xy 40.832577 -77.105055) (xy 40.818387 -77.051191) (xy 40.81218 -76.995837) (xy 40.814087 -76.940169)
			(xy 40.824068 -76.88537) (xy 40.84191 -76.832604) (xy 40.854122 -76.807568) (xy 40.863548 -76.788102)
			(xy 40.876366 -76.746799) (xy 40.882004 -76.703922) (xy 40.880301 -76.660709) (xy 40.871306 -76.618408)
			(xy 40.855277 -76.578242) (xy 40.832678 -76.54137) (xy 40.804162 -76.508857) (xy 40.770552 -76.481642)
			(xy 40.732819 -76.460511) (xy 40.692053 -76.446075) (xy 40.649431 -76.438751) (xy 40.627808 -76.438252)
			(xy 39.427912 -76.438252) (xy 39.41126 -76.438794) (xy 39.379091 -76.447409) (xy 39.350246 -76.464055)
			(xy 39.326691 -76.487598) (xy 39.310032 -76.516435) (xy 39.301402 -76.548601) (xy 39.300912 -76.565252)
			(xy 39.300912 -77.865732) (xy 39.30137 -77.882074) (xy 39.309597 -77.913704) (xy 39.325604 -77.942198)
			(xy 39.348337 -77.965678) (xy 39.376297 -77.982599) (xy 39.391844 -77.987652) (xy 39.392098 -77.987652)
			(xy 39.420561 -77.996486) (xy 39.475099 -78.020515) (xy 39.526059 -78.051416) (xy 39.572579 -78.088668)
			(xy 39.613873 -78.13164) (xy 39.649243 -78.179606) (xy 39.678091 -78.231755) (xy 39.699929 -78.287207)
			(xy 39.714389 -78.345023) (xy 39.721226 -78.404226) (xy 39.720324 -78.463816) (xy 39.716456 -78.493366)
			(xy 39.713722 -78.515019) (xy 39.714829 -78.558644) (xy 39.723371 -78.60144) (xy 39.739098 -78.642147)
			(xy 39.761547 -78.67957) (xy 39.790059 -78.712609) (xy 39.823794 -78.740291) (xy 39.861763 -78.761805)
			(xy 39.902848 -78.776516) (xy 39.945842 -78.783994) (xy 39.967662 -78.78445) (xy 40.630348 -78.78445)
			(xy 40.69588 -78.738222) (xy 40.709596 -78.70063) (xy 40.719208 -78.675384) (xy 40.744534 -78.627669)
			(xy 40.776337 -78.584002) (xy 40.81398 -78.545257) (xy 40.856711 -78.512209) (xy 40.903676 -78.485518)
			(xy 40.953937 -78.465717) (xy 41.006487 -78.453202) (xy 41.060277 -78.448225) (xy 41.114232 -78.450883)
			(xy 41.167272 -78.461124) (xy 41.192958 -78.46949) (xy 41.216619 -78.478076) (xy 41.26163 -78.500608)
			(xy 41.303281 -78.528871) (xy 41.340847 -78.562374) (xy 41.373673 -78.600533) (xy 41.387776 -78.621382)
			(xy 41.405556 -78.648306) (xy 41.46169 -78.678786) (xy 44.269152 -78.678786) (xy 44.336462 -78.629002)
			(xy 44.348654 -78.58887) (xy 44.357012 -78.563191) (xy 44.379956 -78.514305) (xy 44.409565 -78.469143)
			(xy 44.445247 -78.428609) (xy 44.486289 -78.393511) (xy 44.53187 -78.364553) (xy 44.58108 -78.342311)
			(xy 44.632934 -78.327232) (xy 44.686397 -78.319617) (xy 44.740399 -78.319617) (xy 44.793862 -78.327232)
			(xy 44.845716 -78.342311) (xy 44.894926 -78.364553) (xy 44.940507 -78.393511) (xy 44.981549 -78.428609)
			(xy 45.017231 -78.469143) (xy 45.04684 -78.514305) (xy 45.069784 -78.563191) (xy 45.078142 -78.58887)
			(xy 45.090334 -78.629002) (xy 45.157644 -78.678786) (xy 45.422058 -78.678786) (xy 45.438922 -78.678268)
			(xy 45.471473 -78.669434) (xy 45.500567 -78.652372) (xy 45.512736 -78.640686) (xy 45.527174 -78.626348)
			(xy 45.558613 -78.600514) (xy 45.575474 -78.589124) (xy 45.597321 -78.575329) (xy 45.64397 -78.553114)
			(xy 45.693191 -78.537398) (xy 45.744083 -78.528468) (xy 45.795713 -78.526489) (xy 45.847139 -78.531495)
			(xy 45.897419 -78.543396) (xy 45.921676 -78.552294) (xy 45.931836 -78.556358) (xy 45.956982 -78.561438)
			(xy 45.972377 -78.564014) (xy 46.003542 -78.562449) (xy 46.033399 -78.553375) (xy 46.060164 -78.537333)
			(xy 46.071536 -78.52664) (xy 46.171104 -78.427072) (xy 47.44212 -78.427072) (xy 47.72152 -78.706472)
			(xy 47.72152 -79.323692) (xy 47.83836 -79.440532)
		)
		(stroke
			(width 0)
			(type solid)
		)
		(fill yes)
		(layer "B.Cu")
		(net "P1V05_NODE1")
	)
	(gr_poly
		(pts
			(xy 142.995396 -29.866844) (xy 144.219422 -29.866844) (xy 144.236037 -29.8663) (xy 144.268136 -29.8577)
			(xy 144.296918 -29.841092) (xy 144.309084 -29.82976) (xy 145.154904 -28.983686) (xy 145.154904 -25.059894)
			(xy 145.10258 -25.007316) (xy 144.256252 -24.161242) (xy 144.155922 -24.161242) (xy 144.139267 -24.161734)
			(xy 144.107092 -24.170352) (xy 144.078246 -24.187007) (xy 144.054694 -24.210562) (xy 144.038045 -24.239411)
			(xy 144.029431 -24.271587) (xy 144.028922 -24.288242) (xy 144.028922 -24.330406) (xy 144.054068 -24.364188)
			(xy 144.070235 -24.386694) (xy 144.096589 -24.435438) (xy 144.115614 -24.487482) (xy 144.126912 -24.541731)
			(xy 144.130244 -24.597043) (xy 144.12554 -24.652256) (xy 144.112899 -24.706207) (xy 144.092587 -24.757762)
			(xy 144.065031 -24.805838) (xy 144.030811 -24.849421) (xy 143.990646 -24.887596) (xy 143.945382 -24.91956)
			(xy 143.89597 -24.944641) (xy 143.84345 -24.96231) (xy 143.788927 -24.972197) (xy 143.733547 -24.974092)
			(xy 143.678475 -24.967958) (xy 143.62487 -24.953921) (xy 143.573859 -24.932278) (xy 143.526515 -24.903484)
			(xy 143.483833 -24.868145) (xy 143.446713 -24.827004) (xy 143.415934 -24.780925) (xy 143.392144 -24.73088)
			(xy 143.375843 -24.677919) (xy 143.367375 -24.623157) (xy 143.366916 -24.567747) (xy 143.374478 -24.512853)
			(xy 143.38173 -24.486108) (xy 143.387802 -24.463346) (xy 143.392374 -24.416464) (xy 143.388231 -24.369542)
			(xy 143.375513 -24.324187) (xy 143.354658 -24.281951) (xy 143.326378 -24.24428) (xy 143.291641 -24.212465)
			(xy 143.251638 -24.187593) (xy 143.207737 -24.170518) (xy 143.161442 -24.161823) (xy 143.13789 -24.161242)
			(xy 140.648436 -24.161242) (xy 140.625379 -24.161741) (xy 140.58002 -24.170056) (xy 140.536907 -24.186419)
			(xy 140.497454 -24.210294) (xy 140.462957 -24.240895) (xy 140.434548 -24.27722) (xy 140.41316 -24.318074)
			(xy 140.399495 -24.362117) (xy 140.394003 -24.407903) (xy 140.396862 -24.453929) (xy 140.40798 -24.498683)
			(xy 140.417042 -24.51989) (xy 140.428057 -24.545483) (xy 140.443382 -24.59905) (xy 140.450756 -24.654277)
			(xy 140.45002 -24.709988) (xy 140.441191 -24.765001) (xy 140.424456 -24.818145) (xy 140.400171 -24.86829)
			(xy 140.368853 -24.914371) (xy 140.331166 -24.955408) (xy 140.287913 -24.990529) (xy 140.240012 -25.018987)
			(xy 140.188483 -25.040177) (xy 140.134419 -25.053649) (xy 140.078972 -25.059116) (xy 140.023318 -25.056461)
			(xy 139.968643 -25.045743) (xy 139.916107 -25.027187) (xy 139.866828 -25.00119) (xy 139.821852 -24.968303)
			(xy 139.782138 -24.929225) (xy 139.748527 -24.884788) (xy 139.721736 -24.835936) (xy 139.702334 -24.783707)
			(xy 139.690732 -24.729212) (xy 139.687178 -24.673609) (xy 139.691747 -24.61808) (xy 139.704343 -24.563806)
			(xy 139.724696 -24.51194) (xy 139.752376 -24.463585) (xy 139.786792 -24.41977) (xy 139.80668 -24.400256)
			(xy 139.824206 -24.383746) (xy 139.843764 -24.341836) (xy 139.850052 -24.327154) (xy 139.855922 -24.29577)
			(xy 139.853813 -24.263912) (xy 139.843858 -24.233576) (xy 139.82668 -24.206663) (xy 139.803357 -24.184858)
			(xy 139.77535 -24.16953) (xy 139.744412 -24.161637) (xy 139.728448 -24.161242) (xy 139.68222 -24.161242)
			(xy 139.659659 -24.161729) (xy 139.615245 -24.169695) (xy 139.572937 -24.18538) (xy 139.534064 -24.208291)
			(xy 139.499849 -24.237708) (xy 139.471367 -24.272705) (xy 139.449514 -24.312182) (xy 139.434977 -24.354899)
			(xy 139.428213 -24.399511) (xy 139.429435 -24.444617) (xy 139.433554 -24.466804) (xy 139.438611 -24.493454)
			(xy 139.442028 -24.547589) (xy 139.437745 -24.601662) (xy 139.425848 -24.654584) (xy 139.406578 -24.705289)
			(xy 139.380323 -24.752754) (xy 139.347611 -24.796023) (xy 139.309102 -24.834224) (xy 139.265572 -24.866588)
			(xy 139.217899 -24.892463) (xy 139.167042 -24.911326) (xy 139.114026 -24.922798) (xy 139.05992 -24.926648)
			(xy 139.005814 -24.922798) (xy 138.952798 -24.911326) (xy 138.901941 -24.892463) (xy 138.854268 -24.866588)
			(xy 138.810738 -24.834224) (xy 138.772229 -24.796023) (xy 138.739517 -24.752754) (xy 138.713262 -24.705289)
			(xy 138.693992 -24.654584) (xy 138.682095 -24.601662) (xy 138.677812 -24.547589) (xy 138.681229 -24.493454)
			(xy 138.686286 -24.466804) (xy 138.690382 -24.444619) (xy 138.691588 -24.399527) (xy 138.684812 -24.35493)
			(xy 138.670269 -24.31223) (xy 138.648415 -24.272768) (xy 138.619938 -24.237785) (xy 138.58573 -24.20838)
			(xy 138.546869 -24.185477) (xy 138.504574 -24.169794) (xy 138.460174 -24.161826) (xy 138.43762 -24.161242)
			(xy 135.620252 -24.161242) (xy 134.702804 -25.07869) (xy 134.688326 -25.155398) (xy 134.704074 -25.191466)
			(xy 134.715064 -25.217874) (xy 134.729904 -25.273114) (xy 134.736335 -25.32995) (xy 134.734215 -25.387109)
			(xy 134.723591 -25.443312) (xy 134.704701 -25.497301) (xy 134.677967 -25.547868) (xy 134.67387 -25.553416)
			(xy 134.988552 -25.553416) (xy 134.992623 -25.497794) (xy 135.004749 -25.443357) (xy 135.024672 -25.391266)
			(xy 135.051968 -25.342631) (xy 135.086054 -25.298488) (xy 135.126203 -25.259779) (xy 135.171561 -25.227328)
			(xy 135.221161 -25.201827) (xy 135.273945 -25.18382) (xy 135.328788 -25.17369) (xy 135.384522 -25.171653)
			(xy 135.439959 -25.177753) (xy 135.493916 -25.191859) (xy 135.545245 -25.213671) (xy 135.592851 -25.242725)
			(xy 135.635719 -25.2784) (xy 135.672936 -25.319937) (xy 135.703709 -25.36645) (xy 135.727381 -25.416947)
			(xy 135.743449 -25.470354) (xy 135.751569 -25.52553) (xy 135.752078 -25.553416) (xy 135.751569 -25.581302)
			(xy 135.743449 -25.636478) (xy 135.727381 -25.689885) (xy 135.703709 -25.740382) (xy 135.672936 -25.786895)
			(xy 135.635719 -25.828432) (xy 135.592851 -25.864107) (xy 135.545245 -25.893161) (xy 135.493916 -25.914973)
			(xy 135.439959 -25.929079) (xy 135.384522 -25.935179) (xy 135.328788 -25.933142) (xy 135.273945 -25.923012)
			(xy 135.221161 -25.905005) (xy 135.171561 -25.879504) (xy 135.126203 -25.847053) (xy 135.086054 -25.808344)
			(xy 135.051968 -25.764201) (xy 135.024672 -25.715566) (xy 135.004749 -25.663475) (xy 134.992623 -25.609038)
			(xy 134.988552 -25.553416) (xy 134.67387 -25.553416) (xy 134.643989 -25.59388) (xy 134.603526 -25.634307)
			(xy 134.557484 -25.668246) (xy 134.506894 -25.694935) (xy 134.480046 -25.7048) (xy 134.44474 -25.716992)
			(xy 134.350252 -25.837896) (xy 134.350252 -27.601926) (xy 134.988552 -27.601926) (xy 134.992623 -27.546304)
			(xy 135.004749 -27.491867) (xy 135.024672 -27.439776) (xy 135.051968 -27.391141) (xy 135.086054 -27.346998)
			(xy 135.126203 -27.308289) (xy 135.171561 -27.275838) (xy 135.221161 -27.250337) (xy 135.273945 -27.23233)
			(xy 135.328788 -27.2222) (xy 135.384522 -27.220163) (xy 135.439959 -27.226263) (xy 135.493916 -27.240369)
			(xy 135.545245 -27.262181) (xy 135.592851 -27.291235) (xy 135.635719 -27.32691) (xy 135.672936 -27.368447)
			(xy 135.703709 -27.41496) (xy 135.727381 -27.465457) (xy 135.743449 -27.518864) (xy 135.751569 -27.57404)
			(xy 135.752078 -27.601926) (xy 135.751772 -27.618711) (xy 136.577338 -27.618711) (xy 136.581604 -27.557999)
			(xy 136.593879 -27.498389) (xy 136.613948 -27.440931) (xy 136.641454 -27.38664) (xy 136.675915 -27.336474)
			(xy 136.71672 -27.291318) (xy 136.76315 -27.25197) (xy 136.814386 -27.219122) (xy 136.869524 -27.193355)
			(xy 136.927591 -27.175124) (xy 136.987561 -27.164749) (xy 137.048378 -27.162416) (xy 137.07872 -27.164792)
			(xy 137.100025 -27.166392) (xy 137.142632 -27.163285) (xy 137.184118 -27.15309) (xy 137.223312 -27.136095)
			(xy 137.259108 -27.112778) (xy 137.290496 -27.083798) (xy 137.316591 -27.049973) (xy 137.336655 -27.012258)
			(xy 137.350122 -26.971715) (xy 137.353802 -26.95067) (xy 137.358531 -26.923143) (xy 137.374965 -26.869765)
			(xy 137.399004 -26.819352) (xy 137.430135 -26.772981) (xy 137.467692 -26.731643) (xy 137.510873 -26.696221)
			(xy 137.558757 -26.667472) (xy 137.610319 -26.646009) (xy 137.66446 -26.632291) (xy 137.720021 -26.626611)
			(xy 137.775817 -26.62909) (xy 137.830656 -26.639676) (xy 137.883366 -26.658142) (xy 137.932822 -26.684094)
			(xy 137.977966 -26.716977) (xy 138.017836 -26.75609) (xy 138.051578 -26.800596) (xy 138.078473 -26.849545)
			(xy 138.097946 -26.901892) (xy 138.109581 -26.956517) (xy 138.113129 -27.012256) (xy 138.108515 -27.067916)
			(xy 138.095838 -27.122309) (xy 138.075367 -27.174274) (xy 138.04754 -27.222699) (xy 138.012952 -27.266552)
			(xy 137.972342 -27.304894) (xy 137.926576 -27.336908) (xy 137.876633 -27.361909) (xy 137.82358 -27.379363)
			(xy 137.768548 -27.388898) (xy 137.740644 -27.39009) (xy 137.716728 -27.391213) (xy 137.669937 -27.401342)
			(xy 137.625868 -27.420045) (xy 137.586075 -27.446661) (xy 137.551963 -27.480251) (xy 137.524737 -27.51963)
			(xy 137.505358 -27.563406) (xy 137.494509 -27.610035) (xy 137.492994 -27.63393) (xy 137.491557 -27.66423)
			(xy 137.481782 -27.724097) (xy 137.464185 -27.782147) (xy 137.439072 -27.837364) (xy 137.406885 -27.888779)
			(xy 137.368187 -27.935491) (xy 137.333121 -27.967928) (xy 138.380256 -27.967928) (xy 138.387028 -27.914405)
			(xy 138.401272 -27.86237) (xy 138.422704 -27.81286) (xy 138.450897 -27.766863) (xy 138.485288 -27.725296)
			(xy 138.525191 -27.688988) (xy 138.569811 -27.658663) (xy 138.59383 -27.646376) (xy 138.614086 -27.634662)
			(xy 138.650305 -27.605042) (xy 138.680491 -27.569296) (xy 138.703627 -27.528629) (xy 138.71893 -27.484415)
			(xy 138.725884 -27.438147) (xy 138.724254 -27.391388) (xy 138.714095 -27.345717) (xy 138.69575 -27.302676)
			(xy 138.683238 -27.282902) (xy 138.668196 -27.259402) (xy 138.644414 -27.208928) (xy 138.628239 -27.155528)
			(xy 138.620017 -27.100342) (xy 138.619923 -27.044546) (xy 138.627959 -26.989332) (xy 138.643953 -26.935878)
			(xy 138.667564 -26.885324) (xy 138.698288 -26.83875) (xy 138.73547 -26.797149) (xy 138.778316 -26.761409)
			(xy 138.825913 -26.732292) (xy 138.877243 -26.71042) (xy 138.931212 -26.696261) (xy 138.986668 -26.690115)
			(xy 139.042428 -26.692114) (xy 139.097302 -26.702215) (xy 139.150118 -26.720203) (xy 139.19975 -26.745694)
			(xy 139.245139 -26.778145) (xy 139.285316 -26.816861) (xy 139.319424 -26.861018) (xy 139.346734 -26.909673)
			(xy 139.366664 -26.961788) (xy 139.37879 -27.01625) (xy 139.382851 -27.071898) (xy 139.378761 -27.127544)
			(xy 139.366608 -27.182) (xy 139.346651 -27.234104) (xy 139.319316 -27.282745) (xy 139.285185 -27.326884)
			(xy 139.244989 -27.365581) (xy 139.199583 -27.398007) (xy 139.174982 -27.411172) (xy 139.15422 -27.42237)
			(xy 139.116948 -27.451279) (xy 139.085647 -27.486565) (xy 139.06139 -27.527019) (xy 139.045009 -27.571252)
			(xy 139.037066 -27.617748) (xy 139.037834 -27.66491) (xy 139.047287 -27.711123) (xy 139.065099 -27.754799)
			(xy 139.077446 -27.7749) (xy 139.092421 -27.797842) (xy 139.11633 -27.847134) (xy 139.132944 -27.899339)
			(xy 139.137898 -27.926284) (xy 139.141977 -27.953603) (xy 139.143135 -28.008828) (xy 139.140258 -28.031944)
			(xy 141.273512 -28.031944) (xy 141.273512 -27.972008) (xy 141.281335 -27.912586) (xy 141.296848 -27.854693)
			(xy 141.319784 -27.79932) (xy 141.349751 -27.747414) (xy 141.386238 -27.699864) (xy 141.428618 -27.657484)
			(xy 141.476168 -27.620997) (xy 141.528074 -27.59103) (xy 141.583447 -27.568094) (xy 141.64134 -27.552581)
			(xy 141.700762 -27.544758) (xy 141.760698 -27.544758) (xy 141.82012 -27.552581) (xy 141.878013 -27.568094)
			(xy 141.933386 -27.59103) (xy 141.985292 -27.620997) (xy 142.032842 -27.657484) (xy 142.075222 -27.699864)
			(xy 142.091091 -27.720544) (xy 143.404842 -27.720544) (xy 143.408913 -27.664922) (xy 143.421039 -27.610485)
			(xy 143.440962 -27.558394) (xy 143.468258 -27.509759) (xy 143.502344 -27.465616) (xy 143.542493 -27.426907)
			(xy 143.587851 -27.394456) (xy 143.637451 -27.368955) (xy 143.690235 -27.350948) (xy 143.745078 -27.340818)
			(xy 143.800812 -27.338781) (xy 143.856249 -27.344881) (xy 143.910206 -27.358987) (xy 143.961535 -27.380799)
			(xy 144.009141 -27.409853) (xy 144.052009 -27.445528) (xy 144.089226 -27.487065) (xy 144.119999 -27.533578)
			(xy 144.143671 -27.584075) (xy 144.159739 -27.637482) (xy 144.167859 -27.692658) (xy 144.168368 -27.720544)
			(xy 144.167859 -27.74843) (xy 144.159739 -27.803606) (xy 144.143671 -27.857013) (xy 144.119999 -27.90751)
			(xy 144.089226 -27.954023) (xy 144.052009 -27.99556) (xy 144.009141 -28.031235) (xy 143.961535 -28.060289)
			(xy 143.910206 -28.082101) (xy 143.856249 -28.096207) (xy 143.800812 -28.102307) (xy 143.745078 -28.10027)
			(xy 143.690235 -28.09014) (xy 143.637451 -28.072133) (xy 143.587851 -28.046632) (xy 143.542493 -28.014181)
			(xy 143.502344 -27.975472) (xy 143.468258 -27.931329) (xy 143.440962 -27.882694) (xy 143.421039 -27.830603)
			(xy 143.408913 -27.776166) (xy 143.404842 -27.720544) (xy 142.091091 -27.720544) (xy 142.111709 -27.747414)
			(xy 142.141676 -27.79932) (xy 142.164612 -27.854693) (xy 142.180125 -27.912586) (xy 142.187948 -27.972008)
			(xy 142.188438 -28.001976) (xy 142.187948 -28.031944) (xy 142.180125 -28.091366) (xy 142.164612 -28.149259)
			(xy 142.141676 -28.204632) (xy 142.111709 -28.256538) (xy 142.075222 -28.304088) (xy 142.032842 -28.346468)
			(xy 141.985292 -28.382955) (xy 141.933386 -28.412922) (xy 141.878013 -28.435858) (xy 141.82012 -28.451371)
			(xy 141.760698 -28.459194) (xy 141.700762 -28.459194) (xy 141.64134 -28.451371) (xy 141.583447 -28.435858)
			(xy 141.528074 -28.412922) (xy 141.476168 -28.382955) (xy 141.428618 -28.346468) (xy 141.386238 -28.304088)
			(xy 141.349751 -28.256538) (xy 141.319784 -28.204632) (xy 141.296848 -28.149259) (xy 141.281335 -28.091366)
			(xy 141.273512 -28.031944) (xy 139.140258 -28.031944) (xy 139.136314 -28.063641) (xy 139.121655 -28.116897)
			(xy 139.099466 -28.16748) (xy 139.070211 -28.214333) (xy 139.034502 -28.256474) (xy 138.993086 -28.293023)
			(xy 138.946831 -28.323214) (xy 138.896704 -28.346415) (xy 138.843754 -28.362142) (xy 138.789089 -28.370064)
			(xy 138.76147 -28.37053) (xy 138.734495 -28.370056) (xy 138.681088 -28.362424) (xy 138.629289 -28.347345)
			(xy 138.58013 -28.325119) (xy 138.534592 -28.29619) (xy 138.493584 -28.261135) (xy 138.457923 -28.220653)
			(xy 138.428319 -28.175551) (xy 138.405365 -28.126728) (xy 138.389517 -28.075159) (xy 138.381091 -28.021871)
			(xy 138.380256 -27.967928) (xy 137.333121 -27.967928) (xy 137.323658 -27.976682) (xy 137.274077 -28.011628)
			(xy 137.220314 -28.039718) (xy 137.163311 -28.06046) (xy 137.104068 -28.073489) (xy 137.043622 -28.078577)
			(xy 136.983035 -28.075635) (xy 136.923367 -28.064714) (xy 136.865664 -28.046007) (xy 136.810939 -28.01984)
			(xy 136.760151 -27.986674) (xy 136.714189 -27.947088) (xy 136.693656 -27.92476) (xy 136.673831 -27.901667)
			(xy 136.639742 -27.851248) (xy 136.612636 -27.796756) (xy 136.592992 -27.739152) (xy 136.581156 -27.679452)
			(xy 136.577338 -27.618711) (xy 135.751772 -27.618711) (xy 135.751569 -27.629812) (xy 135.743449 -27.684988)
			(xy 135.727381 -27.738395) (xy 135.703709 -27.788892) (xy 135.672936 -27.835405) (xy 135.635719 -27.876942)
			(xy 135.592851 -27.912617) (xy 135.545245 -27.941671) (xy 135.493916 -27.963483) (xy 135.439959 -27.977589)
			(xy 135.384522 -27.983689) (xy 135.328788 -27.981652) (xy 135.273945 -27.971522) (xy 135.221161 -27.953515)
			(xy 135.171561 -27.928014) (xy 135.126203 -27.895563) (xy 135.086054 -27.856854) (xy 135.051968 -27.812711)
			(xy 135.024672 -27.764076) (xy 135.004749 -27.711985) (xy 134.992623 -27.657548) (xy 134.988552 -27.601926)
			(xy 134.350252 -27.601926) (xy 134.350252 -28.48356) (xy 134.376668 -28.51785) (xy 134.39349 -28.540453)
			(xy 134.422076 -28.589008) (xy 134.444487 -28.640703) (xy 134.453626 -28.671774) (xy 137.463782 -28.671774)
			(xy 137.467853 -28.616152) (xy 137.479979 -28.561715) (xy 137.499902 -28.509624) (xy 137.527198 -28.460989)
			(xy 137.561284 -28.416846) (xy 137.601433 -28.378137) (xy 137.646791 -28.345686) (xy 137.696391 -28.320185)
			(xy 137.749175 -28.302178) (xy 137.804018 -28.292048) (xy 137.859752 -28.290011) (xy 137.915189 -28.296111)
			(xy 137.969146 -28.310217) (xy 138.020475 -28.332029) (xy 138.068081 -28.361083) (xy 138.110949 -28.396758)
			(xy 138.148166 -28.438295) (xy 138.178939 -28.484808) (xy 138.202611 -28.535305) (xy 138.218679 -28.588712)
			(xy 138.226799 -28.643888) (xy 138.227308 -28.671774) (xy 138.226799 -28.69966) (xy 138.222456 -28.729174)
			(xy 139.367242 -28.729174) (xy 139.367242 -28.669238) (xy 139.375065 -28.609816) (xy 139.390578 -28.551923)
			(xy 139.413514 -28.49655) (xy 139.443481 -28.444644) (xy 139.479968 -28.397094) (xy 139.522348 -28.354714)
			(xy 139.569898 -28.318227) (xy 139.621804 -28.28826) (xy 139.677177 -28.265324) (xy 139.73507 -28.249811)
			(xy 139.794492 -28.241988) (xy 139.854428 -28.241988) (xy 139.91385 -28.249811) (xy 139.971743 -28.265324)
			(xy 140.027116 -28.28826) (xy 140.079022 -28.318227) (xy 140.126572 -28.354714) (xy 140.168952 -28.397094)
			(xy 140.205439 -28.444644) (xy 140.235406 -28.49655) (xy 140.258342 -28.551923) (xy 140.273855 -28.609816)
			(xy 140.281678 -28.669238) (xy 140.282168 -28.699206) (xy 140.281678 -28.729174) (xy 140.273855 -28.788596)
			(xy 140.258342 -28.846489) (xy 140.235406 -28.901862) (xy 140.205439 -28.953768) (xy 140.168952 -29.001318)
			(xy 140.126572 -29.043698) (xy 140.079022 -29.080185) (xy 140.027116 -29.110152) (xy 139.971743 -29.133088)
			(xy 139.91385 -29.148601) (xy 139.854428 -29.156424) (xy 139.794492 -29.156424) (xy 139.73507 -29.148601)
			(xy 139.677177 -29.133088) (xy 139.621804 -29.110152) (xy 139.569898 -29.080185) (xy 139.522348 -29.043698)
			(xy 139.479968 -29.001318) (xy 139.443481 -28.953768) (xy 139.413514 -28.901862) (xy 139.390578 -28.846489)
			(xy 139.375065 -28.788596) (xy 139.367242 -28.729174) (xy 138.222456 -28.729174) (xy 138.218679 -28.754836)
			(xy 138.202611 -28.808243) (xy 138.178939 -28.85874) (xy 138.148166 -28.905253) (xy 138.110949 -28.94679)
			(xy 138.068081 -28.982465) (xy 138.020475 -29.011519) (xy 137.969146 -29.033331) (xy 137.915189 -29.047437)
			(xy 137.859752 -29.053537) (xy 137.804018 -29.0515) (xy 137.749175 -29.04137) (xy 137.696391 -29.023363)
			(xy 137.646791 -28.997862) (xy 137.601433 -28.965411) (xy 137.561284 -28.926702) (xy 137.527198 -28.882559)
			(xy 137.499902 -28.833924) (xy 137.479979 -28.781833) (xy 137.467853 -28.727396) (xy 137.463782 -28.671774)
			(xy 134.453626 -28.671774) (xy 134.460386 -28.694758) (xy 134.469531 -28.750356) (xy 134.471784 -28.806655)
			(xy 134.467112 -28.862806) (xy 134.461758 -28.890468) (xy 134.455154 -28.922218) (xy 134.473442 -28.983432)
			(xy 135.366252 -29.876242) (xy 142.986252 -29.876242)
		)
		(stroke
			(width 0)
			(type solid)
		)
		(fill yes)
		(layer "B.Cu")
		(net "GNDA")
	)
	(gr_poly
		(pts
			(xy 43.060366 -190.043054) (xy 43.077022 -190.042563) (xy 43.109199 -190.033947) (xy 43.138048 -190.017293)
			(xy 43.161601 -189.993738) (xy 43.178252 -189.964888) (xy 43.186865 -189.93271) (xy 43.187366 -189.916054)
			(xy 43.187366 -185.985912) (xy 42.798492 -185.597292) (xy 42.798492 -184.633108) (xy 43.187366 -184.244488)
			(xy 43.187366 -183.428386) (xy 46.82998 -179.785772) (xy 46.82998 -176.866296) (xy 46.14672 -176.183036)
			(xy 43.54957 -176.183036) (xy 43.534809 -176.183431) (xy 43.506068 -176.19017) (xy 43.479652 -176.203347)
			(xy 43.456981 -176.222255) (xy 43.439276 -176.245877) (xy 43.432984 -176.259236) (xy 43.421491 -176.284419)
			(xy 43.392305 -176.331453) (xy 43.356626 -176.373775) (xy 43.315205 -176.410494) (xy 43.268911 -176.440841)
			(xy 43.218716 -176.464177) (xy 43.165676 -176.480011) (xy 43.110903 -176.488013) (xy 43.055549 -176.488013)
			(xy 43.000776 -176.480011) (xy 42.947736 -176.464177) (xy 42.897541 -176.440841) (xy 42.851247 -176.410494)
			(xy 42.809826 -176.373775) (xy 42.774147 -176.331453) (xy 42.744961 -176.284419) (xy 42.733468 -176.259236)
			(xy 42.727165 -176.245889) (xy 42.70944 -176.222296) (xy 42.686768 -176.203407) (xy 42.660363 -176.190234)
			(xy 42.631637 -176.18348) (xy 42.616882 -176.183036) (xy 35.864038 -176.183036) (xy 35.536632 -176.510442)
			(xy 35.535108 -176.612804) (xy 35.570414 -176.65065) (xy 35.590996 -176.673333) (xy 35.626539 -176.723216)
			(xy 35.655112 -176.777393) (xy 35.676205 -176.834896) (xy 35.689441 -176.894699) (xy 35.694583 -176.955733)
			(xy 35.691539 -177.016908) (xy 35.680364 -177.07713) (xy 35.661258 -177.135324) (xy 35.650203 -177.158152)
			(xy 42.612482 -177.158152) (xy 42.613735 -177.103184) (xy 42.622865 -177.048966) (xy 42.639683 -176.996619)
			(xy 42.663841 -176.947229) (xy 42.694838 -176.901817) (xy 42.732034 -176.861326) (xy 42.774656 -176.826593)
			(xy 42.821822 -176.798338) (xy 42.872556 -176.777146) (xy 42.925806 -176.763456) (xy 42.98047 -176.757551)
			(xy 43.035416 -176.759554) (xy 43.089505 -176.769424) (xy 43.141617 -176.786955) (xy 43.190673 -176.811785)
			(xy 43.235657 -176.8434) (xy 43.275636 -176.881145) (xy 43.309784 -176.924237) (xy 43.337392 -176.971785)
			(xy 43.35789 -177.022803) (xy 43.370852 -177.076236) (xy 43.376009 -177.130975) (xy 43.373256 -177.185888)
			(xy 43.362648 -177.239838) (xy 43.344407 -177.291706) (xy 43.318909 -177.340418) (xy 43.286683 -177.384966)
			(xy 43.267884 -177.40503) (xy 43.252411 -177.421701) (xy 43.227079 -177.459471) (xy 43.208873 -177.501147)
			(xy 43.198374 -177.545398) (xy 43.195917 -177.59081) (xy 43.201581 -177.635935) (xy 43.215184 -177.679332)
			(xy 43.236293 -177.719615) (xy 43.264234 -177.755499) (xy 43.280838 -177.771044) (xy 43.301019 -177.789716)
			(xy 43.336328 -177.831859) (xy 43.365222 -177.878634) (xy 43.387103 -177.929072) (xy 43.401518 -177.982128)
			(xy 43.408167 -178.036704) (xy 43.406914 -178.091669) (xy 43.397784 -178.145886) (xy 43.380966 -178.19823)
			(xy 43.356808 -178.247618) (xy 43.325812 -178.293027) (xy 43.288618 -178.333517) (xy 43.245998 -178.368248)
			(xy 43.198834 -178.396502) (xy 43.148102 -178.417693) (xy 43.094854 -178.431383) (xy 43.040193 -178.437288)
			(xy 42.98525 -178.435285) (xy 42.931163 -178.425417) (xy 42.879053 -178.407887) (xy 42.829999 -178.383059)
			(xy 42.785016 -178.351446) (xy 42.745038 -178.313704) (xy 42.71089 -178.270614) (xy 42.683282 -178.223069)
			(xy 42.662784 -178.172054) (xy 42.649821 -178.118624) (xy 42.644662 -178.063887) (xy 42.647414 -178.008976)
			(xy 42.658018 -177.955029) (xy 42.676257 -177.903163) (xy 42.701752 -177.854452) (xy 42.733975 -177.809904)
			(xy 42.752772 -177.78984) (xy 42.76828 -177.773199) (xy 42.793615 -177.735424) (xy 42.811823 -177.693743)
			(xy 42.822321 -177.649486) (xy 42.824775 -177.604068) (xy 42.819106 -177.558938) (xy 42.805495 -177.515538)
			(xy 42.784378 -177.475253) (xy 42.756427 -177.43937) (xy 42.739818 -177.423826) (xy 42.71964 -177.405149)
			(xy 42.684328 -177.363005) (xy 42.655432 -177.316229) (xy 42.633549 -177.265789) (xy 42.619133 -177.212731)
			(xy 42.612482 -177.158152) (xy 35.650203 -177.158152) (xy 35.634561 -177.19045) (xy 35.600751 -177.241523)
			(xy 35.560432 -177.287631) (xy 35.514324 -177.32795) (xy 35.463251 -177.36176) (xy 35.408125 -177.388457)
			(xy 35.349931 -177.407564) (xy 35.289709 -177.418739) (xy 35.228535 -177.421783) (xy 35.167501 -177.416641)
			(xy 35.107698 -177.403405) (xy 35.050194 -177.382313) (xy 34.996017 -177.35374) (xy 34.946134 -177.318197)
			(xy 34.923476 -177.297588) (xy 34.88563 -177.262282) (xy 34.783268 -177.263806) (xy 34.3535 -177.693574)
			(xy 34.3535 -179.147216) (xy 42.612054 -179.147216) (xy 42.616125 -179.091594) (xy 42.628251 -179.037157)
			(xy 42.648174 -178.985066) (xy 42.67547 -178.936431) (xy 42.709556 -178.892288) (xy 42.749705 -178.853579)
			(xy 42.795063 -178.821128) (xy 42.844663 -178.795627) (xy 42.897447 -178.77762) (xy 42.95229 -178.76749)
			(xy 43.008024 -178.765453) (xy 43.063461 -178.771553) (xy 43.117418 -178.785659) (xy 43.168747 -178.807471)
			(xy 43.216353 -178.836525) (xy 43.259221 -178.8722) (xy 43.296438 -178.913737) (xy 43.327211 -178.96025)
			(xy 43.350883 -179.010747) (xy 43.366951 -179.064154) (xy 43.375071 -179.11933) (xy 43.37558 -179.147216)
			(xy 43.375071 -179.175102) (xy 43.366951 -179.230278) (xy 43.350883 -179.283685) (xy 43.334843 -179.317902)
			(xy 44.900615 -179.317902) (xy 44.90449 -179.26363) (xy 44.916037 -179.210459) (xy 44.935021 -179.159468)
			(xy 44.961057 -179.111691) (xy 44.993617 -179.068098) (xy 45.03204 -179.029573) (xy 45.053504 -179.01285)
			(xy 45.071995 -178.998287) (xy 45.10375 -178.963552) (xy 45.128567 -178.923565) (xy 45.145599 -178.879692)
			(xy 45.154264 -178.833434) (xy 45.154264 -178.786371) (xy 45.145601 -178.740113) (xy 45.12857 -178.69624)
			(xy 45.103753 -178.656252) (xy 45.071999 -178.621516) (xy 45.053504 -178.606958) (xy 45.032044 -178.59023)
			(xy 44.99362 -178.551706) (xy 44.961059 -178.508113) (xy 44.935023 -178.460337) (xy 44.916038 -178.409346)
			(xy 44.904491 -178.356175) (xy 44.900615 -178.301902) (xy 44.90449 -178.24763) (xy 44.916037 -178.194459)
			(xy 44.935021 -178.143468) (xy 44.961057 -178.095691) (xy 44.993617 -178.052098) (xy 45.03204 -178.013573)
			(xy 45.053504 -177.99685) (xy 45.071995 -177.982287) (xy 45.10375 -177.947552) (xy 45.128567 -177.907565)
			(xy 45.145599 -177.863692) (xy 45.154264 -177.817434) (xy 45.154264 -177.770371) (xy 45.145601 -177.724113)
			(xy 45.12857 -177.68024) (xy 45.103753 -177.640252) (xy 45.071999 -177.605516) (xy 45.053504 -177.590958)
			(xy 45.031383 -177.573725) (xy 44.991958 -177.53385) (xy 44.958794 -177.488633) (xy 44.932607 -177.439049)
			(xy 44.91396 -177.386166) (xy 44.903254 -177.331123) (xy 44.900722 -177.275106) (xy 44.906416 -177.219321)
			(xy 44.920214 -177.164971) (xy 44.94182 -177.113226) (xy 44.970767 -177.065201) (xy 45.006433 -177.02193)
			(xy 45.048048 -176.984347) (xy 45.094717 -176.95326) (xy 45.145433 -176.929339) (xy 45.199104 -176.913099)
			(xy 45.254575 -176.904891) (xy 45.310649 -176.904891) (xy 45.36612 -176.913099) (xy 45.419791 -176.929339)
			(xy 45.470507 -176.95326) (xy 45.517176 -176.984347) (xy 45.558791 -177.02193) (xy 45.594457 -177.065201)
			(xy 45.623404 -177.113226) (xy 45.64501 -177.164971) (xy 45.658808 -177.219321) (xy 45.664502 -177.275106)
			(xy 45.66197 -177.331123) (xy 45.651264 -177.386166) (xy 45.632617 -177.439049) (xy 45.60643 -177.488633)
			(xy 45.573266 -177.53385) (xy 45.533841 -177.573725) (xy 45.51172 -177.590958) (xy 45.493219 -177.60551)
			(xy 45.461462 -177.640246) (xy 45.436642 -177.680235) (xy 45.419609 -177.724109) (xy 45.410944 -177.77037)
			(xy 45.410945 -177.817435) (xy 45.41961 -177.863695) (xy 45.436644 -177.90757) (xy 45.461465 -177.947558)
			(xy 45.493223 -177.982293) (xy 45.51172 -177.99685) (xy 45.533187 -178.013569) (xy 45.571609 -178.052095)
			(xy 45.604168 -178.095689) (xy 45.630202 -178.143467) (xy 45.649185 -178.194459) (xy 45.660731 -178.24763)
			(xy 45.664606 -178.301902) (xy 45.660731 -178.356175) (xy 45.649184 -178.409346) (xy 45.6302 -178.460338)
			(xy 45.604165 -178.508115) (xy 45.571606 -178.551708) (xy 45.533183 -178.590234) (xy 45.51172 -178.606958)
			(xy 45.493219 -178.62151) (xy 45.461462 -178.656246) (xy 45.436642 -178.696235) (xy 45.419609 -178.740109)
			(xy 45.410944 -178.78637) (xy 45.410945 -178.833435) (xy 45.41961 -178.879695) (xy 45.436644 -178.92357)
			(xy 45.461465 -178.963558) (xy 45.493223 -178.998293) (xy 45.51172 -179.01285) (xy 45.533187 -179.029569)
			(xy 45.571609 -179.068095) (xy 45.604168 -179.111689) (xy 45.630202 -179.159467) (xy 45.649185 -179.210459)
			(xy 45.660731 -179.26363) (xy 45.664606 -179.317902) (xy 45.660731 -179.372175) (xy 45.649184 -179.425346)
			(xy 45.6302 -179.476338) (xy 45.604165 -179.524115) (xy 45.571606 -179.567708) (xy 45.533183 -179.606234)
			(xy 45.51172 -179.622958) (xy 45.493219 -179.63751) (xy 45.461462 -179.672246) (xy 45.436642 -179.712235)
			(xy 45.419609 -179.756109) (xy 45.410944 -179.80237) (xy 45.410945 -179.849435) (xy 45.41961 -179.895695)
			(xy 45.436644 -179.93957) (xy 45.461465 -179.979558) (xy 45.493223 -180.014293) (xy 45.51172 -180.02885)
			(xy 45.533841 -180.046083) (xy 45.573266 -180.085958) (xy 45.60643 -180.131175) (xy 45.632617 -180.180759)
			(xy 45.651264 -180.233642) (xy 45.66197 -180.288685) (xy 45.664502 -180.344702) (xy 45.658808 -180.400487)
			(xy 45.64501 -180.454837) (xy 45.623404 -180.506582) (xy 45.594457 -180.554607) (xy 45.558791 -180.597878)
			(xy 45.517176 -180.635461) (xy 45.470507 -180.666548) (xy 45.419791 -180.690469) (xy 45.36612 -180.706709)
			(xy 45.310649 -180.714917) (xy 45.254575 -180.714917) (xy 45.199104 -180.706709) (xy 45.145433 -180.690469)
			(xy 45.094717 -180.666548) (xy 45.048048 -180.635461) (xy 45.006433 -180.597878) (xy 44.970767 -180.554607)
			(xy 44.94182 -180.506582) (xy 44.920214 -180.454837) (xy 44.906416 -180.400487) (xy 44.900722 -180.344702)
			(xy 44.903254 -180.288685) (xy 44.91396 -180.233642) (xy 44.932607 -180.180759) (xy 44.958794 -180.131175)
			(xy 44.991958 -180.085958) (xy 45.031383 -180.046083) (xy 45.053504 -180.02885) (xy 45.071995 -180.014287)
			(xy 45.10375 -179.979552) (xy 45.128567 -179.939565) (xy 45.145599 -179.895692) (xy 45.154264 -179.849434)
			(xy 45.154264 -179.802371) (xy 45.145601 -179.756113) (xy 45.12857 -179.71224) (xy 45.103753 -179.672252)
			(xy 45.071999 -179.637516) (xy 45.053504 -179.622958) (xy 45.032044 -179.60623) (xy 44.99362 -179.567706)
			(xy 44.961059 -179.524113) (xy 44.935023 -179.476337) (xy 44.916038 -179.425346) (xy 44.904491 -179.372175)
			(xy 44.900615 -179.317902) (xy 43.334843 -179.317902) (xy 43.327211 -179.334182) (xy 43.296438 -179.380695)
			(xy 43.259221 -179.422232) (xy 43.216353 -179.457907) (xy 43.168747 -179.486961) (xy 43.117418 -179.508773)
			(xy 43.063461 -179.522879) (xy 43.008024 -179.528979) (xy 42.95229 -179.526942) (xy 42.897447 -179.516812)
			(xy 42.844663 -179.498805) (xy 42.795063 -179.473304) (xy 42.749705 -179.440853) (xy 42.709556 -179.402144)
			(xy 42.67547 -179.358001) (xy 42.648174 -179.309366) (xy 42.628251 -179.257275) (xy 42.616125 -179.202838)
			(xy 42.612054 -179.147216) (xy 34.3535 -179.147216) (xy 34.3535 -180.477668) (xy 42.678856 -180.477668)
			(xy 42.682927 -180.422046) (xy 42.695053 -180.367609) (xy 42.714976 -180.315518) (xy 42.742272 -180.266883)
			(xy 42.776358 -180.22274) (xy 42.816507 -180.184031) (xy 42.861865 -180.15158) (xy 42.911465 -180.126079)
			(xy 42.964249 -180.108072) (xy 43.019092 -180.097942) (xy 43.074826 -180.095905) (xy 43.130263 -180.102005)
			(xy 43.18422 -180.116111) (xy 43.235549 -180.137923) (xy 43.283155 -180.166977) (xy 43.326023 -180.202652)
			(xy 43.36324 -180.244189) (xy 43.394013 -180.290702) (xy 43.417685 -180.341199) (xy 43.433753 -180.394606)
			(xy 43.441873 -180.449782) (xy 43.442382 -180.477668) (xy 43.441873 -180.505554) (xy 43.433753 -180.56073)
			(xy 43.417685 -180.614137) (xy 43.394013 -180.664634) (xy 43.36324 -180.711147) (xy 43.326023 -180.752684)
			(xy 43.283155 -180.788359) (xy 43.235549 -180.817413) (xy 43.18422 -180.839225) (xy 43.130263 -180.853331)
			(xy 43.074826 -180.859431) (xy 43.019092 -180.857394) (xy 42.964249 -180.847264) (xy 42.911465 -180.829257)
			(xy 42.861865 -180.803756) (xy 42.816507 -180.771305) (xy 42.776358 -180.732596) (xy 42.742272 -180.688453)
			(xy 42.714976 -180.639818) (xy 42.695053 -180.587727) (xy 42.682927 -180.53329) (xy 42.678856 -180.477668)
			(xy 34.3535 -180.477668) (xy 34.3535 -181.03748) (xy 34.645074 -181.03748) (xy 34.645074 -180.977544)
			(xy 34.652897 -180.918122) (xy 34.66841 -180.860229) (xy 34.691346 -180.804856) (xy 34.721313 -180.75295)
			(xy 34.7578 -180.7054) (xy 34.80018 -180.66302) (xy 34.84773 -180.626533) (xy 34.899636 -180.596566)
			(xy 34.955009 -180.57363) (xy 35.012902 -180.558117) (xy 35.072324 -180.550294) (xy 35.13226 -180.550294)
			(xy 35.191682 -180.558117) (xy 35.249575 -180.57363) (xy 35.304948 -180.596566) (xy 35.356854 -180.626533)
			(xy 35.404404 -180.66302) (xy 35.446784 -180.7054) (xy 35.483271 -180.75295) (xy 35.513238 -180.804856)
			(xy 35.536174 -180.860229) (xy 35.551687 -180.918122) (xy 35.55951 -180.977544) (xy 35.56 -181.007512)
			(xy 35.55951 -181.03748) (xy 35.551687 -181.096902) (xy 35.536174 -181.154795) (xy 35.513238 -181.210168)
			(xy 35.483271 -181.262074) (xy 35.446784 -181.309624) (xy 35.404404 -181.352004) (xy 35.356854 -181.388491)
			(xy 35.304948 -181.418458) (xy 35.249575 -181.441394) (xy 35.191682 -181.456907) (xy 35.13226 -181.46473)
			(xy 35.072324 -181.46473) (xy 35.012902 -181.456907) (xy 34.955009 -181.441394) (xy 34.899636 -181.418458)
			(xy 34.84773 -181.388491) (xy 34.80018 -181.352004) (xy 34.7578 -181.309624) (xy 34.721313 -181.262074)
			(xy 34.691346 -181.210168) (xy 34.66841 -181.154795) (xy 34.652897 -181.096902) (xy 34.645074 -181.03748)
			(xy 34.3535 -181.03748) (xy 34.3535 -181.780942) (xy 43.091098 -181.780942) (xy 43.095169 -181.72532)
			(xy 43.107295 -181.670883) (xy 43.127218 -181.618792) (xy 43.154514 -181.570157) (xy 43.1886 -181.526014)
			(xy 43.228749 -181.487305) (xy 43.274107 -181.454854) (xy 43.323707 -181.429353) (xy 43.376491 -181.411346)
			(xy 43.431334 -181.401216) (xy 43.487068 -181.399179) (xy 43.542505 -181.405279) (xy 43.596462 -181.419385)
			(xy 43.647791 -181.441197) (xy 43.695397 -181.470251) (xy 43.738265 -181.505926) (xy 43.775482 -181.547463)
			(xy 43.806255 -181.593976) (xy 43.829927 -181.644473) (xy 43.845995 -181.69788) (xy 43.854115 -181.753056)
			(xy 43.854624 -181.780942) (xy 43.854115 -181.808828) (xy 43.845995 -181.864004) (xy 43.829927 -181.917411)
			(xy 43.806255 -181.967908) (xy 43.775482 -182.014421) (xy 43.738265 -182.055958) (xy 43.695397 -182.091633)
			(xy 43.647791 -182.120687) (xy 43.596462 -182.142499) (xy 43.542505 -182.156605) (xy 43.487068 -182.162705)
			(xy 43.431334 -182.160668) (xy 43.376491 -182.150538) (xy 43.323707 -182.132531) (xy 43.274107 -182.10703)
			(xy 43.228749 -182.074579) (xy 43.1886 -182.03587) (xy 43.154514 -181.991727) (xy 43.127218 -181.943092)
			(xy 43.107295 -181.891001) (xy 43.095169 -181.836564) (xy 43.091098 -181.780942) (xy 34.3535 -181.780942)
			(xy 34.3535 -183.226202) (xy 34.341308 -183.238648) (xy 34.341308 -183.539892) (xy 34.096452 -183.784494)
			(xy 34.085231 -183.796425) (xy 34.068729 -183.824704) (xy 34.059972 -183.856253) (xy 34.059537 -183.888991)
			(xy 34.067454 -183.920762) (xy 34.074862 -183.93537) (xy 34.087061 -183.956461) (xy 34.118194 -183.993931)
			(xy 34.155893 -184.024788) (xy 34.198778 -184.047901) (xy 34.245279 -184.062424) (xy 34.269426 -184.065672)
			(xy 34.297769 -184.069337) (xy 34.35299 -184.084054) (xy 34.405401 -184.106837) (xy 34.453831 -184.137178)
			(xy 34.497197 -184.174398) (xy 34.53453 -184.217667) (xy 34.564997 -184.266017) (xy 34.587917 -184.318369)
			(xy 34.595816 -184.345834) (xy 34.602259 -184.367961) (xy 34.622011 -184.409595) (xy 34.64895 -184.446982)
			(xy 34.682193 -184.478895) (xy 34.720648 -184.504286) (xy 34.763053 -184.522323) (xy 34.808016 -184.532413)
			(xy 34.83102 -184.533794) (xy 34.85932 -184.535449) (xy 34.915002 -184.546079) (xy 34.963295 -184.563004)
			(xy 37.682422 -184.563004) (xy 37.686493 -184.507382) (xy 37.698619 -184.452945) (xy 37.718542 -184.400854)
			(xy 37.745838 -184.352219) (xy 37.779924 -184.308076) (xy 37.820073 -184.269367) (xy 37.865431 -184.236916)
			(xy 37.915031 -184.211415) (xy 37.967815 -184.193408) (xy 38.022658 -184.183278) (xy 38.078392 -184.181241)
			(xy 38.133829 -184.187341) (xy 38.187786 -184.201447) (xy 38.239115 -184.223259) (xy 38.286721 -184.252313)
			(xy 38.329589 -184.287988) (xy 38.366806 -184.329525) (xy 38.397579 -184.376038) (xy 38.421251 -184.426535)
			(xy 38.437319 -184.479942) (xy 38.445439 -184.535118) (xy 38.445948 -184.563004) (xy 38.445439 -184.59089)
			(xy 38.437319 -184.646066) (xy 38.421251 -184.699473) (xy 38.397579 -184.74997) (xy 38.366806 -184.796483)
			(xy 38.329589 -184.83802) (xy 38.286721 -184.873695) (xy 38.239115 -184.902749) (xy 38.187786 -184.924561)
			(xy 38.133829 -184.938667) (xy 38.078392 -184.944767) (xy 38.022658 -184.94273) (xy 37.967815 -184.9326)
			(xy 37.915031 -184.914593) (xy 37.865431 -184.889092) (xy 37.820073 -184.856641) (xy 37.779924 -184.817932)
			(xy 37.745838 -184.773789) (xy 37.718542 -184.725154) (xy 37.698619 -184.673063) (xy 37.686493 -184.618626)
			(xy 37.682422 -184.563004) (xy 34.963295 -184.563004) (xy 34.968499 -184.564828) (xy 35.018633 -184.591286)
			(xy 35.064302 -184.624868) (xy 35.104501 -184.664837) (xy 35.138345 -184.710313) (xy 35.165089 -184.760295)
			(xy 35.184146 -184.813683) (xy 35.195095 -184.869303) (xy 35.197695 -184.925931) (xy 35.19189 -184.98232)
			(xy 35.177807 -185.03723) (xy 35.155757 -185.089453) (xy 35.126223 -185.137839) (xy 35.089857 -185.181324)
			(xy 35.069018 -185.200544) (xy 35.047408 -185.219021) (xy 34.999753 -185.250029) (xy 34.948025 -185.273621)
			(xy 34.893367 -185.289275) (xy 34.836992 -185.296645) (xy 34.780148 -185.295566) (xy 34.724093 -185.286062)
			(xy 34.670069 -185.268345) (xy 34.619273 -185.242807) (xy 34.57283 -185.210013) (xy 34.531767 -185.170689)
			(xy 34.496996 -185.125707) (xy 34.469285 -185.076062) (xy 34.449249 -185.022855) (xy 34.437331 -184.967263)
			(xy 34.435034 -184.938924) (xy 34.433626 -184.923832) (xy 34.424605 -184.894902) (xy 34.40902 -184.868913)
			(xy 34.387749 -184.84733) (xy 34.361991 -184.831368) (xy 34.333196 -184.821927) (xy 34.302987 -184.819538)
			(xy 34.287968 -184.821576) (xy 34.269426 -184.824116) (xy 34.246436 -184.8272) (xy 34.202041 -184.840626)
			(xy 34.16082 -184.861886) (xy 34.124142 -184.890274) (xy 34.093224 -184.924847) (xy 34.069095 -184.964457)
			(xy 34.052556 -185.007788) (xy 34.044155 -185.053401) (xy 34.04362 -185.076592) (xy 34.04362 -185.988198)
			(xy 34.044124 -186.011198) (xy 34.052412 -186.056446) (xy 34.0687 -186.099467) (xy 34.092456 -186.138859)
			(xy 34.122907 -186.173338) (xy 34.159061 -186.20178) (xy 34.19974 -186.22326) (xy 34.243617 -186.237076)
			(xy 34.266378 -186.24042) (xy 34.293294 -186.243236) (xy 34.346003 -186.2555) (xy 34.39645 -186.275088)
			(xy 34.443623 -186.301609) (xy 34.486575 -186.33453) (xy 34.524444 -186.37319) (xy 34.55647 -186.416814)
			(xy 34.58201 -186.464525) (xy 34.600552 -186.515366) (xy 34.611723 -186.568318) (xy 34.6153 -186.622316)
			(xy 34.61121 -186.676279) (xy 34.599536 -186.729122) (xy 34.580511 -186.779784) (xy 34.554519 -186.827251)
			(xy 34.522079 -186.870567) (xy 34.483844 -186.908866) (xy 34.462466 -186.925458) (xy 34.444191 -186.939855)
			(xy 34.412725 -186.974115) (xy 34.388022 -187.013531) (xy 34.370906 -187.056786) (xy 34.36195 -187.102433)
			(xy 34.361453 -187.148948) (xy 34.369431 -187.194776) (xy 34.385618 -187.238386) (xy 34.409472 -187.278321)
			(xy 34.440198 -187.313247) (xy 34.458148 -187.328048) (xy 34.480852 -187.34525) (xy 34.521384 -187.38527)
			(xy 34.555516 -187.430871) (xy 34.58249 -187.481039) (xy 34.601707 -187.53466) (xy 34.612739 -187.590541)
			(xy 34.615341 -187.647442) (xy 34.609456 -187.704097) (xy 34.595214 -187.759248) (xy 34.572932 -187.811669)
			(xy 34.543105 -187.860195) (xy 34.506395 -187.903748) (xy 34.485326 -187.922916) (xy 34.469313 -187.938707)
			(xy 34.442571 -187.97486) (xy 34.422612 -188.015156) (xy 34.410058 -188.058337) (xy 34.405302 -188.103053)
			(xy 34.408492 -188.147908) (xy 34.419529 -188.191501) (xy 34.438068 -188.23247) (xy 34.46353 -188.269536)
			(xy 34.478976 -188.285882) (xy 34.497904 -188.30414) (xy 34.531074 -188.34495) (xy 34.558332 -188.389925)
			(xy 34.569146 -188.413898) (xy 34.579209 -188.43837) (xy 34.593249 -188.489385) (xy 34.600106 -188.54185)
			(xy 34.599647 -188.59476) (xy 34.591881 -188.647099) (xy 34.576958 -188.697863) (xy 34.555164 -188.746078)
			(xy 34.526917 -188.790819) (xy 34.492758 -188.831227) (xy 34.473388 -188.849254) (xy 34.460462 -188.861591)
			(xy 34.441441 -188.891821) (xy 34.431542 -188.926138) (xy 34.43097 -188.943996) (xy 34.43097 -189.702694)
			(xy 34.442908 -189.728094) (xy 34.454597 -189.754446) (xy 34.470786 -189.809772) (xy 34.478459 -189.866906)
			(xy 34.478468 -189.895734) (xy 34.478468 -189.952122) (xy 34.5694 -190.043054)
		)
		(stroke
			(width 0)
			(type solid)
		)
		(fill yes)
		(layer "B.Cu")
		(net "P12V_PDB")
	)
	(gr_poly
		(pts
			(xy 114.81943 -141.175486) (xy 114.837718 -141.113764) (xy 114.831114 -141.082268) (xy 114.825315 -141.052483)
			(xy 114.820706 -140.991976) (xy 114.824132 -140.931392) (xy 114.835534 -140.871791) (xy 114.854711 -140.81422)
			(xy 114.881328 -140.759688) (xy 114.914917 -140.70915) (xy 114.954889 -140.663495) (xy 115.000544 -140.623522)
			(xy 115.051081 -140.589932) (xy 115.105613 -140.563314) (xy 115.163184 -140.544136) (xy 115.222784 -140.532733)
			(xy 115.283369 -140.529305) (xy 115.343875 -140.533914) (xy 115.373658 -140.539724) (xy 115.389219 -140.542507)
			(xy 115.420792 -140.541208) (xy 115.45108 -140.532193) (xy 115.478224 -140.516013) (xy 115.489736 -140.50518)
			(xy 115.687094 -140.307822) (xy 115.698553 -140.295688) (xy 115.71526 -140.266809) (xy 115.723909 -140.234586)
			(xy 115.72391 -140.201222) (xy 115.715263 -140.168999) (xy 115.698558 -140.140118) (xy 115.687094 -140.12799)
			(xy 115.674753 -140.116432) (xy 115.645394 -140.099685) (xy 115.612672 -140.091218) (xy 115.578875 -140.091626)
			(xy 115.546366 -140.100878) (xy 115.531646 -140.109194) (xy 115.505243 -140.124564) (xy 115.44922 -140.148933)
			(xy 115.390454 -140.165632) (xy 115.329987 -140.174363) (xy 115.268897 -140.17497) (xy 115.208269 -140.167443)
			(xy 115.149182 -140.151915) (xy 115.092687 -140.128663) (xy 115.039787 -140.098101) (xy 114.991425 -140.060771)
			(xy 114.948461 -140.017338) (xy 114.911657 -139.968575) (xy 114.88167 -139.915347) (xy 114.859031 -139.858603)
			(xy 114.844145 -139.799351) (xy 114.837275 -139.738645) (xy 114.838544 -139.677565) (xy 114.847929 -139.617197)
			(xy 114.865264 -139.558615) (xy 114.89024 -139.50286) (xy 114.922412 -139.450924) (xy 114.961209 -139.403731)
			(xy 115.005941 -139.36212) (xy 115.055812 -139.326831) (xy 115.109935 -139.298492) (xy 115.167347 -139.277607)
			(xy 115.227028 -139.264547) (xy 115.287916 -139.259545) (xy 115.348929 -139.262689) (xy 115.40898 -139.273923)
			(xy 115.438174 -139.282932) (xy 115.459049 -139.289337) (xy 115.50224 -139.295717) (xy 115.545887 -139.294622)
			(xy 115.588704 -139.286081) (xy 115.629431 -139.270348) (xy 115.66687 -139.247885) (xy 115.699918 -139.219353)
			(xy 115.727602 -139.185592) (xy 115.749109 -139.147596) (xy 115.763804 -139.106482) (xy 115.771255 -139.063462)
			(xy 115.771676 -139.041632) (xy 115.771676 -138.947652) (xy 115.771269 -138.932801) (xy 115.764383 -138.903909)
			(xy 115.750996 -138.877395) (xy 115.731836 -138.8547) (xy 115.707942 -138.837056) (xy 115.69446 -138.830812)
			(xy 115.627404 -138.802364) (xy 115.612306 -138.796456) (xy 115.580249 -138.791671) (xy 115.548022 -138.79512)
			(xy 115.517704 -138.806581) (xy 115.504214 -138.815572) (xy 115.478853 -138.832911) (xy 115.424406 -138.861371)
			(xy 115.366643 -138.882294) (xy 115.3066 -138.895302) (xy 115.245356 -138.900163) (xy 115.184013 -138.896788)
			(xy 115.123672 -138.88524) (xy 115.065418 -138.865724) (xy 115.010298 -138.838592) (xy 114.959302 -138.804331)
			(xy 114.913346 -138.763558) (xy 114.873257 -138.717004) (xy 114.839755 -138.665506) (xy 114.813442 -138.609991)
			(xy 114.79479 -138.551454) (xy 114.784136 -138.490949) (xy 114.78167 -138.429563) (xy 114.787436 -138.368398)
			(xy 114.801332 -138.308554) (xy 114.823107 -138.251106) (xy 114.85237 -138.197087) (xy 114.888595 -138.147467)
			(xy 114.931131 -138.103139) (xy 114.979215 -138.064898) (xy 115.031981 -138.033431) (xy 115.088481 -138.009305)
			(xy 115.147701 -137.992953) (xy 115.208576 -137.984668) (xy 115.270012 -137.9846) (xy 115.330905 -137.99275)
			(xy 115.390161 -138.008971) (xy 115.418616 -138.020552) (xy 115.439789 -138.028971) (xy 115.484235 -138.038981)
			(xy 115.529754 -138.040905) (xy 115.574887 -138.034682) (xy 115.618187 -138.020512) (xy 115.658266 -137.998848)
			(xy 115.693841 -137.970384) (xy 115.72377 -137.936034) (xy 115.747095 -137.896898) (xy 115.763067 -137.85423)
			(xy 115.771176 -137.809398) (xy 115.771676 -137.786618) (xy 115.771676 -134.931658) (xy 115.746276 -134.879334)
			(xy 115.723416 -134.861046) (xy 115.70058 -134.842395) (xy 115.659421 -134.800176) (xy 115.624024 -134.753022)
			(xy 115.594976 -134.701712) (xy 115.572757 -134.647097) (xy 115.557736 -134.590081) (xy 115.55016 -134.531608)
			(xy 115.550157 -134.472646) (xy 115.557725 -134.414172) (xy 115.57274 -134.357155) (xy 115.594952 -134.302537)
			(xy 115.623994 -134.251224) (xy 115.659386 -134.204065) (xy 115.70054 -134.161842) (xy 115.723416 -134.143242)
			(xy 115.746276 -134.124954) (xy 115.771676 -134.07263) (xy 115.771676 -133.19379) (xy 115.15471 -132.576824)
			(xy 115.137992 -132.560819) (xy 115.099886 -132.534562) (xy 115.057649 -132.515653) (xy 115.012683 -132.50472)
			(xy 114.98961 -132.50291) (xy 114.97361 -132.502448) (xy 114.94221 -132.508616) (xy 114.913333 -132.522405)
			(xy 114.888797 -132.542948) (xy 114.870147 -132.568952) (xy 114.86388 -132.583682) (xy 114.852456 -132.611761)
			(xy 114.823256 -132.664885) (xy 114.787299 -132.713689) (xy 114.745214 -132.757319) (xy 114.697737 -132.795012)
			(xy 114.6457 -132.826107) (xy 114.590014 -132.850061) (xy 114.531653 -132.866453) (xy 114.471638 -132.874998)
			(xy 114.411021 -132.875546) (xy 114.350862 -132.868086) (xy 114.292214 -132.852751) (xy 114.236104 -132.829807)
			(xy 114.183513 -132.799656) (xy 114.135364 -132.762827) (xy 114.092497 -132.719965) (xy 114.055664 -132.671818)
			(xy 114.02551 -132.61923) (xy 114.002561 -132.563122) (xy 113.987221 -132.504475) (xy 113.979756 -132.444317)
			(xy 113.980299 -132.3837) (xy 113.988839 -132.323684) (xy 114.005227 -132.265322) (xy 114.029176 -132.209633)
			(xy 114.060267 -132.157594) (xy 114.097956 -132.110114) (xy 114.141582 -132.068025) (xy 114.190384 -132.032064)
			(xy 114.243505 -132.00286) (xy 114.271552 -131.991354) (xy 114.286306 -131.985132) (xy 114.312321 -131.966478)
			(xy 114.332871 -131.941932) (xy 114.346659 -131.913042) (xy 114.352817 -131.881628) (xy 114.352324 -131.865624)
			(xy 114.350492 -131.842556) (xy 114.339533 -131.797602) (xy 114.320627 -131.755371) (xy 114.294399 -131.717253)
			(xy 114.27841 -131.700524) (xy 113.295684 -130.717798) (xy 113.295684 -129.102104) (xy 112.330484 -128.136904)
			(xy 111.512096 -128.136904) (xy 111.008414 -128.640586) (xy 111.008414 -128.951482) (xy 111.046768 -129.041652)
			(xy 111.062008 -129.057908) (xy 111.081197 -129.079217) (xy 111.113616 -129.126515) (xy 111.138593 -129.178131)
			(xy 111.155565 -129.232903) (xy 111.164149 -129.289599) (xy 111.164154 -129.34694) (xy 111.155578 -129.403637)
			(xy 111.138615 -129.458412) (xy 111.113647 -129.510032) (xy 111.081235 -129.557335) (xy 111.062008 -129.578608)
			(xy 111.046768 -129.594864) (xy 111.008414 -129.685034) (xy 111.008414 -130.385566) (xy 111.008863 -130.407388)
			(xy 111.016316 -130.450391) (xy 111.031006 -130.491489) (xy 111.052504 -130.529471) (xy 111.080175 -130.563222)
			(xy 111.113207 -130.591748) (xy 111.150627 -130.614209) (xy 111.191335 -130.629947) (xy 111.234134 -130.638496)
			(xy 111.277764 -130.639607) (xy 111.320942 -130.633246) (xy 111.362398 -130.6196) (xy 111.400912 -130.599071)
			(xy 111.41837 -130.585972) (xy 111.442387 -130.567883) (xy 111.494264 -130.537484) (xy 111.549674 -130.51414)
			(xy 111.607664 -130.498251) (xy 111.667234 -130.490092) (xy 111.727361 -130.489802) (xy 111.787007 -130.497388)
			(xy 111.845147 -130.512717) (xy 111.90078 -130.535526) (xy 111.952947 -130.565423) (xy 112.000751 -130.601893)
			(xy 112.043368 -130.644308) (xy 112.080065 -130.691938) (xy 112.11021 -130.743962) (xy 112.133284 -130.799485)
			(xy 112.148891 -130.857551) (xy 112.15676 -130.917161) (xy 112.156756 -130.977288) (xy 112.148881 -131.036897)
			(xy 112.133269 -131.094962) (xy 112.110188 -131.150482) (xy 112.080038 -131.202503) (xy 112.043335 -131.250129)
			(xy 112.000714 -131.292539) (xy 111.952906 -131.329004) (xy 111.900735 -131.358895) (xy 111.845101 -131.381699)
			(xy 111.786959 -131.397022) (xy 111.727311 -131.404601) (xy 111.667185 -131.404304) (xy 111.607615 -131.396139)
			(xy 111.549627 -131.380244) (xy 111.49422 -131.356893) (xy 111.442346 -131.32649) (xy 111.41837 -131.308348)
			(xy 111.400874 -131.295307) (xy 111.362365 -131.274789) (xy 111.320917 -131.261151) (xy 111.277749 -131.254795)
			(xy 111.234129 -131.255907) (xy 111.191341 -131.264454) (xy 111.150642 -131.280186) (xy 111.113229 -131.302639)
			(xy 111.080201 -131.331155) (xy 111.052531 -131.364893) (xy 111.031031 -131.402862) (xy 111.016335 -131.443946)
			(xy 111.008872 -131.486937) (xy 111.008414 -131.508754) (xy 111.008414 -132.472684) (xy 111.008865 -132.494505)
			(xy 111.016319 -132.537506) (xy 111.031011 -132.5786) (xy 111.052509 -132.61658) (xy 111.080181 -132.650328)
			(xy 111.113211 -132.678851) (xy 111.15063 -132.701311) (xy 111.191336 -132.717047) (xy 111.234133 -132.725596)
			(xy 111.27776 -132.726707) (xy 111.320936 -132.720347) (xy 111.362391 -132.706703) (xy 111.400904 -132.686176)
			(xy 111.41837 -132.67309) (xy 111.442386 -132.655001) (xy 111.49426 -132.624602) (xy 111.549668 -132.601257)
			(xy 111.607656 -132.585368) (xy 111.667224 -132.577207) (xy 111.727349 -132.576916) (xy 111.786994 -132.584499)
			(xy 111.845132 -132.599827) (xy 111.900764 -132.622634) (xy 111.95293 -132.652529) (xy 112.000733 -132.688997)
			(xy 112.04335 -132.731409) (xy 112.080047 -132.779036) (xy 112.110193 -132.831058) (xy 112.133267 -132.886579)
			(xy 112.148874 -132.944643) (xy 112.156745 -133.004251) (xy 112.156743 -133.064376) (xy 112.148869 -133.123983)
			(xy 112.133259 -133.182047) (xy 112.110181 -133.237566) (xy 112.080032 -133.289586) (xy 112.043332 -133.337211)
			(xy 112.000713 -133.379621) (xy 111.952907 -133.416086) (xy 111.900739 -133.445978) (xy 111.845107 -133.468782)
			(xy 111.786967 -133.484106) (xy 111.727322 -133.491686) (xy 111.667197 -133.491391) (xy 111.607629 -133.483227)
			(xy 111.549643 -133.467334) (xy 111.494236 -133.443986) (xy 111.442363 -133.413584) (xy 111.41837 -133.395466)
			(xy 111.400874 -133.382424) (xy 111.362367 -133.361905) (xy 111.320919 -133.348266) (xy 111.277751 -133.341909)
			(xy 111.234132 -133.343021) (xy 111.191344 -133.351568) (xy 111.150645 -133.3673) (xy 111.113232 -133.389754)
			(xy 111.080206 -133.41827) (xy 111.052537 -133.452009) (xy 111.031039 -133.489979) (xy 111.016345 -133.531064)
			(xy 111.008885 -133.574055) (xy 111.008414 -133.595872) (xy 111.008414 -134.576884) (xy 114.224292 -134.576884)
			(xy 114.225008 -134.517149) (xy 114.233487 -134.458014) (xy 114.249585 -134.400485) (xy 114.273028 -134.345538)
			(xy 114.303418 -134.294106) (xy 114.340239 -134.247064) (xy 114.361214 -134.225792) (xy 114.376776 -134.20997)
			(xy 114.402593 -134.173875) (xy 114.421738 -134.133839) (xy 114.43363 -134.091085) (xy 114.437906 -134.046914)
			(xy 114.434435 -134.002672) (xy 114.423323 -133.959708) (xy 114.404909 -133.919331) (xy 114.379754 -133.882771)
			(xy 114.364516 -133.866636) (xy 114.345616 -133.846738) (xy 114.313142 -133.802499) (xy 114.287341 -133.754064)
			(xy 114.268744 -133.702432) (xy 114.257735 -133.648669) (xy 114.254542 -133.593884) (xy 114.259229 -133.539206)
			(xy 114.271702 -133.485764) (xy 114.291701 -133.434659) (xy 114.318816 -133.386947) (xy 114.352485 -133.343611)
			(xy 114.392016 -133.305545) (xy 114.436592 -133.273535) (xy 114.485293 -133.248241) (xy 114.537116 -133.230184)
			(xy 114.590991 -133.219738) (xy 114.645807 -133.217117) (xy 114.700433 -133.222376) (xy 114.753743 -133.235406)
			(xy 114.804635 -133.255938) (xy 114.852062 -133.28355) (xy 114.895044 -133.31767) (xy 114.932694 -133.357596)
			(xy 114.964237 -133.402504) (xy 114.989021 -133.451467) (xy 115.006535 -133.503476) (xy 115.016418 -133.557457)
			(xy 115.018466 -133.612298) (xy 115.012637 -133.666866) (xy 114.99905 -133.720036) (xy 114.977987 -133.770711)
			(xy 114.949882 -133.817847) (xy 114.932968 -133.839458) (xy 114.919316 -133.856964) (xy 114.897744 -133.895761)
			(xy 114.883246 -133.937718) (xy 114.876263 -133.981556) (xy 114.877007 -134.025941) (xy 114.885456 -134.06952)
			(xy 114.901353 -134.110967) (xy 114.924213 -134.149019) (xy 114.95334 -134.182518) (xy 114.970306 -134.196836)
			(xy 114.993222 -134.216) (xy 115.034343 -134.259334) (xy 115.069478 -134.307649) (xy 115.098032 -134.360122)
			(xy 115.119518 -134.415864) (xy 115.133573 -134.473926) (xy 115.139956 -134.533323) (xy 115.138561 -134.593046)
			(xy 115.12941 -134.652081) (xy 115.112658 -134.709423) (xy 115.088592 -134.7641) (xy 115.057619 -134.815183)
			(xy 115.020265 -134.861804) (xy 114.977165 -134.90317) (xy 114.929051 -134.93858) (xy 114.876741 -134.967431)
			(xy 114.821122 -134.989234) (xy 114.763141 -135.003618) (xy 114.703781 -135.01034) (xy 114.644051 -135.009284)
			(xy 114.584965 -135.000469) (xy 114.527528 -134.984044) (xy 114.472715 -134.960289) (xy 114.421457 -134.929606)
			(xy 114.374625 -134.892518) (xy 114.333014 -134.849654) (xy 114.297332 -134.801743) (xy 114.268183 -134.749597)
			(xy 114.246064 -134.694104) (xy 114.23135 -134.636205) (xy 114.224292 -134.576884) (xy 111.008414 -134.576884)
			(xy 111.008414 -136.551416) (xy 111.160807 -136.703558) (xy 112.785634 -136.703558) (xy 112.785634 -136.643622)
			(xy 112.793457 -136.5842) (xy 112.80897 -136.526307) (xy 112.831906 -136.470934) (xy 112.861873 -136.419028)
			(xy 112.89836 -136.371478) (xy 112.94074 -136.329098) (xy 112.98829 -136.292611) (xy 113.040196 -136.262644)
			(xy 113.095569 -136.239708) (xy 113.153462 -136.224195) (xy 113.212884 -136.216372) (xy 113.27282 -136.216372)
			(xy 113.332242 -136.224195) (xy 113.390135 -136.239708) (xy 113.445508 -136.262644) (xy 113.497414 -136.292611)
			(xy 113.544964 -136.329098) (xy 113.587344 -136.371478) (xy 113.623831 -136.419028) (xy 113.653798 -136.470934)
			(xy 113.676734 -136.526307) (xy 113.692247 -136.5842) (xy 113.70007 -136.643622) (xy 113.70056 -136.67359)
			(xy 113.70007 -136.703558) (xy 113.692247 -136.76298) (xy 113.676734 -136.820873) (xy 113.653798 -136.876246)
			(xy 113.623831 -136.928152) (xy 113.587344 -136.975702) (xy 113.544964 -137.018082) (xy 113.497414 -137.054569)
			(xy 113.445508 -137.084536) (xy 113.390135 -137.107472) (xy 113.332242 -137.122985) (xy 113.27282 -137.130808)
			(xy 113.212884 -137.130808) (xy 113.153462 -137.122985) (xy 113.095569 -137.107472) (xy 113.040196 -137.084536)
			(xy 112.98829 -137.054569) (xy 112.94074 -137.018082) (xy 112.89836 -136.975702) (xy 112.861873 -136.928152)
			(xy 112.831906 -136.876246) (xy 112.80897 -136.820873) (xy 112.793457 -136.76298) (xy 112.785634 -136.703558)
			(xy 111.160807 -136.703558) (xy 111.162592 -136.70534) (xy 111.162592 -137.372848) (xy 113.936 -137.372848)
			(xy 113.936 -137.312912) (xy 113.943823 -137.25349) (xy 113.959336 -137.195597) (xy 113.982272 -137.140224)
			(xy 114.012239 -137.088318) (xy 114.048726 -137.040768) (xy 114.091106 -136.998388) (xy 114.138656 -136.961901)
			(xy 114.190562 -136.931934) (xy 114.245935 -136.908998) (xy 114.303828 -136.893485) (xy 114.36325 -136.885662)
			(xy 114.423186 -136.885662) (xy 114.482608 -136.893485) (xy 114.540501 -136.908998) (xy 114.595874 -136.931934)
			(xy 114.64778 -136.961901) (xy 114.69533 -136.998388) (xy 114.73771 -137.040768) (xy 114.774197 -137.088318)
			(xy 114.804164 -137.140224) (xy 114.8271 -137.195597) (xy 114.842613 -137.25349) (xy 114.850436 -137.312912)
			(xy 114.850926 -137.34288) (xy 114.850436 -137.372848) (xy 114.842613 -137.43227) (xy 114.8271 -137.490163)
			(xy 114.804164 -137.545536) (xy 114.774197 -137.597442) (xy 114.73771 -137.644992) (xy 114.69533 -137.687372)
			(xy 114.64778 -137.723859) (xy 114.595874 -137.753826) (xy 114.540501 -137.776762) (xy 114.482608 -137.792275)
			(xy 114.423186 -137.800098) (xy 114.36325 -137.800098) (xy 114.303828 -137.792275) (xy 114.245935 -137.776762)
			(xy 114.190562 -137.753826) (xy 114.138656 -137.723859) (xy 114.091106 -137.687372) (xy 114.048726 -137.644992)
			(xy 114.012239 -137.597442) (xy 113.982272 -137.545536) (xy 113.959336 -137.490163) (xy 113.943823 -137.43227)
			(xy 113.936 -137.372848) (xy 111.162592 -137.372848) (xy 111.162592 -138.062208) (xy 111.00308 -138.221466)
			(xy 111.00308 -139.59713) (xy 112.079784 -139.59713) (xy 112.083855 -139.541508) (xy 112.095981 -139.487071)
			(xy 112.115904 -139.43498) (xy 112.1432 -139.386345) (xy 112.177286 -139.342202) (xy 112.217435 -139.303493)
			(xy 112.262793 -139.271042) (xy 112.312393 -139.245541) (xy 112.365177 -139.227534) (xy 112.42002 -139.217404)
			(xy 112.475754 -139.215367) (xy 112.531191 -139.221467) (xy 112.585148 -139.235573) (xy 112.636477 -139.257385)
			(xy 112.684083 -139.286439) (xy 112.726951 -139.322114) (xy 112.764168 -139.363651) (xy 112.794941 -139.410164)
			(xy 112.818613 -139.460661) (xy 112.834681 -139.514068) (xy 112.842801 -139.569244) (xy 112.84331 -139.59713)
			(xy 112.842801 -139.625016) (xy 112.834681 -139.680192) (xy 112.818613 -139.733599) (xy 112.794941 -139.784096)
			(xy 112.764168 -139.830609) (xy 112.726951 -139.872146) (xy 112.684083 -139.907821) (xy 112.636477 -139.936875)
			(xy 112.585148 -139.958687) (xy 112.531191 -139.972793) (xy 112.475754 -139.978893) (xy 112.42002 -139.976856)
			(xy 112.365177 -139.966726) (xy 112.312393 -139.948719) (xy 112.262793 -139.923218) (xy 112.217435 -139.890767)
			(xy 112.177286 -139.852058) (xy 112.1432 -139.807915) (xy 112.115904 -139.75928) (xy 112.095981 -139.707189)
			(xy 112.083855 -139.652752) (xy 112.079784 -139.59713) (xy 111.00308 -139.59713) (xy 111.00308 -140.190474)
			(xy 110.664244 -140.52931) (xy 105.563416 -140.52931) (xy 105.53954 -140.505688) (xy 105.34523 -140.505688)
			(xy 104.638348 -139.798552) (xy 103.61422 -139.798552) (xy 103.597568 -139.799093) (xy 103.565396 -139.807706)
			(xy 103.53655 -139.824352) (xy 103.512994 -139.847896) (xy 103.496332 -139.876733) (xy 103.487702 -139.9089)
			(xy 103.48722 -139.925552) (xy 103.48722 -141.439134) (xy 106.447064 -141.439134) (xy 106.447064 -141.379198)
			(xy 106.454887 -141.319776) (xy 106.4704 -141.261883) (xy 106.493336 -141.20651) (xy 106.523303 -141.154604)
			(xy 106.55979 -141.107054) (xy 106.60217 -141.064674) (xy 106.64972 -141.028187) (xy 106.701626 -140.99822)
			(xy 106.756999 -140.975284) (xy 106.814892 -140.959771) (xy 106.874314 -140.951948) (xy 106.93425 -140.951948)
			(xy 106.993672 -140.959771) (xy 107.051565 -140.975284) (xy 107.106938 -140.99822) (xy 107.158844 -141.028187)
			(xy 107.206394 -141.064674) (xy 107.248774 -141.107054) (xy 107.285261 -141.154604) (xy 107.315228 -141.20651)
			(xy 107.338164 -141.261883) (xy 107.353677 -141.319776) (xy 107.3615 -141.379198) (xy 107.361977 -141.4084)
			(xy 109.053612 -141.4084) (xy 109.053612 -141.348464) (xy 109.061435 -141.289042) (xy 109.076948 -141.231149)
			(xy 109.099884 -141.175776) (xy 109.129851 -141.12387) (xy 109.166338 -141.07632) (xy 109.208718 -141.03394)
			(xy 109.256268 -140.997453) (xy 109.308174 -140.967486) (xy 109.363547 -140.94455) (xy 109.42144 -140.929037)
			(xy 109.480862 -140.921214) (xy 109.540798 -140.921214) (xy 109.60022 -140.929037) (xy 109.658113 -140.94455)
			(xy 109.713486 -140.967486) (xy 109.765392 -140.997453) (xy 109.812942 -141.03394) (xy 109.855322 -141.07632)
			(xy 109.891809 -141.12387) (xy 109.921776 -141.175776) (xy 109.944712 -141.231149) (xy 109.960225 -141.289042)
			(xy 109.965792 -141.33133) (xy 110.751324 -141.33133) (xy 110.753633 -141.271446) (xy 110.763739 -141.212375)
			(xy 110.781468 -141.155129) (xy 110.806518 -141.100686) (xy 110.83846 -141.04998) (xy 110.876748 -141.003876)
			(xy 110.920726 -140.963165) (xy 110.969641 -140.928542) (xy 111.022658 -140.9006) (xy 111.078868 -140.879817)
			(xy 111.13731 -140.86655) (xy 111.196983 -140.861024) (xy 111.256868 -140.863334) (xy 111.315938 -140.873442)
			(xy 111.373184 -140.891173) (xy 111.427625 -140.916225) (xy 111.478331 -140.948168) (xy 111.501682 -140.966952)
			(xy 111.519601 -140.981249) (xy 111.559557 -141.003719) (xy 111.602895 -141.018656) (xy 111.64821 -141.025575)
			(xy 111.694031 -141.02425) (xy 111.73887 -141.014727) (xy 111.781274 -140.997312) (xy 111.819865 -140.972572)
			(xy 111.836962 -140.9573) (xy 111.857337 -140.938935) (xy 111.902435 -140.907709) (xy 111.95154 -140.883263)
			(xy 112.00364 -140.866103) (xy 112.05766 -140.85658) (xy 112.112488 -140.854892) (xy 112.166992 -140.861073)
			(xy 112.220049 -140.874997) (xy 112.270565 -140.896375) (xy 112.317498 -140.924768) (xy 112.359882 -140.959589)
			(xy 112.396842 -141.000121) (xy 112.427616 -141.045529) (xy 112.45157 -141.094876) (xy 112.468209 -141.147145)
			(xy 112.477192 -141.201258) (xy 112.478332 -141.256099) (xy 112.471607 -141.310539) (xy 112.457154 -141.363454)
			(xy 112.435273 -141.413754) (xy 112.406413 -141.460402) (xy 112.37117 -141.502435) (xy 112.33027 -141.538988)
			(xy 112.284558 -141.569308) (xy 112.234974 -141.592767) (xy 112.182542 -141.608884) (xy 112.128342 -141.617326)
			(xy 112.073492 -141.617919) (xy 112.019122 -141.61065) (xy 111.966354 -141.59567) (xy 111.916275 -141.573286)
			(xy 111.892842 -141.559026) (xy 111.873206 -141.547174) (xy 111.830704 -141.529952) (xy 111.7858 -141.52064)
			(xy 111.739953 -141.51954) (xy 111.694655 -141.526688) (xy 111.651375 -141.541852) (xy 111.611521 -141.56454)
			(xy 111.576386 -141.594013) (xy 111.561372 -141.61135) (xy 111.54187 -141.634105) (xy 111.497895 -141.674819)
			(xy 111.448981 -141.709444) (xy 111.395967 -141.737389) (xy 111.339758 -141.758175) (xy 111.281317 -141.771446)
			(xy 111.221643 -141.776975) (xy 111.161759 -141.774668) (xy 111.102688 -141.764565) (xy 111.045441 -141.746837)
			(xy 110.990998 -141.721788) (xy 110.94029 -141.689847) (xy 110.894186 -141.651561) (xy 110.853473 -141.607585)
			(xy 110.818849 -141.55867) (xy 110.790905 -141.505654) (xy 110.770121 -141.449445) (xy 110.756852 -141.391004)
			(xy 110.751324 -141.33133) (xy 109.965792 -141.33133) (xy 109.968048 -141.348464) (xy 109.968538 -141.378432)
			(xy 109.968048 -141.4084) (xy 109.960225 -141.467822) (xy 109.944712 -141.525715) (xy 109.921776 -141.581088)
			(xy 109.891809 -141.632994) (xy 109.855322 -141.680544) (xy 109.812942 -141.722924) (xy 109.765392 -141.759411)
			(xy 109.713486 -141.789378) (xy 109.658113 -141.812314) (xy 109.60022 -141.827827) (xy 109.540798 -141.83565)
			(xy 109.480862 -141.83565) (xy 109.42144 -141.827827) (xy 109.363547 -141.812314) (xy 109.308174 -141.789378)
			(xy 109.256268 -141.759411) (xy 109.208718 -141.722924) (xy 109.166338 -141.680544) (xy 109.129851 -141.632994)
			(xy 109.099884 -141.581088) (xy 109.076948 -141.525715) (xy 109.061435 -141.467822) (xy 109.053612 -141.4084)
			(xy 107.361977 -141.4084) (xy 107.36199 -141.409166) (xy 107.3615 -141.439134) (xy 107.353677 -141.498556)
			(xy 107.338164 -141.556449) (xy 107.315228 -141.611822) (xy 107.285261 -141.663728) (xy 107.248774 -141.711278)
			(xy 107.206394 -141.753658) (xy 107.158844 -141.790145) (xy 107.106938 -141.820112) (xy 107.051565 -141.843048)
			(xy 106.993672 -141.858561) (xy 106.93425 -141.866384) (xy 106.874314 -141.866384) (xy 106.814892 -141.858561)
			(xy 106.756999 -141.843048) (xy 106.701626 -141.820112) (xy 106.64972 -141.790145) (xy 106.60217 -141.753658)
			(xy 106.55979 -141.711278) (xy 106.523303 -141.663728) (xy 106.493336 -141.611822) (xy 106.4704 -141.556449)
			(xy 106.454887 -141.498556) (xy 106.447064 -141.439134) (xy 103.48722 -141.439134) (xy 103.48722 -142.111476)
			(xy 103.487712 -142.128132) (xy 103.496329 -142.16031) (xy 103.512983 -142.189159) (xy 103.536537 -142.212715)
			(xy 103.565387 -142.229369) (xy 103.597564 -142.237988) (xy 103.61422 -142.238476) (xy 113.75644 -142.238476)
		)
		(stroke
			(width 0)
			(type solid)
		)
		(fill yes)
		(layer "B.Cu")
		(net "AGND_PVCCP_NODE1")
	)
	(gr_poly
		(pts
			(xy 52.11826 -69.093334) (xy 52.135515 -69.109093) (xy 52.174624 -69.134659) (xy 52.21775 -69.152642)
			(xy 52.263436 -69.162435) (xy 52.310143 -69.16371) (xy 52.356296 -69.156422) (xy 52.400338 -69.140817)
			(xy 52.440783 -69.117422) (xy 52.476269 -69.087026) (xy 52.491386 -69.069204) (xy 52.510997 -69.043931)
			(xy 52.556118 -68.998586) (xy 52.607112 -68.959964) (xy 52.662986 -68.928817) (xy 52.722653 -68.905751)
			(xy 52.784949 -68.891217) (xy 52.81676 -68.887848) (xy 52.837725 -68.884944) (xy 52.878349 -68.873081)
			(xy 52.916448 -68.854655) (xy 52.95097 -68.830173) (xy 52.98096 -68.800313) (xy 53.005591 -68.765898)
			(xy 53.024183 -68.727879) (xy 53.036222 -68.687306) (xy 53.039264 -68.66636) (xy 53.137054 -68.56857)
			(xy 53.148277 -68.556658) (xy 53.164796 -68.528418) (xy 53.173584 -68.496904) (xy 53.174062 -68.46419)
			(xy 53.166199 -68.432433) (xy 53.150512 -68.403722) (xy 53.139594 -68.391532) (xy 53.120707 -68.3708)
			(xy 53.0886 -68.32482) (xy 53.06357 -68.274634) (xy 53.046159 -68.221325) (xy 53.03674 -68.166041)
			(xy 53.035517 -68.109973) (xy 53.042516 -68.054331) (xy 53.057587 -68.000313) (xy 53.080405 -67.949084)
			(xy 53.110477 -67.901747) (xy 53.147157 -67.859324) (xy 53.168042 -67.840606) (xy 53.188034 -67.823979)
			(xy 53.231677 -67.795712) (xy 53.278744 -67.77361) (xy 53.303424 -67.765422) (xy 53.330892 -67.757401)
			(xy 53.387453 -67.748732) (xy 53.444674 -67.748606) (xy 53.501272 -67.757027) (xy 53.555978 -67.773805)
			(xy 53.607566 -67.798565) (xy 53.654877 -67.83075) (xy 53.696851 -67.86964) (xy 53.732548 -67.914362)
			(xy 53.761165 -67.963913) (xy 53.782063 -68.017182) (xy 53.794771 -68.072974) (xy 53.799005 -68.130039)
			(xy 53.797454 -68.158614) (xy 53.79623 -68.181556) (xy 53.801085 -68.227239) (xy 53.814071 -68.271305)
			(xy 53.834763 -68.31232) (xy 53.86249 -68.348949) (xy 53.896347 -68.38) (xy 53.935233 -68.40446)
			(xy 53.977881 -68.421535) (xy 54.022904 -68.430668) (xy 54.068835 -68.431561) (xy 54.091586 -68.428362)
			(xy 54.121541 -68.423974) (xy 54.182044 -68.421815) (xy 54.212236 -68.424044) (xy 54.23563 -68.425591)
			(xy 54.282294 -68.421123) (xy 54.327347 -68.408175) (xy 54.369264 -68.387187) (xy 54.406621 -68.358869)
			(xy 54.438153 -68.324181) (xy 54.462791 -68.284301) (xy 54.4797 -68.240579) (xy 54.488305 -68.194499)
			(xy 54.488842 -68.17106) (xy 54.488842 -65.52057) (xy 54.628542 -65.38087) (xy 54.633368 -65.374774)
			(xy 54.65094 -65.35296) (xy 54.690548 -65.313351) (xy 54.712362 -65.29578) (xy 54.718458 -65.290954)
			(xy 55.000144 -65.009268) (xy 55.089044 -65.009268) (xy 55.136542 -64.985646) (xy 55.149792 -64.978523)
			(xy 55.172768 -64.959116) (xy 55.190564 -64.934872) (xy 55.202193 -64.907136) (xy 55.207009 -64.877449)
			(xy 55.204744 -64.84746) (xy 55.195524 -64.818833) (xy 55.179861 -64.793159) (xy 55.169562 -64.782192)
			(xy 54.9529 -64.56553) (xy 54.9529 -63.917576) (xy 54.879748 -63.844424) (xy 54.879748 -63.132208)
			(xy 55.12308 -63.132208) (xy 55.142384 -63.125858) (xy 55.171297 -63.116984) (xy 55.231017 -63.107441)
			(xy 55.291495 -63.107441) (xy 55.351215 -63.116984) (xy 55.380128 -63.125858) (xy 55.399432 -63.132208)
			(xy 55.642764 -63.132208) (xy 55.642764 -63.330328) (xy 55.715916 -63.40348) (xy 55.715916 -64.249554)
			(xy 55.74919 -64.282828) (xy 56.14289 -64.282828) (xy 56.344566 -64.484504) (xy 56.361209 -64.500441)
			(xy 56.399125 -64.526618) (xy 56.44114 -64.545532) (xy 56.485875 -64.556562) (xy 56.531866 -64.559348)
			(xy 56.577605 -64.553799) (xy 56.621595 -64.540095) (xy 56.662395 -64.518687) (xy 56.698667 -64.490275)
			(xy 56.729224 -64.45579) (xy 56.753064 -64.416362) (xy 56.769407 -64.373283) (xy 56.777717 -64.327963)
			(xy 56.778144 -64.304926) (xy 56.778144 -63.5127) (xy 56.541924 -63.27648) (xy 56.541924 -63.067438)
			(xy 56.506364 -63.031878) (xy 56.506364 -62.186058) (xy 56.633364 -62.059058) (xy 56.633364 -59.985148)
			(xy 56.56072 -59.912504) (xy 56.490362 -59.8424) (xy 55.747666 -59.8424) (xy 55.724074 -59.843659)
			(xy 55.677945 -59.853835) (xy 55.634491 -59.872362) (xy 55.595209 -59.8986) (xy 55.561453 -59.931646)
			(xy 55.534386 -59.970362) (xy 55.51494 -60.013412) (xy 55.503786 -60.059315) (xy 55.501307 -60.106489)
			(xy 55.507589 -60.153308) (xy 55.514494 -60.175902) (xy 55.523373 -60.204495) (xy 55.533064 -60.263573)
			(xy 55.533798 -60.293504) (xy 55.533396 -60.324129) (xy 55.524014 -60.38465) (xy 55.505074 -60.442891)
			(xy 55.477064 -60.497354) (xy 55.459376 -60.522358) (xy 55.447225 -60.540476) (xy 55.42865 -60.579945)
			(xy 55.417087 -60.622007) (xy 55.412875 -60.665425) (xy 55.416139 -60.708924) (xy 55.426782 -60.751228)
			(xy 55.444492 -60.791093) (xy 55.468749 -60.827349) (xy 55.483506 -60.843414) (xy 55.504208 -60.865845)
			(xy 55.540098 -60.915219) (xy 55.569108 -60.968925) (xy 55.590724 -61.026009) (xy 55.604561 -61.08546)
			(xy 55.610374 -61.146223) (xy 55.60806 -61.207219) (xy 55.597661 -61.267367) (xy 55.57936 -61.325599)
			(xy 55.553483 -61.380882) (xy 55.520488 -61.432236) (xy 55.48096 -61.478749) (xy 55.435602 -61.519596)
			(xy 55.385218 -61.554053) (xy 55.330701 -61.581508) (xy 55.273018 -61.601475) (xy 55.213194 -61.613598)
			(xy 55.15229 -61.617663) (xy 55.091386 -61.613598) (xy 55.031562 -61.601475) (xy 54.973879 -61.581508)
			(xy 54.919362 -61.554053) (xy 54.868978 -61.519596) (xy 54.82362 -61.478749) (xy 54.784092 -61.432236)
			(xy 54.751097 -61.380882) (xy 54.72522 -61.325599) (xy 54.706919 -61.267367) (xy 54.69652 -61.207219)
			(xy 54.694206 -61.146223) (xy 54.700019 -61.08546) (xy 54.713856 -61.026009) (xy 54.735472 -60.968925)
			(xy 54.764482 -60.915219) (xy 54.800372 -60.865845) (xy 54.821074 -60.843414) (xy 54.835791 -60.827316)
			(xy 54.860044 -60.791068) (xy 54.877752 -60.751211) (xy 54.888394 -60.708916) (xy 54.891657 -60.665425)
			(xy 54.887446 -60.622016) (xy 54.875885 -60.579963) (xy 54.857312 -60.540501) (xy 54.845204 -60.522358)
			(xy 54.827529 -60.497347) (xy 54.799535 -60.442878) (xy 54.780592 -60.384641) (xy 54.771183 -60.324127)
			(xy 54.770782 -60.293504) (xy 54.771543 -60.263576) (xy 54.781234 -60.204501) (xy 54.790086 -60.175902)
			(xy 54.797018 -60.15331) (xy 54.803321 -60.106482) (xy 54.800857 -60.059295) (xy 54.78971 -60.013378)
			(xy 54.770265 -59.970313) (xy 54.743192 -59.931587) (xy 54.709425 -59.898535) (xy 54.670129 -59.872296)
			(xy 54.626659 -59.853776) (xy 54.580513 -59.843614) (xy 54.556914 -59.8424) (xy 54.426866 -59.8424)
			(xy 54.403274 -59.843659) (xy 54.357145 -59.853835) (xy 54.313691 -59.872362) (xy 54.274409 -59.8986)
			(xy 54.240653 -59.931646) (xy 54.213586 -59.970362) (xy 54.19414 -60.013412) (xy 54.182986 -60.059315)
			(xy 54.180507 -60.106489) (xy 54.186789 -60.153308) (xy 54.193694 -60.175902) (xy 54.202312 -60.203692)
			(xy 54.211993 -60.261063) (xy 54.212855 -60.319238) (xy 54.204879 -60.37687) (xy 54.18825 -60.432625)
			(xy 54.163351 -60.485209) (xy 54.130761 -60.533407) (xy 54.111398 -60.555124) (xy 54.095678 -60.572894)
			(xy 54.07048 -60.613087) (xy 54.053179 -60.657259) (xy 54.044375 -60.703873) (xy 54.044373 -60.751312)
			(xy 54.053175 -60.797927) (xy 54.070474 -60.842099) (xy 54.095669 -60.882294) (xy 54.111398 -60.900056)
			(xy 54.129832 -60.920676) (xy 54.16117 -60.966249) (xy 54.185601 -61.015869) (xy 54.202611 -61.068497)
			(xy 54.211846 -61.123029) (xy 54.21311 -61.178322) (xy 54.206379 -61.233219) (xy 54.191792 -61.28657)
			(xy 54.169656 -61.337255) (xy 54.140435 -61.384213) (xy 54.10474 -61.426461) (xy 54.063319 -61.463113)
			(xy 54.017041 -61.493401) (xy 53.966876 -61.51669) (xy 53.913873 -61.532493) (xy 53.859144 -61.540478)
			(xy 53.803836 -61.540478) (xy 53.749107 -61.532493) (xy 53.696104 -61.51669) (xy 53.645939 -61.493401)
			(xy 53.599661 -61.463113) (xy 53.55824 -61.426461) (xy 53.522545 -61.384213) (xy 53.493324 -61.337255)
			(xy 53.471188 -61.28657) (xy 53.456601 -61.233219) (xy 53.44987 -61.178322) (xy 53.451134 -61.123029)
			(xy 53.460369 -61.068497) (xy 53.477379 -61.015869) (xy 53.50181 -60.966249) (xy 53.533148 -60.920676)
			(xy 53.551582 -60.900056) (xy 53.567296 -60.882284) (xy 53.592482 -60.842089) (xy 53.609774 -60.79792)
			(xy 53.618572 -60.751309) (xy 53.618571 -60.703876) (xy 53.60977 -60.657266) (xy 53.592475 -60.613098)
			(xy 53.567287 -60.572904) (xy 53.551582 -60.555124) (xy 53.532209 -60.533413) (xy 53.499601 -60.485223)
			(xy 53.474691 -60.432639) (xy 53.458058 -60.376882) (xy 53.450088 -60.319245) (xy 53.450966 -60.261066)
			(xy 53.460671 -60.203696) (xy 53.469286 -60.175902) (xy 53.476218 -60.15331) (xy 53.482521 -60.106482)
			(xy 53.480057 -60.059295) (xy 53.46891 -60.013378) (xy 53.449465 -59.970313) (xy 53.422392 -59.931587)
			(xy 53.388625 -59.898535) (xy 53.349329 -59.872296) (xy 53.305859 -59.853776) (xy 53.259713 -59.843614)
			(xy 53.236114 -59.8424) (xy 52.813712 -59.8424) (xy 52.811172 -59.842146) (xy 52.625752 -59.842146)
			(xy 52.608767 -59.842678) (xy 52.575999 -59.851631) (xy 52.546755 -59.868915) (xy 52.534566 -59.880754)
			(xy 52.512929 -59.90235) (xy 52.464921 -59.940196) (xy 52.412302 -59.971314) (xy 52.356009 -59.995151)
			(xy 52.297044 -60.011281) (xy 52.236456 -60.019419) (xy 52.175324 -60.019419) (xy 52.114736 -60.011281)
			(xy 52.055771 -59.995151) (xy 51.999478 -59.971314) (xy 51.946859 -59.940196) (xy 51.898851 -59.90235)
			(xy 51.877214 -59.880754) (xy 51.865007 -59.868936) (xy 51.83577 -59.851651) (xy 51.80301 -59.842687)
			(xy 51.786028 -59.842146) (xy 51.761644 -59.842146) (xy 51.761644 -59.673236) (xy 51.758596 -59.659774)
			(xy 51.752158 -59.627628) (xy 51.747465 -59.562237) (xy 51.752147 -59.496846) (xy 51.758596 -59.464702)
			(xy 51.761644 -59.45124) (xy 51.761644 -58.196226) (xy 51.758596 -58.182764) (xy 51.752159 -58.150618)
			(xy 51.747467 -58.085227) (xy 51.752151 -58.019836) (xy 51.758596 -57.987692) (xy 51.761644 -57.97423)
			(xy 51.761644 -57.558178) (xy 52.188618 -57.131204) (xy 52.188618 -55.55615) (xy 52.25542 -55.489348)
			(xy 52.25542 -54.503066) (xy 52.97932 -53.779166) (xy 52.97932 -44.236386) (xy 52.436776 -43.693842)
			(xy 47.460408 -43.693842) (xy 47.113952 -44.040298) (xy 47.113952 -54.837076) (xy 47.141384 -54.864508)
			(xy 47.141384 -58.21807) (xy 47.155608 -58.245502) (xy 47.169415 -58.273426) (xy 47.190191 -58.332153)
			(xy 47.202812 -58.393155) (xy 47.207044 -58.455305) (xy 47.20281 -58.517455) (xy 47.190188 -58.578457)
			(xy 47.169411 -58.637184) (xy 47.155608 -58.66511) (xy 47.141384 -58.692542) (xy 47.141384 -59.105546)
			(xy 49.985166 -59.105546) (xy 49.989237 -59.049924) (xy 50.001363 -58.995487) (xy 50.021286 -58.943396)
			(xy 50.048582 -58.894761) (xy 50.082668 -58.850618) (xy 50.122817 -58.811909) (xy 50.168175 -58.779458)
			(xy 50.217775 -58.753957) (xy 50.270559 -58.73595) (xy 50.325402 -58.72582) (xy 50.381136 -58.723783)
			(xy 50.436573 -58.729883) (xy 50.49053 -58.743989) (xy 50.541859 -58.765801) (xy 50.589465 -58.794855)
			(xy 50.632333 -58.83053) (xy 50.66955 -58.872067) (xy 50.700323 -58.91858) (xy 50.723995 -58.969077)
			(xy 50.740063 -59.022484) (xy 50.748183 -59.07766) (xy 50.748692 -59.105546) (xy 50.748183 -59.133432)
			(xy 50.740063 -59.188608) (xy 50.723995 -59.242015) (xy 50.700323 -59.292512) (xy 50.66955 -59.339025)
			(xy 50.632333 -59.380562) (xy 50.589465 -59.416237) (xy 50.541859 -59.445291) (xy 50.49053 -59.467103)
			(xy 50.436573 -59.481209) (xy 50.381136 -59.487309) (xy 50.325402 -59.485272) (xy 50.270559 -59.475142)
			(xy 50.217775 -59.457135) (xy 50.168175 -59.431634) (xy 50.122817 -59.399183) (xy 50.082668 -59.360474)
			(xy 50.048582 -59.316331) (xy 50.021286 -59.267696) (xy 50.001363 -59.215605) (xy 49.989237 -59.161168)
			(xy 49.985166 -59.105546) (xy 47.141384 -59.105546) (xy 47.141384 -59.581288) (xy 47.39767 -59.837574)
			(xy 47.414583 -59.85373) (xy 47.45315 -59.880185) (xy 47.495906 -59.899134) (xy 47.541409 -59.909939)
			(xy 47.58812 -59.912234) (xy 47.634462 -59.905942) (xy 47.67887 -59.891276) (xy 47.719845 -59.86873)
			(xy 47.738284 -59.854338) (xy 47.760324 -59.836895) (xy 47.808532 -59.807997) (xy 47.860459 -59.786485)
			(xy 47.91498 -59.772826) (xy 47.970915 -59.767316) (xy 48.027054 -59.770072) (xy 48.08218 -59.781037)
			(xy 48.135101 -59.799971) (xy 48.18467 -59.826467) (xy 48.229815 -59.859949) (xy 48.269558 -59.899693)
			(xy 48.303039 -59.944839) (xy 48.329533 -59.994409) (xy 48.348466 -60.04733) (xy 48.359429 -60.102457)
			(xy 48.362184 -60.158595) (xy 48.356672 -60.214531) (xy 48.343011 -60.269051) (xy 48.321498 -60.320977)
			(xy 48.318632 -60.325758) (xy 50.008772 -60.325758) (xy 50.008772 -60.265822) (xy 50.016595 -60.2064)
			(xy 50.032108 -60.148507) (xy 50.055044 -60.093134) (xy 50.085011 -60.041228) (xy 50.121498 -59.993678)
			(xy 50.163878 -59.951298) (xy 50.211428 -59.914811) (xy 50.263334 -59.884844) (xy 50.318707 -59.861908)
			(xy 50.3766 -59.846395) (xy 50.436022 -59.838572) (xy 50.495958 -59.838572) (xy 50.55538 -59.846395)
			(xy 50.613273 -59.861908) (xy 50.668646 -59.884844) (xy 50.720552 -59.914811) (xy 50.768102 -59.951298)
			(xy 50.810482 -59.993678) (xy 50.846969 -60.041228) (xy 50.876936 -60.093134) (xy 50.899872 -60.148507)
			(xy 50.915385 -60.2064) (xy 50.923208 -60.265822) (xy 50.923698 -60.29579) (xy 50.923208 -60.325758)
			(xy 50.915385 -60.38518) (xy 50.899872 -60.443073) (xy 50.876936 -60.498446) (xy 50.846969 -60.550352)
			(xy 50.810482 -60.597902) (xy 50.768102 -60.640282) (xy 50.720552 -60.676769) (xy 50.668646 -60.706736)
			(xy 50.613273 -60.729672) (xy 50.55538 -60.745185) (xy 50.495958 -60.753008) (xy 50.436022 -60.753008)
			(xy 50.3766 -60.745185) (xy 50.318707 -60.729672) (xy 50.263334 -60.706736) (xy 50.211428 -60.676769)
			(xy 50.163878 -60.640282) (xy 50.121498 -60.597902) (xy 50.085011 -60.550352) (xy 50.055044 -60.498446)
			(xy 50.032108 -60.443073) (xy 50.016595 -60.38518) (xy 50.008772 -60.325758) (xy 48.318632 -60.325758)
			(xy 48.292599 -60.369185) (xy 48.27524 -60.391294) (xy 48.260826 -60.409713) (xy 48.238293 -60.45069)
			(xy 48.223639 -60.495099) (xy 48.217358 -60.541439) (xy 48.219664 -60.588146) (xy 48.230477 -60.633643)
			(xy 48.249434 -60.676393) (xy 48.275893 -60.714952) (xy 48.292004 -60.731908) (xy 48.56018 -61.000084)
			(xy 51.68104 -61.000084) (xy 51.686744 -60.939875) (xy 51.70033 -60.880942) (xy 51.72156 -60.824311)
			(xy 51.750065 -60.770971) (xy 51.785347 -60.72185) (xy 51.826792 -60.677804) (xy 51.873678 -60.639601)
			(xy 51.925187 -60.607907) (xy 51.980422 -60.583274) (xy 52.038421 -60.566131) (xy 52.098172 -60.556777)
			(xy 52.158635 -60.555376) (xy 52.218756 -60.56195) (xy 52.277486 -60.576386) (xy 52.333804 -60.598433)
			(xy 52.386727 -60.627706) (xy 52.435333 -60.663695) (xy 52.478774 -60.705772) (xy 52.516295 -60.753205)
			(xy 52.547241 -60.805167) (xy 52.571073 -60.860753) (xy 52.587376 -60.918993) (xy 52.595865 -60.978873)
			(xy 52.596393 -61.03935) (xy 52.58895 -61.099369) (xy 52.573666 -61.157885) (xy 52.550807 -61.213878)
			(xy 52.520773 -61.266372) (xy 52.502816 -61.290708) (xy 52.490287 -61.307898) (xy 52.470495 -61.345545)
			(xy 52.457246 -61.385961) (xy 52.450908 -61.428019) (xy 52.45166 -61.470545) (xy 52.459479 -61.512353)
			(xy 52.474147 -61.552276) (xy 52.495256 -61.589201) (xy 52.508404 -61.605922) (xy 52.52557 -61.627549)
			(xy 52.55413 -61.674804) (xy 52.575582 -61.725681) (xy 52.589476 -61.77912) (xy 52.595524 -61.834003)
			(xy 52.593598 -61.889184) (xy 52.583738 -61.943512) (xy 52.566152 -61.995851) (xy 52.541205 -62.045109)
			(xy 52.50942 -62.090258) (xy 52.471459 -62.130353) (xy 52.428115 -62.164559) (xy 52.380294 -62.192161)
			(xy 52.328994 -62.212581) (xy 52.275287 -62.225395) (xy 52.220293 -62.230334) (xy 52.165162 -62.227296)
			(xy 52.111044 -62.216343) (xy 52.05907 -62.197704) (xy 52.010325 -62.171769) (xy 51.965827 -62.139079)
			(xy 51.926505 -62.100317) (xy 51.893181 -62.056293) (xy 51.866549 -62.007925) (xy 51.847167 -61.956223)
			(xy 51.835439 -61.902268) (xy 51.83161 -61.847186) (xy 51.83576 -61.792127) (xy 51.847803 -61.738241)
			(xy 51.867486 -61.686654) (xy 51.880516 -61.66231) (xy 51.890572 -61.643545) (xy 51.904856 -61.60344)
			(xy 51.912255 -61.561515) (xy 51.912562 -61.518944) (xy 51.905769 -61.476916) (xy 51.892065 -61.436609)
			(xy 51.871834 -61.399151) (xy 51.845642 -61.365588) (xy 51.830224 -61.350906) (xy 51.808253 -61.330123)
			(xy 51.769376 -61.283794) (xy 51.736941 -61.232748) (xy 51.711512 -61.177875) (xy 51.693532 -61.12013)
			(xy 51.683315 -61.060521) (xy 51.68104 -61.000084) (xy 48.56018 -61.000084) (xy 48.7299 -61.169804)
			(xy 48.7299 -62.027558) (xy 50.008772 -62.027558) (xy 50.008772 -61.967622) (xy 50.016595 -61.9082)
			(xy 50.032108 -61.850307) (xy 50.055044 -61.794934) (xy 50.085011 -61.743028) (xy 50.121498 -61.695478)
			(xy 50.163878 -61.653098) (xy 50.211428 -61.616611) (xy 50.263334 -61.586644) (xy 50.318707 -61.563708)
			(xy 50.3766 -61.548195) (xy 50.436022 -61.540372) (xy 50.495958 -61.540372) (xy 50.55538 -61.548195)
			(xy 50.613273 -61.563708) (xy 50.668646 -61.586644) (xy 50.720552 -61.616611) (xy 50.768102 -61.653098)
			(xy 50.810482 -61.695478) (xy 50.846969 -61.743028) (xy 50.876936 -61.794934) (xy 50.899872 -61.850307)
			(xy 50.915385 -61.9082) (xy 50.923208 -61.967622) (xy 50.923698 -61.99759) (xy 50.923208 -62.027558)
			(xy 50.915385 -62.08698) (xy 50.899872 -62.144873) (xy 50.876936 -62.200246) (xy 50.846969 -62.252152)
			(xy 50.810482 -62.299702) (xy 50.768102 -62.342082) (xy 50.720552 -62.378569) (xy 50.668646 -62.408536)
			(xy 50.613273 -62.431472) (xy 50.55538 -62.446985) (xy 50.495958 -62.454808) (xy 50.436022 -62.454808)
			(xy 50.3766 -62.446985) (xy 50.318707 -62.431472) (xy 50.263334 -62.408536) (xy 50.211428 -62.378569)
			(xy 50.163878 -62.342082) (xy 50.121498 -62.299702) (xy 50.085011 -62.252152) (xy 50.055044 -62.200246)
			(xy 50.032108 -62.144873) (xy 50.016595 -62.08698) (xy 50.008772 -62.027558) (xy 48.7299 -62.027558)
			(xy 48.7299 -62.11316) (xy 49.28108 -62.66434) (xy 49.822354 -63.205868) (xy 49.84877 -63.236856)
			(xy 49.849278 -63.237618) (xy 49.867598 -63.259386) (xy 49.898251 -63.307315) (xy 49.921446 -63.359265)
			(xy 49.936668 -63.414083) (xy 49.94358 -63.470555) (xy 49.942028 -63.527426) (xy 49.932047 -63.583437)
			(xy 49.913858 -63.637344) (xy 49.887865 -63.687951) (xy 49.854644 -63.734137) (xy 49.814932 -63.774877)
			(xy 49.769609 -63.809267) (xy 49.744884 -63.823342) (xy 49.734397 -63.844021) (xy 49.720289 -63.888184)
			(xy 49.714419 -63.934172) (xy 49.71698 -63.980462) (xy 49.727889 -64.025522) (xy 49.746783 -64.067858)
			(xy 49.773038 -64.106069) (xy 49.78908 -64.122808) (xy 49.837594 -64.171576) (xy 49.849761 -64.183063)
			(xy 49.878723 -64.199801) (xy 49.911038 -64.208444) (xy 49.927764 -64.208914) (xy 49.9872 -64.208914)
			(xy 50.347118 -64.568832) (xy 50.39233 -64.614044) (xy 50.443384 -64.665098) (xy 50.443384 -64.768476)
			(xy 50.455272 -64.786359) (xy 50.484064 -64.818213) (xy 50.517811 -64.844762) (xy 50.555548 -64.865246)
			(xy 50.575718 -64.872616) (xy 50.687224 -64.818514) (xy 50.704242 -64.79921) (xy 50.724698 -64.776688)
			(xy 50.770562 -64.736709) (xy 50.821318 -64.703158) (xy 50.876071 -64.676626) (xy 50.933856 -64.657581)
			(xy 50.993655 -64.646359) (xy 51.054413 -64.643157) (xy 51.11506 -64.648032) (xy 51.174527 -64.660897)
			(xy 51.231765 -64.681527) (xy 51.285767 -64.709557) (xy 51.335579 -64.744493) (xy 51.380324 -64.78572)
			(xy 51.419214 -64.832511) (xy 51.451563 -64.884042) (xy 51.464718 -64.911478) (xy 51.470617 -64.924769)
			(xy 51.480912 -64.951968) (xy 51.485292 -64.965834) (xy 51.490526 -64.981144) (xy 51.507546 -65.00865)
			(xy 51.530945 -65.030983) (xy 51.559214 -65.046704) (xy 51.59053 -65.0548) (xy 51.606704 -65.055242)
			(xy 51.62677 -65.055242) (xy 51.863498 -65.29197) (xy 51.863498 -65.852703) (xy 52.959561 -65.852703)
			(xy 52.965901 -65.791977) (xy 52.980259 -65.732634) (xy 53.002378 -65.675725) (xy 53.031868 -65.622263)
			(xy 53.068202 -65.573196) (xy 53.110738 -65.529395) (xy 53.15872 -65.491638) (xy 53.211295 -65.460594)
			(xy 53.267531 -65.436817) (xy 53.326428 -65.420726) (xy 53.386942 -65.412609) (xy 53.447998 -65.412609)
			(xy 53.508512 -65.420726) (xy 53.567409 -65.436817) (xy 53.623645 -65.460594) (xy 53.67622 -65.491638)
			(xy 53.724202 -65.529395) (xy 53.766738 -65.573196) (xy 53.803072 -65.622263) (xy 53.832562 -65.675725)
			(xy 53.854681 -65.732634) (xy 53.869039 -65.791977) (xy 53.875379 -65.852703) (xy 53.87359 -65.913733)
			(xy 53.863703 -65.973983) (xy 53.845894 -66.032384) (xy 53.820478 -66.087898) (xy 53.787908 -66.139541)
			(xy 53.748761 -66.186396) (xy 53.726588 -66.207386) (xy 53.715048 -66.218513) (xy 53.697546 -66.245363)
			(xy 53.687283 -66.275727) (xy 53.684907 -66.307689) (xy 53.690566 -66.339237) (xy 53.703904 -66.36838)
			(xy 53.713634 -66.381122) (xy 53.730714 -66.402964) (xy 53.759044 -66.450626) (xy 53.780174 -66.501888)
			(xy 53.793658 -66.555669) (xy 53.799212 -66.610836) (xy 53.796719 -66.666225) (xy 53.786232 -66.72067)
			(xy 53.767971 -66.773023) (xy 53.742322 -66.822179) (xy 53.709825 -66.867103) (xy 53.671165 -66.906848)
			(xy 53.627158 -66.940576) (xy 53.57873 -66.967576) (xy 53.526903 -66.987279) (xy 53.472769 -66.999269)
			(xy 53.41747 -67.003294) (xy 53.362171 -66.999269) (xy 53.308037 -66.987279) (xy 53.25621 -66.967576)
			(xy 53.207782 -66.940576) (xy 53.163775 -66.906848) (xy 53.125115 -66.867103) (xy 53.092618 -66.822179)
			(xy 53.066969 -66.773023) (xy 53.048708 -66.72067) (xy 53.038221 -66.666225) (xy 53.035728 -66.610836)
			(xy 53.041282 -66.555669) (xy 53.054766 -66.501888) (xy 53.075896 -66.450626) (xy 53.104226 -66.402964)
			(xy 53.121306 -66.381122) (xy 53.130974 -66.368343) (xy 53.144291 -66.339212) (xy 53.14994 -66.307683)
			(xy 53.147567 -66.275741) (xy 53.13732 -66.245393) (xy 53.119844 -66.21855) (xy 53.108352 -66.207386)
			(xy 53.086179 -66.186396) (xy 53.047032 -66.139541) (xy 53.014462 -66.087898) (xy 52.989046 -66.032384)
			(xy 52.971237 -65.973983) (xy 52.96135 -65.913733) (xy 52.959561 -65.852703) (xy 51.863498 -65.852703)
			(xy 51.863498 -68.492624) (xy 51.709574 -68.646548) (xy 51.698131 -68.658677) (xy 51.68145 -68.687539)
			(xy 51.672815 -68.719736) (xy 51.672816 -68.753072) (xy 51.681453 -68.785269) (xy 51.698135 -68.814129)
			(xy 51.721725 -68.837683) (xy 51.750611 -68.854322) (xy 51.782821 -68.862909) (xy 51.79949 -68.863464)
			(xy 51.88839 -68.863464)
		)
		(stroke
			(width 0)
			(type solid)
		)
		(fill yes)
		(layer "B.Cu")
		(net "GND")
	)
	(gr_poly
		(pts
			(xy 76.391262 -24.350218) (xy 78.870048 -24.350218) (xy 78.886358 -24.34975) (xy 78.917925 -24.341535)
			(xy 78.946373 -24.325576) (xy 78.969839 -24.302921) (xy 78.97876 -24.289258) (xy 78.985277 -24.278633)
			(xy 78.99951 -24.258168) (xy 79.007208 -24.248364) (xy 79.02097 -24.230503) (xy 79.042611 -24.190951)
			(xy 79.05693 -24.1482) (xy 79.063477 -24.103592) (xy 79.062046 -24.058529) (xy 79.052683 -24.014427)
			(xy 79.035682 -23.97267) (xy 79.011576 -23.93457) (xy 78.981123 -23.901324) (xy 78.945279 -23.873976)
			(xy 78.92542 -23.8633) (xy 78.898566 -23.848949) (xy 78.848565 -23.814201) (xy 78.803612 -23.773131)
			(xy 78.764502 -23.726464) (xy 78.731924 -23.675023) (xy 78.706453 -23.619718) (xy 78.688539 -23.561524)
			(xy 78.678499 -23.501468) (xy 78.676509 -23.440612) (xy 78.682606 -23.380029) (xy 78.69668 -23.320789)
			(xy 78.718485 -23.263938) (xy 78.747634 -23.210479) (xy 78.783613 -23.161357) (xy 78.825787 -23.117439)
			(xy 78.873411 -23.0795) (xy 78.925645 -23.048209) (xy 78.981566 -23.02412) (xy 79.040188 -23.007658)
			(xy 79.100474 -22.999113) (xy 79.161361 -22.998636) (xy 79.221774 -23.006235) (xy 79.280646 -23.021777)
			(xy 79.30896 -23.032974) (xy 79.330079 -23.041163) (xy 79.37434 -23.050769) (xy 79.419603 -23.052381)
			(xy 79.464435 -23.045949) (xy 79.507419 -23.031676) (xy 79.547195 -23.010015) (xy 79.582504 -22.981649)
			(xy 79.612229 -22.947477) (xy 79.63543 -22.908579) (xy 79.651373 -22.866187) (xy 79.655924 -22.843998)
			(xy 79.661436 -22.816607) (xy 79.679409 -22.763707) (xy 79.704908 -22.713994) (xy 79.737386 -22.668533)
			(xy 79.776149 -22.628296) (xy 79.820367 -22.594145) (xy 79.869094 -22.56681) (xy 79.921288 -22.546877)
			(xy 79.975831 -22.53477) (xy 80.031557 -22.530751) (xy 80.087273 -22.534904) (xy 80.141788 -22.547141)
			(xy 80.193933 -22.567199) (xy 80.206646 -22.574371) (xy 81.93173 -22.574371) (xy 81.935262 -22.518743)
			(xy 81.946849 -22.46422) (xy 81.966246 -22.411963) (xy 81.99304 -22.363085) (xy 82.02666 -22.318625)
			(xy 82.066392 -22.27953) (xy 82.111388 -22.246631) (xy 82.160693 -22.22063) (xy 82.213256 -22.202079)
			(xy 82.267958 -22.191372) (xy 82.323637 -22.188739) (xy 82.379106 -22.194235) (xy 82.433185 -22.207743)
			(xy 82.484723 -22.228975) (xy 82.532624 -22.25748) (xy 82.575868 -22.292651) (xy 82.613534 -22.333739)
			(xy 82.644821 -22.379871) (xy 82.669064 -22.430063) (xy 82.685745 -22.483249) (xy 82.691014 -22.516338)
			(xy 86.115904 -22.516338) (xy 86.119975 -22.460716) (xy 86.132101 -22.406279) (xy 86.152024 -22.354188)
			(xy 86.17932 -22.305553) (xy 86.213406 -22.26141) (xy 86.253555 -22.222701) (xy 86.298913 -22.19025)
			(xy 86.348513 -22.164749) (xy 86.401297 -22.146742) (xy 86.45614 -22.136612) (xy 86.511874 -22.134575)
			(xy 86.567311 -22.140675) (xy 86.621268 -22.154781) (xy 86.672597 -22.176593) (xy 86.720203 -22.205647)
			(xy 86.763071 -22.241322) (xy 86.800288 -22.282859) (xy 86.831061 -22.329372) (xy 86.854733 -22.379869)
			(xy 86.870801 -22.433276) (xy 86.878921 -22.488452) (xy 86.87943 -22.516338) (xy 86.878921 -22.544224)
			(xy 86.870801 -22.5994) (xy 86.854733 -22.652807) (xy 86.831061 -22.703304) (xy 86.800288 -22.749817)
			(xy 86.763071 -22.791354) (xy 86.720203 -22.827029) (xy 86.672597 -22.856083) (xy 86.621268 -22.877895)
			(xy 86.567311 -22.892001) (xy 86.511874 -22.898101) (xy 86.45614 -22.896064) (xy 86.401297 -22.885934)
			(xy 86.348513 -22.867927) (xy 86.298913 -22.842426) (xy 86.253555 -22.809975) (xy 86.213406 -22.771266)
			(xy 86.17932 -22.727123) (xy 86.152024 -22.678488) (xy 86.132101 -22.626397) (xy 86.119975 -22.57196)
			(xy 86.115904 -22.516338) (xy 82.691014 -22.516338) (xy 82.694511 -22.538296) (xy 82.695174 -22.594033)
			(xy 82.687721 -22.649273) (xy 82.67231 -22.702841) (xy 82.661252 -22.728428) (xy 82.652099 -22.749662)
			(xy 82.640888 -22.79452) (xy 82.637984 -22.840665) (xy 82.643483 -22.886574) (xy 82.657203 -22.930728)
			(xy 82.67869 -22.971669) (xy 82.707235 -23.008042) (xy 82.741894 -23.038646) (xy 82.78152 -23.06247)
			(xy 82.802984 -23.071074) (xy 82.83107 -23.082226) (xy 82.884309 -23.110815) (xy 82.933323 -23.146162)
			(xy 82.977259 -23.187652) (xy 83.015352 -23.234563) (xy 83.04694 -23.286079) (xy 83.071473 -23.341305)
			(xy 83.088526 -23.399278) (xy 83.0978 -23.458992) (xy 83.099135 -23.519407) (xy 83.092508 -23.579472)
			(xy 83.085777 -23.606756) (xy 83.532454 -23.606756) (xy 83.532454 -23.54682) (xy 83.540277 -23.487398)
			(xy 83.55579 -23.429505) (xy 83.578726 -23.374132) (xy 83.608693 -23.322226) (xy 83.64518 -23.274676)
			(xy 83.68756 -23.232296) (xy 83.73511 -23.195809) (xy 83.787016 -23.165842) (xy 83.842389 -23.142906)
			(xy 83.900282 -23.127393) (xy 83.959704 -23.11957) (xy 84.01964 -23.11957) (xy 84.079062 -23.127393)
			(xy 84.136955 -23.142906) (xy 84.192328 -23.165842) (xy 84.244234 -23.195809) (xy 84.291784 -23.232296)
			(xy 84.334164 -23.274676) (xy 84.370651 -23.322226) (xy 84.400618 -23.374132) (xy 84.423554 -23.429505)
			(xy 84.439067 -23.487398) (xy 84.44689 -23.54682) (xy 84.44738 -23.576788) (xy 84.44689 -23.606756)
			(xy 84.802454 -23.606756) (xy 84.802454 -23.54682) (xy 84.810277 -23.487398) (xy 84.82579 -23.429505)
			(xy 84.848726 -23.374132) (xy 84.878693 -23.322226) (xy 84.91518 -23.274676) (xy 84.95756 -23.232296)
			(xy 85.00511 -23.195809) (xy 85.057016 -23.165842) (xy 85.112389 -23.142906) (xy 85.170282 -23.127393)
			(xy 85.229704 -23.11957) (xy 85.28964 -23.11957) (xy 85.349062 -23.127393) (xy 85.406955 -23.142906)
			(xy 85.462328 -23.165842) (xy 85.514234 -23.195809) (xy 85.561784 -23.232296) (xy 85.604164 -23.274676)
			(xy 85.640651 -23.322226) (xy 85.670618 -23.374132) (xy 85.693554 -23.429505) (xy 85.709067 -23.487398)
			(xy 85.71689 -23.54682) (xy 85.71738 -23.576788) (xy 85.71689 -23.606756) (xy 85.709067 -23.666178)
			(xy 85.693554 -23.724071) (xy 85.670618 -23.779444) (xy 85.640651 -23.83135) (xy 85.604164 -23.8789)
			(xy 85.561784 -23.92128) (xy 85.514234 -23.957767) (xy 85.462328 -23.987734) (xy 85.406955 -24.01067)
			(xy 85.349062 -24.026183) (xy 85.28964 -24.034006) (xy 85.229704 -24.034006) (xy 85.170282 -24.026183)
			(xy 85.112389 -24.01067) (xy 85.057016 -23.987734) (xy 85.00511 -23.957767) (xy 84.95756 -23.92128)
			(xy 84.91518 -23.8789) (xy 84.878693 -23.83135) (xy 84.848726 -23.779444) (xy 84.82579 -23.724071)
			(xy 84.810277 -23.666178) (xy 84.802454 -23.606756) (xy 84.44689 -23.606756) (xy 84.439067 -23.666178)
			(xy 84.423554 -23.724071) (xy 84.400618 -23.779444) (xy 84.370651 -23.83135) (xy 84.334164 -23.8789)
			(xy 84.291784 -23.92128) (xy 84.244234 -23.957767) (xy 84.192328 -23.987734) (xy 84.136955 -24.01067)
			(xy 84.079062 -24.026183) (xy 84.01964 -24.034006) (xy 83.959704 -24.034006) (xy 83.900282 -24.026183)
			(xy 83.842389 -24.01067) (xy 83.787016 -23.987734) (xy 83.73511 -23.957767) (xy 83.68756 -23.92128)
			(xy 83.64518 -23.8789) (xy 83.608693 -23.83135) (xy 83.578726 -23.779444) (xy 83.55579 -23.724071)
			(xy 83.540277 -23.666178) (xy 83.532454 -23.606756) (xy 83.085777 -23.606756) (xy 83.078033 -23.638143)
			(xy 83.055963 -23.694398) (xy 83.026682 -23.747259) (xy 82.990698 -23.795807) (xy 82.948638 -23.839198)
			(xy 82.901234 -23.876675) (xy 82.84931 -23.907588) (xy 82.793769 -23.931399) (xy 82.735577 -23.947693)
			(xy 82.675748 -23.956187) (xy 82.61532 -23.956734) (xy 82.555347 -23.949323) (xy 82.49687 -23.934084)
			(xy 82.440908 -23.911281) (xy 82.388433 -23.881312) (xy 82.340359 -23.844698) (xy 82.297521 -23.802076)
			(xy 82.260666 -23.754186) (xy 82.230433 -23.701863) (xy 82.207349 -23.646016) (xy 82.191816 -23.587617)
			(xy 82.184103 -23.527681) (xy 82.184346 -23.467252) (xy 82.192539 -23.40738) (xy 82.20854 -23.349108)
			(xy 82.232071 -23.293448) (xy 82.246978 -23.267162) (xy 82.258243 -23.24699) (xy 82.274076 -23.203592)
			(xy 82.281806 -23.158047) (xy 82.281177 -23.111854) (xy 82.272211 -23.066536) (xy 82.255202 -23.023585)
			(xy 82.230711 -22.984414) (xy 82.199545 -22.950315) (xy 82.162729 -22.92241) (xy 82.14233 -22.911562)
			(xy 82.117653 -22.898598) (xy 82.072033 -22.866571) (xy 82.031558 -22.828246) (xy 81.997089 -22.784441)
			(xy 81.969361 -22.736086) (xy 81.948963 -22.684212) (xy 81.93633 -22.629922) (xy 81.93173 -22.574371)
			(xy 80.206646 -22.574371) (xy 80.242595 -22.594651) (xy 80.286731 -22.628908) (xy 80.325398 -22.669237)
			(xy 80.357767 -22.714776) (xy 80.383147 -22.764549) (xy 80.400993 -22.817493) (xy 80.410925 -22.872474)
			(xy 80.41273 -22.928315) (xy 80.406369 -22.983823) (xy 80.391978 -23.037808) (xy 80.369866 -23.089117)
			(xy 80.340505 -23.136651) (xy 80.304523 -23.179393) (xy 80.262691 -23.216428) (xy 80.215904 -23.246965)
			(xy 80.165162 -23.270349) (xy 80.111552 -23.28608) (xy 80.05622 -23.293822) (xy 80.000351 -23.29341)
			(xy 79.94514 -23.284851) (xy 79.918306 -23.277068) (xy 79.896537 -23.270868) (xy 79.851612 -23.265392)
			(xy 79.806427 -23.267959) (xy 79.762411 -23.278488) (xy 79.720955 -23.296645) (xy 79.68337 -23.321857)
			(xy 79.650844 -23.353327) (xy 79.624406 -23.39006) (xy 79.604891 -23.430894) (xy 79.592916 -23.474539)
			(xy 79.590392 -23.497032) (xy 79.587097 -23.527977) (xy 79.573198 -23.588635) (xy 79.551199 -23.646847)
			(xy 79.521508 -23.701537) (xy 79.484673 -23.751695) (xy 79.463392 -23.7744) (xy 79.448055 -23.790931)
			(xy 79.422888 -23.828342) (xy 79.404714 -23.869605) (xy 79.394103 -23.913427) (xy 79.391388 -23.958434)
			(xy 79.396655 -24.003213) (xy 79.409737 -24.046362) (xy 79.430226 -24.086527) (xy 79.457478 -24.122447)
			(xy 79.490638 -24.152998) (xy 79.509366 -24.16556) (xy 79.533647 -24.181657) (xy 79.577469 -24.220039)
			(xy 79.614932 -24.26465) (xy 79.630524 -24.289258) (xy 79.639433 -24.302928) (xy 79.662908 -24.325573)
			(xy 79.69136 -24.341524) (xy 79.722926 -24.349738) (xy 79.739236 -24.350218) (xy 80.278732 -24.350218)
			(xy 80.294891 -24.349724) (xy 80.326168 -24.341582) (xy 80.354401 -24.325852) (xy 80.377784 -24.303542)
			(xy 80.394821 -24.276077) (xy 80.400144 -24.26081) (xy 80.408577 -24.235252) (xy 80.431625 -24.186618)
			(xy 80.461281 -24.141706) (xy 80.496955 -24.101409) (xy 80.537939 -24.066527) (xy 80.58342 -24.037751)
			(xy 80.632493 -24.015655) (xy 80.684186 -24.000675) (xy 80.73747 -23.99311) (xy 80.79129 -23.99311)
			(xy 80.844574 -24.000675) (xy 80.896267 -24.015655) (xy 80.94534 -24.037751) (xy 80.990821 -24.066527)
			(xy 81.031805 -24.101409) (xy 81.067479 -24.141706) (xy 81.097135 -24.186618) (xy 81.120183 -24.235252)
			(xy 81.128616 -24.26081) (xy 81.133849 -24.276121) (xy 81.150868 -24.303628) (xy 81.174266 -24.325961)
			(xy 81.202536 -24.34168) (xy 81.233854 -24.349772) (xy 81.250028 -24.350218) (xy 86.886034 -24.350218)
			(xy 86.908314 -24.349752) (xy 86.952189 -24.341975) (xy 86.994036 -24.326666) (xy 87.032572 -24.304294)
			(xy 87.066615 -24.275544) (xy 87.095124 -24.241298) (xy 87.117223 -24.202605) (xy 87.132236 -24.160652)
			(xy 87.139703 -24.116722) (xy 87.140034 -24.09444) (xy 87.1403 -24.063825) (xy 87.148023 -24.00309)
			(xy 87.163777 -23.943928) (xy 87.18728 -23.887396) (xy 87.218114 -23.834503) (xy 87.255727 -23.786195)
			(xy 87.299447 -23.743336) (xy 87.348492 -23.70669) (xy 87.374984 -23.691342) (xy 87.394018 -23.680172)
			(xy 87.428252 -23.652325) (xy 87.457163 -23.618986) (xy 87.479883 -23.581154) (xy 87.495727 -23.539967)
			(xy 87.504221 -23.496663) (xy 87.505109 -23.452542) (xy 87.498364 -23.408932) (xy 87.484189 -23.367141)
			(xy 87.463011 -23.328426) (xy 87.44966 -23.31085) (xy 87.433064 -23.289334) (xy 87.405487 -23.242514)
			(xy 87.384834 -23.192254) (xy 87.371524 -23.139572) (xy 87.365825 -23.085534) (xy 87.367852 -23.031234)
			(xy 87.377566 -22.977772) (xy 87.394769 -22.926229) (xy 87.419113 -22.87765) (xy 87.450105 -22.833018)
			(xy 87.487118 -22.793235) (xy 87.529402 -22.759109) (xy 87.576102 -22.731329) (xy 87.626271 -22.710458)
			(xy 87.678895 -22.696918) (xy 87.732908 -22.690984) (xy 87.787216 -22.692776) (xy 87.84072 -22.702258)
			(xy 87.892337 -22.719236) (xy 87.941021 -22.743369) (xy 87.985788 -22.774167) (xy 88.025731 -22.811007)
			(xy 88.060041 -22.853142) (xy 88.088023 -22.899721) (xy 88.109112 -22.949799) (xy 88.12288 -23.002364)
			(xy 88.129049 -23.05635) (xy 88.127493 -23.110665) (xy 88.118244 -23.16421) (xy 88.110314 -23.1902)
			(xy 88.110314 -23.190454) (xy 88.099392 -23.224744) (xy 88.10752 -23.259288) (xy 88.111925 -23.275599)
			(xy 88.128063 -23.305268) (xy 88.15142 -23.329664) (xy 88.180358 -23.347077) (xy 88.212852 -23.356289)
			(xy 88.246624 -23.356652) (xy 88.279308 -23.348143) (xy 88.308615 -23.331357) (xy 88.32088 -23.31974)
			(xy 88.522302 -23.118318) (xy 88.522302 -22.013418) (xy 87.658702 -21.149818) (xy 63.074042 -21.149818)
			(xy 62.837822 -21.386038) (xy 62.837822 -23.169118) (xy 63.063882 -23.395178) (xy 63.063882 -23.557738)
			(xy 63.064339 -23.573353) (xy 63.071927 -23.603647) (xy 63.08664 -23.631194) (xy 63.107597 -23.654347)
			(xy 63.133547 -23.671722) (xy 63.162938 -23.68228) (xy 63.178436 -23.68423) (xy 63.209075 -23.687756)
			(xy 63.269084 -23.70199) (xy 63.32664 -23.724148) (xy 63.380702 -23.75383) (xy 63.430291 -23.790499)
			(xy 63.47451 -23.833491) (xy 63.51256 -23.882029) (xy 63.543752 -23.935234) (xy 63.567521 -23.992143)
			(xy 63.583438 -24.051728) (xy 63.591214 -24.11291) (xy 63.590709 -24.174582) (xy 63.586868 -24.205184)
			(xy 63.585598 -24.214074) (xy 63.585598 -24.223218) (xy 63.586143 -24.239865) (xy 63.594764 -24.272023)
			(xy 63.611414 -24.300855) (xy 63.634958 -24.324396) (xy 63.663792 -24.341042) (xy 63.695951 -24.349659)
			(xy 63.712598 -24.350218) (xy 63.824866 -24.350218) (xy 63.841525 -24.349728) (xy 63.873708 -24.341112)
			(xy 63.902565 -24.324461) (xy 63.926129 -24.300907) (xy 63.942792 -24.272057) (xy 63.951421 -24.239876)
			(xy 63.951866 -24.223218) (xy 63.951866 -24.214074) (xy 63.950596 -24.205184) (xy 63.946682 -24.174663)
			(xy 63.946104 -24.113131) (xy 63.953773 -24.052077) (xy 63.969551 -23.9926) (xy 63.993153 -23.935772)
			(xy 64.024155 -23.882618) (xy 64.061996 -23.834095) (xy 64.105997 -23.791078) (xy 64.155362 -23.754343)
			(xy 64.209204 -23.724551) (xy 64.26655 -23.702239) (xy 64.326369 -23.68781) (xy 64.387581 -23.681523)
			(xy 64.449084 -23.683491) (xy 64.509769 -23.693681) (xy 64.568542 -23.711906) (xy 64.624344 -23.73784)
			(xy 64.67617 -23.771015) (xy 64.723085 -23.810833) (xy 64.764244 -23.856575) (xy 64.798905 -23.907419)
			(xy 64.826443 -23.962447) (xy 64.846362 -24.020668) (xy 64.858304 -24.081033) (xy 64.860678 -24.111712)
			(xy 64.862414 -24.13296) (xy 64.872085 -24.174479) (xy 64.888551 -24.2138) (xy 64.91135 -24.249821)
			(xy 64.939843 -24.281529) (xy 64.973229 -24.308037) (xy 65.010573 -24.328598) (xy 65.050825 -24.342637)
			(xy 65.092855 -24.349758) (xy 65.11417 -24.350218) (xy 66.317622 -24.350218) (xy 66.34007 -24.349729)
			(xy 66.384265 -24.341823) (xy 66.426385 -24.326277) (xy 66.465119 -24.303575) (xy 66.499264 -24.274423)
			(xy 66.527758 -24.239727) (xy 66.549716 -24.200566) (xy 66.564454 -24.158157) (xy 66.571514 -24.113819)
			(xy 66.570678 -24.06893) (xy 66.56197 -24.024885) (xy 66.55435 -24.003762) (xy 66.543639 -23.975007)
			(xy 66.529134 -23.915384) (xy 66.522727 -23.854357) (xy 66.524532 -23.793022) (xy 66.534517 -23.732477)
			(xy 66.552504 -23.67381) (xy 66.578169 -23.618073) (xy 66.611052 -23.566266) (xy 66.650563 -23.519317)
			(xy 66.695994 -23.478069) (xy 66.746529 -23.443262) (xy 66.801262 -23.415521) (xy 66.859211 -23.395342)
			(xy 66.919338 -23.383088) (xy 66.980562 -23.378979) (xy 67.041786 -23.383088) (xy 67.101913 -23.395342)
			(xy 67.159862 -23.415521) (xy 67.214595 -23.443262) (xy 67.26513 -23.478069) (xy 67.310561 -23.519317)
			(xy 67.349376 -23.565439) (xy 68.485736 -23.565439) (xy 68.490173 -23.509786) (xy 68.502674 -23.455374)
			(xy 68.522971 -23.403364) (xy 68.55063 -23.354868) (xy 68.585062 -23.31092) (xy 68.625531 -23.27246)
			(xy 68.648072 -23.255986) (xy 68.66576 -23.242958) (xy 68.696814 -23.211893) (xy 68.722064 -23.175951)
			(xy 68.740755 -23.136201) (xy 68.752332 -23.093829) (xy 68.75645 -23.050097) (xy 68.752985 -23.006309)
			(xy 68.742041 -22.963769) (xy 68.733416 -22.943566) (xy 68.721334 -22.91557) (xy 68.703758 -22.857183)
			(xy 68.69409 -22.79698) (xy 68.692503 -22.736026) (xy 68.699023 -22.675402) (xy 68.713536 -22.616179)
			(xy 68.735784 -22.559409) (xy 68.765373 -22.506095) (xy 68.80178 -22.457183) (xy 68.844359 -22.413538)
			(xy 68.892357 -22.375933) (xy 68.944923 -22.345035) (xy 69.001126 -22.321391) (xy 69.059972 -22.305419)
			(xy 69.120417 -22.297402) (xy 69.181391 -22.297482) (xy 69.241815 -22.305659) (xy 69.300618 -22.321786)
			(xy 69.356758 -22.345579) (xy 69.409243 -22.376616) (xy 69.457141 -22.414347) (xy 69.499605 -22.458105)
			(xy 69.535882 -22.507113) (xy 69.56533 -22.560505) (xy 69.587428 -22.617334) (xy 69.601785 -22.676594)
			(xy 69.608145 -22.737236) (xy 69.606396 -22.798185) (xy 69.59657 -22.858363) (xy 69.578839 -22.916702)
			(xy 69.55352 -22.972171) (xy 69.521058 -23.023787) (xy 69.482031 -23.070634) (xy 69.437128 -23.111885)
			(xy 69.387146 -23.146808) (xy 69.360288 -23.161244) (xy 69.341007 -23.171759) (xy 69.306048 -23.198335)
			(xy 69.276181 -23.230527) (xy 69.252295 -23.267377) (xy 69.235103 -23.307785) (xy 69.225116 -23.350548)
			(xy 69.222633 -23.394391) (xy 69.226581 -23.428194) (xy 69.799944 -23.428194) (xy 69.799944 -23.368258)
			(xy 69.807767 -23.308836) (xy 69.82328 -23.250943) (xy 69.846216 -23.19557) (xy 69.876183 -23.143664)
			(xy 69.91267 -23.096114) (xy 69.95505 -23.053734) (xy 70.0026 -23.017247) (xy 70.054506 -22.98728)
			(xy 70.109879 -22.964344) (xy 70.167772 -22.948831) (xy 70.227194 -22.941008) (xy 70.28713 -22.941008)
			(xy 70.346552 -22.948831) (xy 70.404445 -22.964344) (xy 70.459818 -22.98728) (xy 70.511724 -23.017247)
			(xy 70.559274 -23.053734) (xy 70.601654 -23.096114) (xy 70.638141 -23.143664) (xy 70.668108 -23.19557)
			(xy 70.691044 -23.250943) (xy 70.706557 -23.308836) (xy 70.71351 -23.361646) (xy 72.548224 -23.361646)
			(xy 72.548224 -23.30171) (xy 72.556047 -23.242288) (xy 72.57156 -23.184395) (xy 72.594496 -23.129022)
			(xy 72.624463 -23.077116) (xy 72.66095 -23.029566) (xy 72.70333 -22.987186) (xy 72.75088 -22.950699)
			(xy 72.802786 -22.920732) (xy 72.858159 -22.897796) (xy 72.916052 -22.882283) (xy 72.975474 -22.87446)
			(xy 73.03541 -22.87446) (xy 73.094832 -22.882283) (xy 73.152725 -22.897796) (xy 73.208098 -22.920732)
			(xy 73.260004 -22.950699) (xy 73.307554 -22.987186) (xy 73.349934 -23.029566) (xy 73.386421 -23.077116)
			(xy 73.416388 -23.129022) (xy 73.439324 -23.184395) (xy 73.454837 -23.242288) (xy 73.46266 -23.30171)
			(xy 73.46315 -23.331678) (xy 73.46266 -23.361646) (xy 73.455471 -23.416256) (xy 74.947762 -23.416256)
			(xy 74.947762 -23.35632) (xy 74.955585 -23.296898) (xy 74.971098 -23.239005) (xy 74.994034 -23.183632)
			(xy 75.024001 -23.131726) (xy 75.060488 -23.084176) (xy 75.102868 -23.041796) (xy 75.150418 -23.005309)
			(xy 75.202324 -22.975342) (xy 75.257697 -22.952406) (xy 75.31559 -22.936893) (xy 75.375012 -22.92907)
			(xy 75.434948 -22.92907) (xy 75.49437 -22.936893) (xy 75.552263 -22.952406) (xy 75.607636 -22.975342)
			(xy 75.659542 -23.005309) (xy 75.707092 -23.041796) (xy 75.749472 -23.084176) (xy 75.785959 -23.131726)
			(xy 75.815926 -23.183632) (xy 75.838862 -23.239005) (xy 75.854375 -23.296898) (xy 75.862198 -23.35632)
			(xy 75.862688 -23.386288) (xy 75.862198 -23.416256) (xy 76.217762 -23.416256) (xy 76.217762 -23.35632)
			(xy 76.225585 -23.296898) (xy 76.241098 -23.239005) (xy 76.264034 -23.183632) (xy 76.294001 -23.131726)
			(xy 76.330488 -23.084176) (xy 76.372868 -23.041796) (xy 76.420418 -23.005309) (xy 76.472324 -22.975342)
			(xy 76.527697 -22.952406) (xy 76.58559 -22.936893) (xy 76.645012 -22.92907) (xy 76.704948 -22.92907)
			(xy 76.76437 -22.936893) (xy 76.822263 -22.952406) (xy 76.877636 -22.975342) (xy 76.929542 -23.005309)
			(xy 76.977092 -23.041796) (xy 77.019472 -23.084176) (xy 77.055959 -23.131726) (xy 77.085926 -23.183632)
			(xy 77.108862 -23.239005) (xy 77.124375 -23.296898) (xy 77.132198 -23.35632) (xy 77.132688 -23.386288)
			(xy 77.132198 -23.416256) (xy 77.124375 -23.475678) (xy 77.108862 -23.533571) (xy 77.085926 -23.588944)
			(xy 77.055959 -23.64085) (xy 77.019472 -23.6884) (xy 76.977092 -23.73078) (xy 76.929542 -23.767267)
			(xy 76.877636 -23.797234) (xy 76.822263 -23.82017) (xy 76.76437 -23.835683) (xy 76.704948 -23.843506)
			(xy 76.645012 -23.843506) (xy 76.58559 -23.835683) (xy 76.527697 -23.82017) (xy 76.472324 -23.797234)
			(xy 76.420418 -23.767267) (xy 76.372868 -23.73078) (xy 76.330488 -23.6884) (xy 76.294001 -23.64085)
			(xy 76.264034 -23.588944) (xy 76.241098 -23.533571) (xy 76.225585 -23.475678) (xy 76.217762 -23.416256)
			(xy 75.862198 -23.416256) (xy 75.854375 -23.475678) (xy 75.838862 -23.533571) (xy 75.815926 -23.588944)
			(xy 75.785959 -23.64085) (xy 75.749472 -23.6884) (xy 75.707092 -23.73078) (xy 75.659542 -23.767267)
			(xy 75.607636 -23.797234) (xy 75.552263 -23.82017) (xy 75.49437 -23.835683) (xy 75.434948 -23.843506)
			(xy 75.375012 -23.843506) (xy 75.31559 -23.835683) (xy 75.257697 -23.82017) (xy 75.202324 -23.797234)
			(xy 75.150418 -23.767267) (xy 75.102868 -23.73078) (xy 75.060488 -23.6884) (xy 75.024001 -23.64085)
			(xy 74.994034 -23.588944) (xy 74.971098 -23.533571) (xy 74.955585 -23.475678) (xy 74.947762 -23.416256)
			(xy 73.455471 -23.416256) (xy 73.454837 -23.421068) (xy 73.439324 -23.478961) (xy 73.416388 -23.534334)
			(xy 73.386421 -23.58624) (xy 73.349934 -23.63379) (xy 73.307554 -23.67617) (xy 73.260004 -23.712657)
			(xy 73.208098 -23.742624) (xy 73.152725 -23.76556) (xy 73.094832 -23.781073) (xy 73.03541 -23.788896)
			(xy 72.975474 -23.788896) (xy 72.916052 -23.781073) (xy 72.858159 -23.76556) (xy 72.802786 -23.742624)
			(xy 72.75088 -23.712657) (xy 72.70333 -23.67617) (xy 72.66095 -23.63379) (xy 72.624463 -23.58624)
			(xy 72.594496 -23.534334) (xy 72.57156 -23.478961) (xy 72.556047 -23.421068) (xy 72.548224 -23.361646)
			(xy 70.71351 -23.361646) (xy 70.71438 -23.368258) (xy 70.71487 -23.398226) (xy 70.71438 -23.428194)
			(xy 70.706557 -23.487616) (xy 70.691044 -23.545509) (xy 70.668108 -23.600882) (xy 70.638141 -23.652788)
			(xy 70.601654 -23.700338) (xy 70.559274 -23.742718) (xy 70.511724 -23.779205) (xy 70.459818 -23.809172)
			(xy 70.404445 -23.832108) (xy 70.346552 -23.847621) (xy 70.28713 -23.855444) (xy 70.227194 -23.855444)
			(xy 70.167772 -23.847621) (xy 70.109879 -23.832108) (xy 70.054506 -23.809172) (xy 70.0026 -23.779205)
			(xy 69.95505 -23.742718) (xy 69.91267 -23.700338) (xy 69.876183 -23.652788) (xy 69.846216 -23.600882)
			(xy 69.82328 -23.545509) (xy 69.807767 -23.487616) (xy 69.799944 -23.428194) (xy 69.226581 -23.428194)
			(xy 69.227727 -23.438008) (xy 69.233542 -23.459186) (xy 69.24101 -23.486088) (xy 69.248949 -23.54135)
			(xy 69.248749 -23.59718) (xy 69.240415 -23.652384) (xy 69.224125 -23.705784) (xy 69.200226 -23.75624)
			(xy 69.16923 -23.802675) (xy 69.131798 -23.844097) (xy 69.088728 -23.879621) (xy 69.040942 -23.90849)
			(xy 68.989458 -23.930086) (xy 68.935377 -23.943949) (xy 68.879853 -23.949782) (xy 68.824072 -23.947462)
			(xy 68.769224 -23.937037) (xy 68.716481 -23.91873) (xy 68.666969 -23.892933) (xy 68.621745 -23.860195)
			(xy 68.581775 -23.821216) (xy 68.547912 -23.776828) (xy 68.52088 -23.72798) (xy 68.501255 -23.675713)
			(xy 68.489456 -23.621144) (xy 68.485736 -23.565439) (xy 67.349376 -23.565439) (xy 67.350072 -23.566266)
			(xy 67.382955 -23.618073) (xy 67.40862 -23.67381) (xy 67.426607 -23.732477) (xy 67.436592 -23.793022)
			(xy 67.438397 -23.854357) (xy 67.43199 -23.915384) (xy 67.417485 -23.975007) (xy 67.406774 -24.003762)
			(xy 67.399046 -24.024854) (xy 67.390307 -24.06891) (xy 67.38945 -24.113817) (xy 67.396502 -24.158176)
			(xy 67.411244 -24.200603) (xy 67.433215 -24.239777) (xy 67.461732 -24.274478) (xy 67.495906 -24.303625)
			(xy 67.534672 -24.326309) (xy 67.576822 -24.341823) (xy 67.621044 -24.349685) (xy 67.643502 -24.350218)
			(xy 73.11517 -24.350218) (xy 73.130411 -24.349764) (xy 73.160021 -24.342522) (xy 73.18707 -24.328469)
			(xy 73.210018 -24.308405) (xy 73.227556 -24.283473) (xy 73.233534 -24.269446) (xy 73.243636 -24.244717)
			(xy 73.269762 -24.198122) (xy 73.302132 -24.155628) (xy 73.340113 -24.118064) (xy 73.382963 -24.086166)
			(xy 73.429843 -24.060556) (xy 73.479836 -24.041736) (xy 73.531967 -24.030074) (xy 73.585214 -24.025797)
			(xy 73.638538 -24.02899) (xy 73.690895 -24.039589) (xy 73.741261 -24.057388) (xy 73.788652 -24.082039)
			(xy 73.810622 -24.097234) (xy 73.829725 -24.110255) (xy 73.871582 -24.129872) (xy 73.916299 -24.141586)
			(xy 73.962398 -24.145009) (xy 74.008355 -24.140029) (xy 74.052651 -24.126811) (xy 74.093821 -24.10579)
			(xy 74.130504 -24.077663) (xy 74.161488 -24.043358) (xy 74.185749 -24.00401) (xy 74.19467 -23.98268)
			(xy 74.204948 -23.957577) (xy 74.231579 -23.910319) (xy 74.264634 -23.867311) (xy 74.303449 -23.829419)
			(xy 74.34724 -23.797406) (xy 74.395123 -23.77192) (xy 74.446134 -23.753473) (xy 74.499244 -23.742438)
			(xy 74.553381 -23.739037) (xy 74.607454 -23.743339) (xy 74.660373 -23.755257) (xy 74.711069 -23.774551)
			(xy 74.758522 -23.800832) (xy 74.801773 -23.833569) (xy 74.839951 -23.872102) (xy 74.872286 -23.915655)
			(xy 74.898125 -23.963349) (xy 74.916948 -24.014223) (xy 74.928375 -24.067249) (xy 74.932176 -24.12136)
			(xy 74.928273 -24.175463) (xy 74.916746 -24.228469) (xy 74.897828 -24.279306) (xy 74.871898 -24.326952)
			(xy 74.839481 -24.370444) (xy 74.82078 -24.390096) (xy 74.80551 -24.406133) (xy 74.780205 -24.442465)
			(xy 74.761579 -24.482633) (xy 74.750198 -24.525422) (xy 74.746404 -24.569536) (xy 74.750314 -24.613639)
			(xy 74.761809 -24.656398) (xy 74.78054 -24.696517) (xy 74.805941 -24.732782) (xy 74.821288 -24.748744)
			(xy 74.940922 -24.868378) (xy 75.873102 -24.868378)
		)
		(stroke
			(width 0)
			(type solid)
		)
		(fill yes)
		(layer "B.Cu")
		(net "GND")
	)
	(gr_poly
		(pts
			(xy 45.277532 -161.716974) (xy 45.289664 -161.728435) (xy 45.318543 -161.745144) (xy 45.350766 -161.753795)
			(xy 45.38413 -161.753795) (xy 45.416353 -161.745144) (xy 45.445232 -161.728435) (xy 45.457364 -161.716974)
			(xy 45.548042 -161.626042) (xy 45.663358 -161.626042) (xy 45.686479 -161.625521) (xy 45.731955 -161.617134)
			(xy 45.775167 -161.600666) (xy 45.81469 -161.576659) (xy 45.849222 -161.545903) (xy 45.877627 -161.509412)
			(xy 45.898969 -161.468388) (xy 45.912544 -161.424183) (xy 45.917905 -161.378252) (xy 45.914876 -161.332108)
			(xy 45.909738 -161.309558) (xy 45.901956 -161.280371) (xy 45.893248 -161.220597) (xy 45.89248 -161.160197)
			(xy 45.899667 -161.100221) (xy 45.914682 -161.041712) (xy 45.937265 -160.985688) (xy 45.967024 -160.933122)
			(xy 46.00344 -160.884928) (xy 46.04588 -160.841945) (xy 46.093607 -160.804919) (xy 46.145791 -160.774496)
			(xy 46.201524 -160.751202) (xy 46.259838 -160.735445) (xy 46.319718 -160.727497) (xy 46.380122 -160.727497)
			(xy 46.440002 -160.735445) (xy 46.498316 -160.751202) (xy 46.554049 -160.774496) (xy 46.606233 -160.804919)
			(xy 46.65396 -160.841945) (xy 46.6964 -160.884928) (xy 46.732816 -160.933122) (xy 46.762575 -160.985688)
			(xy 46.785158 -161.041712) (xy 46.800173 -161.100221) (xy 46.80736 -161.160197) (xy 46.806592 -161.220597)
			(xy 46.797884 -161.280371) (xy 46.790102 -161.309558) (xy 46.784898 -161.332105) (xy 46.78181 -161.37827)
			(xy 46.787132 -161.424231) (xy 46.800689 -161.468469) (xy 46.822032 -161.50952) (xy 46.850455 -161.546029)
			(xy 46.88502 -161.576787) (xy 46.924582 -161.600778) (xy 46.967835 -161.617209) (xy 47.013347 -161.625536)
			(xy 47.036482 -161.626042) (xy 50.707798 -161.626042) (xy 50.74158 -161.600642) (xy 50.765424 -161.583338)
			(xy 50.816709 -161.554339) (xy 50.871291 -161.53216) (xy 50.928267 -161.517167) (xy 50.986696 -161.509608)
			(xy 51.045612 -161.509608) (xy 51.104041 -161.517167) (xy 51.161017 -161.53216) (xy 51.215599 -161.554339)
			(xy 51.266884 -161.583338) (xy 51.290728 -161.600642) (xy 51.32451 -161.626042) (xy 53.2257 -161.626042)
			(xy 53.868828 -160.982914) (xy 53.868828 -157.981396) (xy 53.868828 -157.662626) (xy 53.334666 -157.128464)
			(xy 52.950618 -157.128464) (xy 52.767992 -156.945838) (xy 52.746461 -156.927267) (xy 52.707701 -156.885667)
			(xy 52.674389 -156.839587) (xy 52.647039 -156.789738) (xy 52.636166 -156.763466) (xy 52.626514 -156.739082)
			(xy 51.925982 -156.03855) (xy 51.925982 -155.304744) (xy 51.925488 -155.288514) (xy 51.917291 -155.257104)
			(xy 51.901442 -155.228775) (xy 51.878963 -155.205357) (xy 51.851307 -155.188361) (xy 51.820259 -155.178885)
			(xy 51.804062 -155.177744) (xy 51.773613 -155.17604) (xy 51.713533 -155.165567) (xy 51.655376 -155.147211)
			(xy 51.600171 -155.121295) (xy 51.548895 -155.088279) (xy 51.502457 -155.048748) (xy 51.461678 -155.003401)
			(xy 51.427282 -154.953041) (xy 51.399876 -154.89856) (xy 51.379946 -154.840923) (xy 51.367845 -154.78115)
			(xy 51.363788 -154.7203) (xy 51.367846 -154.659449) (xy 51.379946 -154.599676) (xy 51.399876 -154.542039)
			(xy 51.427282 -154.487558) (xy 51.461679 -154.437199) (xy 51.502457 -154.391851) (xy 51.548895 -154.35232)
			(xy 51.600171 -154.319304) (xy 51.655376 -154.293389) (xy 51.713534 -154.275032) (xy 51.773614 -154.26456)
			(xy 51.804062 -154.262836) (xy 51.820272 -154.26171) (xy 51.851355 -154.252279) (xy 51.879045 -154.235298)
			(xy 51.901545 -154.21187) (xy 51.917394 -154.183516) (xy 51.925563 -154.152078) (xy 51.925982 -154.135836)
			(xy 51.925982 -154.034744) (xy 51.925488 -154.018514) (xy 51.917291 -153.987104) (xy 51.901442 -153.958775)
			(xy 51.878963 -153.935357) (xy 51.851307 -153.918361) (xy 51.820259 -153.908885) (xy 51.804062 -153.907744)
			(xy 51.773613 -153.90604) (xy 51.713533 -153.895567) (xy 51.655376 -153.877211) (xy 51.600171 -153.851295)
			(xy 51.548895 -153.818279) (xy 51.502457 -153.778748) (xy 51.461678 -153.733401) (xy 51.427282 -153.683041)
			(xy 51.399876 -153.62856) (xy 51.379946 -153.570923) (xy 51.367845 -153.51115) (xy 51.363788 -153.4503)
			(xy 51.367846 -153.389449) (xy 51.379946 -153.329676) (xy 51.399876 -153.272039) (xy 51.427282 -153.217558)
			(xy 51.461679 -153.167199) (xy 51.502457 -153.121851) (xy 51.548895 -153.08232) (xy 51.600171 -153.049304)
			(xy 51.655376 -153.023389) (xy 51.713534 -153.005032) (xy 51.773614 -152.99456) (xy 51.804062 -152.992836)
			(xy 51.820272 -152.99171) (xy 51.851355 -152.982279) (xy 51.879045 -152.965298) (xy 51.901545 -152.94187)
			(xy 51.917394 -152.913516) (xy 51.925563 -152.882078) (xy 51.925982 -152.865836) (xy 51.925982 -148.739606)
			(xy 51.9049 -148.71827) (xy 51.9049 -147.11299) (xy 51.84521 -147.0533) (xy 49.67478 -147.0533) (xy 49.653099 -147.05375)
			(xy 49.61037 -147.061129) (xy 49.569512 -147.075652) (xy 49.531712 -147.096898) (xy 49.498065 -147.124252)
			(xy 49.469549 -147.156918) (xy 49.44699 -147.19395) (xy 49.431043 -147.234273) (xy 49.42217 -147.276718)
			(xy 49.420629 -147.320052) (xy 49.426464 -147.36302) (xy 49.439507 -147.404374) (xy 49.448974 -147.423886)
			(xy 49.462402 -147.450973) (xy 49.482805 -147.507884) (xy 49.495536 -147.566986) (xy 49.500373 -147.62725)
			(xy 49.497232 -147.687626) (xy 49.486168 -147.747062) (xy 49.467373 -147.804524) (xy 49.441174 -147.859011)
			(xy 49.408029 -147.909573) (xy 49.368513 -147.955329) (xy 49.323317 -147.995484) (xy 49.273226 -148.029337)
			(xy 49.219113 -148.056299) (xy 49.161921 -148.0759) (xy 49.102646 -148.087799) (xy 49.04232 -148.091788)
			(xy 48.981994 -148.087799) (xy 48.922719 -148.0759) (xy 48.865527 -148.056299) (xy 48.811414 -148.029337)
			(xy 48.761323 -147.995484) (xy 48.716127 -147.955329) (xy 48.676611 -147.909573) (xy 48.643466 -147.859011)
			(xy 48.617267 -147.804524) (xy 48.598472 -147.747062) (xy 48.587408 -147.687626) (xy 48.584267 -147.62725)
			(xy 48.589104 -147.566986) (xy 48.601835 -147.507884) (xy 48.622238 -147.450973) (xy 48.635666 -147.423886)
			(xy 48.645231 -147.404411) (xy 48.658307 -147.363045) (xy 48.664168 -147.320058) (xy 48.662641 -147.2767)
			(xy 48.653773 -147.234232) (xy 48.637819 -147.193888) (xy 48.615245 -147.156839) (xy 48.586706 -147.124163)
			(xy 48.553031 -147.09681) (xy 48.515199 -147.075574) (xy 48.47431 -147.061072) (xy 48.431552 -147.053726)
			(xy 48.40986 -147.0533) (xy 45.032422 -147.0533) (xy 44.968922 -147.094956) (xy 44.953936 -147.129754)
			(xy 44.941763 -147.156707) (xy 44.911474 -147.207503) (xy 44.874896 -147.253976) (xy 44.832637 -147.295352)
			(xy 44.785402 -147.330941) (xy 44.733978 -147.36015) (xy 44.679219 -147.382494) (xy 44.62204 -147.397599)
			(xy 44.563391 -147.405216) (xy 44.504249 -147.405216) (xy 44.4456 -147.397599) (xy 44.388421 -147.382494)
			(xy 44.333662 -147.36015) (xy 44.282238 -147.330941) (xy 44.235003 -147.295352) (xy 44.192744 -147.253976)
			(xy 44.156166 -147.207503) (xy 44.125877 -147.156707) (xy 44.113704 -147.129754) (xy 44.098718 -147.094956)
			(xy 44.035218 -147.0533) (xy 43.133264 -147.0533) (xy 42.607738 -147.578826) (xy 42.592837 -147.594358)
			(xy 42.567961 -147.629477) (xy 42.549363 -147.668288) (xy 42.537574 -147.709679) (xy 42.532933 -147.752466)
			(xy 42.535573 -147.795422) (xy 42.545418 -147.837318) (xy 42.562185 -147.876954) (xy 42.585396 -147.913196)
			(xy 42.614385 -147.945006) (xy 42.631106 -147.958556) (xy 42.654875 -147.977742) (xy 42.697611 -148.021388)
			(xy 42.734161 -148.070331) (xy 42.763876 -148.123701) (xy 42.786227 -148.180549) (xy 42.800818 -148.239866)
			(xy 42.807387 -148.300596) (xy 42.80582 -148.36166) (xy 42.803703 -148.374858) (xy 43.340002 -148.374858)
			(xy 43.340002 -148.314922) (xy 43.347825 -148.2555) (xy 43.363338 -148.197607) (xy 43.386274 -148.142234)
			(xy 43.416241 -148.090328) (xy 43.452728 -148.042778) (xy 43.495108 -148.000398) (xy 43.542658 -147.963911)
			(xy 43.594564 -147.933944) (xy 43.649937 -147.911008) (xy 43.70783 -147.895495) (xy 43.767252 -147.887672)
			(xy 43.827188 -147.887672) (xy 43.88661 -147.895495) (xy 43.944503 -147.911008) (xy 43.999876 -147.933944)
			(xy 44.051782 -147.963911) (xy 44.099332 -148.000398) (xy 44.141712 -148.042778) (xy 44.178199 -148.090328)
			(xy 44.208166 -148.142234) (xy 44.231102 -148.197607) (xy 44.246615 -148.2555) (xy 44.254438 -148.314922)
			(xy 44.254928 -148.34489) (xy 44.254438 -148.374858) (xy 44.246615 -148.43428) (xy 44.231102 -148.492173)
			(xy 44.208166 -148.547546) (xy 44.178199 -148.599452) (xy 44.141712 -148.647002) (xy 44.099332 -148.689382)
			(xy 44.051782 -148.725869) (xy 43.999876 -148.755836) (xy 43.944503 -148.778772) (xy 43.88661 -148.794285)
			(xy 43.827188 -148.802108) (xy 43.767252 -148.802108) (xy 43.70783 -148.794285) (xy 43.649937 -148.778772)
			(xy 43.594564 -148.755836) (xy 43.542658 -148.725869) (xy 43.495108 -148.689382) (xy 43.452728 -148.647002)
			(xy 43.416241 -148.599452) (xy 43.386274 -148.547546) (xy 43.363338 -148.492173) (xy 43.347825 -148.43428)
			(xy 43.340002 -148.374858) (xy 42.803703 -148.374858) (xy 42.796144 -148.421974) (xy 42.778531 -148.480464)
			(xy 42.753293 -148.536091) (xy 42.72088 -148.587867) (xy 42.681867 -148.63487) (xy 42.636949 -148.676266)
			(xy 42.586923 -148.711319) (xy 42.532678 -148.739406) (xy 42.47518 -148.760028) (xy 42.415449 -148.772817)
			(xy 42.354548 -148.777547) (xy 42.32402 -148.776436) (xy 42.301045 -148.775635) (xy 42.255433 -148.781343)
			(xy 42.211593 -148.795165) (xy 42.170956 -148.81665) (xy 42.134848 -148.845096) (xy 42.104448 -148.879576)
			(xy 42.080749 -148.918963) (xy 42.064524 -148.961972) (xy 42.056303 -149.007198) (xy 42.055796 -149.030182)
			(xy 42.055796 -149.989286) (xy 42.056289 -150.005942) (xy 42.064908 -150.03812) (xy 42.081561 -150.066971)
			(xy 42.105115 -150.090528) (xy 42.133963 -150.107185) (xy 42.16614 -150.115809) (xy 42.182796 -150.116286)
			(xy 44.008548 -150.116286) (xy 44.030725 -150.115799) (xy 44.074403 -150.108089) (xy 44.116079 -150.092913)
			(xy 44.154487 -150.07073) (xy 44.18846 -150.042216) (xy 44.216966 -150.008236) (xy 44.239139 -149.969823)
			(xy 44.254305 -149.928143) (xy 44.262004 -149.884463) (xy 44.262548 -149.862286) (xy 44.262228 -149.828762)
			(xy 44.269345 -149.762097) (xy 44.285169 -149.696948) (xy 44.309425 -149.634447) (xy 44.341691 -149.575679)
			(xy 44.3611 -149.548342) (xy 44.367196 -149.540214) (xy 44.402502 -149.493224) (xy 44.405296 -149.493224)
			(xy 44.44111 -149.462744) (xy 44.472352 -149.437852) (xy 44.48048 -149.43201) (xy 44.958254 -148.954236)
			(xy 44.974424 -148.938358) (xy 45.009145 -148.909229) (xy 45.027596 -148.89607) (xy 45.051726 -148.879306)
			(xy 45.071792 -148.843492) (xy 45.0785 -148.830698) (xy 45.086556 -148.802963) (xy 45.088162 -148.774126)
			(xy 45.083236 -148.745667) (xy 45.07203 -148.719048) (xy 45.063918 -148.707094) (xy 45.025818 -148.654262)
			(xy 44.992544 -148.640292) (xy 44.965258 -148.628389) (xy 44.913754 -148.598534) (xy 44.866555 -148.562253)
			(xy 44.824459 -148.520159) (xy 44.788176 -148.472962) (xy 44.758319 -148.421459) (xy 44.735391 -148.36652)
			(xy 44.71978 -148.309072) (xy 44.71175 -148.250084) (xy 44.711435 -148.190554) (xy 44.718841 -148.131485)
			(xy 44.733843 -148.073874) (xy 44.756188 -148.018696) (xy 44.785499 -147.96688) (xy 44.82128 -147.919302)
			(xy 44.862929 -147.876764) (xy 44.90974 -147.839986) (xy 44.960926 -147.809588) (xy 45.01562 -147.786082)
			(xy 45.0729 -147.769866) (xy 45.102272 -147.765008) (xy 45.132562 -147.761063) (xy 45.193642 -147.760289)
			(xy 45.254281 -147.767646) (xy 45.313403 -147.783004) (xy 45.369956 -147.80609) (xy 45.422936 -147.836494)
			(xy 45.471401 -147.873675) (xy 45.514489 -147.916973) (xy 45.551435 -147.965617) (xy 45.581581 -148.018744)
			(xy 45.604392 -148.075409) (xy 45.619463 -148.134605) (xy 45.626526 -148.195279) (xy 45.625455 -148.256354)
			(xy 45.616269 -148.316743) (xy 45.602845 -148.36267) (xy 50.136042 -148.36267) (xy 50.140113 -148.307048)
			(xy 50.152239 -148.252611) (xy 50.172162 -148.20052) (xy 50.199458 -148.151885) (xy 50.233544 -148.107742)
			(xy 50.273693 -148.069033) (xy 50.319051 -148.036582) (xy 50.368651 -148.011081) (xy 50.421435 -147.993074)
			(xy 50.476278 -147.982944) (xy 50.532012 -147.980907) (xy 50.587449 -147.987007) (xy 50.641406 -148.001113)
			(xy 50.692735 -148.022925) (xy 50.740341 -148.051979) (xy 50.783209 -148.087654) (xy 50.820426 -148.129191)
			(xy 50.851199 -148.175704) (xy 50.874871 -148.226201) (xy 50.890939 -148.279608) (xy 50.899059 -148.334784)
			(xy 50.899568 -148.36267) (xy 50.899059 -148.390556) (xy 50.890939 -148.445732) (xy 50.874871 -148.499139)
			(xy 50.851199 -148.549636) (xy 50.820426 -148.596149) (xy 50.783209 -148.637686) (xy 50.740341 -148.673361)
			(xy 50.692735 -148.702415) (xy 50.641406 -148.724227) (xy 50.587449 -148.738333) (xy 50.532012 -148.744433)
			(xy 50.476278 -148.742396) (xy 50.421435 -148.732266) (xy 50.368651 -148.714259) (xy 50.319051 -148.688758)
			(xy 50.273693 -148.656307) (xy 50.233544 -148.617598) (xy 50.199458 -148.573455) (xy 50.172162 -148.52482)
			(xy 50.152239 -148.472729) (xy 50.140113 -148.418292) (xy 50.136042 -148.36267) (xy 45.602845 -148.36267)
			(xy 45.599132 -148.375374) (xy 45.574347 -148.431204) (xy 45.542357 -148.483241) (xy 45.523404 -148.507196)
			(xy 45.508953 -148.525886) (xy 45.48654 -148.56747) (xy 45.472199 -148.61248) (xy 45.466424 -148.659365)
			(xy 45.469413 -148.706509) (xy 45.481065 -148.752289) (xy 45.500977 -148.795127) (xy 45.528464 -148.833546)
			(xy 45.562577 -148.866223) (xy 45.582078 -148.87956) (xy 45.609829 -148.89706) (xy 45.661009 -148.938111)
			(xy 45.706482 -148.985406) (xy 45.745491 -149.038158) (xy 45.777388 -149.095491) (xy 45.801643 -149.156452)
			(xy 45.817853 -149.220027) (xy 45.825749 -149.285159) (xy 45.825198 -149.350766) (xy 45.81621 -149.415756)
			(xy 45.798935 -149.47905) (xy 45.77366 -149.539595) (xy 45.740805 -149.596385) (xy 45.700915 -149.648475)
			(xy 45.67809 -149.67204) (xy 45.677074 -149.673056) (xy 45.671994 -149.67839) (xy 45.667676 -149.682708)
			(xy 45.651744 -149.69935) (xy 45.625577 -149.737265) (xy 45.606673 -149.779275) (xy 45.595981 -149.822658)
			(xy 49.514742 -149.822658) (xy 49.514742 -149.762722) (xy 49.522565 -149.7033) (xy 49.538078 -149.645407)
			(xy 49.561014 -149.590034) (xy 49.590981 -149.538128) (xy 49.627468 -149.490578) (xy 49.669848 -149.448198)
			(xy 49.717398 -149.411711) (xy 49.769304 -149.381744) (xy 49.824677 -149.358808) (xy 49.88257 -149.343295)
			(xy 49.941992 -149.335472) (xy 50.001928 -149.335472) (xy 50.06135 -149.343295) (xy 50.119243 -149.358808)
			(xy 50.174616 -149.381744) (xy 50.226522 -149.411711) (xy 50.274072 -149.448198) (xy 50.316452 -149.490578)
			(xy 50.352939 -149.538128) (xy 50.382906 -149.590034) (xy 50.405842 -149.645407) (xy 50.421355 -149.7033)
			(xy 50.429178 -149.762722) (xy 50.429668 -149.79269) (xy 50.429178 -149.822658) (xy 50.421355 -149.88208)
			(xy 50.405842 -149.939973) (xy 50.382906 -149.995346) (xy 50.352939 -150.047252) (xy 50.316452 -150.094802)
			(xy 50.274072 -150.137182) (xy 50.226522 -150.173669) (xy 50.174616 -150.203636) (xy 50.119243 -150.226572)
			(xy 50.06135 -150.242085) (xy 50.001928 -150.249908) (xy 49.941992 -150.249908) (xy 49.88257 -150.242085)
			(xy 49.824677 -150.226572) (xy 49.769304 -150.203636) (xy 49.717398 -150.173669) (xy 49.669848 -150.137182)
			(xy 49.627468 -150.094802) (xy 49.590981 -150.047252) (xy 49.561014 -149.995346) (xy 49.538078 -149.939973)
			(xy 49.522565 -149.88208) (xy 49.514742 -149.822658) (xy 45.595981 -149.822658) (xy 45.595649 -149.824004)
			(xy 45.592868 -149.869987) (xy 45.59842 -149.915719) (xy 45.612124 -149.959701) (xy 45.63353 -150.000492)
			(xy 45.661938 -150.036758) (xy 45.696417 -150.06731) (xy 45.735838 -150.091147) (xy 45.778909 -150.107488)
			(xy 45.82422 -150.1158) (xy 45.847254 -150.116286) (xy 46.325536 -150.116286) (xy 46.352206 -150.089616)
			(xy 48.64354 -150.089616) (xy 48.924464 -150.37054) (xy 48.924464 -150.69947) (xy 48.928528 -150.70328)
			(xy 48.928528 -151.50211) (xy 48.929024 -151.518763) (xy 48.937647 -151.550932) (xy 48.954303 -151.579773)
			(xy 48.977857 -151.60332) (xy 49.006703 -151.619967) (xy 49.038875 -151.628581) (xy 49.055528 -151.62911)
			(xy 49.064672 -151.62911) (xy 49.087947 -151.62497) (xy 49.135014 -151.620515) (xy 49.158652 -151.62022)
			(xy 49.73955 -151.62022) (xy 49.75479 -151.610568) (xy 49.780843 -151.592984) (xy 49.83645 -151.563675)
			(xy 49.895244 -151.541442) (xy 49.95633 -151.526622) (xy 50.018777 -151.519443) (xy 50.081632 -151.520012)
			(xy 50.143938 -151.528322) (xy 50.204745 -151.544246) (xy 50.263127 -151.567541) (xy 50.318193 -151.597852)
			(xy 50.369105 -151.634717) (xy 50.415087 -151.677575) (xy 50.455438 -151.725772) (xy 50.489542 -151.778573)
			(xy 50.51688 -151.835174) (xy 50.537036 -151.894713) (xy 50.549702 -151.956281) (xy 50.554686 -152.018941)
			(xy 50.55191 -152.081737) (xy 50.541418 -152.143713) (xy 50.52337 -152.203924) (xy 50.49804 -152.261452)
			(xy 50.465814 -152.315421) (xy 50.427185 -152.365008) (xy 50.405284 -152.387554) (xy 50.155094 -152.637744)
			(xy 49.998884 -152.637744) (xy 49.982602 -152.638966) (xy 49.95143 -152.648639) (xy 49.923733 -152.665908)
			(xy 49.901327 -152.689642) (xy 49.885679 -152.718285) (xy 49.877815 -152.749963) (xy 49.878248 -152.782599)
			(xy 49.886952 -152.814057) (xy 49.903356 -152.842274) (xy 49.914556 -152.854152) (xy 50.12182 -153.06167)
			(xy 50.373788 -153.313638) (xy 50.395192 -153.335674) (xy 50.433078 -153.384034) (xy 50.464857 -153.436609)
			(xy 50.490067 -153.492632) (xy 50.508341 -153.551285) (xy 50.519411 -153.611712) (xy 50.523116 -153.673034)
			(xy 50.519403 -153.734355) (xy 50.508324 -153.794781) (xy 50.490043 -153.853432) (xy 50.464825 -153.909451)
			(xy 50.433039 -153.962021) (xy 50.395147 -154.010377) (xy 50.373788 -154.032458) (xy 49.898808 -154.507438)
			(xy 49.507902 -154.898598) (xy 49.15027 -154.898598) (xy 49.132619 -154.898402) (xy 49.097408 -154.895857)
			(xy 49.079912 -154.893518) (xy 49.07534 -154.89301) (xy 49.074578 -154.892756) (xy 49.064926 -154.891486)
			(xy 49.055528 -154.891486) (xy 49.03887 -154.891977) (xy 49.006688 -154.900593) (xy 48.977833 -154.917246)
			(xy 48.954272 -154.9408) (xy 48.93761 -154.969649) (xy 48.928983 -155.001828) (xy 48.928528 -155.018486)
			(xy 48.928528 -157.22879) (xy 50.288426 -157.22879) (xy 50.288426 -157.168854) (xy 50.296249 -157.109432)
			(xy 50.311762 -157.051539) (xy 50.334698 -156.996166) (xy 50.364665 -156.94426) (xy 50.401152 -156.89671)
			(xy 50.443532 -156.85433) (xy 50.491082 -156.817843) (xy 50.542988 -156.787876) (xy 50.598361 -156.76494)
			(xy 50.656254 -156.749427) (xy 50.715676 -156.741604) (xy 50.775612 -156.741604) (xy 50.835034 -156.749427)
			(xy 50.892927 -156.76494) (xy 50.9483 -156.787876) (xy 51.000206 -156.817843) (xy 51.047756 -156.85433)
			(xy 51.090136 -156.89671) (xy 51.126623 -156.94426) (xy 51.15659 -156.996166) (xy 51.179526 -157.051539)
			(xy 51.195039 -157.109432) (xy 51.202862 -157.168854) (xy 51.203352 -157.198822) (xy 51.202862 -157.22879)
			(xy 51.195039 -157.288212) (xy 51.179526 -157.346105) (xy 51.15659 -157.401478) (xy 51.126623 -157.453384)
			(xy 51.090136 -157.500934) (xy 51.047756 -157.543314) (xy 51.000206 -157.579801) (xy 50.9483 -157.609768)
			(xy 50.892927 -157.632704) (xy 50.835034 -157.648217) (xy 50.775612 -157.65604) (xy 50.715676 -157.65604)
			(xy 50.656254 -157.648217) (xy 50.598361 -157.632704) (xy 50.542988 -157.609768) (xy 50.491082 -157.579801)
			(xy 50.443532 -157.543314) (xy 50.401152 -157.500934) (xy 50.364665 -157.453384) (xy 50.334698 -157.401478)
			(xy 50.311762 -157.346105) (xy 50.296249 -157.288212) (xy 50.288426 -157.22879) (xy 48.928528 -157.22879)
			(xy 48.928528 -157.62351) (xy 48.929024 -157.640163) (xy 48.937647 -157.672332) (xy 48.954303 -157.701173)
			(xy 48.977857 -157.72472) (xy 49.006703 -157.741367) (xy 49.038875 -157.749981) (xy 49.055528 -157.75051)
			(xy 49.065942 -157.75051) (xy 49.076356 -157.748732) (xy 49.096782 -157.745549) (xy 49.137981 -157.742112)
			(xy 49.158652 -157.741874) (xy 49.493678 -157.741874) (xy 49.916588 -158.165038) (xy 50.278788 -158.527238)
			(xy 50.980322 -158.527238) (xy 50.980322 -158.467302) (xy 50.988145 -158.40788) (xy 51.003658 -158.349987)
			(xy 51.026594 -158.294614) (xy 51.056561 -158.242708) (xy 51.093048 -158.195158) (xy 51.135428 -158.152778)
			(xy 51.182978 -158.116291) (xy 51.234884 -158.086324) (xy 51.290257 -158.063388) (xy 51.34815 -158.047875)
			(xy 51.407572 -158.040052) (xy 51.467508 -158.040052) (xy 51.52693 -158.047875) (xy 51.584823 -158.063388)
			(xy 51.640196 -158.086324) (xy 51.692102 -158.116291) (xy 51.739652 -158.152778) (xy 51.782032 -158.195158)
			(xy 51.818519 -158.242708) (xy 51.848486 -158.294614) (xy 51.871422 -158.349987) (xy 51.886935 -158.40788)
			(xy 51.894758 -158.467302) (xy 51.895248 -158.49727) (xy 51.894758 -158.527238) (xy 51.886935 -158.58666)
			(xy 51.871422 -158.644553) (xy 51.848486 -158.699926) (xy 51.818519 -158.751832) (xy 51.782032 -158.799382)
			(xy 51.739652 -158.841762) (xy 51.692102 -158.878249) (xy 51.640196 -158.908216) (xy 51.584823 -158.931152)
			(xy 51.52693 -158.946665) (xy 51.467508 -158.954488) (xy 51.407572 -158.954488) (xy 51.34815 -158.946665)
			(xy 51.290257 -158.931152) (xy 51.234884 -158.908216) (xy 51.182978 -158.878249) (xy 51.135428 -158.841762)
			(xy 51.093048 -158.799382) (xy 51.056561 -158.751832) (xy 51.026594 -158.699926) (xy 51.003658 -158.644553)
			(xy 50.988145 -158.58666) (xy 50.980322 -158.527238) (xy 50.278788 -158.527238) (xy 50.43043 -158.67888)
			(xy 50.451142 -158.700171) (xy 50.487979 -158.74677) (xy 50.519132 -158.797347) (xy 50.544173 -158.851211)
			(xy 50.553874 -158.879286) (xy 50.563282 -158.909306) (xy 50.57547 -158.971025) (xy 50.579952 -159.033777)
			(xy 50.578766 -159.065214) (xy 50.578066 -159.08698) (xy 50.583216 -159.130221) (xy 50.595661 -159.17195)
			(xy 50.615035 -159.210949) (xy 50.640773 -159.246075) (xy 50.67212 -159.2763) (xy 50.70816 -159.300741)
			(xy 50.747839 -159.318682) (xy 50.789994 -159.329599) (xy 50.833393 -159.333171) (xy 50.855118 -159.33166)
			(xy 50.884877 -159.329442) (xy 50.944504 -159.331816) (xy 51.003318 -159.341917) (xy 51.060321 -159.359574)
			(xy 51.114546 -159.384488) (xy 51.165075 -159.416236) (xy 51.21105 -159.45428) (xy 51.251692 -159.497976)
			(xy 51.286312 -159.546582) (xy 51.314324 -159.599274) (xy 51.335251 -159.655158) (xy 51.34874 -159.713289)
			(xy 51.354562 -159.772679) (xy 51.352618 -159.832322) (xy 51.342941 -159.891207) (xy 51.325694 -159.948335)
			(xy 51.301171 -160.002739) (xy 51.269788 -160.053494) (xy 51.232075 -160.099742) (xy 51.210718 -160.120584)
			(xy 51.189252 -160.140222) (xy 51.142221 -160.174474) (xy 51.091228 -160.202488) (xy 51.037096 -160.223813)
			(xy 50.980697 -160.238105) (xy 50.922942 -160.245132) (xy 50.864761 -160.244782) (xy 50.807095 -160.237061)
			(xy 50.750872 -160.222092) (xy 50.697 -160.200118) (xy 50.646347 -160.171493) (xy 50.599732 -160.136678)
			(xy 50.578512 -160.116774) (xy 50.556922 -160.095211) (xy 50.51906 -160.04736) (xy 50.487885 -159.994906)
			(xy 50.463947 -159.938779) (xy 50.455322 -159.90951) (xy 50.448988 -159.888328) (xy 50.430041 -159.848389)
			(xy 50.404467 -159.812331) (xy 50.373038 -159.781244) (xy 50.336703 -159.756066) (xy 50.296559 -159.737556)
			(xy 50.253816 -159.726275) (xy 50.209766 -159.722562) (xy 50.165738 -159.726529) (xy 50.123062 -159.738057)
			(xy 50.083025 -159.756797) (xy 50.046835 -159.782184) (xy 50.030888 -159.797496) (xy 50.027586 -159.800798)
			(xy 49.15027 -159.800798) (xy 49.116145 -159.800195) (xy 49.04852 -159.790973) (xy 48.982731 -159.772806)
			(xy 48.951134 -159.759904) (xy 48.95088 -159.759904) (xy 48.92675 -159.749744) (xy 48.70323 -159.749744)
			(xy 48.67021 -159.782764) (xy 47.30623 -159.782764) (xy 47.27321 -159.749744) (xy 47.101506 -159.749744)
			(xy 46.74616 -159.394398) (xy 44.872148 -159.394398) (xy 44.699428 -159.567118) (xy 44.699428 -159.874712)
			(xy 44.007278 -160.566862) (xy 44.007278 -160.617658) (xy 48.343802 -160.617658) (xy 48.343802 -160.557722)
			(xy 48.351625 -160.4983) (xy 48.367138 -160.440407) (xy 48.390074 -160.385034) (xy 48.420041 -160.333128)
			(xy 48.456528 -160.285578) (xy 48.498908 -160.243198) (xy 48.546458 -160.206711) (xy 48.598364 -160.176744)
			(xy 48.653737 -160.153808) (xy 48.71163 -160.138295) (xy 48.771052 -160.130472) (xy 48.830988 -160.130472)
			(xy 48.89041 -160.138295) (xy 48.948303 -160.153808) (xy 49.003676 -160.176744) (xy 49.055582 -160.206711)
			(xy 49.103132 -160.243198) (xy 49.134946 -160.275012) (xy 51.668916 -160.275012) (xy 51.668916 -160.215076)
			(xy 51.676739 -160.155654) (xy 51.692252 -160.097761) (xy 51.715188 -160.042388) (xy 51.745155 -159.990482)
			(xy 51.781642 -159.942932) (xy 51.824022 -159.900552) (xy 51.871572 -159.864065) (xy 51.923478 -159.834098)
			(xy 51.978851 -159.811162) (xy 52.036744 -159.795649) (xy 52.096166 -159.787826) (xy 52.156102 -159.787826)
			(xy 52.215524 -159.795649) (xy 52.273417 -159.811162) (xy 52.32879 -159.834098) (xy 52.380696 -159.864065)
			(xy 52.428246 -159.900552) (xy 52.470626 -159.942932) (xy 52.507113 -159.990482) (xy 52.53708 -160.042388)
			(xy 52.560016 -160.097761) (xy 52.575529 -160.155654) (xy 52.583352 -160.215076) (xy 52.583842 -160.245044)
			(xy 52.583352 -160.275012) (xy 52.575529 -160.334434) (xy 52.560016 -160.392327) (xy 52.53708 -160.4477)
			(xy 52.507113 -160.499606) (xy 52.470626 -160.547156) (xy 52.428246 -160.589536) (xy 52.380696 -160.626023)
			(xy 52.32879 -160.65599) (xy 52.273417 -160.678926) (xy 52.215524 -160.694439) (xy 52.156102 -160.702262)
			(xy 52.096166 -160.702262) (xy 52.036744 -160.694439) (xy 51.978851 -160.678926) (xy 51.923478 -160.65599)
			(xy 51.871572 -160.626023) (xy 51.824022 -160.589536) (xy 51.781642 -160.547156) (xy 51.745155 -160.499606)
			(xy 51.715188 -160.4477) (xy 51.692252 -160.392327) (xy 51.676739 -160.334434) (xy 51.668916 -160.275012)
			(xy 49.134946 -160.275012) (xy 49.145512 -160.285578) (xy 49.181999 -160.333128) (xy 49.211966 -160.385034)
			(xy 49.234902 -160.440407) (xy 49.250415 -160.4983) (xy 49.258238 -160.557722) (xy 49.258728 -160.58769)
			(xy 49.258238 -160.617658) (xy 49.250415 -160.67708) (xy 49.234902 -160.734973) (xy 49.211966 -160.790346)
			(xy 49.181999 -160.842252) (xy 49.145512 -160.889802) (xy 49.103132 -160.932182) (xy 49.055582 -160.968669)
			(xy 49.003676 -160.998636) (xy 48.948303 -161.021572) (xy 48.89041 -161.037085) (xy 48.830988 -161.044908)
			(xy 48.771052 -161.044908) (xy 48.71163 -161.037085) (xy 48.653737 -161.021572) (xy 48.598364 -160.998636)
			(xy 48.546458 -160.968669) (xy 48.498908 -160.932182) (xy 48.456528 -160.889802) (xy 48.420041 -160.842252)
			(xy 48.390074 -160.790346) (xy 48.367138 -160.734973) (xy 48.351625 -160.67708) (xy 48.343802 -160.617658)
			(xy 44.007278 -160.617658) (xy 44.007278 -160.755076) (xy 44.302172 -161.04997) (xy 44.610528 -161.04997)
		)
		(stroke
			(width 0)
			(type solid)
		)
		(fill yes)
		(layer "B.Cu")
		(net "P1V05_LAN1")
	)
	(gr_poly
		(pts
			(xy 3.751072 -167.87622) (xy 3.773876 -167.875739) (xy 3.81876 -167.867655) (xy 3.86148 -167.851688)
			(xy 3.900663 -167.828351) (xy 3.93505 -167.798393) (xy 3.963537 -167.762778) (xy 3.985208 -167.722649)
			(xy 3.999367 -167.679297) (xy 4.005559 -167.634113) (xy 4.003585 -167.588549) (xy 3.993508 -167.54407)
			(xy 3.985006 -167.522906) (xy 3.974532 -167.497051) (xy 3.960401 -167.443088) (xy 3.954279 -167.387642)
			(xy 3.956298 -167.331896) (xy 3.966413 -167.277038) (xy 3.98441 -167.224237) (xy 4.009904 -167.174621)
			(xy 4.042352 -167.129247) (xy 4.081062 -167.089081) (xy 4.125209 -167.054982) (xy 4.173852 -167.027675)
			(xy 4.225952 -167.007744) (xy 4.2804 -166.995612) (xy 4.336034 -166.991539) (xy 4.391668 -166.995612)
			(xy 4.446116 -167.007744) (xy 4.498216 -167.027675) (xy 4.546859 -167.054982) (xy 4.591006 -167.089081)
			(xy 4.629716 -167.129247) (xy 4.662164 -167.174621) (xy 4.687658 -167.224237) (xy 4.705655 -167.277038)
			(xy 4.71577 -167.331896) (xy 4.717789 -167.387642) (xy 4.711667 -167.443088) (xy 4.697536 -167.497051)
			(xy 4.687062 -167.522906) (xy 4.678621 -167.544087) (xy 4.668573 -167.588558) (xy 4.666619 -167.634107)
			(xy 4.672821 -167.679275) (xy 4.686981 -167.722611) (xy 4.708644 -167.762727) (xy 4.737115 -167.798336)
			(xy 4.771482 -167.828294) (xy 4.810641 -167.851642) (xy 4.853337 -167.86763) (xy 4.8982 -167.875746)
			(xy 4.920996 -167.87622) (xy 6.066028 -167.87622) (xy 7.23138 -166.710868) (xy 7.23138 -156.05252)
			(xy 7.230912 -156.036872) (xy 7.223274 -156.006522) (xy 7.208477 -155.978945) (xy 7.187412 -155.955799)
			(xy 7.161346 -155.938478) (xy 7.131847 -155.928024) (xy 7.116318 -155.926028) (xy 7.08575 -155.922665)
			(xy 7.025842 -155.908784) (xy 6.968331 -155.887006) (xy 6.914255 -155.857723) (xy 6.864587 -155.821462)
			(xy 6.820221 -155.778877) (xy 6.781958 -155.730734) (xy 6.750487 -155.677902) (xy 6.726373 -155.621331)
			(xy 6.710052 -155.56204) (xy 6.701817 -155.501098) (xy 6.701817 -155.439602) (xy 6.710051 -155.37866)
			(xy 6.726373 -155.31937) (xy 6.750486 -155.262798) (xy 6.781958 -155.209966) (xy 6.820221 -155.161823)
			(xy 6.864586 -155.119238) (xy 6.914254 -155.082978) (xy 6.968331 -155.053694) (xy 7.025841 -155.031916)
			(xy 7.08575 -155.018035) (xy 7.116318 -155.014676) (xy 7.131859 -155.012748) (xy 7.161371 -155.002298)
			(xy 7.187444 -154.984969) (xy 7.208506 -154.961806) (xy 7.223286 -154.934207) (xy 7.23089 -154.903838)
			(xy 7.23138 -154.888184) (xy 7.23138 -153.459942) (xy 7.230958 -153.444897) (xy 7.223902 -153.415647)
			(xy 7.210176 -153.388871) (xy 7.190546 -153.366067) (xy 7.166111 -153.348509) (xy 7.138236 -153.337181)
			(xy 7.12343 -153.334466) (xy 7.096701 -153.329935) (xy 7.044791 -153.314307) (xy 6.995616 -153.291489)
			(xy 6.950166 -153.261938) (xy 6.909358 -153.226252) (xy 6.874012 -153.185147) (xy 6.844842 -153.139453)
			(xy 6.822434 -153.090089) (xy 6.807239 -153.038051) (xy 6.799565 -152.984385) (xy 6.799565 -152.930174)
			(xy 6.80724 -152.876508) (xy 6.822434 -152.82447) (xy 6.844842 -152.775106) (xy 6.874013 -152.729412)
			(xy 6.909359 -152.688307) (xy 6.950167 -152.652621) (xy 6.995617 -152.623071) (xy 7.044792 -152.600252)
			(xy 7.096703 -152.584625) (xy 7.12343 -152.580086) (xy 7.138239 -152.577404) (xy 7.166098 -152.566037)
			(xy 7.19052 -152.548464) (xy 7.210149 -152.52566) (xy 7.223892 -152.498894) (xy 7.230986 -152.469653)
			(xy 7.23138 -152.45461) (xy 7.23138 -150.880064) (xy 7.230917 -150.864073) (xy 7.222951 -150.8331)
			(xy 7.20753 -150.805083) (xy 7.185623 -150.781783) (xy 7.158607 -150.764666) (xy 7.128183 -150.754809)
			(xy 7.112254 -150.753318) (xy 7.082288 -150.750994) (xy 7.023298 -150.739474) (xy 6.966323 -150.720334)
			(xy 6.912342 -150.693903) (xy 6.862284 -150.660636) (xy 6.817009 -150.621104) (xy 6.777297 -150.575987)
			(xy 6.74383 -150.526062) (xy 6.717184 -150.472187) (xy 6.697817 -150.415289) (xy 6.686061 -150.356345)
			(xy 6.68212 -150.29637) (xy 6.686061 -150.236395) (xy 6.697817 -150.177451) (xy 6.717184 -150.120553)
			(xy 6.74383 -150.066678) (xy 6.777297 -150.016753) (xy 6.817009 -149.971636) (xy 6.862283 -149.932105)
			(xy 6.912341 -149.898837) (xy 6.966322 -149.872406) (xy 7.023298 -149.853266) (xy 7.082288 -149.841746)
			(xy 7.112254 -149.839426) (xy 7.128189 -149.837979) (xy 7.158618 -149.828117) (xy 7.185635 -149.810993)
			(xy 7.207541 -149.787683) (xy 7.222957 -149.759656) (xy 7.230913 -149.728674) (xy 7.23138 -149.71268)
			(xy 7.23138 -136.299194) (xy 5.62864 -134.696454) (xy 5.62864 -105.826052) (xy 9.767316 -101.687376)
			(xy 12.65174 -101.687376) (xy 14.605 -99.734116) (xy 14.605 -98.019362) (xy 14.04874 -97.463102)
			(xy 2.146046 -97.463102) (xy 1.61798 -97.991168) (xy 1.61798 -139.797637) (xy 4.558888 -139.797637)
			(xy 4.559652 -139.742648) (xy 4.568304 -139.688339) (xy 4.584662 -139.635834) (xy 4.60839 -139.586222)
			(xy 4.638994 -139.540531) (xy 4.675841 -139.499706) (xy 4.718167 -139.464595) (xy 4.765096 -139.435924)
			(xy 4.790186 -139.424664) (xy 4.811498 -139.414955) (xy 4.850436 -139.388943) (xy 4.883949 -139.356237)
			(xy 4.910902 -139.317944) (xy 4.930384 -139.275362) (xy 4.941734 -139.229931) (xy 4.944569 -139.18319)
			(xy 4.938792 -139.13672) (xy 4.924599 -139.092096) (xy 4.90247 -139.050827) (xy 4.88823 -139.032234)
			(xy 4.869503 -139.008101) (xy 4.837938 -138.955803) (xy 4.813611 -138.899771) (xy 4.796953 -138.841001)
			(xy 4.788261 -138.780537) (xy 4.78769 -138.719455) (xy 4.795249 -138.658839) (xy 4.810805 -138.599767)
			(xy 4.83408 -138.54329) (xy 4.864661 -138.490411) (xy 4.902004 -138.44207) (xy 4.945446 -138.399126)
			(xy 4.994215 -138.362342) (xy 5.047443 -138.332373) (xy 5.104185 -138.309751) (xy 5.163432 -138.294877)
			(xy 5.224131 -138.288018) (xy 5.285203 -138.289293) (xy 5.345562 -138.298682) (xy 5.404136 -138.316016)
			(xy 5.459884 -138.340988) (xy 5.511815 -138.373153) (xy 5.559005 -138.411941) (xy 5.600616 -138.456662)
			(xy 5.635908 -138.50652) (xy 5.664254 -138.56063) (xy 5.685151 -138.61803) (xy 5.698226 -138.677699)
			(xy 5.703248 -138.738578) (xy 5.700126 -138.799583) (xy 5.688917 -138.859631) (xy 5.66982 -138.917655)
			(xy 5.643175 -138.972622) (xy 5.609453 -139.023556) (xy 5.569257 -139.069552) (xy 5.523299 -139.109792)
			(xy 5.472396 -139.143561) (xy 5.417454 -139.170259) (xy 5.38861 -139.180316) (xy 5.366552 -139.188214)
			(xy 5.325516 -139.210805) (xy 5.289313 -139.240533) (xy 5.25917 -139.276389) (xy 5.236106 -139.317162)
			(xy 5.220902 -139.361469) (xy 5.214073 -139.407813) (xy 5.21585 -139.454623) (xy 5.226173 -139.500315)
			(xy 5.244692 -139.543343) (xy 5.257292 -139.563094) (xy 5.2722 -139.586204) (xy 5.29593 -139.635815)
			(xy 5.312291 -139.688318) (xy 5.320946 -139.742627) (xy 5.321713 -139.797615) (xy 5.314578 -139.852145)
			(xy 5.299689 -139.905084) (xy 5.277353 -139.955338) (xy 5.248033 -140.001864) (xy 5.212338 -140.0437)
			(xy 5.171006 -140.079976) (xy 5.124894 -140.109944) (xy 5.074958 -140.13298) (xy 5.022232 -140.148609)
			(xy 4.967808 -140.156506) (xy 4.912814 -140.156507) (xy 4.858389 -140.148614) (xy 4.805662 -140.132988)
			(xy 4.755724 -140.109954) (xy 4.709611 -140.079989) (xy 4.668277 -140.043715) (xy 4.632579 -140.001882)
			(xy 4.603257 -139.955357) (xy 4.580919 -139.905104) (xy 4.566026 -139.852165) (xy 4.558888 -139.797637)
			(xy 1.61798 -139.797637) (xy 1.61798 -141.204946) (xy 4.711682 -141.204946) (xy 4.711682 -141.14501)
			(xy 4.719505 -141.085588) (xy 4.735018 -141.027695) (xy 4.757954 -140.972322) (xy 4.787921 -140.920416)
			(xy 4.824408 -140.872866) (xy 4.866788 -140.830486) (xy 4.914338 -140.793999) (xy 4.966244 -140.764032)
			(xy 5.021617 -140.741096) (xy 5.07951 -140.725583) (xy 5.138932 -140.71776) (xy 5.198868 -140.71776)
			(xy 5.25829 -140.725583) (xy 5.316183 -140.741096) (xy 5.371556 -140.764032) (xy 5.423462 -140.793999)
			(xy 5.471012 -140.830486) (xy 5.513392 -140.872866) (xy 5.549879 -140.920416) (xy 5.579846 -140.972322)
			(xy 5.602782 -141.027695) (xy 5.618295 -141.085588) (xy 5.626118 -141.14501) (xy 5.626608 -141.174978)
			(xy 5.626118 -141.204946) (xy 5.618295 -141.264368) (xy 5.602782 -141.322261) (xy 5.579846 -141.377634)
			(xy 5.549879 -141.42954) (xy 5.513392 -141.47709) (xy 5.471012 -141.51947) (xy 5.423462 -141.555957)
			(xy 5.371556 -141.585924) (xy 5.316183 -141.60886) (xy 5.25829 -141.624373) (xy 5.198868 -141.632196)
			(xy 5.138932 -141.632196) (xy 5.07951 -141.624373) (xy 5.021617 -141.60886) (xy 4.966244 -141.585924)
			(xy 4.914338 -141.555957) (xy 4.866788 -141.51947) (xy 4.824408 -141.47709) (xy 4.787921 -141.42954)
			(xy 4.757954 -141.377634) (xy 4.735018 -141.322261) (xy 4.719505 -141.264368) (xy 4.711682 -141.204946)
			(xy 1.61798 -141.204946) (xy 1.61798 -144.027902) (xy 3.657582 -144.027902) (xy 3.657582 -143.967966)
			(xy 3.665405 -143.908544) (xy 3.680918 -143.850651) (xy 3.703854 -143.795278) (xy 3.733821 -143.743372)
			(xy 3.770308 -143.695822) (xy 3.812688 -143.653442) (xy 3.860238 -143.616955) (xy 3.912144 -143.586988)
			(xy 3.967517 -143.564052) (xy 4.02541 -143.548539) (xy 4.084832 -143.540716) (xy 4.144768 -143.540716)
			(xy 4.20419 -143.548539) (xy 4.262083 -143.564052) (xy 4.317456 -143.586988) (xy 4.369362 -143.616955)
			(xy 4.416912 -143.653442) (xy 4.459292 -143.695822) (xy 4.495779 -143.743372) (xy 4.525746 -143.795278)
			(xy 4.548682 -143.850651) (xy 4.564195 -143.908544) (xy 4.572018 -143.967966) (xy 4.572508 -143.997934)
			(xy 4.572018 -144.027902) (xy 4.564195 -144.087324) (xy 4.548682 -144.145217) (xy 4.525746 -144.20059)
			(xy 4.495779 -144.252496) (xy 4.459292 -144.300046) (xy 4.429176 -144.330162) (xy 5.539722 -144.330162)
			(xy 5.539722 -144.270226) (xy 5.547545 -144.210804) (xy 5.563058 -144.152911) (xy 5.585994 -144.097538)
			(xy 5.615961 -144.045632) (xy 5.652448 -143.998082) (xy 5.694828 -143.955702) (xy 5.742378 -143.919215)
			(xy 5.794284 -143.889248) (xy 5.849657 -143.866312) (xy 5.90755 -143.850799) (xy 5.966972 -143.842976)
			(xy 6.026908 -143.842976) (xy 6.08633 -143.850799) (xy 6.144223 -143.866312) (xy 6.199596 -143.889248)
			(xy 6.251502 -143.919215) (xy 6.299052 -143.955702) (xy 6.341432 -143.998082) (xy 6.377919 -144.045632)
			(xy 6.407886 -144.097538) (xy 6.430822 -144.152911) (xy 6.446335 -144.210804) (xy 6.454158 -144.270226)
			(xy 6.454648 -144.300194) (xy 6.454158 -144.330162) (xy 6.446335 -144.389584) (xy 6.430822 -144.447477)
			(xy 6.407886 -144.50285) (xy 6.377919 -144.554756) (xy 6.341432 -144.602306) (xy 6.299052 -144.644686)
			(xy 6.251502 -144.681173) (xy 6.199596 -144.71114) (xy 6.144223 -144.734076) (xy 6.08633 -144.749589)
			(xy 6.026908 -144.757412) (xy 5.966972 -144.757412) (xy 5.90755 -144.749589) (xy 5.849657 -144.734076)
			(xy 5.794284 -144.71114) (xy 5.742378 -144.681173) (xy 5.694828 -144.644686) (xy 5.652448 -144.602306)
			(xy 5.615961 -144.554756) (xy 5.585994 -144.50285) (xy 5.563058 -144.447477) (xy 5.547545 -144.389584)
			(xy 5.539722 -144.330162) (xy 4.429176 -144.330162) (xy 4.416912 -144.342426) (xy 4.369362 -144.378913)
			(xy 4.317456 -144.40888) (xy 4.262083 -144.431816) (xy 4.20419 -144.447329) (xy 4.144768 -144.455152)
			(xy 4.084832 -144.455152) (xy 4.02541 -144.447329) (xy 3.967517 -144.431816) (xy 3.912144 -144.40888)
			(xy 3.860238 -144.378913) (xy 3.812688 -144.342426) (xy 3.770308 -144.300046) (xy 3.733821 -144.252496)
			(xy 3.703854 -144.20059) (xy 3.680918 -144.145217) (xy 3.665405 -144.087324) (xy 3.657582 -144.027902)
			(xy 1.61798 -144.027902) (xy 1.61798 -145.303494) (xy 4.433822 -145.303494) (xy 4.437893 -145.247872)
			(xy 4.450019 -145.193435) (xy 4.469942 -145.141344) (xy 4.497238 -145.092709) (xy 4.531324 -145.048566)
			(xy 4.571473 -145.009857) (xy 4.616831 -144.977406) (xy 4.666431 -144.951905) (xy 4.719215 -144.933898)
			(xy 4.774058 -144.923768) (xy 4.829792 -144.921731) (xy 4.885229 -144.927831) (xy 4.939186 -144.941937)
			(xy 4.990515 -144.963749) (xy 5.038121 -144.992803) (xy 5.080989 -145.028478) (xy 5.118206 -145.070015)
			(xy 5.148979 -145.116528) (xy 5.172651 -145.167025) (xy 5.188719 -145.220432) (xy 5.196839 -145.275608)
			(xy 5.197348 -145.303494) (xy 5.196839 -145.33138) (xy 5.188719 -145.386556) (xy 5.172651 -145.439963)
			(xy 5.148979 -145.49046) (xy 5.118206 -145.536973) (xy 5.080989 -145.57851) (xy 5.038121 -145.614185)
			(xy 4.990515 -145.643239) (xy 4.939186 -145.665051) (xy 4.885229 -145.679157) (xy 4.829792 -145.685257)
			(xy 4.774058 -145.68322) (xy 4.719215 -145.67309) (xy 4.666431 -145.655083) (xy 4.616831 -145.629582)
			(xy 4.571473 -145.597131) (xy 4.531324 -145.558422) (xy 4.497238 -145.514279) (xy 4.469942 -145.465644)
			(xy 4.450019 -145.413553) (xy 4.437893 -145.359116) (xy 4.433822 -145.303494) (xy 1.61798 -145.303494)
			(xy 1.61798 -146.919188) (xy 4.158486 -146.919188) (xy 4.162557 -146.863566) (xy 4.174683 -146.809129)
			(xy 4.194606 -146.757038) (xy 4.221902 -146.708403) (xy 4.255988 -146.66426) (xy 4.296137 -146.625551)
			(xy 4.341495 -146.5931) (xy 4.391095 -146.567599) (xy 4.443879 -146.549592) (xy 4.498722 -146.539462)
			(xy 4.554456 -146.537425) (xy 4.609893 -146.543525) (xy 4.66385 -146.557631) (xy 4.715179 -146.579443)
			(xy 4.762785 -146.608497) (xy 4.805653 -146.644172) (xy 4.84287 -146.685709) (xy 4.873643 -146.732222)
			(xy 4.897315 -146.782719) (xy 4.913383 -146.836126) (xy 4.921503 -146.891302) (xy 4.922012 -146.919188)
			(xy 4.921503 -146.947074) (xy 4.913383 -147.00225) (xy 4.897315 -147.055657) (xy 4.873643 -147.106154)
			(xy 4.84287 -147.152667) (xy 4.805653 -147.194204) (xy 4.762785 -147.229879) (xy 4.715179 -147.258933)
			(xy 4.66385 -147.280745) (xy 4.609893 -147.294851) (xy 4.554456 -147.300951) (xy 4.498722 -147.298914)
			(xy 4.443879 -147.288784) (xy 4.391095 -147.270777) (xy 4.341495 -147.245276) (xy 4.296137 -147.212825)
			(xy 4.255988 -147.174116) (xy 4.221902 -147.129973) (xy 4.194606 -147.081338) (xy 4.174683 -147.029247)
			(xy 4.162557 -146.97481) (xy 4.158486 -146.919188) (xy 1.61798 -146.919188) (xy 1.61798 -150.357548)
			(xy 3.049578 -150.357548) (xy 3.052851 -150.302413) (xy 3.064041 -150.248326) (xy 3.082914 -150.196418)
			(xy 3.109075 -150.147775) (xy 3.141977 -150.103412) (xy 3.180933 -150.064257) (xy 3.225128 -150.03113)
			(xy 3.273638 -150.004722) (xy 3.325449 -149.985586) (xy 3.379478 -149.974121) (xy 3.434596 -149.970568)
			(xy 3.489651 -149.975) (xy 3.54349 -149.987325) (xy 3.59499 -150.007285) (xy 3.643073 -150.034463)
			(xy 3.686733 -150.068291) (xy 3.72506 -150.108062) (xy 3.75725 -150.152944) (xy 3.770376 -150.177246)
			(xy 3.781425 -150.197507) (xy 3.809713 -150.233965) (xy 3.844116 -150.264718) (xy 3.883505 -150.288757)
			(xy 3.926587 -150.305291) (xy 3.971945 -150.313778) (xy 4.018089 -150.313939) (xy 4.063505 -150.305768)
			(xy 4.106701 -150.289534) (xy 4.126738 -150.278084) (xy 4.150668 -150.264291) (xy 4.201629 -150.242992)
			(xy 4.255128 -150.229265) (xy 4.310048 -150.223397) (xy 4.36524 -150.225509) (xy 4.41955 -150.235559)
			(xy 4.471844 -150.253336) (xy 4.521027 -150.278468) (xy 4.566072 -150.310429) (xy 4.606038 -150.348553)
			(xy 4.640087 -150.392041) (xy 4.66751 -150.439985) (xy 4.687732 -150.491383) (xy 4.700331 -150.545159)
			(xy 4.705043 -150.60019) (xy 4.70177 -150.655326) (xy 4.69058 -150.709413) (xy 4.671708 -150.761321)
			(xy 4.645547 -150.809965) (xy 4.612645 -150.854328) (xy 4.573689 -150.893482) (xy 4.529494 -150.92661)
			(xy 4.480984 -150.953018) (xy 4.429173 -150.972155) (xy 4.375143 -150.98362) (xy 4.320025 -150.987173)
			(xy 4.264971 -150.982741) (xy 4.211131 -150.970417) (xy 4.159631 -150.950457) (xy 4.111548 -150.923279)
			(xy 4.067887 -150.889451) (xy 4.029561 -150.84968) (xy 3.99737 -150.804798) (xy 3.984244 -150.780496)
			(xy 3.97316 -150.760255) (xy 3.944879 -150.723795) (xy 3.910482 -150.693038) (xy 3.871098 -150.668996)
			(xy 3.828021 -150.652459) (xy 3.782666 -150.643969) (xy 3.736524 -150.643806) (xy 3.691111 -150.651975)
			(xy 3.647918 -150.668208) (xy 3.627882 -150.679658) (xy 3.603951 -150.693449) (xy 3.55299 -150.714747)
			(xy 3.499491 -150.728474) (xy 3.444571 -150.734343) (xy 3.389379 -150.73223) (xy 3.335069 -150.72218)
			(xy 3.282775 -150.704403) (xy 3.233592 -150.679271) (xy 3.188547 -150.647309) (xy 3.148582 -150.609186)
			(xy 3.114533 -150.565697) (xy 3.08711 -150.517753) (xy 3.066889 -150.466356) (xy 3.05429 -150.412579)
			(xy 3.049578 -150.357548) (xy 1.61798 -150.357548) (xy 1.61798 -151.331168) (xy 5.175756 -151.331168)
			(xy 5.179827 -151.275546) (xy 5.191953 -151.221109) (xy 5.211876 -151.169018) (xy 5.239172 -151.120383)
			(xy 5.273258 -151.07624) (xy 5.313407 -151.037531) (xy 5.358765 -151.00508) (xy 5.408365 -150.979579)
			(xy 5.461149 -150.961572) (xy 5.515992 -150.951442) (xy 5.571726 -150.949405) (xy 5.627163 -150.955505)
			(xy 5.68112 -150.969611) (xy 5.732449 -150.991423) (xy 5.780055 -151.020477) (xy 5.822923 -151.056152)
			(xy 5.86014 -151.097689) (xy 5.890913 -151.144202) (xy 5.914585 -151.194699) (xy 5.930653 -151.248106)
			(xy 5.938773 -151.303282) (xy 5.939282 -151.331168) (xy 5.938773 -151.359054) (xy 5.930653 -151.41423)
			(xy 5.914585 -151.467637) (xy 5.890913 -151.518134) (xy 5.86014 -151.564647) (xy 5.822923 -151.606184)
			(xy 5.780055 -151.641859) (xy 5.732449 -151.670913) (xy 5.68112 -151.692725) (xy 5.627163 -151.706831)
			(xy 5.571726 -151.712931) (xy 5.515992 -151.710894) (xy 5.461149 -151.700764) (xy 5.408365 -151.682757)
			(xy 5.358765 -151.657256) (xy 5.313407 -151.624805) (xy 5.273258 -151.586096) (xy 5.239172 -151.541953)
			(xy 5.211876 -151.493318) (xy 5.191953 -151.441227) (xy 5.179827 -151.38679) (xy 5.175756 -151.331168)
			(xy 1.61798 -151.331168) (xy 1.61798 -152.897078) (xy 3.300982 -152.897078) (xy 3.305053 -152.841456)
			(xy 3.317179 -152.787019) (xy 3.337102 -152.734928) (xy 3.364398 -152.686293) (xy 3.398484 -152.64215)
			(xy 3.438633 -152.603441) (xy 3.483991 -152.57099) (xy 3.533591 -152.545489) (xy 3.586375 -152.527482)
			(xy 3.641218 -152.517352) (xy 3.696952 -152.515315) (xy 3.752389 -152.521415) (xy 3.806346 -152.535521)
			(xy 3.857675 -152.557333) (xy 3.905281 -152.586387) (xy 3.948149 -152.622062) (xy 3.985366 -152.663599)
			(xy 4.016139 -152.710112) (xy 4.039811 -152.760609) (xy 4.055879 -152.814016) (xy 4.063999 -152.869192)
			(xy 4.064508 -152.897078) (xy 4.063999 -152.924964) (xy 4.055879 -152.98014) (xy 4.039811 -153.033547)
			(xy 4.016139 -153.084044) (xy 3.985366 -153.130557) (xy 3.948149 -153.172094) (xy 3.905281 -153.207769)
			(xy 3.857675 -153.236823) (xy 3.806346 -153.258635) (xy 3.752389 -153.272741) (xy 3.696952 -153.278841)
			(xy 3.641218 -153.276804) (xy 3.586375 -153.266674) (xy 3.533591 -153.248667) (xy 3.483991 -153.223166)
			(xy 3.438633 -153.190715) (xy 3.398484 -153.152006) (xy 3.364398 -153.107863) (xy 3.337102 -153.059228)
			(xy 3.317179 -153.007137) (xy 3.305053 -152.9527) (xy 3.300982 -152.897078) (xy 1.61798 -152.897078)
			(xy 1.61798 -155.979913) (xy 3.440717 -155.979913) (xy 3.446223 -155.920217) (xy 3.459477 -155.861751)
			(xy 3.480251 -155.805516) (xy 3.50819 -155.752475) (xy 3.542815 -155.703537) (xy 3.583534 -155.659538)
			(xy 3.606292 -155.640024) (xy 3.623992 -155.624617) (xy 3.65397 -155.588522) (xy 3.676822 -155.547543)
			(xy 3.691773 -155.503069) (xy 3.698315 -155.456607) (xy 3.696228 -155.409733) (xy 3.68558 -155.364037)
			(xy 3.67665 -155.342336) (xy 3.666106 -155.317199) (xy 3.65151 -155.26468) (xy 3.644537 -155.210619)
			(xy 3.645328 -155.156115) (xy 3.653869 -155.102279) (xy 3.669984 -155.050206) (xy 3.693346 -155.000956)
			(xy 3.723479 -154.955533) (xy 3.759769 -154.91486) (xy 3.801479 -154.879766) (xy 3.847759 -154.850966)
			(xy 3.897666 -154.829045) (xy 3.950185 -154.814449) (xy 4.004247 -154.807477) (xy 4.058751 -154.808269)
			(xy 4.112587 -154.81681) (xy 4.16466 -154.832926) (xy 4.213909 -154.856288) (xy 4.259332 -154.886422)
			(xy 4.300004 -154.922713) (xy 4.335097 -154.964424) (xy 4.363897 -155.010704) (xy 4.385817 -155.060611)
			(xy 4.400412 -155.113131) (xy 4.407384 -155.167193) (xy 4.406591 -155.221696) (xy 4.398049 -155.275532)
			(xy 4.381932 -155.327605) (xy 4.358569 -155.376854) (xy 4.328435 -155.422276) (xy 4.310634 -155.44292)
			(xy 4.295438 -155.460773) (xy 4.271194 -155.500892) (xy 4.25472 -155.544778) (xy 4.246576 -155.590942)
			(xy 4.247038 -155.637816) (xy 4.256091 -155.683809) (xy 4.273427 -155.727362) (xy 4.285488 -155.747466)
			(xy 4.301112 -155.773051) (xy 4.326262 -155.82747) (xy 4.344092 -155.884706) (xy 4.354295 -155.943781)
			(xy 4.356698 -156.003682) (xy 4.351258 -156.063384) (xy 4.33807 -156.121865) (xy 4.317359 -156.178123)
			(xy 4.289479 -156.231195) (xy 4.254908 -156.280173) (xy 4.214238 -156.324217) (xy 4.168165 -156.362573)
			(xy 4.117479 -156.394586) (xy 4.063046 -156.419706) (xy 4.005799 -156.437504) (xy 3.946719 -156.447674)
			(xy 3.886817 -156.450043) (xy 3.827117 -156.444571) (xy 3.768644 -156.43135) (xy 3.712398 -156.410607)
			(xy 3.659341 -156.382698) (xy 3.610383 -156.348099) (xy 3.566362 -156.307405) (xy 3.528031 -156.261311)
			(xy 3.496046 -156.210606) (xy 3.470957 -156.15616) (xy 3.453191 -156.098903) (xy 3.443053 -156.039817)
			(xy 3.440717 -155.979913) (xy 1.61798 -155.979913) (xy 1.61798 -156.990792) (xy 2.585702 -156.990792)
			(xy 2.585702 -156.930856) (xy 2.593525 -156.871434) (xy 2.609038 -156.813541) (xy 2.631974 -156.758168)
			(xy 2.661941 -156.706262) (xy 2.698428 -156.658712) (xy 2.740808 -156.616332) (xy 2.788358 -156.579845)
			(xy 2.840264 -156.549878) (xy 2.895637 -156.526942) (xy 2.95353 -156.511429) (xy 3.012952 -156.503606)
			(xy 3.072888 -156.503606) (xy 3.13231 -156.511429) (xy 3.190203 -156.526942) (xy 3.245576 -156.549878)
			(xy 3.297482 -156.579845) (xy 3.345032 -156.616332) (xy 3.387412 -156.658712) (xy 3.423899 -156.706262)
			(xy 3.453866 -156.758168) (xy 3.476802 -156.813541) (xy 3.492315 -156.871434) (xy 3.500138 -156.930856)
			(xy 3.500628 -156.960824) (xy 3.500138 -156.990792) (xy 3.492315 -157.050214) (xy 3.476802 -157.108107)
			(xy 3.453866 -157.16348) (xy 3.423899 -157.215386) (xy 3.387412 -157.262936) (xy 3.345032 -157.305316)
			(xy 3.297482 -157.341803) (xy 3.245576 -157.37177) (xy 3.190203 -157.394706) (xy 3.13231 -157.410219)
			(xy 3.072888 -157.418042) (xy 3.012952 -157.418042) (xy 2.95353 -157.410219) (xy 2.895637 -157.394706)
			(xy 2.840264 -157.37177) (xy 2.788358 -157.341803) (xy 2.740808 -157.305316) (xy 2.698428 -157.262936)
			(xy 2.661941 -157.215386) (xy 2.631974 -157.16348) (xy 2.609038 -157.108107) (xy 2.593525 -157.050214)
			(xy 2.585702 -156.990792) (xy 1.61798 -156.990792) (xy 1.61798 -159.617406) (xy 3.238482 -159.617406)
			(xy 3.238482 -159.55747) (xy 3.246305 -159.498048) (xy 3.261818 -159.440155) (xy 3.284754 -159.384782)
			(xy 3.314721 -159.332876) (xy 3.351208 -159.285326) (xy 3.393588 -159.242946) (xy 3.441138 -159.206459)
			(xy 3.493044 -159.176492) (xy 3.548417 -159.153556) (xy 3.60631 -159.138043) (xy 3.665732 -159.13022)
			(xy 3.725668 -159.13022) (xy 3.78509 -159.138043) (xy 3.842983 -159.153556) (xy 3.898356 -159.176492)
			(xy 3.950262 -159.206459) (xy 3.997812 -159.242946) (xy 4.040192 -159.285326) (xy 4.076679 -159.332876)
			(xy 4.106646 -159.384782) (xy 4.129582 -159.440155) (xy 4.145095 -159.498048) (xy 4.152918 -159.55747)
			(xy 4.153408 -159.587438) (xy 4.152918 -159.617406) (xy 4.145095 -159.676828) (xy 4.129582 -159.734721)
			(xy 4.106646 -159.790094) (xy 4.076679 -159.842) (xy 4.040192 -159.88955) (xy 3.997812 -159.93193)
			(xy 3.950262 -159.968417) (xy 3.898356 -159.998384) (xy 3.842983 -160.02132) (xy 3.78509 -160.036833)
			(xy 3.725668 -160.044656) (xy 3.665732 -160.044656) (xy 3.60631 -160.036833) (xy 3.548417 -160.02132)
			(xy 3.493044 -159.998384) (xy 3.441138 -159.968417) (xy 3.393588 -159.93193) (xy 3.351208 -159.88955)
			(xy 3.314721 -159.842) (xy 3.284754 -159.790094) (xy 3.261818 -159.734721) (xy 3.246305 -159.676828)
			(xy 3.238482 -159.617406) (xy 1.61798 -159.617406) (xy 1.61798 -160.423856) (xy 1.904982 -160.423856)
			(xy 1.904982 -160.36392) (xy 1.912805 -160.304498) (xy 1.928318 -160.246605) (xy 1.951254 -160.191232)
			(xy 1.981221 -160.139326) (xy 2.017708 -160.091776) (xy 2.060088 -160.049396) (xy 2.107638 -160.012909)
			(xy 2.159544 -159.982942) (xy 2.214917 -159.960006) (xy 2.27281 -159.944493) (xy 2.332232 -159.93667)
			(xy 2.392168 -159.93667) (xy 2.45159 -159.944493) (xy 2.509483 -159.960006) (xy 2.564856 -159.982942)
			(xy 2.616762 -160.012909) (xy 2.664312 -160.049396) (xy 2.706692 -160.091776) (xy 2.743179 -160.139326)
			(xy 2.773146 -160.191232) (xy 2.796082 -160.246605) (xy 2.811595 -160.304498) (xy 2.819418 -160.36392)
			(xy 2.819908 -160.393888) (xy 2.819418 -160.423856) (xy 2.811595 -160.483278) (xy 2.796082 -160.541171)
			(xy 2.773146 -160.596544) (xy 2.743179 -160.64845) (xy 2.706692 -160.696) (xy 2.664312 -160.73838)
			(xy 2.616762 -160.774867) (xy 2.564856 -160.804834) (xy 2.509483 -160.82777) (xy 2.45159 -160.843283)
			(xy 2.392168 -160.851106) (xy 2.332232 -160.851106) (xy 2.27281 -160.843283) (xy 2.214917 -160.82777)
			(xy 2.159544 -160.804834) (xy 2.107638 -160.774867) (xy 2.060088 -160.73838) (xy 2.017708 -160.696)
			(xy 1.981221 -160.64845) (xy 1.951254 -160.596544) (xy 1.928318 -160.541171) (xy 1.912805 -160.483278)
			(xy 1.904982 -160.423856) (xy 1.61798 -160.423856) (xy 1.61798 -161.275772) (xy 3.04976 -161.275772)
			(xy 3.04976 -161.215836) (xy 3.057583 -161.156414) (xy 3.073096 -161.098521) (xy 3.096032 -161.043148)
			(xy 3.125999 -160.991242) (xy 3.162486 -160.943692) (xy 3.204866 -160.901312) (xy 3.252416 -160.864825)
			(xy 3.304322 -160.834858) (xy 3.359695 -160.811922) (xy 3.417588 -160.796409) (xy 3.47701 -160.788586)
			(xy 3.536946 -160.788586) (xy 3.596368 -160.796409) (xy 3.654261 -160.811922) (xy 3.709634 -160.834858)
			(xy 3.76154 -160.864825) (xy 3.80909 -160.901312) (xy 3.85147 -160.943692) (xy 3.887957 -160.991242)
			(xy 3.917924 -161.043148) (xy 3.94086 -161.098521) (xy 3.956373 -161.156414) (xy 3.964196 -161.215836)
			(xy 3.964686 -161.245804) (xy 3.964196 -161.275772) (xy 3.956373 -161.335194) (xy 3.94086 -161.393087)
			(xy 3.917924 -161.44846) (xy 3.887957 -161.500366) (xy 3.85147 -161.547916) (xy 3.80909 -161.590296)
			(xy 3.76154 -161.626783) (xy 3.709634 -161.65675) (xy 3.654261 -161.679686) (xy 3.596368 -161.695199)
			(xy 3.536946 -161.703022) (xy 3.47701 -161.703022) (xy 3.417588 -161.695199) (xy 3.359695 -161.679686)
			(xy 3.304322 -161.65675) (xy 3.252416 -161.626783) (xy 3.204866 -161.590296) (xy 3.162486 -161.547916)
			(xy 3.125999 -161.500366) (xy 3.096032 -161.44846) (xy 3.073096 -161.393087) (xy 3.057583 -161.335194)
			(xy 3.04976 -161.275772) (xy 1.61798 -161.275772) (xy 1.61798 -162.229546) (xy 1.964942 -162.229546)
			(xy 1.969013 -162.173924) (xy 1.981139 -162.119487) (xy 2.001062 -162.067396) (xy 2.028358 -162.018761)
			(xy 2.062444 -161.974618) (xy 2.102593 -161.935909) (xy 2.147951 -161.903458) (xy 2.197551 -161.877957)
			(xy 2.250335 -161.85995) (xy 2.305178 -161.84982) (xy 2.360912 -161.847783) (xy 2.416349 -161.853883)
			(xy 2.470306 -161.867989) (xy 2.521635 -161.889801) (xy 2.569241 -161.918855) (xy 2.612109 -161.95453)
			(xy 2.649326 -161.996067) (xy 2.680099 -162.04258) (xy 2.703771 -162.093077) (xy 2.719839 -162.146484)
			(xy 2.727959 -162.20166) (xy 2.728468 -162.229546) (xy 2.727959 -162.257432) (xy 2.719839 -162.312608)
			(xy 2.703771 -162.366015) (xy 2.680099 -162.416512) (xy 2.649326 -162.463025) (xy 2.612109 -162.504562)
			(xy 2.569241 -162.540237) (xy 2.521635 -162.569291) (xy 2.470306 -162.591103) (xy 2.416349 -162.605209)
			(xy 2.360912 -162.611309) (xy 2.305178 -162.609272) (xy 2.250335 -162.599142) (xy 2.197551 -162.581135)
			(xy 2.147951 -162.555634) (xy 2.102593 -162.523183) (xy 2.062444 -162.484474) (xy 2.028358 -162.440331)
			(xy 2.001062 -162.391696) (xy 1.981139 -162.339605) (xy 1.969013 -162.285168) (xy 1.964942 -162.229546)
			(xy 1.61798 -162.229546) (xy 1.61798 -166.590468) (xy 5.681454 -166.590468) (xy 5.681454 -166.530532)
			(xy 5.689277 -166.47111) (xy 5.70479 -166.413217) (xy 5.727726 -166.357844) (xy 5.757693 -166.305938)
			(xy 5.79418 -166.258388) (xy 5.83656 -166.216008) (xy 5.88411 -166.179521) (xy 5.936016 -166.149554)
			(xy 5.991389 -166.126618) (xy 6.049282 -166.111105) (xy 6.108704 -166.103282) (xy 6.16864 -166.103282)
			(xy 6.228062 -166.111105) (xy 6.285955 -166.126618) (xy 6.341328 -166.149554) (xy 6.393234 -166.179521)
			(xy 6.440784 -166.216008) (xy 6.483164 -166.258388) (xy 6.519651 -166.305938) (xy 6.549618 -166.357844)
			(xy 6.572554 -166.413217) (xy 6.588067 -166.47111) (xy 6.59589 -166.530532) (xy 6.59638 -166.5605)
			(xy 6.59589 -166.590468) (xy 6.588067 -166.64989) (xy 6.572554 -166.707783) (xy 6.549618 -166.763156)
			(xy 6.519651 -166.815062) (xy 6.483164 -166.862612) (xy 6.440784 -166.904992) (xy 6.393234 -166.941479)
			(xy 6.341328 -166.971446) (xy 6.285955 -166.994382) (xy 6.228062 -167.009895) (xy 6.16864 -167.017718)
			(xy 6.108704 -167.017718) (xy 6.049282 -167.009895) (xy 5.991389 -166.994382) (xy 5.936016 -166.971446)
			(xy 5.88411 -166.941479) (xy 5.83656 -166.904992) (xy 5.79418 -166.862612) (xy 5.757693 -166.815062)
			(xy 5.727726 -166.763156) (xy 5.70479 -166.707783) (xy 5.689277 -166.64989) (xy 5.681454 -166.590468)
			(xy 1.61798 -166.590468) (xy 1.61798 -167.2463) (xy 2.2479 -167.87622)
		)
		(stroke
			(width 0)
			(type solid)
		)
		(fill yes)
		(layer "B.Cu")
		(net "P12V_PDB")
	)
	(gr_poly
		(pts
			(xy 131.377944 -152.097232) (xy 131.39459 -152.096684) (xy 131.426746 -152.088059) (xy 131.455576 -152.071408)
			(xy 131.479116 -152.047866) (xy 131.495764 -152.019035) (xy 131.504385 -151.986878) (xy 131.504944 -151.970232)
			(xy 131.504944 -151.6888) (xy 131.505349 -151.660505) (xy 131.511965 -151.604304) (xy 131.525107 -151.549262)
			(xy 131.544594 -151.496134) (xy 131.570159 -151.445649) (xy 131.585462 -151.421846) (xy 131.606544 -151.390096)
			(xy 131.606544 -151.332946) (xy 131.606544 -151.332692) (xy 131.661662 -151.332692) (xy 131.683157 -151.313598)
			(xy 131.729891 -151.280108) (xy 131.75488 -151.26589) (xy 131.78536 -151.249126) (xy 131.820412 -151.189436)
			(xy 131.820412 -151.13381) (xy 133.366256 -151.13381) (xy 133.382915 -151.133321) (xy 133.4151 -151.124707)
			(xy 133.443958 -151.108056) (xy 133.467523 -151.084501) (xy 133.484186 -151.05565) (xy 133.492814 -151.023469)
			(xy 133.493256 -151.00681) (xy 133.493256 -150.996396) (xy 133.491732 -150.986998) (xy 133.487922 -150.95474)
			(xy 133.486144 -150.9141) (xy 133.486144 -149.793198) (xy 133.678422 -149.60092) (xy 133.701105 -149.578945)
			(xy 133.751187 -149.540466) (xy 133.805857 -149.508844) (xy 133.864182 -149.484616) (xy 133.925167 -149.468198)
			(xy 133.987772 -149.459869) (xy 134.050928 -149.459771) (xy 134.113559 -149.467905) (xy 134.174595 -149.484134)
			(xy 134.232995 -149.508179) (xy 134.287762 -149.539632) (xy 134.337963 -149.577954) (xy 134.382741 -149.622493)
			(xy 134.421331 -149.672489) (xy 134.453076 -149.727088) (xy 134.477434 -149.785358) (xy 134.493988 -149.846307)
			(xy 134.502458 -149.908893) (xy 134.502585 -149.94255) (xy 135.009634 -149.94255) (xy 135.013705 -149.886928)
			(xy 135.025831 -149.832491) (xy 135.045754 -149.7804) (xy 135.07305 -149.731765) (xy 135.107136 -149.687622)
			(xy 135.147285 -149.648913) (xy 135.192643 -149.616462) (xy 135.242243 -149.590961) (xy 135.295027 -149.572954)
			(xy 135.34987 -149.562824) (xy 135.405604 -149.560787) (xy 135.461041 -149.566887) (xy 135.514998 -149.580993)
			(xy 135.566327 -149.602805) (xy 135.613933 -149.631859) (xy 135.656801 -149.667534) (xy 135.694018 -149.709071)
			(xy 135.724791 -149.755584) (xy 135.748463 -149.806081) (xy 135.764531 -149.859488) (xy 135.772651 -149.914664)
			(xy 135.77316 -149.94255) (xy 135.772651 -149.970436) (xy 135.764531 -150.025612) (xy 135.748463 -150.079019)
			(xy 135.724791 -150.129516) (xy 135.694018 -150.176029) (xy 135.656801 -150.217566) (xy 135.613933 -150.253241)
			(xy 135.566327 -150.282295) (xy 135.514998 -150.304107) (xy 135.461041 -150.318213) (xy 135.405604 -150.324313)
			(xy 135.34987 -150.322276) (xy 135.295027 -150.312146) (xy 135.242243 -150.294139) (xy 135.192643 -150.268638)
			(xy 135.147285 -150.236187) (xy 135.107136 -150.197478) (xy 135.07305 -150.153335) (xy 135.045754 -150.1047)
			(xy 135.025831 -150.052609) (xy 135.013705 -149.998172) (xy 135.009634 -149.94255) (xy 134.502585 -149.94255)
			(xy 134.502697 -149.972049) (xy 134.494702 -150.034697) (xy 134.478611 -150.09577) (xy 134.467092 -150.125176)
			(xy 134.463028 -150.135336) (xy 134.45236 -150.159466) (xy 134.45236 -150.9141) (xy 134.450582 -150.95474)
			(xy 134.446772 -150.986998) (xy 134.445248 -150.996396) (xy 134.445248 -151.00681) (xy 134.445744 -151.023462)
			(xy 134.454368 -151.055629) (xy 134.471024 -151.084467) (xy 134.494579 -151.108011) (xy 134.523425 -151.124655)
			(xy 134.555596 -151.133264) (xy 134.572248 -151.13381) (xy 136.647428 -151.13381) (xy 136.664074 -151.133263)
			(xy 136.696231 -151.124641) (xy 136.725062 -151.107991) (xy 136.748602 -151.084448) (xy 136.765248 -151.055615)
			(xy 136.773866 -151.023456) (xy 136.774428 -151.00681) (xy 136.774428 -150.994364) (xy 136.771888 -150.982172)
			(xy 136.767616 -150.95904) (xy 136.763039 -150.912221) (xy 136.762744 -150.8887) (xy 136.762744 -149.793198)
			(xy 136.996424 -149.559518) (xy 137.018396 -149.538202) (xy 137.066795 -149.500716) (xy 137.119543 -149.469646)
			(xy 137.175794 -149.445489) (xy 137.234646 -149.428633) (xy 137.295156 -149.419347) (xy 137.356355 -149.417782)
			(xy 137.41726 -149.42396) (xy 137.476898 -149.437785) (xy 137.53431 -149.459033) (xy 137.588578 -149.487365)
			(xy 137.638831 -149.522326) (xy 137.684265 -149.563356) (xy 137.72415 -149.609798) (xy 137.757849 -149.660907)
			(xy 137.784819 -149.715864) (xy 137.80463 -149.773788) (xy 137.816964 -149.833752) (xy 137.821623 -149.894792)
			(xy 137.818533 -149.955933) (xy 137.807742 -150.016193) (xy 137.789425 -150.074606) (xy 137.763874 -150.130238)
			(xy 137.74801 -150.156418) (xy 137.72896 -150.187406) (xy 137.72896 -150.8887) (xy 137.728681 -150.912222)
			(xy 137.724103 -150.959042) (xy 137.719816 -150.982172) (xy 137.717276 -150.994364) (xy 137.717276 -151.00681)
			(xy 137.71782 -151.023459) (xy 137.726439 -151.055621) (xy 137.743088 -151.084458) (xy 137.766631 -151.108004)
			(xy 137.795466 -151.124655) (xy 137.827627 -151.133278) (xy 137.844276 -151.13381) (xy 138.261852 -151.13381)
			(xy 138.439652 -150.95601) (xy 138.439652 -149.71395) (xy 139.503912 -148.64969) (xy 141.947392 -148.64969)
			(xy 142.181326 -148.415756) (xy 142.197686 -148.398639) (xy 142.224372 -148.359533) (xy 142.243362 -148.316165)
			(xy 142.254 -148.270032) (xy 142.255919 -148.222727) (xy 142.249052 -148.175884) (xy 142.233636 -148.13112)
			(xy 142.210204 -148.089982) (xy 142.195296 -148.071586) (xy 142.176691 -148.048947) (xy 142.144784 -147.999796)
			(xy 142.119413 -147.946974) (xy 142.100995 -147.891345) (xy 142.08983 -147.833819) (xy 142.086102 -147.775339)
			(xy 142.089871 -147.716861) (xy 142.101076 -147.659343) (xy 142.119534 -147.603727) (xy 142.144942 -147.550923)
			(xy 142.176884 -147.501795) (xy 142.214837 -147.457148) (xy 142.258181 -147.417712) (xy 142.28191 -147.400518)
			(xy 142.29417 -147.391399) (xy 142.314316 -147.368438) (xy 142.328403 -147.341334) (xy 142.335615 -147.311652)
			(xy 142.336012 -147.296378) (xy 142.336012 -145.616676) (xy 142.335552 -145.60141) (xy 142.32829 -145.571752)
			(xy 142.31421 -145.544659) (xy 142.304516 -145.532856) (xy 142.285073 -145.510007) (xy 142.251708 -145.460144)
			(xy 142.225144 -145.406349) (xy 142.205836 -145.349545) (xy 142.194115 -145.290705) (xy 142.190183 -145.230838)
			(xy 142.194106 -145.17097) (xy 142.205817 -145.112128) (xy 142.225115 -145.05532) (xy 142.251671 -145.001521)
			(xy 142.285027 -144.951653) (xy 142.304516 -144.928844) (xy 142.314258 -144.917072) (xy 142.328367 -144.889978)
			(xy 142.335597 -144.860299) (xy 142.336012 -144.845024) (xy 142.336012 -143.858996) (xy 142.335564 -143.843501)
			(xy 142.328087 -143.813427) (xy 142.313597 -143.786033) (xy 142.292944 -143.762927) (xy 142.280386 -143.75384)
			(xy 142.256121 -143.73673) (xy 142.211794 -143.697225) (xy 142.172948 -143.652321) (xy 142.140234 -143.602771)
			(xy 142.114202 -143.549407) (xy 142.095288 -143.493125) (xy 142.08381 -143.434869) (xy 142.079961 -143.375619)
			(xy 142.083805 -143.316369) (xy 142.095278 -143.258112) (xy 142.114187 -143.201829) (xy 142.140215 -143.148462)
			(xy 142.172925 -143.09891) (xy 142.211768 -143.054002) (xy 142.25609 -143.014494) (xy 142.280386 -142.997428)
			(xy 142.292972 -142.988364) (xy 142.313674 -142.965281) (xy 142.328178 -142.937876) (xy 142.335623 -142.907776)
			(xy 142.336012 -142.892272) (xy 142.336012 -139.487656) (xy 142.335464 -139.471011) (xy 142.326839 -139.438857)
			(xy 142.310188 -139.41003) (xy 142.286645 -139.386493) (xy 142.257813 -139.369849) (xy 142.225657 -139.361232)
			(xy 142.209012 -139.360656) (xy 142.172182 -139.360656) (xy 142.11046 -139.399518) (xy 142.094458 -139.432792)
			(xy 142.083258 -139.455429) (xy 142.056787 -139.498444) (xy 142.041626 -139.518644) (xy 142.01521 -139.552934)
			(xy 142.01521 -139.605258) (xy 141.957806 -139.605258) (xy 141.925802 -139.62634) (xy 141.899342 -139.643265)
			(xy 141.842923 -139.670872) (xy 141.783401 -139.690931) (xy 141.721781 -139.703104) (xy 141.659102 -139.707184)
			(xy 141.596423 -139.703104) (xy 141.534803 -139.690931) (xy 141.475281 -139.670872) (xy 141.418862 -139.643265)
			(xy 141.392402 -139.62634) (xy 141.360398 -139.605258) (xy 141.157706 -139.605258) (xy 141.125702 -139.62634)
			(xy 141.10192 -139.641617) (xy 141.051476 -139.667123) (xy 140.998396 -139.686555) (xy 140.943407 -139.699648)
			(xy 140.887265 -139.706222) (xy 140.859002 -139.706604) (xy 140.776706 -139.706604) (xy 140.75416 -139.707099)
			(xy 140.709777 -139.71507) (xy 140.667497 -139.730746) (xy 140.628646 -139.753634) (xy 140.594441 -139.783017)
			(xy 140.565956 -139.817974) (xy 140.544084 -139.857407) (xy 140.529512 -139.90008) (xy 140.522697 -139.944655)
			(xy 140.522706 -139.967208) (xy 140.522982 -139.999344) (xy 140.51606 -140.063234) (xy 140.500728 -140.125644)
			(xy 140.477259 -140.185469) (xy 140.446065 -140.241656) (xy 140.407699 -140.293211) (xy 140.362836 -140.339226)
			(xy 140.31227 -140.378886) (xy 140.256892 -140.411494) (xy 140.19768 -140.436472) (xy 140.135679 -140.45338)
			(xy 140.071984 -140.461919) (xy 140.039852 -140.462508) (xy 139.252452 -140.462508) (xy 139.220717 -140.461985)
			(xy 139.157797 -140.453635) (xy 139.096511 -140.437124) (xy 139.037912 -140.412736) (xy 138.983008 -140.38089)
			(xy 138.957558 -140.361924) (xy 138.923268 -140.335508) (xy 138.870944 -140.335508) (xy 138.870944 -140.278104)
			(xy 138.849862 -140.2461) (xy 138.833056 -140.219883) (xy 138.805594 -140.163991) (xy 138.785549 -140.105031)
			(xy 138.773253 -140.043983) (xy 138.768911 -139.98186) (xy 138.772595 -139.919695) (xy 138.784243 -139.85852)
			(xy 138.793474 -139.828778) (xy 138.799824 -139.809474) (xy 138.799824 -139.789408) (xy 138.799282 -139.772758)
			(xy 138.790666 -139.740591) (xy 138.774019 -139.711751) (xy 138.750475 -139.688201) (xy 138.721638 -139.671547)
			(xy 138.689474 -139.662922) (xy 138.672824 -139.662408) (xy 138.534902 -139.662408) (xy 138.50327 -139.661913)
			(xy 138.440547 -139.653656) (xy 138.379438 -139.637282) (xy 138.320989 -139.613072) (xy 138.2662 -139.58144)
			(xy 138.216009 -139.542927) (xy 138.171274 -139.498192) (xy 138.132761 -139.448001) (xy 138.101129 -139.393213)
			(xy 138.076919 -139.334764) (xy 138.060545 -139.273655) (xy 138.052287 -139.210932) (xy 138.052287 -139.147668)
			(xy 138.060545 -139.084945) (xy 138.076919 -139.023836) (xy 138.101129 -138.965387) (xy 138.132761 -138.910599)
			(xy 138.171274 -138.860408) (xy 138.216009 -138.815673) (xy 138.2662 -138.77716) (xy 138.320989 -138.745528)
			(xy 138.379438 -138.721318) (xy 138.440547 -138.704944) (xy 138.50327 -138.696687) (xy 138.534902 -138.696192)
			(xy 139.252452 -138.696192) (xy 139.285891 -138.696778) (xy 139.352125 -138.706043) (xy 139.416446 -138.724361)
			(xy 139.44727 -138.73734) (xy 139.463396 -138.743767) (xy 139.497754 -138.748628) (xy 139.532151 -138.744061)
			(xy 139.564051 -138.730405) (xy 139.591098 -138.708668) (xy 139.601702 -138.694922) (xy 139.620893 -138.668972)
			(xy 139.665058 -138.621909) (xy 139.715096 -138.581145) (xy 139.770116 -138.547406) (xy 139.829138 -138.521292)
			(xy 139.891112 -138.503269) (xy 139.954933 -138.493656) (xy 140.019465 -138.492626) (xy 140.083561 -138.500197)
			(xy 140.146077 -138.516234) (xy 140.205903 -138.540451) (xy 140.261971 -138.572418) (xy 140.313285 -138.611564)
			(xy 140.336524 -138.633962) (xy 140.443204 -138.740896) (xy 140.859002 -138.740896) (xy 140.88364 -138.741404)
			(xy 140.906559 -138.742111) (xy 140.952031 -138.736251) (xy 140.995714 -138.722328) (xy 141.03619 -138.700792)
			(xy 141.072145 -138.672344) (xy 141.102413 -138.637906) (xy 141.12601 -138.598597) (xy 141.142172 -138.555691)
			(xy 141.150373 -138.510582) (xy 141.150848 -138.487658) (xy 141.150848 -138.23315) (xy 141.151298 -138.203274)
			(xy 141.158675 -138.143979) (xy 141.173311 -138.086048) (xy 141.194982 -138.030364) (xy 141.223356 -137.977779)
			(xy 141.258001 -137.929096) (xy 141.277848 -137.90676) (xy 141.277848 -137.56894) (xy 141.257979 -137.54662)
			(xy 141.223324 -137.497935) (xy 141.194942 -137.445346) (xy 141.173265 -137.389657) (xy 141.158626 -137.331718)
			(xy 141.151248 -137.272416) (xy 141.151243 -137.212657) (xy 141.158612 -137.153354) (xy 141.173243 -137.095414)
			(xy 141.194911 -137.039721) (xy 141.223285 -136.987128) (xy 141.257932 -136.938438) (xy 141.277848 -136.91616)
			(xy 141.277848 -136.861296) (xy 141.334998 -136.861296) (xy 141.366748 -136.83996) (xy 141.390552 -136.824673)
			(xy 141.441045 -136.799155) (xy 141.494178 -136.779722) (xy 141.54922 -136.76664) (xy 141.605414 -136.760089)
			(xy 141.633702 -136.759696) (xy 142.209012 -136.759696) (xy 142.225659 -136.759151) (xy 142.257818 -136.750531)
			(xy 142.286651 -136.733882) (xy 142.310192 -136.710338) (xy 142.326838 -136.681503) (xy 142.335453 -136.649343)
			(xy 142.336012 -136.632696) (xy 142.336012 -135.582152) (xy 141.803374 -135.049514) (xy 141.787277 -135.034083)
			(xy 141.750726 -135.008548) (xy 141.710282 -134.989778) (xy 141.667184 -134.978349) (xy 141.622754 -134.974612)
			(xy 141.578352 -134.978679) (xy 141.535341 -134.990428) (xy 141.495037 -135.009498) (xy 141.458677 -135.035304)
			(xy 141.427374 -135.067056) (xy 141.402088 -135.10378) (xy 141.383594 -135.144351) (xy 141.37767 -135.165846)
			(xy 141.369721 -135.194897) (xy 141.347226 -135.25077) (xy 141.317596 -135.303209) (xy 141.281343 -135.351308)
			(xy 141.239094 -135.394236) (xy 141.191578 -135.43125) (xy 141.139617 -135.461711) (xy 141.08411 -135.485092)
			(xy 141.026015 -135.50099) (xy 140.966336 -135.509129) (xy 140.906105 -135.509369) (xy 140.846364 -135.501705)
			(xy 140.788144 -135.486271) (xy 140.732452 -135.463333) (xy 140.68025 -135.433286) (xy 140.632441 -135.396652)
			(xy 140.589851 -135.354062) (xy 140.553216 -135.306254) (xy 140.523169 -135.254052) (xy 140.50023 -135.19836)
			(xy 140.484796 -135.14014) (xy 140.477131 -135.080399) (xy 140.477371 -135.020168) (xy 140.485509 -134.96049)
			(xy 140.501406 -134.902394) (xy 140.524787 -134.846886) (xy 140.555248 -134.794925) (xy 140.592261 -134.747409)
			(xy 140.635188 -134.705159) (xy 140.683287 -134.668906) (xy 140.735726 -134.639276) (xy 140.791598 -134.616781)
			(xy 140.820648 -134.608824) (xy 140.842132 -134.602829) (xy 140.882732 -134.584371) (xy 140.919486 -134.559109)
			(xy 140.951267 -134.527818) (xy 140.977097 -134.491461) (xy 140.996185 -134.451153) (xy 141.007943 -134.408131)
			(xy 141.012011 -134.363718) (xy 141.008264 -134.319277) (xy 140.996816 -134.276172) (xy 140.97802 -134.235727)
			(xy 140.952452 -134.199184) (xy 140.93698 -134.18312) (xy 140.409168 -133.655308) (xy 140.248132 -133.655308)
			(xy 140.231475 -133.655799) (xy 140.199294 -133.664415) (xy 140.170441 -133.681067) (xy 140.146882 -133.704622)
			(xy 140.130224 -133.733472) (xy 140.121602 -133.765651) (xy 140.121132 -133.782308) (xy 140.121132 -133.797294)
			(xy 140.124688 -133.812026) (xy 140.131211 -133.841175) (xy 140.137525 -133.900572) (xy 140.136058 -133.960285)
			(xy 140.126835 -134.019301) (xy 140.110015 -134.076615) (xy 140.085881 -134.131254) (xy 140.054845 -134.18229)
			(xy 140.017434 -134.228855) (xy 139.974283 -134.270157) (xy 139.926127 -134.305496) (xy 139.873782 -134.334269)
			(xy 139.818139 -134.355989) (xy 139.760144 -134.370287) (xy 139.700782 -134.376918) (xy 139.641061 -134.375771)
			(xy 139.581997 -134.366866) (xy 139.524593 -134.350352) (xy 139.469826 -134.326512) (xy 139.418624 -134.29575)
			(xy 139.37186 -134.258589) (xy 139.330327 -134.21566) (xy 139.294731 -134.167693) (xy 139.265677 -134.115504)
			(xy 139.243659 -134.059978) (xy 139.229051 -134.00206) (xy 139.222101 -133.942734) (xy 139.221972 -133.912864)
			(xy 139.221814 -133.890478) (xy 139.214591 -133.846302) (xy 139.19974 -133.804075) (xy 139.177721 -133.765103)
			(xy 139.149214 -133.730591) (xy 139.115103 -133.701607) (xy 139.076441 -133.679048) (xy 139.034424 -133.66361)
			(xy 138.990353 -133.655773) (xy 138.967972 -133.655308) (xy 135.60044 -133.655308) (xy 135.27532 -133.980428)
			(xy 135.27532 -135.566912) (xy 135.275732 -135.588546) (xy 135.283013 -135.631196) (xy 135.297416 -135.671996)
			(xy 135.318521 -135.709766) (xy 135.345721 -135.743414) (xy 135.378228 -135.771968) (xy 135.415103 -135.794602)
			(xy 135.455279 -135.810661) (xy 135.497595 -135.819682) (xy 135.540828 -135.821404) (xy 135.583727 -135.815776)
			(xy 135.604504 -135.809736) (xy 135.634708 -135.800902) (xy 135.696727 -135.790231) (xy 135.759606 -135.787709)
			(xy 135.822281 -135.793377) (xy 135.883687 -135.80714) (xy 135.942786 -135.828764) (xy 135.998573 -135.857883)
			(xy 136.050105 -135.894004) (xy 136.073642 -135.914892) (xy 136.12876 -135.914892) (xy 136.12876 -135.972296)
			(xy 136.149842 -136.004046) (xy 136.165151 -136.027846) (xy 136.190716 -136.078333) (xy 136.210206 -136.131461)
			(xy 136.223353 -136.186503) (xy 136.229978 -136.242705) (xy 136.23036 -136.271) (xy 136.23036 -136.89838)
			(xy 136.240774 -136.92251) (xy 136.252929 -136.951687) (xy 136.27041 -137.012429) (xy 136.27467 -137.040731)
			(xy 136.991462 -137.040731) (xy 136.998692 -136.978283) (xy 137.013962 -136.917301) (xy 137.037015 -136.858815)
			(xy 137.051796 -136.83107) (xy 137.067544 -136.802368) (xy 137.067544 -136.2456) (xy 137.067925 -136.217305)
			(xy 137.07455 -136.161103) (xy 137.087698 -136.106061) (xy 137.107188 -136.052933) (xy 137.132753 -136.002446)
			(xy 137.148062 -135.978646) (xy 137.169144 -135.946896) (xy 137.169144 -135.889492) (xy 137.224262 -135.889492)
			(xy 137.247226 -135.869084) (xy 137.297423 -135.83366) (xy 137.351705 -135.804887) (xy 137.409198 -135.783228)
			(xy 137.468973 -135.769032) (xy 137.530065 -135.76253) (xy 137.591488 -135.763825) (xy 137.652252 -135.772898)
			(xy 137.711375 -135.789601) (xy 137.767903 -135.813665) (xy 137.820924 -135.844701) (xy 137.845546 -135.863076)
			(xy 137.879836 -135.889492) (xy 138.020298 -135.889492) (xy 138.036953 -135.889004) (xy 138.069129 -135.880382)
			(xy 138.097977 -135.863727) (xy 138.12153 -135.840172) (xy 138.138185 -135.811323) (xy 138.146804 -135.779147)
			(xy 138.147298 -135.762492) (xy 138.147298 -135.726932) (xy 138.128756 -135.696706) (xy 138.112004 -135.668219)
			(xy 138.085616 -135.60763) (xy 138.067737 -135.544008) (xy 138.058699 -135.478543) (xy 138.058144 -135.4455)
			(xy 138.058144 -135.182102) (xy 137.869422 -134.99338) (xy 137.84742 -134.970647) (xy 137.808907 -134.920455)
			(xy 137.777274 -134.865666) (xy 137.753063 -134.807216) (xy 137.736689 -134.746107) (xy 137.728431 -134.683383)
			(xy 137.728431 -134.620117) (xy 137.736689 -134.557393) (xy 137.753063 -134.496284) (xy 137.777274 -134.437834)
			(xy 137.808907 -134.383045) (xy 137.84742 -134.332853) (xy 137.892155 -134.288118) (xy 137.942347 -134.249605)
			(xy 137.997136 -134.217972) (xy 138.055586 -134.193761) (xy 138.116695 -134.177387) (xy 138.179419 -134.169129)
			(xy 138.242685 -134.169129) (xy 138.305409 -134.177387) (xy 138.366518 -134.193761) (xy 138.424968 -134.217972)
			(xy 138.479757 -134.249605) (xy 138.529949 -134.288118) (xy 138.552682 -134.31012) (xy 139.02436 -134.781798)
			(xy 139.02436 -135.4455) (xy 139.023922 -135.473767) (xy 139.017272 -135.52991) (xy 139.004122 -135.584895)
			(xy 138.984651 -135.637972) (xy 138.959125 -135.688417) (xy 138.943842 -135.7122) (xy 138.92276 -135.744204)
			(xy 138.92276 -135.946896) (xy 138.943842 -135.9789) (xy 138.959122 -136.002688) (xy 138.984678 -136.053121)
			(xy 139.004164 -136.106195) (xy 139.017313 -136.161183) (xy 139.023945 -136.217331) (xy 139.02436 -136.2456)
			(xy 139.02436 -137.214102) (xy 138.806682 -137.43178) (xy 138.785039 -137.452841) (xy 138.737348 -137.489894)
			(xy 138.68541 -137.520711) (xy 138.630034 -137.544812) (xy 138.572085 -137.561819) (xy 138.512468 -137.571467)
			(xy 138.452113 -137.573607) (xy 138.391962 -137.568204) (xy 138.332955 -137.555342) (xy 138.276011 -137.535223)
			(xy 138.222021 -137.508161) (xy 138.171827 -137.474578) (xy 138.126212 -137.434998) (xy 138.085889 -137.390038)
			(xy 138.068304 -137.365486) (xy 138.0617 -137.356088) (xy 138.053826 -137.348214) (xy 138.041694 -137.336753)
			(xy 138.012815 -137.320044) (xy 137.980592 -137.311393) (xy 137.947228 -137.311393) (xy 137.915005 -137.320044)
			(xy 137.886126 -137.336753) (xy 137.873994 -137.348214) (xy 137.816082 -137.40638) (xy 137.793531 -137.428282)
			(xy 137.743704 -137.466613) (xy 137.689326 -137.498157) (xy 137.631315 -137.522379) (xy 137.570651 -137.538871)
			(xy 137.508361 -137.547353) (xy 137.445497 -137.547683) (xy 137.383121 -137.539854) (xy 137.322288 -137.523999)
			(xy 137.264026 -137.500386) (xy 137.20932 -137.469414) (xy 137.159095 -137.431607) (xy 137.114198 -137.387603)
			(xy 137.07539 -137.338147) (xy 137.043326 -137.284073) (xy 137.018548 -137.226297) (xy 137.001475 -137.165795)
			(xy 136.992395 -137.103589) (xy 136.991462 -137.040731) (xy 136.27467 -137.040731) (xy 136.279818 -137.074933)
			(xy 136.280993 -137.138129) (xy 136.273915 -137.200939) (xy 136.258704 -137.262288) (xy 136.23562 -137.32113)
			(xy 136.205058 -137.376457) (xy 136.16754 -137.427325) (xy 136.123707 -137.472865) (xy 136.074308 -137.512298)
			(xy 136.020188 -137.54495) (xy 135.962271 -137.570263) (xy 135.901546 -137.587806) (xy 135.839053 -137.597277)
			(xy 135.775857 -137.598516) (xy 135.713041 -137.591501) (xy 135.651676 -137.576351) (xy 135.62203 -137.565384)
			(xy 135.600937 -137.55763) (xy 135.55687 -137.548839) (xy 135.511944 -137.547934) (xy 135.467559 -137.554943)
			(xy 135.425097 -137.569647) (xy 135.385883 -137.591587) (xy 135.351137 -137.620082) (xy 135.321943 -137.654242)
			(xy 135.299211 -137.693002) (xy 135.283648 -137.735157) (xy 135.275739 -137.77939) (xy 135.27532 -137.801858)
			(xy 135.27532 -142.582709) (xy 139.583013 -142.582709) (xy 139.583013 -142.519491) (xy 139.591264 -142.456814)
			(xy 139.607625 -142.395751) (xy 139.631815 -142.337345) (xy 139.663422 -142.282596) (xy 139.701905 -142.23244)
			(xy 139.746604 -142.187736) (xy 139.796756 -142.149249) (xy 139.851502 -142.117637) (xy 139.909905 -142.09344)
			(xy 139.970967 -142.077073) (xy 140.033643 -142.068816) (xy 140.065252 -142.068296) (xy 141.148054 -142.068296)
			(xy 141.332204 -142.252192) (xy 141.38656 -142.252192) (xy 141.38656 -142.309596) (xy 141.407642 -142.341346)
			(xy 141.424597 -142.367826) (xy 141.452254 -142.424294) (xy 141.47235 -142.483873) (xy 141.484546 -142.545556)
			(xy 141.488634 -142.6083) (xy 141.484546 -142.671044) (xy 141.47235 -142.732727) (xy 141.452254 -142.792306)
			(xy 141.424597 -142.848774) (xy 141.407642 -142.875254) (xy 141.38656 -142.907004) (xy 141.38656 -142.964408)
			(xy 141.331442 -142.964408) (xy 141.307758 -142.985381) (xy 141.255923 -143.02165) (xy 141.199799 -143.050844)
			(xy 141.140346 -143.072464) (xy 141.078579 -143.086141) (xy 141.015556 -143.091641) (xy 140.952354 -143.08887)
			(xy 140.890054 -143.077875) (xy 140.829721 -143.058844) (xy 140.800836 -143.045942) (xy 140.775436 -143.034004)
			(xy 140.065252 -143.034004) (xy 140.033643 -143.033384) (xy 139.970967 -143.025127) (xy 139.909905 -143.00876)
			(xy 139.851502 -142.984563) (xy 139.796756 -142.952951) (xy 139.746604 -142.914464) (xy 139.701905 -142.86976)
			(xy 139.663422 -142.819604) (xy 139.631815 -142.764855) (xy 139.607625 -142.706449) (xy 139.591264 -142.645386)
			(xy 139.583013 -142.582709) (xy 135.27532 -142.582709) (xy 135.27532 -143.967962) (xy 134.005922 -145.23736)
			(xy 139.531117 -145.23736) (xy 139.53258 -145.176019) (xy 139.541799 -145.115357) (xy 139.558626 -145.056351)
			(xy 139.58279 -144.999951) (xy 139.613901 -144.947065) (xy 139.651459 -144.898544) (xy 139.672822 -144.87652)
			(xy 139.690856 -144.85874) (xy 139.701156 -144.847731) (xy 139.716809 -144.821977) (xy 139.72598 -144.793269)
			(xy 139.728155 -144.763209) (xy 139.723214 -144.73348) (xy 139.711433 -144.70574) (xy 139.702794 -144.693386)
			(xy 139.684563 -144.667955) (xy 139.654048 -144.613328) (xy 139.630842 -144.555218) (xy 139.615333 -144.494598)
			(xy 139.607781 -144.432483) (xy 139.608313 -144.369913) (xy 139.616919 -144.307935) (xy 139.633457 -144.247588)
			(xy 139.657648 -144.189881) (xy 139.689087 -144.135781) (xy 139.727249 -144.086193) (xy 139.749022 -144.06372)
			(xy 139.93495 -143.877792) (xy 141.005052 -143.877792) (xy 141.03679 -143.878294) (xy 141.099718 -143.88662)
			(xy 141.161012 -143.903123) (xy 141.219615 -143.927517) (xy 141.274514 -143.959382) (xy 141.299946 -143.978376)
			(xy 141.334236 -144.004792) (xy 141.38656 -144.004792) (xy 141.38656 -144.062196) (xy 141.407642 -144.0942)
			(xy 141.424568 -144.120659) (xy 141.452178 -144.177078) (xy 141.472239 -144.2366) (xy 141.484413 -144.298221)
			(xy 141.488494 -144.3609) (xy 141.484413 -144.423579) (xy 141.472239 -144.4852) (xy 141.452178 -144.544722)
			(xy 141.424568 -144.601141) (xy 141.407642 -144.6276) (xy 141.38656 -144.659604) (xy 141.38656 -144.862296)
			(xy 141.407642 -144.8943) (xy 141.424568 -144.920759) (xy 141.452178 -144.977178) (xy 141.472239 -145.0367)
			(xy 141.484413 -145.098321) (xy 141.488494 -145.161) (xy 141.484413 -145.223679) (xy 141.472239 -145.2853)
			(xy 141.452178 -145.344822) (xy 141.424568 -145.401241) (xy 141.407642 -145.4277) (xy 141.38656 -145.459704)
			(xy 141.38656 -145.517108) (xy 141.334236 -145.517108) (xy 141.299946 -145.543524) (xy 141.274495 -145.562488)
			(xy 141.219591 -145.594334) (xy 141.160992 -145.618723) (xy 141.099707 -145.635234) (xy 141.036787 -145.643584)
			(xy 141.005052 -145.644108) (xy 140.244068 -145.644108) (xy 140.218668 -145.655792) (xy 140.190713 -145.668435)
			(xy 140.132278 -145.68715) (xy 140.071944 -145.698315) (xy 140.010682 -145.70175) (xy 139.949478 -145.697399)
			(xy 139.889318 -145.685332) (xy 139.83117 -145.665745) (xy 139.77597 -145.638952) (xy 139.724608 -145.605384)
			(xy 139.67791 -145.565583) (xy 139.636628 -145.520189) (xy 139.601427 -145.469932) (xy 139.572873 -145.415622)
			(xy 139.551427 -145.358134) (xy 139.537433 -145.298393) (xy 139.531117 -145.23736) (xy 134.005922 -145.23736)
			(xy 133.962902 -145.28038) (xy 130.244342 -145.28038) (xy 129.727452 -145.79727) (xy 127.962152 -145.79727)
			(xy 127.517906 -146.241516) (xy 127.50927 -146.256502) (xy 127.499297 -146.273719) (xy 127.476788 -146.306534)
			(xy 127.464312 -146.322034) (xy 127.457292 -146.33047) (xy 127.442556 -146.346734) (xy 127.434848 -146.354546)
			(xy 127.122936 -146.666458) (xy 126.292102 -146.666458) (xy 126.249176 -146.664426) (xy 126.223776 -146.661124)
			(xy 126.20902 -146.659327) (xy 126.179408 -146.661854) (xy 126.151181 -146.671155) (xy 126.125868 -146.686727)
			(xy 126.115064 -146.696938) (xy 126.044452 -146.76755) (xy 126.044452 -148.757022) (xy 126.584722 -148.757022)
			(xy 126.591096 -148.702644) (xy 126.605177 -148.649735) (xy 126.626676 -148.599383) (xy 126.655152 -148.55262)
			(xy 126.690019 -148.510407) (xy 126.730561 -148.473612) (xy 126.775947 -148.442989) (xy 126.825244 -148.419167)
			(xy 126.877439 -148.402637) (xy 126.931461 -148.393736) (xy 126.986201 -148.392649) (xy 127.040534 -148.399397)
			(xy 127.093345 -148.413841) (xy 127.143548 -148.435686) (xy 127.190115 -148.464482) (xy 127.232086 -148.499639)
			(xy 127.268602 -148.540433) (xy 127.298913 -148.586028) (xy 127.322395 -148.635487) (xy 127.338566 -148.687795)
			(xy 127.347095 -148.741877) (xy 127.347806 -148.796623) (xy 127.340685 -148.850908) (xy 127.325878 -148.903619)
			(xy 127.315214 -148.928836) (xy 127.309317 -148.943162) (xy 127.303938 -148.973664) (xy 127.30607 -149.004562)
			(xy 127.315587 -149.034036) (xy 127.331928 -149.060347) (xy 127.354129 -149.081943) (xy 127.367284 -149.090126)
			(xy 127.393162 -149.105801) (xy 127.440943 -149.142916) (xy 127.483416 -149.186004) (xy 127.519842 -149.234312)
			(xy 127.549585 -149.286999) (xy 127.572126 -149.343145) (xy 127.587073 -149.401772) (xy 127.594164 -149.461857)
			(xy 127.593277 -149.522353) (xy 127.584426 -149.582204) (xy 127.567766 -149.640368) (xy 127.543588 -149.695829)
			(xy 127.512313 -149.74762) (xy 127.474486 -149.794839) (xy 127.430767 -149.836663) (xy 127.381918 -149.872361)
			(xy 127.328792 -149.901311) (xy 127.272314 -149.923008) (xy 127.21347 -149.937075) (xy 127.153285 -149.943266)
			(xy 127.092809 -149.941472) (xy 127.033097 -149.931726) (xy 126.97519 -149.914196) (xy 126.920097 -149.88919)
			(xy 126.86878 -149.857142) (xy 126.822133 -149.818612) (xy 126.78097 -149.774271) (xy 126.746008 -149.724893)
			(xy 126.717857 -149.671339) (xy 126.697007 -149.614543) (xy 126.683824 -149.555494) (xy 126.678536 -149.495223)
			(xy 126.681235 -149.434781) (xy 126.691875 -149.375222) (xy 126.71027 -149.317584) (xy 126.736099 -149.262872)
			(xy 126.752096 -149.237192) (xy 126.760119 -149.223961) (xy 126.770118 -149.194687) (xy 126.772757 -149.163866)
			(xy 126.767881 -149.133318) (xy 126.755778 -149.10485) (xy 126.737162 -149.080144) (xy 126.725426 -149.07006)
			(xy 126.704513 -149.052388) (xy 126.66744 -149.012099) (xy 126.636506 -148.966925) (xy 126.612346 -148.917793)
			(xy 126.595457 -148.865713) (xy 126.586185 -148.811753) (xy 126.584722 -148.757022) (xy 126.044452 -148.757022)
			(xy 126.044452 -151.03475) (xy 129.631948 -151.03475) (xy 129.631948 -149.892512) (xy 129.796286 -149.72792)
			(xy 129.818265 -149.706687) (xy 129.866577 -149.669264) (xy 129.919225 -149.638237) (xy 129.975367 -149.614101)
			(xy 130.034107 -149.597243) (xy 130.094504 -149.587931) (xy 130.155593 -149.586316) (xy 130.216398 -149.592422)
			(xy 130.275946 -149.606152) (xy 130.333286 -149.627287) (xy 130.3875 -149.655488) (xy 130.437722 -149.690305)
			(xy 130.46075 -149.710394) (xy 130.471893 -149.71992) (xy 130.497586 -149.734023) (xy 130.525824 -149.741878)
			(xy 130.55511 -149.743068) (xy 130.583891 -149.737529) (xy 130.610644 -149.725556) (xy 130.622548 -149.716998)
			(xy 130.647978 -149.698308) (xy 130.702756 -149.666967) (xy 130.76115 -149.64303) (xy 130.822166 -149.626905)
			(xy 130.884762 -149.618866) (xy 130.947872 -149.619052) (xy 131.01042 -149.627458) (xy 131.07134 -149.643941)
			(xy 131.129593 -149.668221) (xy 131.184186 -149.699883) (xy 131.234189 -149.738388) (xy 131.278749 -149.783079)
			(xy 131.317106 -149.833195) (xy 131.348608 -149.887881) (xy 131.372716 -149.946205) (xy 131.389021 -150.007173)
			(xy 131.397243 -150.069745) (xy 131.397756 -150.1013) (xy 131.397756 -151.03475) (xy 131.397241 -151.066478)
			(xy 131.388963 -151.129392) (xy 131.372516 -151.19068) (xy 131.348184 -151.249285) (xy 131.316386 -151.3042)
			(xy 131.297426 -151.329644) (xy 131.27101 -151.363934) (xy 131.27101 -151.416258) (xy 131.213606 -151.416258)
			(xy 131.181602 -151.43734) (xy 131.155142 -151.454265) (xy 131.098723 -151.481872) (xy 131.039201 -151.501931)
			(xy 130.977581 -151.514104) (xy 130.914902 -151.518184) (xy 130.852223 -151.514104) (xy 130.790603 -151.501931)
			(xy 130.731081 -151.481872) (xy 130.674662 -151.454265) (xy 130.648202 -151.43734) (xy 130.616198 -151.416258)
			(xy 130.413506 -151.416258) (xy 130.381502 -151.43734) (xy 130.355042 -151.454265) (xy 130.298623 -151.481872)
			(xy 130.239101 -151.501931) (xy 130.177481 -151.514104) (xy 130.114802 -151.518184) (xy 130.052123 -151.514104)
			(xy 129.990503 -151.501931) (xy 129.930981 -151.481872) (xy 129.874562 -151.454265) (xy 129.848102 -151.43734)
			(xy 129.816098 -151.416258) (xy 129.758694 -151.416258) (xy 129.758694 -151.363934) (xy 129.732278 -151.329644)
			(xy 129.713321 -151.304195) (xy 129.681511 -151.249286) (xy 129.657169 -151.190682) (xy 129.640716 -151.129394)
			(xy 129.632434 -151.066479) (xy 129.631948 -151.03475) (xy 126.044452 -151.03475) (xy 126.044452 -151.20747)
			(xy 126.16434 -151.327358) (xy 127.459994 -151.327358) (xy 127.651764 -151.135588) (xy 128.897634 -151.135588)
			(xy 128.99898 -151.236934) (xy 128.99898 -151.636222) (xy 129.45999 -152.097232)
		)
		(stroke
			(width 0)
			(type solid)
		)
		(fill yes)
		(layer "B.Cu")
		(net "P1V0_NODE1")
	)
	(gr_poly
		(pts
			(xy 140.895832 -71.77913) (xy 140.919235 -71.778602) (xy 140.965252 -71.770041) (xy 141.008923 -71.753198)
			(xy 141.048769 -71.72864) (xy 141.083444 -71.6972) (xy 141.111774 -71.659942) (xy 141.132801 -71.618124)
			(xy 141.145813 -71.573163) (xy 141.15037 -71.526579) (xy 141.146318 -71.479949) (xy 141.133794 -71.434849)
			(xy 141.123924 -71.413624) (xy 141.110457 -71.386523) (xy 141.089981 -71.329575) (xy 141.077186 -71.270425)
			(xy 141.072296 -71.210105) (xy 141.075396 -71.149667) (xy 141.086432 -71.090164) (xy 141.105211 -71.032634)
			(xy 141.131406 -70.978079) (xy 141.16456 -70.927452) (xy 141.204095 -70.881633) (xy 141.249323 -70.841423)
			(xy 141.299454 -70.807522) (xy 141.353614 -70.780521) (xy 141.41086 -70.760892) (xy 141.470192 -70.748975)
			(xy 141.530578 -70.74498) (xy 141.590964 -70.748975) (xy 141.650296 -70.760892) (xy 141.707542 -70.780521)
			(xy 141.761702 -70.807522) (xy 141.811833 -70.841423) (xy 141.857061 -70.881633) (xy 141.896596 -70.927452)
			(xy 141.92975 -70.978079) (xy 141.938498 -70.996298) (xy 142.868378 -70.996298) (xy 142.868378 -70.936362)
			(xy 142.876201 -70.87694) (xy 142.891714 -70.819047) (xy 142.91465 -70.763674) (xy 142.944617 -70.711768)
			(xy 142.981104 -70.664218) (xy 143.023484 -70.621838) (xy 143.071034 -70.585351) (xy 143.12294 -70.555384)
			(xy 143.178313 -70.532448) (xy 143.236206 -70.516935) (xy 143.295628 -70.509112) (xy 143.355564 -70.509112)
			(xy 143.414986 -70.516935) (xy 143.472879 -70.532448) (xy 143.528252 -70.555384) (xy 143.580158 -70.585351)
			(xy 143.627708 -70.621838) (xy 143.670088 -70.664218) (xy 143.706575 -70.711768) (xy 143.736542 -70.763674)
			(xy 143.759478 -70.819047) (xy 143.774991 -70.87694) (xy 143.782814 -70.936362) (xy 143.783304 -70.96633)
			(xy 143.782814 -70.996298) (xy 143.774991 -71.05572) (xy 143.759478 -71.113613) (xy 143.736542 -71.168986)
			(xy 143.706575 -71.220892) (xy 143.670088 -71.268442) (xy 143.627708 -71.310822) (xy 143.580158 -71.347309)
			(xy 143.528252 -71.377276) (xy 143.472879 -71.400212) (xy 143.414986 -71.415725) (xy 143.355564 -71.423548)
			(xy 143.295628 -71.423548) (xy 143.236206 -71.415725) (xy 143.178313 -71.400212) (xy 143.12294 -71.377276)
			(xy 143.071034 -71.347309) (xy 143.023484 -71.310822) (xy 142.981104 -71.268442) (xy 142.944617 -71.220892)
			(xy 142.91465 -71.168986) (xy 142.891714 -71.113613) (xy 142.876201 -71.05572) (xy 142.868378 -70.996298)
			(xy 141.938498 -70.996298) (xy 141.955945 -71.032634) (xy 141.974724 -71.090164) (xy 141.98576 -71.149667)
			(xy 141.98886 -71.210105) (xy 141.98397 -71.270425) (xy 141.971175 -71.329575) (xy 141.950699 -71.386523)
			(xy 141.937232 -71.413624) (xy 141.927446 -71.434878) (xy 141.914955 -71.479965) (xy 141.910926 -71.526577)
			(xy 141.915496 -71.573138) (xy 141.928508 -71.618077) (xy 141.949525 -71.659877) (xy 141.977836 -71.697124)
			(xy 142.012485 -71.728561) (xy 142.052302 -71.753127) (xy 142.095942 -71.769991) (xy 142.141932 -71.778585)
			(xy 142.165324 -71.77913) (xy 144.493996 -71.77913) (xy 145.306796 -70.96633) (xy 145.306796 -69.01053)
			(xy 145.306305 -68.993873) (xy 145.297689 -68.961692) (xy 145.281036 -68.932839) (xy 145.257482 -68.90928)
			(xy 145.228632 -68.892621) (xy 145.196453 -68.883998) (xy 145.179796 -68.88353) (xy 142.14602 -68.88353)
			(xy 142.129365 -68.884022) (xy 142.097189 -68.892641) (xy 142.068341 -68.909295) (xy 142.044789 -68.932849)
			(xy 142.028137 -68.961698) (xy 142.019521 -68.993875) (xy 142.01902 -69.01053) (xy 142.01902 -69.022722)
			(xy 142.021306 -69.03466) (xy 142.022068 -69.038978) (xy 142.0241 -69.0499) (xy 142.027189 -69.070078)
			(xy 142.030496 -69.110768) (xy 142.030704 -69.13118) (xy 142.030704 -69.714618) (xy 142.032228 -69.724524)
			(xy 142.036899 -69.756189) (xy 142.039184 -69.820155) (xy 142.03342 -69.883902) (xy 142.019697 -69.946421)
			(xy 141.998233 -70.006723) (xy 141.969368 -70.063852) (xy 141.933558 -70.116904) (xy 141.89137 -70.165041)
			(xy 141.843472 -70.2075) (xy 141.790622 -70.243608) (xy 141.733657 -70.272795) (xy 141.673477 -70.294599)
			(xy 141.611037 -70.308674) (xy 141.547323 -70.314798) (xy 141.483345 -70.312874) (xy 141.420114 -70.302931)
			(xy 141.358633 -70.285129) (xy 141.299873 -70.259748) (xy 141.244764 -70.227189) (xy 141.19418 -70.18797)
			(xy 141.171168 -70.165722) (xy 141.123924 -70.118478) (xy 141.084808 -70.079616) (xy 141.013688 -70.008496)
			(xy 141.013688 -69.13118) (xy 141.013913 -69.110769) (xy 141.01722 -69.07008) (xy 141.020292 -69.0499)
			(xy 141.022324 -69.038978) (xy 141.023086 -69.03466) (xy 141.025372 -69.022722) (xy 141.025372 -69.01053)
			(xy 141.024881 -68.993874) (xy 141.016264 -68.961696) (xy 140.999611 -68.932846) (xy 140.976056 -68.90929)
			(xy 140.947206 -68.892636) (xy 140.915028 -68.884019) (xy 140.898372 -68.88353) (xy 140.683996 -68.88353)
			(xy 140.506196 -68.70573) (xy 140.506196 -62.457584) (xy 140.505651 -62.440937) (xy 140.49703 -62.408779)
			(xy 140.480381 -62.379947) (xy 140.456837 -62.356407) (xy 140.428002 -62.339762) (xy 140.395843 -62.331147)
			(xy 140.379196 -62.330584) (xy 140.372846 -62.330584) (xy 140.360146 -62.330838) (xy 140.055854 -62.330838)
			(xy 140.03314 -62.351278) (xy 139.983671 -62.387151) (xy 139.930259 -62.416837) (xy 139.873674 -62.439906)
			(xy 139.814732 -62.456027) (xy 139.754282 -62.464966) (xy 139.693197 -62.466594) (xy 139.632357 -62.46089)
			(xy 139.572639 -62.447933) (xy 139.514905 -62.427912) (xy 139.459987 -62.401115) (xy 139.434062 -62.38494)
			(xy 139.41555 -62.373496) (xy 139.375518 -62.35643) (xy 139.333163 -62.346434) (xy 139.289725 -62.3438)
			(xy 139.246473 -62.348606) (xy 139.204673 -62.360711) (xy 139.165546 -62.379761) (xy 139.130237 -62.405199)
			(xy 139.099778 -62.436281) (xy 139.075061 -62.472099) (xy 139.056807 -62.511603) (xy 139.050776 -62.532514)
			(xy 139.042489 -62.561601) (xy 139.019298 -62.617459) (xy 138.988952 -62.669776) (xy 138.95198 -62.717642)
			(xy 138.909027 -62.760221) (xy 138.86084 -62.796772) (xy 138.808259 -62.82666) (xy 138.752201 -62.849362)
			(xy 138.69364 -62.864483) (xy 138.633599 -62.871761) (xy 138.573121 -62.871068) (xy 138.513262 -62.862416)
			(xy 138.455064 -62.845956) (xy 138.39954 -62.821975) (xy 138.347658 -62.790891) (xy 138.300322 -62.753245)
			(xy 138.258356 -62.709692) (xy 138.222491 -62.660992) (xy 138.193352 -62.607993) (xy 138.171447 -62.551618)
			(xy 138.163808 -62.522354) (xy 138.157245 -62.493401) (xy 138.15078 -62.434386) (xy 138.151999 -62.375031)
			(xy 138.160883 -62.316332) (xy 138.177282 -62.259274) (xy 138.200922 -62.204816) (xy 138.231405 -62.153872)
			(xy 138.268219 -62.107296) (xy 138.310746 -62.065872) (xy 138.358273 -62.030295) (xy 138.410001 -62.001162)
			(xy 138.465062 -61.978962) (xy 138.522531 -61.964068) (xy 138.581443 -61.95673) (xy 138.64081 -61.957071)
			(xy 138.699634 -61.965085) (xy 138.756928 -61.980639) (xy 138.81173 -62.00347) (xy 138.83767 -62.01791)
			(xy 138.856736 -62.028399) (xy 138.897577 -62.043415) (xy 138.940377 -62.051257) (xy 138.983888 -62.051697)
			(xy 139.026839 -62.044723) (xy 139.067975 -62.030537) (xy 139.106094 -62.009554) (xy 139.140085 -61.982387)
			(xy 139.168953 -61.949829) (xy 139.191856 -61.912831) (xy 139.208125 -61.872474) (xy 139.213082 -61.851286)
			(xy 139.222988 -61.812424) (xy 139.230567 -61.78819) (xy 139.24991 -61.74124) (xy 139.261596 -61.718698)
			(xy 139.279892 -61.685892) (xy 139.324658 -61.625577) (xy 139.35075 -61.598556) (xy 139.436348 -61.512958)
			(xy 139.506706 -61.442346) (xy 139.63523 -61.313822) (xy 139.713716 -61.313822) (xy 139.730364 -61.313277)
			(xy 139.762525 -61.304657) (xy 139.79136 -61.288008) (xy 139.814904 -61.264465) (xy 139.831555 -61.235631)
			(xy 139.840176 -61.20347) (xy 139.840716 -61.186822) (xy 139.840716 -60.833254) (xy 139.841013 -60.808454)
			(xy 139.845848 -60.759089) (xy 139.850368 -60.734702) (xy 139.857405 -60.701933) (xy 139.87895 -60.638468)
			(xy 139.908642 -60.57838) (xy 139.945964 -60.52271) (xy 139.967716 -60.497212) (xy 139.968732 -60.496196)
			(xy 140.00607 -60.452) (xy 140.010388 -60.452) (xy 140.044424 -60.426346) (xy 140.064494 -60.411722)
			(xy 140.106989 -60.386024) (xy 140.12926 -60.375038) (xy 140.160112 -60.360855) (xy 140.224694 -60.339878)
			(xy 140.291492 -60.327677) (xy 140.359319 -60.324471) (xy 140.42697 -60.330316) (xy 140.460222 -60.337192)
			(xy 140.492226 -60.344304) (xy 140.554456 -60.32627) (xy 141.090396 -59.79033) (xy 144.119854 -59.79033)
			(xy 144.136514 -59.789841) (xy 144.168702 -59.781228) (xy 144.197563 -59.764577) (xy 144.221131 -59.741024)
			(xy 144.237799 -59.712172) (xy 144.246431 -59.67999) (xy 144.246854 -59.66333) (xy 144.246854 -59.653678)
			(xy 144.24533 -59.64428) (xy 144.242609 -59.625347) (xy 144.239684 -59.587206) (xy 144.239488 -59.56808)
			(xy 144.239488 -58.87593) (xy 144.23999 -58.843969) (xy 144.248001 -58.780551) (xy 144.263898 -58.718637)
			(xy 144.28743 -58.659204) (xy 144.318224 -58.603189) (xy 144.355797 -58.551474) (xy 144.399554 -58.504877)
			(xy 144.448807 -58.464132) (xy 144.502778 -58.429881) (xy 144.560617 -58.402664) (xy 144.62141 -58.382911)
			(xy 144.6842 -58.370933) (xy 144.747996 -58.36692) (xy 144.811792 -58.370933) (xy 144.874582 -58.382911)
			(xy 144.935375 -58.402664) (xy 144.993214 -58.429881) (xy 145.047185 -58.464132) (xy 145.096438 -58.504877)
			(xy 145.140195 -58.551474) (xy 145.177768 -58.603189) (xy 145.208562 -58.659204) (xy 145.232094 -58.718637)
			(xy 145.247991 -58.780551) (xy 145.256002 -58.843969) (xy 145.256504 -58.87593) (xy 145.256504 -59.56808)
			(xy 145.256296 -59.587206) (xy 145.253371 -59.625346) (xy 145.250662 -59.64428) (xy 145.249138 -59.653678)
			(xy 145.249138 -59.66333) (xy 145.249636 -59.67998) (xy 145.258263 -59.712144) (xy 145.274921 -59.74098)
			(xy 145.298475 -59.764521) (xy 145.327319 -59.781163) (xy 145.359487 -59.789773) (xy 145.376138 -59.79033)
			(xy 149.370796 -59.79033) (xy 149.675596 -60.09513) (xy 149.675596 -61.59373) (xy 149.853396 -61.77153)
			(xy 150.793196 -61.77153) (xy 151.021288 -61.543438) (xy 151.021288 -61.54293) (xy 151.060658 -61.503814)
			(xy 151.072121 -61.491682) (xy 151.08884 -61.462804) (xy 151.097508 -61.430582) (xy 151.097996 -61.413898)
			(xy 151.097996 -60.672472) (xy 151.097373 -60.654695) (xy 151.087504 -60.620536) (xy 151.068596 -60.590424)
			(xy 151.042116 -60.566696) (xy 151.026368 -60.558426) (xy 151.026114 -60.558172) (xy 150.999121 -60.544612)
			(xy 150.948639 -60.511438) (xy 150.90296 -60.471911) (xy 150.862877 -60.426719) (xy 150.829086 -60.376648)
			(xy 150.802174 -60.322567) (xy 150.78261 -60.265416) (xy 150.770733 -60.206188) (xy 150.76675 -60.145913)
			(xy 150.77073 -60.085638) (xy 150.782603 -60.026409) (xy 150.802164 -59.969257) (xy 150.829072 -59.915175)
			(xy 150.862861 -59.865101) (xy 150.902941 -59.819908) (xy 150.948619 -59.780378) (xy 150.999098 -59.7472)
			(xy 151.026114 -59.733688) (xy 151.026368 -59.733434) (xy 151.042112 -59.725153) (xy 151.068601 -59.701431)
			(xy 151.08752 -59.671323) (xy 151.097403 -59.637166) (xy 151.097996 -59.619388) (xy 151.097996 -56.48579)
			(xy 150.977346 -56.36514) (xy 150.961746 -56.350165) (xy 150.926425 -56.325222) (xy 150.887389 -56.306623)
			(xy 150.845768 -56.294904) (xy 150.802762 -56.290406) (xy 150.759616 -56.293257) (xy 150.717577 -56.303376)
			(xy 150.677859 -56.32047) (xy 150.64161 -56.344044) (xy 150.609879 -56.373419) (xy 150.596346 -56.390286)
			(xy 150.578836 -56.412294) (xy 150.538432 -56.451411) (xy 150.492723 -56.484174) (xy 150.442699 -56.509872)
			(xy 150.389446 -56.527948) (xy 150.334116 -56.538011) (xy 150.277907 -56.539843) (xy 150.222039 -56.533404)
			(xy 150.167722 -56.518834) (xy 150.116131 -56.496447) (xy 150.068386 -56.46673) (xy 150.02552 -56.430327)
			(xy 149.988463 -56.388025) (xy 149.958017 -56.340741) (xy 149.934841 -56.289501) (xy 149.919439 -56.235413)
			(xy 149.912143 -56.17965) (xy 149.91207 -56.151526) (xy 149.91207 -56.149494) (xy 149.911575 -56.132841)
			(xy 149.902952 -56.100671) (xy 149.886296 -56.071829) (xy 149.862742 -56.048282) (xy 149.833896 -56.031634)
			(xy 149.801723 -56.023021) (xy 149.78507 -56.022494) (xy 149.732238 -56.022494) (xy 149.661626 -56.082438)
			(xy 149.653752 -56.128412) (xy 149.648559 -56.15613) (xy 149.631089 -56.209747) (xy 149.605917 -56.260209)
			(xy 149.573591 -56.306415) (xy 149.534815 -56.347359) (xy 149.490435 -56.382149) (xy 149.441416 -56.410027)
			(xy 149.388828 -56.430386) (xy 149.333816 -56.442781) (xy 149.277578 -56.446943) (xy 149.22134 -56.442781)
			(xy 149.166328 -56.430386) (xy 149.11374 -56.410027) (xy 149.064721 -56.382149) (xy 149.020341 -56.347359)
			(xy 148.981565 -56.306415) (xy 148.949239 -56.260209) (xy 148.924067 -56.209747) (xy 148.906597 -56.15613)
			(xy 148.901404 -56.128412) (xy 148.89353 -56.082438) (xy 148.822918 -56.022494) (xy 148.717 -56.022494)
			(xy 148.64588 -56.083708) (xy 148.638768 -56.130444) (xy 148.634252 -56.157185) (xy 148.61865 -56.209124)
			(xy 148.595849 -56.25833) (xy 148.566308 -56.30381) (xy 148.530624 -56.344648) (xy 148.489516 -56.380021)
			(xy 148.443813 -56.409214) (xy 148.394435 -56.43164) (xy 148.342379 -56.446847) (xy 148.288694 -56.454528)
			(xy 148.234462 -56.454528) (xy 148.180777 -56.446847) (xy 148.128721 -56.43164) (xy 148.079343 -56.409214)
			(xy 148.03364 -56.380021) (xy 147.992532 -56.344648) (xy 147.956848 -56.30381) (xy 147.927307 -56.25833)
			(xy 147.904506 -56.209124) (xy 147.888904 -56.157185) (xy 147.884388 -56.130444) (xy 147.877276 -56.083708)
			(xy 147.806156 -56.022494) (xy 147.69846 -56.022494) (xy 147.628356 -56.079644) (xy 147.619466 -56.124094)
			(xy 147.613513 -56.150978) (xy 147.594909 -56.202801) (xy 147.569049 -56.251412) (xy 147.53647 -56.295801)
			(xy 147.497847 -56.335045) (xy 147.453985 -56.36833) (xy 147.405794 -56.394963) (xy 147.354274 -56.414392)
			(xy 147.300496 -56.426214) (xy 147.245578 -56.430182) (xy 147.19066 -56.426214) (xy 147.136882 -56.414392)
			(xy 147.085362 -56.394963) (xy 147.037171 -56.36833) (xy 146.993309 -56.335045) (xy 146.954686 -56.295801)
			(xy 146.922107 -56.251412) (xy 146.896247 -56.202801) (xy 146.877643 -56.150978) (xy 146.87169 -56.124094)
			(xy 146.867671 -56.107129) (xy 146.851718 -56.076141) (xy 146.827975 -56.050626) (xy 146.798215 -56.032486)
			(xy 146.764657 -56.023075) (xy 146.74723 -56.022494) (xy 139.480544 -56.022494) (xy 139.416028 -56.066436)
			(xy 139.40155 -56.103012) (xy 139.389967 -56.131164) (xy 139.360414 -56.184384) (xy 139.324066 -56.233215)
			(xy 139.281563 -56.276796) (xy 139.233658 -56.314356) (xy 139.181195 -56.345233) (xy 139.125101 -56.36888)
			(xy 139.066367 -56.384881) (xy 139.006029 -56.392953) (xy 138.945155 -56.392953) (xy 138.884817 -56.384881)
			(xy 138.826083 -56.36888) (xy 138.769989 -56.345233) (xy 138.717526 -56.314356) (xy 138.669621 -56.276796)
			(xy 138.627118 -56.233215) (xy 138.59077 -56.184384) (xy 138.561217 -56.131164) (xy 138.549634 -56.103012)
			(xy 138.535156 -56.066436) (xy 138.47064 -56.022494) (xy 138.342878 -56.022494) (xy 137.432796 -56.932576)
			(xy 137.432796 -56.948832) (xy 136.79424 -57.587388) (xy 138.155678 -57.587388) (xy 138.159749 -57.531766)
			(xy 138.171875 -57.477329) (xy 138.191798 -57.425238) (xy 138.219094 -57.376603) (xy 138.25318 -57.33246)
			(xy 138.293329 -57.293751) (xy 138.338687 -57.2613) (xy 138.388287 -57.235799) (xy 138.441071 -57.217792)
			(xy 138.495914 -57.207662) (xy 138.551648 -57.205625) (xy 138.607085 -57.211725) (xy 138.661042 -57.225831)
			(xy 138.712371 -57.247643) (xy 138.759977 -57.276697) (xy 138.802845 -57.312372) (xy 138.840062 -57.353909)
			(xy 138.870835 -57.400422) (xy 138.894507 -57.450919) (xy 138.910575 -57.504326) (xy 138.918695 -57.559502)
			(xy 138.919204 -57.587388) (xy 138.918695 -57.615274) (xy 138.910575 -57.67045) (xy 138.894507 -57.723857)
			(xy 138.870835 -57.774354) (xy 138.840062 -57.820867) (xy 138.802845 -57.862404) (xy 138.759977 -57.898079)
			(xy 138.712371 -57.927133) (xy 138.661042 -57.948945) (xy 138.607085 -57.963051) (xy 138.551648 -57.969151)
			(xy 138.495914 -57.967114) (xy 138.441071 -57.956984) (xy 138.388287 -57.938977) (xy 138.338687 -57.913476)
			(xy 138.293329 -57.881025) (xy 138.25318 -57.842316) (xy 138.219094 -57.798173) (xy 138.191798 -57.749538)
			(xy 138.171875 -57.697447) (xy 138.159749 -57.64301) (xy 138.155678 -57.587388) (xy 136.79424 -57.587388)
			(xy 136.63168 -57.749948) (xy 136.63168 -58.704079) (xy 138.045385 -58.704079) (xy 138.048313 -58.647984)
			(xy 138.059435 -58.592923) (xy 138.078508 -58.540089) (xy 138.105122 -58.490621) (xy 138.1387 -58.44559)
			(xy 138.178517 -58.405969) (xy 138.223714 -58.372613) (xy 138.273312 -58.346244) (xy 138.32624 -58.327431)
			(xy 138.381354 -58.316581) (xy 138.437464 -58.313929) (xy 138.493356 -58.319532) (xy 138.547822 -58.333269)
			(xy 138.599686 -58.354843) (xy 138.647827 -58.383787) (xy 138.691204 -58.419476) (xy 138.72888 -58.46114)
			(xy 138.760041 -58.507876) (xy 138.784012 -58.558677) (xy 138.800277 -58.612442) (xy 138.808484 -58.668012)
			(xy 138.808968 -58.696098) (xy 138.809417 -58.711138) (xy 138.816504 -58.740371) (xy 138.830238 -58.767133)
			(xy 138.849856 -58.789936) (xy 138.874267 -58.807513) (xy 138.902114 -58.818887) (xy 138.916918 -58.821574)
			(xy 138.943618 -58.826121) (xy 138.995464 -58.841785) (xy 139.044581 -58.864609) (xy 139.06754 -58.878978)
			(xy 139.081374 -58.887522) (xy 139.112224 -58.897776) (xy 139.144665 -58.899897) (xy 139.176588 -58.893749)
			(xy 139.20592 -58.879729) (xy 139.230755 -58.85875) (xy 139.249479 -58.832173) (xy 139.260876 -58.801727)
			(xy 139.264206 -58.769388) (xy 139.259252 -58.737257) (xy 139.246336 -58.707423) (xy 139.236704 -58.69432)
			(xy 139.21989 -58.67205) (xy 139.19221 -58.623601) (xy 139.171881 -58.571636) (xy 139.159339 -58.517265)
			(xy 139.154849 -58.461647) (xy 139.158509 -58.405968) (xy 139.17024 -58.351416) (xy 139.189792 -58.299154)
			(xy 139.216748 -58.250298) (xy 139.250532 -58.205889) (xy 139.290425 -58.166874) (xy 139.335574 -58.134087)
			(xy 139.385019 -58.108225) (xy 139.437702 -58.089841) (xy 139.492502 -58.079327) (xy 139.548249 -58.076907)
			(xy 139.603753 -58.082633) (xy 139.630912 -58.089038) (xy 139.652634 -58.094051) (xy 139.697085 -58.097348)
			(xy 139.741429 -58.092834) (xy 139.784303 -58.080645) (xy 139.82439 -58.061156) (xy 139.860458 -58.034967)
			(xy 139.891398 -58.002882) (xy 139.904216 -57.984644) (xy 139.920273 -57.96159) (xy 139.958127 -57.920074)
			(xy 140.00166 -57.88456) (xy 140.049932 -57.855816) (xy 140.101899 -57.834463) (xy 140.156435 -57.820963)
			(xy 140.212362 -57.81561) (xy 140.268469 -57.818517) (xy 140.323542 -57.829623) (xy 140.376391 -57.848688)
			(xy 140.425872 -57.875298) (xy 140.470914 -57.908878) (xy 140.510543 -57.948702) (xy 140.543903 -57.993908)
			(xy 140.57027 -58.043518) (xy 140.589076 -58.09646) (xy 140.599912 -58.151587) (xy 140.602545 -58.207708)
			(xy 140.596918 -58.263607) (xy 140.588656 -58.296298) (xy 146.78836 -58.296298) (xy 146.78836 -58.236362)
			(xy 146.796183 -58.17694) (xy 146.811696 -58.119047) (xy 146.834632 -58.063674) (xy 146.864599 -58.011768)
			(xy 146.901086 -57.964218) (xy 146.943466 -57.921838) (xy 146.991016 -57.885351) (xy 147.042922 -57.855384)
			(xy 147.098295 -57.832448) (xy 147.156188 -57.816935) (xy 147.21561 -57.809112) (xy 147.275546 -57.809112)
			(xy 147.334968 -57.816935) (xy 147.392861 -57.832448) (xy 147.448234 -57.855384) (xy 147.50014 -57.885351)
			(xy 147.54769 -57.921838) (xy 147.59007 -57.964218) (xy 147.626557 -58.011768) (xy 147.656524 -58.063674)
			(xy 147.67946 -58.119047) (xy 147.694973 -58.17694) (xy 147.702796 -58.236362) (xy 147.703286 -58.26633)
			(xy 147.702796 -58.296298) (xy 147.694973 -58.35572) (xy 147.67946 -58.413613) (xy 147.656524 -58.468986)
			(xy 147.653573 -58.474098) (xy 148.279848 -58.474098) (xy 148.279848 -58.414162) (xy 148.287671 -58.35474)
			(xy 148.303184 -58.296847) (xy 148.32612 -58.241474) (xy 148.356087 -58.189568) (xy 148.392574 -58.142018)
			(xy 148.434954 -58.099638) (xy 148.482504 -58.063151) (xy 148.53441 -58.033184) (xy 148.589783 -58.010248)
			(xy 148.647676 -57.994735) (xy 148.707098 -57.986912) (xy 148.767034 -57.986912) (xy 148.826456 -57.994735)
			(xy 148.884349 -58.010248) (xy 148.939722 -58.033184) (xy 148.991628 -58.063151) (xy 149.039178 -58.099638)
			(xy 149.081558 -58.142018) (xy 149.118045 -58.189568) (xy 149.148012 -58.241474) (xy 149.170948 -58.296847)
			(xy 149.186461 -58.35474) (xy 149.194284 -58.414162) (xy 149.194774 -58.44413) (xy 149.194284 -58.474098)
			(xy 149.192044 -58.491116) (xy 149.83636 -58.491116) (xy 149.83636 -58.43118) (xy 149.844183 -58.371758)
			(xy 149.859696 -58.313865) (xy 149.882632 -58.258492) (xy 149.912599 -58.206586) (xy 149.949086 -58.159036)
			(xy 149.991466 -58.116656) (xy 150.039016 -58.080169) (xy 150.090922 -58.050202) (xy 150.146295 -58.027266)
			(xy 150.204188 -58.011753) (xy 150.26361 -58.00393) (xy 150.323546 -58.00393) (xy 150.382968 -58.011753)
			(xy 150.440861 -58.027266) (xy 150.496234 -58.050202) (xy 150.54814 -58.080169) (xy 150.59569 -58.116656)
			(xy 150.63807 -58.159036) (xy 150.674557 -58.206586) (xy 150.704524 -58.258492) (xy 150.72746 -58.313865)
			(xy 150.742973 -58.371758) (xy 150.750796 -58.43118) (xy 150.751286 -58.461148) (xy 150.750796 -58.491116)
			(xy 150.742973 -58.550538) (xy 150.72746 -58.608431) (xy 150.704524 -58.663804) (xy 150.674557 -58.71571)
			(xy 150.63807 -58.76326) (xy 150.59569 -58.80564) (xy 150.54814 -58.842127) (xy 150.496234 -58.872094)
			(xy 150.440861 -58.89503) (xy 150.382968 -58.910543) (xy 150.323546 -58.918366) (xy 150.26361 -58.918366)
			(xy 150.204188 -58.910543) (xy 150.146295 -58.89503) (xy 150.090922 -58.872094) (xy 150.039016 -58.842127)
			(xy 149.991466 -58.80564) (xy 149.949086 -58.76326) (xy 149.912599 -58.71571) (xy 149.882632 -58.663804)
			(xy 149.859696 -58.608431) (xy 149.844183 -58.550538) (xy 149.83636 -58.491116) (xy 149.192044 -58.491116)
			(xy 149.186461 -58.53352) (xy 149.170948 -58.591413) (xy 149.148012 -58.646786) (xy 149.118045 -58.698692)
			(xy 149.081558 -58.746242) (xy 149.039178 -58.788622) (xy 148.991628 -58.825109) (xy 148.939722 -58.855076)
			(xy 148.884349 -58.878012) (xy 148.826456 -58.893525) (xy 148.767034 -58.901348) (xy 148.707098 -58.901348)
			(xy 148.647676 -58.893525) (xy 148.589783 -58.878012) (xy 148.53441 -58.855076) (xy 148.482504 -58.825109)
			(xy 148.434954 -58.788622) (xy 148.392574 -58.746242) (xy 148.356087 -58.698692) (xy 148.32612 -58.646786)
			(xy 148.303184 -58.591413) (xy 148.287671 -58.53352) (xy 148.279848 -58.474098) (xy 147.653573 -58.474098)
			(xy 147.626557 -58.520892) (xy 147.59007 -58.568442) (xy 147.54769 -58.610822) (xy 147.50014 -58.647309)
			(xy 147.448234 -58.677276) (xy 147.392861 -58.700212) (xy 147.334968 -58.715725) (xy 147.275546 -58.723548)
			(xy 147.21561 -58.723548) (xy 147.156188 -58.715725) (xy 147.098295 -58.700212) (xy 147.042922 -58.677276)
			(xy 146.991016 -58.647309) (xy 146.943466 -58.610822) (xy 146.901086 -58.568442) (xy 146.864599 -58.520892)
			(xy 146.834632 -58.468986) (xy 146.811696 -58.413613) (xy 146.796183 -58.35572) (xy 146.78836 -58.296298)
			(xy 140.588656 -58.296298) (xy 140.583151 -58.318077) (xy 140.561544 -58.369938) (xy 140.532564 -58.418069)
			(xy 140.515086 -58.440066) (xy 140.501115 -58.457827) (xy 140.478978 -58.497216) (xy 140.464156 -58.539899)
			(xy 140.457117 -58.584531) (xy 140.458083 -58.629704) (xy 140.467023 -58.673994) (xy 140.483655 -58.716004)
			(xy 140.507455 -58.754411) (xy 140.522198 -58.771536) (xy 140.54072 -58.792899) (xy 140.571902 -58.840064)
			(xy 140.595782 -58.891313) (xy 140.611837 -58.945527) (xy 140.619714 -59.001516) (xy 140.619241 -59.058054)
			(xy 140.610429 -59.113903) (xy 140.593471 -59.16784) (xy 140.568738 -59.218684) (xy 140.536771 -59.26532)
			(xy 140.498272 -59.306728) (xy 140.454083 -59.342) (xy 140.405171 -59.370364) (xy 140.35261 -59.391198)
			(xy 140.297549 -59.404047) (xy 140.241194 -59.408629) (xy 140.184781 -59.404842) (xy 140.129544 -59.392772)
			(xy 140.076694 -59.372681) (xy 140.05179 -59.359292) (xy 140.037865 -59.351972) (xy 140.007526 -59.34369)
			(xy 139.976083 -59.343092) (xy 139.945451 -59.350214) (xy 139.917496 -59.364623) (xy 139.893923 -59.38544)
			(xy 139.884658 -59.398154) (xy 139.868858 -59.420521) (xy 139.831805 -59.460845) (xy 139.789365 -59.495454)
			(xy 139.74241 -59.523635) (xy 139.691907 -59.54481) (xy 139.638894 -59.558542) (xy 139.584462 -59.56455)
			(xy 139.529731 -59.562709) (xy 139.475825 -59.553057) (xy 139.423855 -59.535793) (xy 139.374889 -59.511273)
			(xy 139.329934 -59.48) (xy 139.309602 -59.461654) (xy 139.297284 -59.4508) (xy 139.268387 -59.435238)
			(xy 139.236477 -59.427557) (xy 139.203663 -59.428264) (xy 139.172114 -59.437314) (xy 139.143914 -59.454108)
			(xy 139.132056 -59.465464) (xy 139.121134 -59.476132) (xy 139.105953 -59.49103) (xy 139.080309 -59.524964)
			(xy 139.060672 -59.562692) (xy 139.047587 -59.603162) (xy 139.04142 -59.645245) (xy 139.042343 -59.687768)
			(xy 139.05033 -59.729545) (xy 139.065158 -59.769409) (xy 139.075414 -59.788044) (xy 139.090128 -59.814459)
			(xy 139.113206 -59.870348) (xy 139.128725 -59.928788) (xy 139.136412 -59.988764) (xy 139.136135 -60.049229)
			(xy 139.127898 -60.109132) (xy 139.111844 -60.167428) (xy 139.088254 -60.223102) (xy 139.057537 -60.275185)
			(xy 139.02023 -60.32277) (xy 138.976981 -60.365027) (xy 138.928545 -60.401222) (xy 138.875764 -60.430723)
			(xy 138.819558 -60.453017) (xy 138.760905 -60.467715) (xy 138.700828 -60.474561) (xy 138.640373 -60.473437)
			(xy 138.580591 -60.464362) (xy 138.522526 -60.447493) (xy 138.467187 -60.423125) (xy 138.41554 -60.391683)
			(xy 138.368482 -60.353712) (xy 138.326835 -60.309876) (xy 138.291322 -60.260937) (xy 138.262563 -60.207748)
			(xy 138.241059 -60.151235) (xy 138.227184 -60.092383) (xy 138.221179 -60.032216) (xy 138.22315 -59.971782)
			(xy 138.233062 -59.912134) (xy 138.250742 -59.85431) (xy 138.275883 -59.799318) (xy 138.308046 -59.748116)
			(xy 138.346671 -59.701595) (xy 138.391087 -59.660566) (xy 138.415522 -59.642756) (xy 138.432686 -59.630183)
			(xy 138.462921 -59.600252) (xy 138.487747 -59.565702) (xy 138.506471 -59.527499) (xy 138.518568 -59.48671)
			(xy 138.5237 -59.444476) (xy 138.521725 -59.401978) (xy 138.512697 -59.360402) (xy 138.505184 -59.340496)
			(xy 138.496489 -59.317847) (xy 138.484277 -59.270893) (xy 138.478127 -59.222768) (xy 138.477752 -59.19851)
			(xy 138.477364 -59.183466) (xy 138.470272 -59.154223) (xy 138.45653 -59.127455) (xy 138.4369 -59.10465)
			(xy 138.412474 -59.087077) (xy 138.384613 -59.075713) (xy 138.369802 -59.073034) (xy 138.342104 -59.068361)
			(xy 138.288419 -59.051831) (xy 138.237738 -59.027609) (xy 138.191155 -58.996218) (xy 138.149678 -58.958337)
			(xy 138.114203 -58.914785) (xy 138.085497 -58.866502) (xy 138.064179 -58.814532) (xy 138.050712 -58.759998)
			(xy 138.045385 -58.704079) (xy 136.63168 -58.704079) (xy 136.63168 -59.471814) (xy 136.647936 -59.50077)
			(xy 136.661268 -59.525405) (xy 136.68136 -59.577692) (xy 136.69359 -59.632355) (xy 136.697694 -59.688219)
			(xy 136.693584 -59.744083) (xy 136.681349 -59.798744) (xy 136.661252 -59.851029) (xy 136.647936 -59.875674)
			(xy 136.63168 -59.90463) (xy 136.63168 -60.59805) (xy 136.635236 -60.613036) (xy 136.641978 -60.643002)
			(xy 136.646912 -60.704221) (xy 136.641972 -60.76544) (xy 136.635236 -60.795408) (xy 136.63168 -60.810394)
			(xy 136.63168 -61.369194) (xy 136.632155 -61.385337) (xy 136.640254 -61.416592) (xy 136.655933 -61.444815)
			(xy 136.666732 -61.456824) (xy 136.684666 -61.47626) (xy 136.715553 -61.519187) (xy 136.740212 -61.565971)
			(xy 136.758171 -61.615712) (xy 136.769085 -61.667458) (xy 136.772745 -61.720216) (xy 136.76908 -61.772973)
			(xy 136.758162 -61.824718) (xy 136.740199 -61.874458) (xy 136.715536 -61.92124) (xy 136.684646 -61.964165)
			(xy 136.666732 -61.98362) (xy 136.655939 -61.995635) (xy 136.640247 -62.023852) (xy 136.632147 -62.055106)
			(xy 136.63168 -62.07125) (xy 136.63168 -62.56401) (xy 136.641586 -62.587632) (xy 136.65111 -62.611234)
			(xy 136.664524 -62.660329) (xy 136.67129 -62.710773) (xy 136.671288 -62.761668) (xy 136.664516 -62.81211)
			(xy 136.651097 -62.861204) (xy 136.641586 -62.884812) (xy 136.63168 -62.908434) (xy 136.63168 -62.96025)
			(xy 136.632185 -62.982861) (xy 136.640208 -63.027366) (xy 136.655973 -63.069751) (xy 136.678986 -63.10868)
			(xy 136.708519 -63.142926) (xy 136.743643 -63.171411) (xy 136.78325 -63.193236) (xy 136.826092 -63.207713)
			(xy 136.870819 -63.214387) (xy 136.916021 -63.213047) (xy 136.938258 -63.208916) (xy 136.965209 -63.203703)
			(xy 137.019987 -63.200158) (xy 137.074708 -63.204502) (xy 137.128241 -63.216645) (xy 137.179481 -63.236336)
			(xy 137.227368 -63.263169) (xy 137.270915 -63.29659) (xy 137.309221 -63.335907) (xy 137.341496 -63.380309)
			(xy 137.367073 -63.428879) (xy 137.385423 -63.480614) (xy 137.396168 -63.534445) (xy 137.399085 -63.589261)
			(xy 137.394115 -63.643928) (xy 137.38136 -63.697319) (xy 137.361083 -63.748329) (xy 137.333703 -63.795906)
			(xy 137.299787 -63.839068) (xy 137.260033 -63.876921) (xy 137.215264 -63.908685) (xy 137.166404 -63.933704)
			(xy 137.114463 -63.951461) (xy 137.060512 -63.961589) (xy 137.005667 -63.963878) (xy 136.95106 -63.958282)
			(xy 136.897819 -63.944916) (xy 136.847044 -63.924057) (xy 136.823196 -63.910464) (xy 136.793478 -63.892938)
			(xy 136.75868 -63.892938) (xy 136.742029 -63.893435) (xy 136.709863 -63.90206) (xy 136.681025 -63.918717)
			(xy 136.657482 -63.942271) (xy 136.640838 -63.971116) (xy 136.632228 -64.003287) (xy 136.63168 -64.019938)
			(xy 136.63168 -64.176148) (xy 137.432796 -64.977264) (xy 137.432796 -69.662548) (xy 139.658596 -69.662548)
			(xy 139.662667 -69.606926) (xy 139.674793 -69.552489) (xy 139.694716 -69.500398) (xy 139.722012 -69.451763)
			(xy 139.756098 -69.40762) (xy 139.796247 -69.368911) (xy 139.841605 -69.33646) (xy 139.891205 -69.310959)
			(xy 139.943989 -69.292952) (xy 139.998832 -69.282822) (xy 140.054566 -69.280785) (xy 140.110003 -69.286885)
			(xy 140.16396 -69.300991) (xy 140.215289 -69.322803) (xy 140.262895 -69.351857) (xy 140.305763 -69.387532)
			(xy 140.34298 -69.429069) (xy 140.373753 -69.475582) (xy 140.397425 -69.526079) (xy 140.413493 -69.579486)
			(xy 140.421613 -69.634662) (xy 140.422122 -69.662548) (xy 140.421613 -69.690434) (xy 140.413493 -69.74561)
			(xy 140.397425 -69.799017) (xy 140.373753 -69.849514) (xy 140.34298 -69.896027) (xy 140.305763 -69.937564)
			(xy 140.262895 -69.973239) (xy 140.215289 -70.002293) (xy 140.16396 -70.024105) (xy 140.110003 -70.038211)
			(xy 140.054566 -70.044311) (xy 139.998832 -70.042274) (xy 139.943989 -70.032144) (xy 139.891205 -70.014137)
			(xy 139.841605 -69.988636) (xy 139.796247 -69.956185) (xy 139.756098 -69.917476) (xy 139.722012 -69.873333)
			(xy 139.694716 -69.824698) (xy 139.674793 -69.772607) (xy 139.662667 -69.71817) (xy 139.658596 -69.662548)
			(xy 137.432796 -69.662548) (xy 137.432796 -69.72173) (xy 137.762996 -70.05193) (xy 137.779679 -70.06789)
			(xy 137.817686 -70.094093) (xy 137.859798 -70.113008) (xy 137.904632 -70.124013) (xy 137.950715 -70.126747)
			(xy 137.996536 -70.121121) (xy 138.040589 -70.107318) (xy 138.081427 -70.085792) (xy 138.117711 -70.05725)
			(xy 138.133328 -70.040246) (xy 138.153134 -70.017002) (xy 138.197887 -69.975453) (xy 138.247768 -69.940223)
			(xy 138.30189 -69.911938) (xy 138.359292 -69.891101) (xy 138.418955 -69.878082) (xy 138.47982 -69.873112)
			(xy 138.540805 -69.876279) (xy 138.600827 -69.887527) (xy 138.658821 -69.906656) (xy 138.713756 -69.933327)
			(xy 138.764657 -69.967066) (xy 138.81062 -70.007273) (xy 138.850828 -70.053235) (xy 138.884568 -70.104135)
			(xy 138.91124 -70.15907) (xy 138.930371 -70.217063) (xy 138.94162 -70.277085) (xy 138.944788 -70.33807)
			(xy 138.93982 -70.398935) (xy 138.926802 -70.458599) (xy 138.905966 -70.516001) (xy 138.877683 -70.570124)
			(xy 138.842454 -70.620005) (xy 138.800905 -70.664759) (xy 138.777726 -70.684644) (xy 138.760721 -70.700273)
			(xy 138.732127 -70.736536) (xy 138.710558 -70.77737) (xy 138.696726 -70.821431) (xy 138.691085 -70.867266)
			(xy 138.693821 -70.913365) (xy 138.704845 -70.958211) (xy 138.723793 -71.000325) (xy 138.750042 -71.038321)
			(xy 138.766042 -71.054976) (xy 139.490196 -71.77913)
		)
		(stroke
			(width 0)
			(type solid)
		)
		(fill yes)
		(layer "B.Cu")
		(net "P1V0_SATA")
	)
	(gr_poly
		(pts
			(xy 156.21508 -161.492438) (xy 156.229558 -161.45637) (xy 156.238911 -161.434082) (xy 156.262443 -161.391862)
			(xy 156.291116 -161.352949) (xy 156.307536 -161.335212) (xy 156.318129 -161.323404) (xy 156.333675 -161.295765)
			(xy 156.341915 -161.265143) (xy 156.342339 -161.233435) (xy 156.33492 -161.202604) (xy 156.320118 -161.174559)
			(xy 156.309822 -161.162492) (xy 156.289786 -161.139568) (xy 156.255322 -161.089378) (xy 156.227817 -161.035062)
			(xy 156.207756 -160.977578) (xy 156.195495 -160.917942) (xy 156.19125 -160.857207) (xy 156.195096 -160.796445)
			(xy 156.206964 -160.73673) (xy 156.226646 -160.679115) (xy 156.253793 -160.624619) (xy 156.287926 -160.574204)
			(xy 156.328443 -160.52876) (xy 156.374628 -160.489089) (xy 156.425665 -160.455893) (xy 156.480653 -160.429757)
			(xy 156.538621 -160.411142) (xy 156.598545 -160.400379) (xy 156.659368 -160.397656) (xy 156.720014 -160.403022)
			(xy 156.779414 -160.416383) (xy 156.836517 -160.437501) (xy 156.890316 -160.466004) (xy 156.939861 -160.50139)
			(xy 156.984276 -160.543032) (xy 157.022778 -160.590196) (xy 157.054686 -160.642048) (xy 157.079436 -160.697674)
			(xy 157.096593 -160.75609) (xy 157.105852 -160.816265) (xy 157.10705 -160.877137) (xy 157.100167 -160.93763)
			(xy 157.085323 -160.996676) (xy 157.062781 -161.053233) (xy 157.032939 -161.106301) (xy 156.996324 -161.154944)
			(xy 156.953583 -161.198302) (xy 156.929836 -161.217356) (xy 156.917566 -161.227449) (xy 156.898011 -161.252474)
			(xy 156.885252 -161.281558) (xy 156.880084 -161.312895) (xy 156.882826 -161.344536) (xy 156.893309 -161.374515)
			(xy 156.901642 -161.388044) (xy 156.912166 -161.404287) (xy 156.930232 -161.438518) (xy 156.93771 -161.45637)
			(xy 156.943742 -161.470203) (xy 156.961275 -161.494754) (xy 156.984091 -161.514491) (xy 157.010911 -161.528306)
			(xy 157.040228 -161.535424) (xy 157.055312 -161.535872) (xy 157.584648 -161.535872) (xy 157.658308 -161.464498)
			(xy 157.660086 -161.41319) (xy 157.661578 -161.382602) (xy 157.671727 -161.322209) (xy 157.689838 -161.263709)
			(xy 157.715589 -161.208145) (xy 157.748518 -161.156512) (xy 157.788039 -161.109731) (xy 157.833444 -161.068637)
			(xy 157.883924 -161.033966) (xy 157.938576 -161.006334) (xy 157.996425 -160.986238) (xy 158.056437 -160.974034)
			(xy 158.11754 -160.969942) (xy 158.178643 -160.974034) (xy 158.238655 -160.986238) (xy 158.296504 -161.006334)
			(xy 158.351156 -161.033966) (xy 158.401636 -161.068637) (xy 158.447041 -161.109731) (xy 158.486562 -161.156512)
			(xy 158.519491 -161.208145) (xy 158.545242 -161.263709) (xy 158.563353 -161.322209) (xy 158.573502 -161.382602)
			(xy 158.574994 -161.41319) (xy 158.576042 -161.429461) (xy 158.585365 -161.460694) (xy 158.602301 -161.488543)
			(xy 158.625743 -161.511189) (xy 158.65416 -161.527154) (xy 158.685696 -161.535393) (xy 158.701994 -161.535872)
			(xy 162.520884 -161.535872) (xy 162.830002 -161.226754) (xy 162.846172 -161.209824) (xy 162.872644 -161.171219)
			(xy 162.891598 -161.128418) (xy 162.902394 -161.08287) (xy 162.904664 -161.036116) (xy 162.898334 -160.989736)
			(xy 162.883616 -160.9453) (xy 162.861009 -160.904312) (xy 162.831277 -160.868157) (xy 162.795427 -160.838058)
			(xy 162.754671 -160.815035) (xy 162.73272 -160.806892) (xy 162.704142 -160.796597) (xy 162.649769 -160.769515)
			(xy 162.599457 -160.735479) (xy 162.554088 -160.695086) (xy 162.514462 -160.649048) (xy 162.481273 -160.598173)
			(xy 162.455105 -160.543354) (xy 162.436417 -160.485556) (xy 162.42554 -160.425794) (xy 162.422663 -160.365119)
			(xy 162.427836 -160.304596) (xy 162.44097 -160.245289) (xy 162.461834 -160.18824) (xy 162.490059 -160.134453)
			(xy 162.525152 -160.084871) (xy 162.566495 -160.040367) (xy 162.613361 -160.001723) (xy 162.664926 -159.969617)
			(xy 162.720286 -159.944614) (xy 162.778466 -159.927153) (xy 162.838445 -159.917542) (xy 162.899168 -159.915949)
			(xy 162.959568 -159.922401) (xy 163.018584 -159.936786) (xy 163.075178 -159.958851) (xy 163.128357 -159.988209)
			(xy 163.177185 -160.024342) (xy 163.199318 -160.045146) (xy 163.211527 -160.056255) (xy 163.240318 -160.072378)
			(xy 163.272282 -160.080573) (xy 163.305278 -160.080291) (xy 163.337098 -160.071551) (xy 163.365609 -160.054939)
			(xy 163.377626 -160.043622) (xy 163.531804 -159.889444) (xy 163.531804 -159.8041) (xy 163.531347 -159.788766)
			(xy 163.524033 -159.758983) (xy 163.509828 -159.731803) (xy 163.489551 -159.708794) (xy 163.477194 -159.699706)
			(xy 163.45321 -159.682563) (xy 163.409429 -159.643081) (xy 163.37108 -159.598304) (xy 163.338799 -159.548972)
			(xy 163.31312 -159.495904) (xy 163.294469 -159.439978) (xy 163.283154 -159.38212) (xy 163.279362 -159.323287)
			(xy 163.283157 -159.264455) (xy 163.294475 -159.206598) (xy 163.31313 -159.150672) (xy 163.338812 -159.097606)
			(xy 163.371095 -159.048276) (xy 163.409446 -159.003501) (xy 163.45323 -158.964022) (xy 163.477194 -158.94685)
			(xy 163.503102 -158.92907) (xy 163.531804 -158.873952) (xy 163.531804 -158.030926) (xy 163.531313 -158.014269)
			(xy 163.522696 -157.982088) (xy 163.506043 -157.953235) (xy 163.482489 -157.929675) (xy 163.45364 -157.913016)
			(xy 163.421461 -157.904391) (xy 163.404804 -157.903926) (xy 161.579052 -157.903926) (xy 161.556876 -157.904413)
			(xy 161.513198 -157.912123) (xy 161.471523 -157.9273) (xy 161.433116 -157.949482) (xy 161.399144 -157.977997)
			(xy 161.37064 -158.011977) (xy 161.348468 -158.05039) (xy 161.333304 -158.09207) (xy 161.325607 -158.13575)
			(xy 161.325052 -158.157926) (xy 161.325382 -158.191961) (xy 161.31803 -158.259626) (xy 161.301705 -158.325703)
			(xy 161.276701 -158.389007) (xy 161.243465 -158.448404) (xy 161.223452 -158.475934) (xy 161.198052 -158.509716)
			(xy 161.198052 -158.526988) (xy 161.182558 -158.526988) (xy 161.146998 -158.557468) (xy 161.115248 -158.58236)
			(xy 161.10712 -158.588202) (xy 160.629346 -159.065976) (xy 160.605355 -159.089216) (xy 160.552349 -159.12986)
			(xy 160.523682 -159.147002) (xy 160.504886 -159.157416) (xy 160.48424 -159.168739) (xy 160.447195 -159.197798)
			(xy 160.416142 -159.233188) (xy 160.392145 -159.273697) (xy 160.378154 -159.312098) (xy 161.312842 -159.312098)
			(xy 161.312842 -159.252162) (xy 161.320665 -159.19274) (xy 161.336178 -159.134847) (xy 161.359114 -159.079474)
			(xy 161.389081 -159.027568) (xy 161.425568 -158.980018) (xy 161.467948 -158.937638) (xy 161.515498 -158.901151)
			(xy 161.567404 -158.871184) (xy 161.622777 -158.848248) (xy 161.68067 -158.832735) (xy 161.740092 -158.824912)
			(xy 161.800028 -158.824912) (xy 161.85945 -158.832735) (xy 161.917343 -158.848248) (xy 161.972716 -158.871184)
			(xy 162.024622 -158.901151) (xy 162.072172 -158.937638) (xy 162.114552 -158.980018) (xy 162.151039 -159.027568)
			(xy 162.181006 -159.079474) (xy 162.203942 -159.134847) (xy 162.219455 -159.19274) (xy 162.227278 -159.252162)
			(xy 162.227768 -159.28213) (xy 162.227278 -159.312098) (xy 162.219455 -159.37152) (xy 162.203942 -159.429413)
			(xy 162.181006 -159.484786) (xy 162.151039 -159.536692) (xy 162.114552 -159.584242) (xy 162.072172 -159.626622)
			(xy 162.024622 -159.663109) (xy 161.972716 -159.693076) (xy 161.917343 -159.716012) (xy 161.85945 -159.731525)
			(xy 161.800028 -159.739348) (xy 161.740092 -159.739348) (xy 161.68067 -159.731525) (xy 161.622777 -159.716012)
			(xy 161.567404 -159.693076) (xy 161.515498 -159.663109) (xy 161.467948 -159.626622) (xy 161.425568 -159.584242)
			(xy 161.389081 -159.536692) (xy 161.359114 -159.484786) (xy 161.336178 -159.429413) (xy 161.320665 -159.37152)
			(xy 161.312842 -159.312098) (xy 160.378154 -159.312098) (xy 160.376027 -159.317935) (xy 160.36834 -159.364386)
			(xy 160.369348 -159.411458) (xy 160.379016 -159.457537) (xy 160.387538 -159.479488) (xy 160.399415 -159.509857)
			(xy 160.415429 -159.573069) (xy 160.422315 -159.637912) (xy 160.419935 -159.703077) (xy 160.414716 -159.735266)
			(xy 160.408735 -159.765519) (xy 160.389719 -159.824182) (xy 160.363002 -159.879762) (xy 160.329067 -159.931254)
			(xy 160.288529 -159.977726) (xy 160.24212 -160.018336) (xy 160.190681 -160.052351) (xy 160.135142 -160.079154)
			(xy 160.076508 -160.098262) (xy 160.015841 -160.109327) (xy 159.954237 -160.11215) (xy 159.92348 -160.109916)
			(xy 159.893562 -160.106752) (xy 159.834861 -160.093571) (xy 159.778392 -160.072813) (xy 159.72513 -160.044836)
			(xy 159.675992 -160.010123) (xy 159.631824 -159.969272) (xy 159.593389 -159.922987) (xy 159.561349 -159.872066)
			(xy 159.536255 -159.817386) (xy 159.518541 -159.75989) (xy 159.508512 -159.700569) (xy 159.50634 -159.640446)
			(xy 159.512063 -159.580556) (xy 159.525583 -159.521932) (xy 159.546665 -159.465584) (xy 159.574948 -159.412483)
			(xy 159.609944 -159.363546) (xy 159.651048 -159.319615) (xy 159.697554 -159.281447) (xy 159.72282 -159.265112)
			(xy 159.742562 -159.252278) (xy 159.777331 -159.220531) (xy 159.805653 -159.182918) (xy 159.826556 -159.14073)
			(xy 159.839324 -159.095412) (xy 159.843519 -159.048516) (xy 159.838998 -159.001651) (xy 159.825916 -158.956422)
			(xy 159.815784 -158.935166) (xy 159.802734 -158.908197) (xy 159.782329 -158.851863) (xy 159.768679 -158.793524)
			(xy 159.76197 -158.733986) (xy 159.761682 -158.704026) (xy 159.762379 -158.670963) (xy 159.771286 -158.605433)
			(xy 159.788614 -158.541611) (xy 159.814071 -158.480574) (xy 159.847227 -158.423353) (xy 159.887522 -158.370915)
			(xy 159.910526 -158.347156) (xy 159.915606 -158.341822) (xy 159.919924 -158.337504) (xy 159.935857 -158.320861)
			(xy 159.962026 -158.282946) (xy 159.980933 -158.240935) (xy 159.991958 -158.196204) (xy 159.994741 -158.150218)
			(xy 159.989189 -158.104484) (xy 159.975486 -158.0605) (xy 159.954079 -158.019706) (xy 159.92567 -157.983438)
			(xy 159.89119 -157.952885) (xy 159.851768 -157.929046) (xy 159.808694 -157.912704) (xy 159.763381 -157.904392)
			(xy 159.740346 -157.903926) (xy 159.262064 -157.903926) (xy 159.235394 -157.930596) (xy 157.94482 -157.930596)
			(xy 157.922976 -157.908752) (xy 156.922216 -157.908752) (xy 156.663136 -157.649672) (xy 156.663136 -156.517594)
			(xy 156.662592 -156.500944) (xy 156.653974 -156.46878) (xy 156.637326 -156.439941) (xy 156.613783 -156.416392)
			(xy 156.584948 -156.399738) (xy 156.552785 -156.391112) (xy 156.536136 -156.390594) (xy 156.525468 -156.390594)
			(xy 156.5148 -156.392372) (xy 156.493499 -156.395752) (xy 156.450514 -156.39931) (xy 156.428948 -156.399484)
			(xy 155.848558 -156.399484) (xy 155.817062 -156.419804) (xy 155.789569 -156.436865) (xy 155.731132 -156.464646)
			(xy 155.669642 -156.484788) (xy 155.606093 -156.496964) (xy 155.541513 -156.500978) (xy 155.476946 -156.496764)
			(xy 155.413435 -156.484392) (xy 155.352007 -156.46406) (xy 155.293657 -156.436098) (xy 155.239326 -156.400957)
			(xy 155.189893 -156.359206) (xy 155.146158 -156.31152) (xy 155.108828 -156.25867) (xy 155.078506 -156.201509)
			(xy 155.055682 -156.140964) (xy 155.040726 -156.078011) (xy 155.033879 -156.01367) (xy 155.035252 -155.94898)
			(xy 155.044822 -155.884987) (xy 155.062436 -155.822725) (xy 155.087808 -155.763202) (xy 155.120528 -155.70738)
			(xy 155.160066 -155.656161) (xy 155.18257 -155.632912) (xy 155.432506 -155.382976) (xy 155.583382 -155.382976)
			(xy 155.600046 -155.382482) (xy 155.632239 -155.373854) (xy 155.661097 -155.357183) (xy 155.684654 -155.333605)
			(xy 155.701299 -155.304731) (xy 155.709897 -155.272531) (xy 155.709862 -155.239203) (xy 155.701196 -155.207021)
			(xy 155.68449 -155.178182) (xy 155.673044 -155.16606) (xy 155.213812 -154.706574) (xy 155.191577 -154.68363)
			(xy 155.152416 -154.633144) (xy 155.119891 -154.578148) (xy 155.094516 -154.519509) (xy 155.07669 -154.458152)
			(xy 155.066695 -154.395045) (xy 155.064688 -154.331183) (xy 155.070701 -154.267572) (xy 155.084639 -154.205218)
			(xy 155.106282 -154.145101) (xy 155.135289 -154.088171) (xy 155.171203 -154.035326) (xy 155.213457 -153.987399)
			(xy 155.261384 -153.945145) (xy 155.314229 -153.909231) (xy 155.371159 -153.880224) (xy 155.431276 -153.858581)
			(xy 155.49363 -153.844643) (xy 155.557241 -153.83863) (xy 155.621103 -153.840637) (xy 155.68421 -153.850632)
			(xy 155.745567 -153.868458) (xy 155.804206 -153.893833) (xy 155.859202 -153.926358) (xy 155.909688 -153.965519)
			(xy 155.932632 -153.987754) (xy 156.083254 -154.138376) (xy 156.428948 -154.138376) (xy 156.450514 -154.138561)
			(xy 156.493498 -154.14212) (xy 156.5148 -154.145488) (xy 156.525468 -154.147266) (xy 156.536136 -154.147266)
			(xy 156.55278 -154.146718) (xy 156.58493 -154.138094) (xy 156.613754 -154.121442) (xy 156.637285 -154.097898)
			(xy 156.653921 -154.069065) (xy 156.662528 -154.03691) (xy 156.663136 -154.020266) (xy 156.663136 -150.396194)
			(xy 156.662592 -150.379544) (xy 156.653974 -150.34738) (xy 156.637326 -150.318541) (xy 156.613783 -150.294992)
			(xy 156.584948 -150.278338) (xy 156.552785 -150.269712) (xy 156.536136 -150.269194) (xy 156.525468 -150.269194)
			(xy 156.5148 -150.270972) (xy 156.48686 -150.274782) (xy 156.472432 -150.276334) (xy 156.443458 -150.277984)
			(xy 156.428948 -150.278084) (xy 155.787598 -150.278084) (xy 155.360116 -149.850602) (xy 155.008072 -149.498812)
			(xy 155.008072 -148.981922) (xy 155.008834 -148.954998) (xy 155.009386 -148.94124) (xy 155.007862 -148.913746)
			(xy 155.005786 -148.900134) (xy 155.005786 -148.82114) (xy 155.051506 -148.77542) (xy 155.060904 -148.756624)
			(xy 155.073494 -148.732011) (xy 155.103246 -148.68541) (xy 155.137872 -148.642308) (xy 155.15717 -148.622512)
			(xy 155.560014 -148.219668) (xy 156.43733 -148.219668) (xy 156.473901 -148.220284) (xy 156.546293 -148.230728)
			(xy 156.61644 -148.25144) (xy 156.649928 -148.26615) (xy 156.66162 -148.271604) (xy 156.684491 -148.283547)
			(xy 156.695648 -148.290026) (xy 156.73324 -148.312124) (xy 156.819346 -148.301202) (xy 157.01137 -148.109178)
			(xy 157.195012 -148.109178) (xy 157.20314 -148.108924) (xy 157.99562 -148.108924) (xy 158.003748 -148.109178)
			(xy 158.32455 -148.109178) (xy 158.84144 -148.626068) (xy 158.900622 -148.684996) (xy 160.5534 -148.684996)
			(xy 160.553908 -148.68525) (xy 160.656016 -148.68525) (xy 161.580322 -147.760944) (xy 161.580322 -145.82648)
			(xy 161.413444 -145.659602) (xy 159.22371 -145.659602) (xy 159.15894 -145.704306) (xy 159.144716 -145.74139)
			(xy 159.133319 -145.769898) (xy 159.103977 -145.823828) (xy 159.067689 -145.873352) (xy 159.025108 -145.917581)
			(xy 158.976997 -145.955722) (xy 158.92422 -145.98709) (xy 158.867724 -146.011122) (xy 158.808522 -146.027388)
			(xy 158.747678 -146.035594) (xy 158.686282 -146.035594) (xy 158.625438 -146.027388) (xy 158.566236 -146.011122)
			(xy 158.50974 -145.98709) (xy 158.456963 -145.955722) (xy 158.408852 -145.917581) (xy 158.366271 -145.873352)
			(xy 158.329983 -145.823828) (xy 158.300641 -145.769898) (xy 158.289244 -145.74139) (xy 158.27502 -145.704306)
			(xy 158.21025 -145.659602) (xy 153.00198 -145.659602) (xy 152.96388 -145.697702) (xy 152.96388 -147.129496)
			(xy 154.235386 -147.129496) (xy 154.235386 -147.06956) (xy 154.243209 -147.010138) (xy 154.258722 -146.952245)
			(xy 154.281658 -146.896872) (xy 154.311625 -146.844966) (xy 154.348112 -146.797416) (xy 154.390492 -146.755036)
			(xy 154.438042 -146.718549) (xy 154.489948 -146.688582) (xy 154.545321 -146.665646) (xy 154.603214 -146.650133)
			(xy 154.662636 -146.64231) (xy 154.722572 -146.64231) (xy 154.781994 -146.650133) (xy 154.839887 -146.665646)
			(xy 154.89526 -146.688582) (xy 154.947166 -146.718549) (xy 154.994716 -146.755036) (xy 155.037096 -146.797416)
			(xy 155.073583 -146.844966) (xy 155.10355 -146.896872) (xy 155.107847 -146.907246) (xy 158.822118 -146.907246)
			(xy 158.822118 -146.84731) (xy 158.829941 -146.787888) (xy 158.845454 -146.729995) (xy 158.86839 -146.674622)
			(xy 158.898357 -146.622716) (xy 158.934844 -146.575166) (xy 158.977224 -146.532786) (xy 159.024774 -146.496299)
			(xy 159.07668 -146.466332) (xy 159.132053 -146.443396) (xy 159.189946 -146.427883) (xy 159.249368 -146.42006)
			(xy 159.309304 -146.42006) (xy 159.368726 -146.427883) (xy 159.426619 -146.443396) (xy 159.481992 -146.466332)
			(xy 159.533898 -146.496299) (xy 159.581448 -146.532786) (xy 159.623828 -146.575166) (xy 159.660315 -146.622716)
			(xy 159.690282 -146.674622) (xy 159.713218 -146.729995) (xy 159.728731 -146.787888) (xy 159.736554 -146.84731)
			(xy 159.737044 -146.877278) (xy 159.736554 -146.907246) (xy 159.728731 -146.966668) (xy 159.713218 -147.024561)
			(xy 159.690282 -147.079934) (xy 159.660315 -147.13184) (xy 159.623828 -147.17939) (xy 159.581448 -147.22177)
			(xy 159.533898 -147.258257) (xy 159.481992 -147.288224) (xy 159.426619 -147.31116) (xy 159.368726 -147.326673)
			(xy 159.309304 -147.334496) (xy 159.249368 -147.334496) (xy 159.189946 -147.326673) (xy 159.132053 -147.31116)
			(xy 159.07668 -147.288224) (xy 159.024774 -147.258257) (xy 158.977224 -147.22177) (xy 158.934844 -147.17939)
			(xy 158.898357 -147.13184) (xy 158.86839 -147.079934) (xy 158.845454 -147.024561) (xy 158.829941 -146.966668)
			(xy 158.822118 -146.907246) (xy 155.107847 -146.907246) (xy 155.126486 -146.952245) (xy 155.141999 -147.010138)
			(xy 155.149822 -147.06956) (xy 155.150312 -147.099528) (xy 155.149822 -147.129496) (xy 155.141999 -147.188918)
			(xy 155.126486 -147.246811) (xy 155.10355 -147.302184) (xy 155.073583 -147.35409) (xy 155.037096 -147.40164)
			(xy 154.994716 -147.44402) (xy 154.970646 -147.46249) (xy 156.329362 -147.46249) (xy 156.329362 -147.402554)
			(xy 156.337185 -147.343132) (xy 156.352698 -147.285239) (xy 156.375634 -147.229866) (xy 156.405601 -147.17796)
			(xy 156.442088 -147.13041) (xy 156.484468 -147.08803) (xy 156.532018 -147.051543) (xy 156.583924 -147.021576)
			(xy 156.639297 -146.99864) (xy 156.69719 -146.983127) (xy 156.756612 -146.975304) (xy 156.816548 -146.975304)
			(xy 156.87597 -146.983127) (xy 156.933863 -146.99864) (xy 156.989236 -147.021576) (xy 157.041142 -147.051543)
			(xy 157.088692 -147.08803) (xy 157.131072 -147.13041) (xy 157.167559 -147.17796) (xy 157.197526 -147.229866)
			(xy 157.220462 -147.285239) (xy 157.235975 -147.343132) (xy 157.243798 -147.402554) (xy 157.244288 -147.432522)
			(xy 157.243798 -147.46249) (xy 157.235975 -147.521912) (xy 157.220462 -147.579805) (xy 157.197526 -147.635178)
			(xy 157.167559 -147.687084) (xy 157.131072 -147.734634) (xy 157.088692 -147.777014) (xy 157.041142 -147.813501)
			(xy 156.989236 -147.843468) (xy 156.933863 -147.866404) (xy 156.87597 -147.881917) (xy 156.816548 -147.88974)
			(xy 156.756612 -147.88974) (xy 156.69719 -147.881917) (xy 156.639297 -147.866404) (xy 156.583924 -147.843468)
			(xy 156.532018 -147.813501) (xy 156.484468 -147.777014) (xy 156.442088 -147.734634) (xy 156.405601 -147.687084)
			(xy 156.375634 -147.635178) (xy 156.352698 -147.579805) (xy 156.337185 -147.521912) (xy 156.329362 -147.46249)
			(xy 154.970646 -147.46249) (xy 154.947166 -147.480507) (xy 154.89526 -147.510474) (xy 154.839887 -147.53341)
			(xy 154.781994 -147.548923) (xy 154.722572 -147.556746) (xy 154.662636 -147.556746) (xy 154.603214 -147.548923)
			(xy 154.545321 -147.53341) (xy 154.489948 -147.510474) (xy 154.438042 -147.480507) (xy 154.390492 -147.44402)
			(xy 154.348112 -147.40164) (xy 154.311625 -147.35409) (xy 154.281658 -147.302184) (xy 154.258722 -147.246811)
			(xy 154.243209 -147.188918) (xy 154.235386 -147.129496) (xy 152.96388 -147.129496) (xy 152.96388 -148.404576)
			(xy 153.285426 -148.404576) (xy 153.285426 -148.34464) (xy 153.293249 -148.285218) (xy 153.308762 -148.227325)
			(xy 153.331698 -148.171952) (xy 153.361665 -148.120046) (xy 153.398152 -148.072496) (xy 153.440532 -148.030116)
			(xy 153.488082 -147.993629) (xy 153.539988 -147.963662) (xy 153.595361 -147.940726) (xy 153.653254 -147.925213)
			(xy 153.712676 -147.91739) (xy 153.772612 -147.91739) (xy 153.832034 -147.925213) (xy 153.889927 -147.940726)
			(xy 153.9453 -147.963662) (xy 153.997206 -147.993629) (xy 154.044756 -148.030116) (xy 154.087136 -148.072496)
			(xy 154.123623 -148.120046) (xy 154.15359 -148.171952) (xy 154.176526 -148.227325) (xy 154.192039 -148.285218)
			(xy 154.199862 -148.34464) (xy 154.200352 -148.374608) (xy 154.199862 -148.404576) (xy 154.192039 -148.463998)
			(xy 154.176526 -148.521891) (xy 154.15359 -148.577264) (xy 154.123623 -148.62917) (xy 154.087136 -148.67672)
			(xy 154.044756 -148.7191) (xy 153.997206 -148.755587) (xy 153.9453 -148.785554) (xy 153.889927 -148.80849)
			(xy 153.832034 -148.824003) (xy 153.772612 -148.831826) (xy 153.712676 -148.831826) (xy 153.653254 -148.824003)
			(xy 153.595361 -148.80849) (xy 153.539988 -148.785554) (xy 153.488082 -148.755587) (xy 153.440532 -148.7191)
			(xy 153.398152 -148.67672) (xy 153.361665 -148.62917) (xy 153.331698 -148.577264) (xy 153.308762 -148.521891)
			(xy 153.293249 -148.463998) (xy 153.285426 -148.404576) (xy 152.96388 -148.404576) (xy 152.96388 -150.024256)
			(xy 153.313154 -150.024256) (xy 153.313976 -149.963725) (xy 153.322771 -149.903831) (xy 153.339386 -149.84562)
			(xy 153.36353 -149.790106) (xy 153.394781 -149.738261) (xy 153.432595 -149.690988) (xy 153.476311 -149.649112)
			(xy 153.525167 -149.613366) (xy 153.578308 -149.584373) (xy 153.634808 -149.562638) (xy 153.69368 -149.548542)
			(xy 153.753897 -149.54233) (xy 153.814407 -149.544111) (xy 153.874154 -149.553854) (xy 153.932095 -149.571389)
			(xy 153.987219 -149.596409) (xy 154.038563 -149.628479) (xy 154.085231 -149.667037) (xy 154.126408 -149.711411)
			(xy 154.161376 -149.760827) (xy 154.189524 -149.814421) (xy 154.21036 -149.871258) (xy 154.223522 -149.930346)
			(xy 154.228779 -149.990654) (xy 154.226039 -150.051128) (xy 154.21535 -150.110713) (xy 154.1969 -150.168369)
			(xy 154.171009 -150.223089) (xy 154.138131 -150.273919) (xy 154.098838 -150.31997) (xy 154.076654 -150.340568)
			(xy 154.059343 -150.356869) (xy 154.030512 -150.394672) (xy 154.009212 -150.437177) (xy 153.996185 -150.4829)
			(xy 153.991885 -150.530248) (xy 153.996463 -150.57757) (xy 154.009759 -150.623216) (xy 154.031308 -150.665595)
			(xy 154.045412 -150.684738) (xy 154.062062 -150.707018) (xy 154.089353 -150.755482) (xy 154.109316 -150.807396)
			(xy 154.12153 -150.861659) (xy 154.125736 -150.91712) (xy 154.121844 -150.972603) (xy 154.109937 -151.026934)
			(xy 154.090267 -151.07896) (xy 154.063252 -151.127578) (xy 154.029463 -151.171759) (xy 153.989617 -151.210565)
			(xy 153.944559 -151.243174) (xy 153.895244 -151.268895) (xy 153.842716 -151.287183) (xy 153.78809 -151.29765)
			(xy 153.732522 -151.300074) (xy 153.677192 -151.294404) (xy 153.623271 -151.28076) (xy 153.571903 -151.259431)
			(xy 153.524177 -151.230869) (xy 153.481103 -151.195681) (xy 153.443595 -151.15461) (xy 153.412449 -151.108529)
			(xy 153.388323 -151.058414) (xy 153.37173 -151.005326) (xy 153.363021 -150.950392) (xy 153.362381 -150.894776)
			(xy 153.369824 -150.839656) (xy 153.385191 -150.786201) (xy 153.408157 -150.735544) (xy 153.438235 -150.688758)
			(xy 153.456132 -150.667466) (xy 153.471307 -150.649159) (xy 153.495319 -150.608125) (xy 153.511284 -150.563342)
			(xy 153.518646 -150.516372) (xy 153.517148 -150.468852) (xy 153.506842 -150.422439) (xy 153.488088 -150.378751)
			(xy 153.461539 -150.33931) (xy 153.44521 -150.322026) (xy 153.424321 -150.300115) (xy 153.387805 -150.251832)
			(xy 153.357973 -150.199156) (xy 153.335346 -150.143008) (xy 153.320319 -150.084366) (xy 153.313154 -150.024256)
			(xy 152.96388 -150.024256) (xy 152.96388 -152.063704) (xy 151.962086 -153.065498) (xy 152.529545 -153.065498)
			(xy 152.534197 -153.00546) (xy 152.546683 -152.94655) (xy 152.566786 -152.889787) (xy 152.59416 -152.83615)
			(xy 152.628332 -152.786566) (xy 152.668711 -152.741892) (xy 152.714601 -152.702899) (xy 152.765207 -152.670262)
			(xy 152.819657 -152.644542) (xy 152.877009 -152.626186) (xy 152.936274 -152.61551) (xy 152.996426 -152.612697)
			(xy 153.056428 -152.617798) (xy 153.115243 -152.630724) (xy 153.143712 -152.640538) (xy 153.165825 -152.647951)
			(xy 153.211822 -152.655601) (xy 153.258443 -152.65473) (xy 153.304123 -152.645367) (xy 153.347327 -152.627827)
			(xy 153.386606 -152.602698) (xy 153.42064 -152.570823) (xy 153.448287 -152.533274) (xy 153.458926 -152.512522)
			(xy 153.471446 -152.487909) (xy 153.50241 -152.442189) (xy 153.539641 -152.401411) (xy 153.582362 -152.366426)
			(xy 153.629681 -152.337966) (xy 153.680608 -152.316625) (xy 153.73408 -152.302849) (xy 153.788979 -152.296926)
			(xy 153.844159 -152.29898) (xy 153.898466 -152.308967) (xy 153.950766 -152.326679) (xy 153.999966 -152.351746)
			(xy 154.045039 -152.383644) (xy 154.085042 -152.421707) (xy 154.119139 -152.46514) (xy 154.146619 -152.513035)
			(xy 154.166906 -152.564391) (xy 154.179578 -152.618135) (xy 154.184369 -152.673145) (xy 154.18118 -152.72827)
			(xy 154.170076 -152.78236) (xy 154.151291 -152.834285) (xy 154.125216 -152.882958) (xy 154.092396 -152.927364)
			(xy 154.053517 -152.966574) (xy 154.009391 -152.99977) (xy 153.960941 -153.026257) (xy 153.909178 -153.045483)
			(xy 153.855184 -153.057045) (xy 153.800088 -153.060703) (xy 153.745039 -153.056379) (xy 153.718006 -153.050748)
			(xy 153.695155 -153.046112) (xy 153.648569 -153.044279) (xy 153.60243 -153.050976) (xy 153.558288 -153.065978)
			(xy 153.517623 -153.088782) (xy 153.481802 -153.118622) (xy 153.452026 -153.154497) (xy 153.429294 -153.195202)
			(xy 153.421334 -153.217118) (xy 153.411273 -153.2455) (xy 153.384704 -153.29954) (xy 153.351277 -153.349629)
			(xy 153.31157 -153.394902) (xy 153.266269 -153.434576) (xy 153.216156 -153.467967) (xy 153.162097 -153.494498)
			(xy 153.105026 -153.513709) (xy 153.045927 -153.525271) (xy 152.985824 -153.528982) (xy 152.925752 -153.524779)
			(xy 152.866751 -153.512734) (xy 152.809838 -153.493055) (xy 152.755998 -153.466083) (xy 152.706161 -153.432283)
			(xy 152.661186 -153.392238) (xy 152.621851 -153.346642) (xy 152.588836 -153.296281) (xy 152.56271 -153.242025)
			(xy 152.543926 -153.184811) (xy 152.532807 -153.125628) (xy 152.529545 -153.065498) (xy 151.962086 -153.065498)
			(xy 151.94026 -153.087324) (xy 151.94026 -154.369575) (xy 152.530466 -154.369575) (xy 152.530616 -154.309545)
			(xy 152.538612 -154.250049) (xy 152.554316 -154.192108) (xy 152.57746 -154.136718) (xy 152.607645 -154.084828)
			(xy 152.644355 -154.03733) (xy 152.686959 -153.995038) (xy 152.734726 -153.958677) (xy 152.786836 -153.928873)
			(xy 152.842394 -153.906137) (xy 152.900448 -153.890858) (xy 152.960002 -153.8833) (xy 153.020032 -153.883591)
			(xy 153.079509 -153.891726) (xy 153.137412 -153.907567) (xy 153.192748 -153.930841) (xy 153.244566 -153.961149)
			(xy 153.291978 -153.997971) (xy 153.33417 -154.040674) (xy 153.370418 -154.088526) (xy 153.400099 -154.140706)
			(xy 153.422704 -154.196318) (xy 153.430732 -154.225244) (xy 153.436993 -154.24743) (xy 153.456479 -154.289206)
			(xy 153.483176 -154.326785) (xy 153.516209 -154.358936) (xy 153.554497 -154.384606) (xy 153.596784 -154.402955)
			(xy 153.641686 -154.41338) (xy 153.687732 -154.415541) (xy 153.71064 -154.41295) (xy 153.737932 -154.409749)
			(xy 153.79288 -154.410255) (xy 153.847187 -154.418641) (xy 153.899727 -154.434734) (xy 153.949415 -154.458201)
			(xy 153.99522 -154.488556) (xy 154.036195 -154.525169) (xy 154.071491 -154.567285) (xy 154.100378 -154.614029)
			(xy 154.122257 -154.664436) (xy 154.136676 -154.717461) (xy 154.143336 -154.772006) (xy 154.142099 -154.826942)
			(xy 154.132991 -154.881132) (xy 154.1162 -154.933454) (xy 154.092075 -154.982825) (xy 154.061114 -155.028222)
			(xy 154.023958 -155.068706) (xy 153.981377 -155.103439) (xy 153.934252 -155.131701) (xy 153.883559 -155.152908)
			(xy 153.830347 -155.16662) (xy 153.775718 -155.172554) (xy 153.720803 -155.170586) (xy 153.666739 -155.160758)
			(xy 153.614645 -155.143273) (xy 153.5656 -155.118492) (xy 153.520618 -155.08693) (xy 153.480632 -155.049238)
			(xy 153.446469 -155.006199) (xy 153.418836 -154.958702) (xy 153.408126 -154.933396) (xy 153.399028 -154.912192)
			(xy 153.374399 -154.873183) (xy 153.343132 -154.839261) (xy 153.306255 -154.811541) (xy 153.26498 -154.790933)
			(xy 153.220662 -154.778115) (xy 153.174759 -154.773508) (xy 153.128779 -154.777263) (xy 153.106374 -154.782774)
			(xy 153.077269 -154.790125) (xy 153.017752 -154.797964) (xy 152.957721 -154.797956) (xy 152.898207 -154.790101)
			(xy 152.840229 -154.774533) (xy 152.784785 -154.75152) (xy 152.732824 -154.721456) (xy 152.685239 -154.684858)
			(xy 152.642847 -154.642354) (xy 152.606374 -154.594673) (xy 152.576448 -154.542634) (xy 152.553581 -154.487129)
			(xy 152.538165 -154.429111) (xy 152.530466 -154.369575) (xy 151.94026 -154.369575) (xy 151.94026 -158.916112)
			(xy 155.928042 -158.916112) (xy 155.928042 -158.856176) (xy 155.935865 -158.796754) (xy 155.951378 -158.738861)
			(xy 155.974314 -158.683488) (xy 156.004281 -158.631582) (xy 156.040768 -158.584032) (xy 156.083148 -158.541652)
			(xy 156.130698 -158.505165) (xy 156.182604 -158.475198) (xy 156.237977 -158.452262) (xy 156.29587 -158.436749)
			(xy 156.355292 -158.428926) (xy 156.415228 -158.428926) (xy 156.47465 -158.436749) (xy 156.532543 -158.452262)
			(xy 156.587916 -158.475198) (xy 156.639822 -158.505165) (xy 156.687372 -158.541652) (xy 156.729752 -158.584032)
			(xy 156.766239 -158.631582) (xy 156.796206 -158.683488) (xy 156.819142 -158.738861) (xy 156.834655 -158.796754)
			(xy 156.842478 -158.856176) (xy 156.842968 -158.886144) (xy 156.842478 -158.916112) (xy 156.834655 -158.975534)
			(xy 156.819142 -159.033427) (xy 156.796206 -159.0888) (xy 156.766239 -159.140706) (xy 156.729752 -159.188256)
			(xy 156.687372 -159.230636) (xy 156.639822 -159.267123) (xy 156.587916 -159.29709) (xy 156.532543 -159.320026)
			(xy 156.47465 -159.335539) (xy 156.415228 -159.343362) (xy 156.355292 -159.343362) (xy 156.29587 -159.335539)
			(xy 156.237977 -159.320026) (xy 156.182604 -159.29709) (xy 156.130698 -159.267123) (xy 156.083148 -159.230636)
			(xy 156.040768 -159.188256) (xy 156.004281 -159.140706) (xy 155.974314 -159.0888) (xy 155.951378 -159.033427)
			(xy 155.935865 -158.975534) (xy 155.928042 -158.916112) (xy 151.94026 -158.916112) (xy 151.94026 -159.113474)
			(xy 152.84983 -160.023044) (xy 154.88207 -160.023044) (xy 154.88207 -159.963108) (xy 154.889893 -159.903686)
			(xy 154.905406 -159.845793) (xy 154.928342 -159.79042) (xy 154.958309 -159.738514) (xy 154.994796 -159.690964)
			(xy 155.037176 -159.648584) (xy 155.084726 -159.612097) (xy 155.136632 -159.58213) (xy 155.192005 -159.559194)
			(xy 155.249898 -159.543681) (xy 155.30932 -159.535858) (xy 155.369256 -159.535858) (xy 155.428678 -159.543681)
			(xy 155.486571 -159.559194) (xy 155.541944 -159.58213) (xy 155.59385 -159.612097) (xy 155.6414 -159.648584)
			(xy 155.68378 -159.690964) (xy 155.709781 -159.724848) (xy 158.023542 -159.724848) (xy 158.023542 -159.664912)
			(xy 158.031365 -159.60549) (xy 158.046878 -159.547597) (xy 158.069814 -159.492224) (xy 158.099781 -159.440318)
			(xy 158.136268 -159.392768) (xy 158.178648 -159.350388) (xy 158.226198 -159.313901) (xy 158.278104 -159.283934)
			(xy 158.333477 -159.260998) (xy 158.39137 -159.245485) (xy 158.450792 -159.237662) (xy 158.510728 -159.237662)
			(xy 158.57015 -159.245485) (xy 158.628043 -159.260998) (xy 158.683416 -159.283934) (xy 158.735322 -159.313901)
			(xy 158.782872 -159.350388) (xy 158.825252 -159.392768) (xy 158.861739 -159.440318) (xy 158.891706 -159.492224)
			(xy 158.914642 -159.547597) (xy 158.930155 -159.60549) (xy 158.937978 -159.664912) (xy 158.938468 -159.69488)
			(xy 158.937978 -159.724848) (xy 158.930155 -159.78427) (xy 158.914642 -159.842163) (xy 158.891706 -159.897536)
			(xy 158.861739 -159.949442) (xy 158.825252 -159.996992) (xy 158.782872 -160.039372) (xy 158.735322 -160.075859)
			(xy 158.683416 -160.105826) (xy 158.628043 -160.128762) (xy 158.57015 -160.144275) (xy 158.510728 -160.152098)
			(xy 158.450792 -160.152098) (xy 158.39137 -160.144275) (xy 158.333477 -160.128762) (xy 158.278104 -160.105826)
			(xy 158.226198 -160.075859) (xy 158.178648 -160.039372) (xy 158.136268 -159.996992) (xy 158.099781 -159.949442)
			(xy 158.069814 -159.897536) (xy 158.046878 -159.842163) (xy 158.031365 -159.78427) (xy 158.023542 -159.724848)
			(xy 155.709781 -159.724848) (xy 155.720267 -159.738514) (xy 155.750234 -159.79042) (xy 155.77317 -159.845793)
			(xy 155.788683 -159.903686) (xy 155.796506 -159.963108) (xy 155.796996 -159.993076) (xy 155.796506 -160.023044)
			(xy 155.788683 -160.082466) (xy 155.77317 -160.140359) (xy 155.750234 -160.195732) (xy 155.720267 -160.247638)
			(xy 155.68378 -160.295188) (xy 155.6414 -160.337568) (xy 155.59385 -160.374055) (xy 155.564784 -160.390836)
			(xy 160.61358 -160.390836) (xy 160.61358 -160.3309) (xy 160.621403 -160.271478) (xy 160.636916 -160.213585)
			(xy 160.659852 -160.158212) (xy 160.689819 -160.106306) (xy 160.726306 -160.058756) (xy 160.768686 -160.016376)
			(xy 160.816236 -159.979889) (xy 160.868142 -159.949922) (xy 160.923515 -159.926986) (xy 160.981408 -159.911473)
			(xy 161.04083 -159.90365) (xy 161.100766 -159.90365) (xy 161.160188 -159.911473) (xy 161.218081 -159.926986)
			(xy 161.273454 -159.949922) (xy 161.32536 -159.979889) (xy 161.37291 -160.016376) (xy 161.41529 -160.058756)
			(xy 161.451777 -160.106306) (xy 161.481744 -160.158212) (xy 161.50468 -160.213585) (xy 161.520193 -160.271478)
			(xy 161.528016 -160.3309) (xy 161.528506 -160.360868) (xy 161.528016 -160.390836) (xy 161.520193 -160.450258)
			(xy 161.50468 -160.508151) (xy 161.481744 -160.563524) (xy 161.451777 -160.61543) (xy 161.41529 -160.66298)
			(xy 161.37291 -160.70536) (xy 161.32536 -160.741847) (xy 161.273454 -160.771814) (xy 161.218081 -160.79475)
			(xy 161.160188 -160.810263) (xy 161.100766 -160.818086) (xy 161.04083 -160.818086) (xy 160.981408 -160.810263)
			(xy 160.923515 -160.79475) (xy 160.868142 -160.771814) (xy 160.816236 -160.741847) (xy 160.768686 -160.70536)
			(xy 160.726306 -160.66298) (xy 160.689819 -160.61543) (xy 160.659852 -160.563524) (xy 160.636916 -160.508151)
			(xy 160.621403 -160.450258) (xy 160.61358 -160.390836) (xy 155.564784 -160.390836) (xy 155.541944 -160.404022)
			(xy 155.486571 -160.426958) (xy 155.428678 -160.442471) (xy 155.369256 -160.450294) (xy 155.30932 -160.450294)
			(xy 155.249898 -160.442471) (xy 155.192005 -160.426958) (xy 155.136632 -160.404022) (xy 155.084726 -160.374055)
			(xy 155.037176 -160.337568) (xy 154.994796 -160.295188) (xy 154.958309 -160.247638) (xy 154.928342 -160.195732)
			(xy 154.905406 -160.140359) (xy 154.889893 -160.082466) (xy 154.88207 -160.023044) (xy 152.84983 -160.023044)
			(xy 154.362658 -161.535872) (xy 156.150818 -161.535872)
		)
		(stroke
			(width 0)
			(type solid)
		)
		(fill yes)
		(layer "B.Cu")
		(net "P1V05_LAN2")
	)
	(gr_poly
		(pts
			(xy 138.646916 -122.876564) (xy 138.655806 -122.843544) (xy 138.66371 -122.816105) (xy 138.68654 -122.763768)
			(xy 138.716915 -122.715417) (xy 138.754155 -122.672133) (xy 138.797429 -122.63488) (xy 138.84577 -122.604492)
			(xy 138.898101 -122.581646) (xy 138.925554 -122.573796) (xy 138.958574 -122.564906) (xy 140.263626 -121.259854)
			(xy 140.263626 -113.86566) (xy 140.263129 -113.843022) (xy 140.255106 -113.798462) (xy 140.239322 -113.756026)
			(xy 140.216274 -113.717055) (xy 140.186692 -113.682779) (xy 140.151508 -113.654282) (xy 140.111836 -113.632463)
			(xy 140.068928 -113.618013) (xy 140.024139 -113.611387) (xy 140.001498 -113.61166) (xy 139.973707 -113.612025)
			(xy 139.918493 -113.605678) (xy 139.864785 -113.591387) (xy 139.81372 -113.569452) (xy 139.766378 -113.540339)
			(xy 139.723762 -113.504663) (xy 139.686775 -113.463181) (xy 139.656199 -113.41677) (xy 139.632682 -113.366414)
			(xy 139.616722 -113.313177) (xy 139.608657 -113.258188) (xy 139.608657 -113.202611) (xy 139.616722 -113.147622)
			(xy 139.632682 -113.094386) (xy 139.656199 -113.044029) (xy 139.686775 -112.997619) (xy 139.723762 -112.956137)
			(xy 139.766378 -112.920461) (xy 139.81372 -112.891348) (xy 139.864786 -112.869413) (xy 139.918494 -112.855121)
			(xy 139.973708 -112.848775) (xy 140.001498 -112.849152) (xy 140.024143 -112.849387) (xy 140.068944 -112.842803)
			(xy 140.111867 -112.828381) (xy 140.151554 -112.806577) (xy 140.186746 -112.778082) (xy 140.216329 -112.7438)
			(xy 140.239365 -112.704816) (xy 140.255126 -112.662366) (xy 140.26311 -112.617793) (xy 140.263626 -112.595152)
			(xy 140.263626 -107.424728) (xy 139.854432 -107.015534) (xy 138.75131 -107.015534) (xy 138.342116 -106.60634)
			(xy 138.342116 -105.725976) (xy 138.032236 -105.416096) (xy 134.16407 -105.416096) (xy 133.1722 -106.407966)
			(xy 133.1722 -106.559926) (xy 134.215226 -106.559926) (xy 134.217475 -106.504162) (xy 134.227823 -106.44932)
			(xy 134.246051 -106.39657) (xy 134.271769 -106.347039) (xy 134.304428 -106.301783) (xy 134.343331 -106.261767)
			(xy 134.387649 -106.227845) (xy 134.436436 -106.200742) (xy 134.488651 -106.181035) (xy 134.543179 -106.169144)
			(xy 134.598858 -106.165324) (xy 134.6545 -106.169656) (xy 134.708917 -106.182048) (xy 134.760948 -106.202235)
			(xy 134.809483 -106.229786) (xy 134.853487 -106.264114) (xy 134.89202 -106.304487) (xy 134.924261 -106.350042)
			(xy 134.949522 -106.399807) (xy 134.967264 -106.452722) (xy 134.977107 -106.507657) (xy 134.978843 -106.56344)
			(xy 134.972434 -106.618881) (xy 134.965694 -106.645964) (xy 134.96035 -106.66793) (xy 134.956602 -106.712976)
			(xy 134.960872 -106.757976) (xy 134.973026 -106.801513) (xy 134.992683 -106.842217) (xy 135.019222 -106.878808)
			(xy 135.051809 -106.910133) (xy 135.070342 -106.923078) (xy 135.093302 -106.938945) (xy 135.134746 -106.976326)
			(xy 135.170301 -107.019345) (xy 135.19921 -107.067085) (xy 135.220857 -107.118527) (xy 135.234778 -107.172573)
			(xy 135.240677 -107.228071) (xy 135.238428 -107.283837) (xy 135.228079 -107.33868) (xy 135.209852 -107.39143)
			(xy 135.184133 -107.440962) (xy 135.151474 -107.486219) (xy 135.11257 -107.526236) (xy 135.068251 -107.560158)
			(xy 135.019464 -107.587261) (xy 134.967248 -107.606969) (xy 134.912718 -107.618859) (xy 134.857038 -107.622678)
			(xy 134.801396 -107.618346) (xy 134.746979 -107.605953) (xy 134.694947 -107.585765) (xy 134.646411 -107.558213)
			(xy 134.602407 -107.523884) (xy 134.563874 -107.48351) (xy 134.531633 -107.437954) (xy 134.506373 -107.388187)
			(xy 134.488632 -107.335271) (xy 134.478789 -107.280335) (xy 134.477055 -107.224551) (xy 134.483465 -107.169109)
			(xy 134.490206 -107.142026) (xy 134.495559 -107.120062) (xy 134.499306 -107.075015) (xy 134.495035 -107.030015)
			(xy 134.482879 -106.986477) (xy 134.463221 -106.945773) (xy 134.43668 -106.909182) (xy 134.404092 -106.877857)
			(xy 134.385558 -106.864912) (xy 134.362595 -106.84905) (xy 134.321153 -106.811669) (xy 134.285598 -106.76865)
			(xy 134.25669 -106.720911) (xy 134.235045 -106.669469) (xy 134.221124 -106.615423) (xy 134.215226 -106.559926)
			(xy 133.1722 -106.559926) (xy 133.1722 -107.771692) (xy 133.439662 -108.039154) (xy 133.439662 -109.112558)
			(xy 133.440168 -109.135068) (xy 133.448142 -109.179377) (xy 133.463793 -109.22159) (xy 133.486634 -109.260387)
			(xy 133.51595 -109.294555) (xy 133.550825 -109.323027) (xy 133.590169 -109.344912) (xy 133.632753 -109.359526)
			(xy 133.677244 -109.366413) (xy 133.699758 -109.366304) (xy 133.711958 -109.365939) (xy 133.736361 -109.366577)
			(xy 133.748526 -109.367574) (xy 133.775958 -109.370876) (xy 133.792474 -109.372922) (xy 133.825559 -109.369436)
			(xy 133.856631 -109.357552) (xy 133.870446 -109.34827) (xy 133.912864 -109.317536) (xy 133.921246 -109.26572)
			(xy 133.926465 -109.236458) (xy 133.943483 -109.179505) (xy 133.967731 -109.125235) (xy 133.998799 -109.074559)
			(xy 134.036166 -109.028332) (xy 134.079202 -108.987331) (xy 134.127183 -108.952245) (xy 134.179303 -108.923666)
			(xy 134.234683 -108.902073) (xy 134.292392 -108.887831) (xy 134.35146 -108.881179) (xy 134.410891 -108.882228)
			(xy 134.469687 -108.890962) (xy 134.526857 -108.907234) (xy 134.581441 -108.930769) (xy 134.632518 -108.961171)
			(xy 134.679231 -108.997929) (xy 134.720792 -109.040425) (xy 134.756503 -109.087943) (xy 134.785762 -109.139684)
			(xy 134.808078 -109.194776) (xy 134.823074 -109.252294) (xy 134.827264 -109.281722) (xy 134.829735 -109.297529)
			(xy 134.841533 -109.327258) (xy 134.860353 -109.35312) (xy 134.885014 -109.373489) (xy 134.913966 -109.387084)
			(xy 134.945389 -109.393053) (xy 134.961376 -109.392466) (xy 134.992981 -109.391045) (xy 135.055921 -109.397431)
			(xy 135.086598 -109.405166) (xy 135.112953 -109.412879) (xy 135.16329 -109.434827) (xy 135.209961 -109.463763)
			(xy 135.252001 -109.499091) (xy 135.288544 -109.54008) (xy 135.318834 -109.585884) (xy 135.342245 -109.635556)
			(xy 135.358295 -109.688072) (xy 135.361431 -109.708442) (xy 135.873742 -109.708442) (xy 135.877813 -109.65282)
			(xy 135.889939 -109.598383) (xy 135.909862 -109.546292) (xy 135.937158 -109.497657) (xy 135.971244 -109.453514)
			(xy 136.011393 -109.414805) (xy 136.056751 -109.382354) (xy 136.106351 -109.356853) (xy 136.159135 -109.338846)
			(xy 136.213978 -109.328716) (xy 136.269712 -109.326679) (xy 136.325149 -109.332779) (xy 136.379106 -109.346885)
			(xy 136.430435 -109.368697) (xy 136.478041 -109.397751) (xy 136.520909 -109.433426) (xy 136.558126 -109.474963)
			(xy 136.588899 -109.521476) (xy 136.612571 -109.571973) (xy 136.628639 -109.62538) (xy 136.635779 -109.673898)
			(xy 137.143742 -109.673898) (xy 137.147813 -109.618276) (xy 137.159939 -109.563839) (xy 137.179862 -109.511748)
			(xy 137.207158 -109.463113) (xy 137.241244 -109.41897) (xy 137.281393 -109.380261) (xy 137.326751 -109.34781)
			(xy 137.376351 -109.322309) (xy 137.429135 -109.304302) (xy 137.483978 -109.294172) (xy 137.539712 -109.292135)
			(xy 137.595149 -109.298235) (xy 137.649106 -109.312341) (xy 137.700435 -109.334153) (xy 137.748041 -109.363207)
			(xy 137.790909 -109.398882) (xy 137.828126 -109.440419) (xy 137.858899 -109.486932) (xy 137.882571 -109.537429)
			(xy 137.898639 -109.590836) (xy 137.906759 -109.646012) (xy 137.907268 -109.673898) (xy 137.906759 -109.701784)
			(xy 137.898639 -109.75696) (xy 137.882571 -109.810367) (xy 137.858899 -109.860864) (xy 137.828126 -109.907377)
			(xy 137.790909 -109.948914) (xy 137.748041 -109.984589) (xy 137.700435 -110.013643) (xy 137.649106 -110.035455)
			(xy 137.595149 -110.049561) (xy 137.539712 -110.055661) (xy 137.483978 -110.053624) (xy 137.429135 -110.043494)
			(xy 137.376351 -110.025487) (xy 137.326751 -109.999986) (xy 137.281393 -109.967535) (xy 137.241244 -109.928826)
			(xy 137.207158 -109.884683) (xy 137.179862 -109.836048) (xy 137.159939 -109.783957) (xy 137.147813 -109.72952)
			(xy 137.143742 -109.673898) (xy 136.635779 -109.673898) (xy 136.636759 -109.680556) (xy 136.637268 -109.708442)
			(xy 136.636759 -109.736328) (xy 136.628639 -109.791504) (xy 136.612571 -109.844911) (xy 136.588899 -109.895408)
			(xy 136.558126 -109.941921) (xy 136.520909 -109.983458) (xy 136.478041 -110.019133) (xy 136.430435 -110.048187)
			(xy 136.379106 -110.069999) (xy 136.325149 -110.084105) (xy 136.269712 -110.090205) (xy 136.213978 -110.088168)
			(xy 136.159135 -110.078038) (xy 136.106351 -110.060031) (xy 136.056751 -110.03453) (xy 136.011393 -110.002079)
			(xy 135.971244 -109.96337) (xy 135.937158 -109.919227) (xy 135.909862 -109.870592) (xy 135.889939 -109.818501)
			(xy 135.877813 -109.764064) (xy 135.873742 -109.708442) (xy 135.361431 -109.708442) (xy 135.366651 -109.742346)
			(xy 135.36714 -109.797257) (xy 135.359754 -109.851671) (xy 135.344644 -109.904465) (xy 135.322122 -109.954547)
			(xy 135.292654 -110.000884) (xy 135.256848 -110.042518) (xy 135.215444 -110.07859) (xy 135.169296 -110.108354)
			(xy 135.119359 -110.131196) (xy 135.066664 -110.146644) (xy 135.012298 -110.154378) (xy 134.957385 -110.15424)
			(xy 134.903058 -110.146232) (xy 134.850441 -110.130519) (xy 134.80062 -110.107426) (xy 134.754623 -110.07743)
			(xy 134.713401 -110.041151) (xy 134.677805 -109.999337) (xy 134.64857 -109.952853) (xy 134.626301 -109.902657)
			(xy 134.618476 -109.876336) (xy 134.613638 -109.861088) (xy 134.597552 -109.833451) (xy 134.575104 -109.810677)
			(xy 134.547701 -109.794194) (xy 134.517063 -109.785036) (xy 134.48511 -109.783778) (xy 134.469378 -109.786674)
			(xy 134.440753 -109.792359) (xy 134.382601 -109.797278) (xy 134.324295 -109.794772) (xy 134.266779 -109.784881)
			(xy 134.238746 -109.776768) (xy 134.222705 -109.772445) (xy 134.189515 -109.771289) (xy 134.157149 -109.778724)
			(xy 134.127791 -109.794248) (xy 134.103424 -109.816812) (xy 134.085694 -109.844892) (xy 134.08025 -109.860588)
			(xy 134.070797 -109.888996) (xy 134.044299 -109.942681) (xy 134.009741 -109.991568) (xy 133.967973 -110.034459)
			(xy 133.94436 -110.052866) (xy 133.923126 -110.06822) (xy 133.877273 -110.093582) (xy 133.828378 -110.112425)
			(xy 133.777364 -110.124393) (xy 133.75132 -110.127288) (xy 133.738463 -110.128438) (xy 133.71266 -110.129203)
			(xy 133.699758 -110.128812) (xy 133.67724 -110.12875) (xy 133.63274 -110.135609) (xy 133.590145 -110.150202)
			(xy 133.550789 -110.172074) (xy 133.515904 -110.20054) (xy 133.486582 -110.234708) (xy 133.46374 -110.27351)
			(xy 133.448094 -110.315729) (xy 133.440134 -110.360046) (xy 133.439662 -110.382558) (xy 133.439662 -111.014256)
			(xy 133.413246 -111.040672) (xy 133.400292 -111.121952) (xy 133.419088 -111.159036) (xy 133.432606 -111.186668)
			(xy 133.452939 -111.244727) (xy 133.46531 -111.304986) (xy 133.469499 -111.366359) (xy 133.465429 -111.42774)
			(xy 133.453173 -111.488022) (xy 133.432953 -111.54612) (xy 133.405132 -111.600985) (xy 133.370213 -111.65163)
			(xy 133.328825 -111.69714) (xy 133.281713 -111.736696) (xy 133.229727 -111.769585) (xy 133.173805 -111.795214)
			(xy 133.168478 -111.796835) (xy 134.153988 -111.796835) (xy 134.160323 -111.736874) (xy 134.174475 -111.678264)
			(xy 134.1962 -111.622019) (xy 134.22512 -111.569113) (xy 134.260736 -111.520462) (xy 134.302431 -111.476907)
			(xy 134.349484 -111.439204) (xy 134.401078 -111.408004) (xy 134.456323 -111.383848) (xy 134.51426 -111.367154)
			(xy 134.573888 -111.358211) (xy 134.634174 -111.357173) (xy 134.694074 -111.364059) (xy 134.752552 -111.37875)
			(xy 134.808595 -111.400991) (xy 134.861233 -111.430396) (xy 134.909555 -111.466458) (xy 134.952724 -111.508552)
			(xy 134.989993 -111.555949) (xy 135.020717 -111.607828) (xy 135.044364 -111.663293) (xy 135.060525 -111.721381)
			(xy 135.068919 -111.781089) (xy 135.069403 -111.841381) (xy 135.062723 -111.895124) (xy 135.52219 -111.895124)
			(xy 135.52219 -111.835188) (xy 135.530013 -111.775766) (xy 135.545526 -111.717873) (xy 135.568462 -111.6625)
			(xy 135.598429 -111.610594) (xy 135.634916 -111.563044) (xy 135.677296 -111.520664) (xy 135.724846 -111.484177)
			(xy 135.776752 -111.45421) (xy 135.832125 -111.431274) (xy 135.890018 -111.415761) (xy 135.94944 -111.407938)
			(xy 136.009376 -111.407938) (xy 136.068798 -111.415761) (xy 136.126691 -111.431274) (xy 136.182064 -111.45421)
			(xy 136.23397 -111.484177) (xy 136.28152 -111.520664) (xy 136.3239 -111.563044) (xy 136.360387 -111.610594)
			(xy 136.390354 -111.6625) (xy 136.41329 -111.717873) (xy 136.428803 -111.775766) (xy 136.436626 -111.835188)
			(xy 136.437116 -111.865156) (xy 136.436626 -111.895124) (xy 136.428803 -111.954546) (xy 136.41329 -112.012439)
			(xy 136.390354 -112.067812) (xy 136.360387 -112.119718) (xy 136.3239 -112.167268) (xy 136.28152 -112.209648)
			(xy 136.23397 -112.246135) (xy 136.182064 -112.276102) (xy 136.126691 -112.299038) (xy 136.068798 -112.314551)
			(xy 136.009376 -112.322374) (xy 135.94944 -112.322374) (xy 135.890018 -112.314551) (xy 135.832125 -112.299038)
			(xy 135.776752 -112.276102) (xy 135.724846 -112.246135) (xy 135.677296 -112.209648) (xy 135.634916 -112.167268)
			(xy 135.598429 -112.119718) (xy 135.568462 -112.067812) (xy 135.545526 -112.012439) (xy 135.530013 -111.954546)
			(xy 135.52219 -111.895124) (xy 135.062723 -111.895124) (xy 135.061966 -111.901216) (xy 135.046738 -111.959556)
			(xy 135.023983 -112.015392) (xy 134.994095 -112.067757) (xy 134.95759 -112.115746) (xy 134.915101 -112.158526)
			(xy 134.891526 -112.177322) (xy 134.874069 -112.19148) (xy 134.843858 -112.224749) (xy 134.819971 -112.262815)
			(xy 134.803154 -112.304489) (xy 134.79393 -112.348472) (xy 134.792589 -112.393391) (xy 134.79917 -112.437846)
			(xy 134.81347 -112.48045) (xy 134.835041 -112.519874) (xy 134.859637 -112.550444) (xy 136.738596 -112.550444)
			(xy 136.738596 -112.490508) (xy 136.746419 -112.431086) (xy 136.761932 -112.373193) (xy 136.784868 -112.31782)
			(xy 136.814835 -112.265914) (xy 136.851322 -112.218364) (xy 136.893702 -112.175984) (xy 136.941252 -112.139497)
			(xy 136.993158 -112.10953) (xy 137.048531 -112.086594) (xy 137.106424 -112.071081) (xy 137.165846 -112.063258)
			(xy 137.225782 -112.063258) (xy 137.285204 -112.071081) (xy 137.343097 -112.086594) (xy 137.39847 -112.10953)
			(xy 137.450376 -112.139497) (xy 137.497926 -112.175984) (xy 137.540306 -112.218364) (xy 137.576793 -112.265914)
			(xy 137.60676 -112.31782) (xy 137.629696 -112.373193) (xy 137.645209 -112.431086) (xy 137.653032 -112.490508)
			(xy 137.653522 -112.520476) (xy 137.653032 -112.550444) (xy 137.645209 -112.609866) (xy 137.629696 -112.667759)
			(xy 137.60676 -112.723132) (xy 137.576793 -112.775038) (xy 137.540306 -112.822588) (xy 137.497926 -112.864968)
			(xy 137.450376 -112.901455) (xy 137.39847 -112.931422) (xy 137.343097 -112.954358) (xy 137.285204 -112.969871)
			(xy 137.225782 -112.977694) (xy 137.165846 -112.977694) (xy 137.106424 -112.969871) (xy 137.048531 -112.954358)
			(xy 136.993158 -112.931422) (xy 136.941252 -112.901455) (xy 136.893702 -112.864968) (xy 136.851322 -112.822588)
			(xy 136.814835 -112.775038) (xy 136.784868 -112.723132) (xy 136.761932 -112.667759) (xy 136.746419 -112.609866)
			(xy 136.738596 -112.550444) (xy 134.859637 -112.550444) (xy 134.863212 -112.554887) (xy 134.879842 -112.570006)
			(xy 134.900574 -112.588621) (xy 134.936884 -112.630882) (xy 134.96666 -112.677976) (xy 134.989267 -112.728901)
			(xy 135.004225 -112.782574) (xy 135.011215 -112.837851) (xy 135.010088 -112.893557) (xy 135.000868 -112.948507)
			(xy 134.983752 -113.00153) (xy 134.959104 -113.051499) (xy 134.934493 -113.087146) (xy 138.324318 -113.087146)
			(xy 138.324318 -113.02721) (xy 138.332141 -112.967788) (xy 138.347654 -112.909895) (xy 138.37059 -112.854522)
			(xy 138.400557 -112.802616) (xy 138.437044 -112.755066) (xy 138.479424 -112.712686) (xy 138.526974 -112.676199)
			(xy 138.57888 -112.646232) (xy 138.634253 -112.623296) (xy 138.692146 -112.607783) (xy 138.751568 -112.59996)
			(xy 138.811504 -112.59996) (xy 138.870926 -112.607783) (xy 138.928819 -112.623296) (xy 138.984192 -112.646232)
			(xy 139.036098 -112.676199) (xy 139.083648 -112.712686) (xy 139.126028 -112.755066) (xy 139.162515 -112.802616)
			(xy 139.192482 -112.854522) (xy 139.215418 -112.909895) (xy 139.230931 -112.967788) (xy 139.238754 -113.02721)
			(xy 139.239244 -113.057178) (xy 139.238754 -113.087146) (xy 139.230931 -113.146568) (xy 139.215418 -113.204461)
			(xy 139.192482 -113.259834) (xy 139.162515 -113.31174) (xy 139.126028 -113.35929) (xy 139.083648 -113.40167)
			(xy 139.036098 -113.438157) (xy 138.984192 -113.468124) (xy 138.928819 -113.49106) (xy 138.870926 -113.506573)
			(xy 138.811504 -113.514396) (xy 138.751568 -113.514396) (xy 138.692146 -113.506573) (xy 138.634253 -113.49106)
			(xy 138.57888 -113.468124) (xy 138.526974 -113.438157) (xy 138.479424 -113.40167) (xy 138.437044 -113.35929)
			(xy 138.400557 -113.31174) (xy 138.37059 -113.259834) (xy 138.347654 -113.204461) (xy 138.332141 -113.146568)
			(xy 138.324318 -113.087146) (xy 134.934493 -113.087146) (xy 134.927448 -113.097351) (xy 134.889458 -113.138109)
			(xy 134.845942 -113.172906) (xy 134.797827 -113.201002) (xy 134.746136 -113.221798) (xy 134.69197 -113.234853)
			(xy 134.63648 -113.239888) (xy 134.580848 -113.236797) (xy 134.526258 -113.225644) (xy 134.473872 -113.206668)
			(xy 134.424803 -113.180272) (xy 134.380097 -113.147018) (xy 134.340705 -113.107614) (xy 134.307465 -113.062898)
			(xy 134.281084 -113.013821) (xy 134.262124 -112.961429) (xy 134.250988 -112.906835) (xy 134.247914 -112.851203)
			(xy 134.252966 -112.795715) (xy 134.266038 -112.741552) (xy 134.28685 -112.689868) (xy 134.314961 -112.641761)
			(xy 134.349771 -112.598256) (xy 134.36981 -112.578896) (xy 134.385902 -112.563198) (xy 134.412878 -112.527243)
			(xy 134.433111 -112.487105) (xy 134.445971 -112.444035) (xy 134.451058 -112.399374) (xy 134.448213 -112.354515)
			(xy 134.437524 -112.310855) (xy 134.419325 -112.269755) (xy 134.394183 -112.232495) (xy 134.362881 -112.200236)
			(xy 134.344918 -112.18672) (xy 134.320703 -112.168756) (xy 134.276767 -112.127463) (xy 134.238633 -112.08076)
			(xy 134.20696 -112.029454) (xy 134.182297 -111.974434) (xy 134.165071 -111.916652) (xy 134.15558 -111.857109)
			(xy 134.153988 -111.796835) (xy 133.168478 -111.796835) (xy 133.114953 -111.813121) (xy 133.054233 -111.822983)
			(xy 132.992739 -111.824623) (xy 132.93158 -111.818011) (xy 132.871857 -111.803266) (xy 132.814648 -111.780653)
			(xy 132.760984 -111.750581) (xy 132.711831 -111.713592) (xy 132.668076 -111.670352) (xy 132.630508 -111.621641)
			(xy 132.599803 -111.568336) (xy 132.587746 -111.540036) (xy 132.581666 -111.526263) (xy 132.564076 -111.50184)
			(xy 132.541247 -111.482225) (xy 132.514455 -111.468511) (xy 132.485193 -111.461464) (xy 132.470144 -111.461042)
			(xy 132.347208 -111.461042) (xy 132.247386 -111.36122) (xy 132.136642 -111.36122) (xy 132.119985 -111.36171)
			(xy 132.087803 -111.370324) (xy 132.058949 -111.386976) (xy 132.03539 -111.410531) (xy 132.018732 -111.439383)
			(xy 132.010112 -111.471563) (xy 132.009642 -111.48822) (xy 132.009642 -111.489998) (xy 132.009515 -111.512681)
			(xy 132.005312 -111.557849) (xy 132.00126 -111.580168) (xy 132.007186 -111.609675) (xy 132.012152 -111.669655)
			(xy 132.009215 -111.729769) (xy 131.998427 -111.788979) (xy 131.979974 -111.846266) (xy 131.954173 -111.90064)
			(xy 131.921469 -111.951165) (xy 131.882427 -111.996969) (xy 131.83772 -112.037262) (xy 131.788119 -112.071349)
			(xy 131.734478 -112.098644) (xy 131.677724 -112.118673) (xy 131.618834 -112.131094) (xy 131.558824 -112.135691)
			(xy 131.49873 -112.132384) (xy 131.439587 -112.121232) (xy 131.382415 -112.102426) (xy 131.328201 -112.076291)
			(xy 131.277878 -112.043278) (xy 131.232315 -112.003954) (xy 131.192298 -111.959) (xy 131.158517 -111.90919)
			(xy 131.131553 -111.855382) (xy 131.111873 -111.798506) (xy 131.099815 -111.739541) (xy 131.095588 -111.679504)
			(xy 131.099264 -111.619431) (xy 131.10464 -111.58982) (xy 131.099644 -111.565171) (xy 131.094422 -111.515147)
			(xy 131.094226 -111.489998) (xy 131.094226 -111.48822) (xy 131.093685 -111.471569) (xy 131.085071 -111.439399)
			(xy 131.068425 -111.410556) (xy 131.044881 -111.387003) (xy 131.016043 -111.370346) (xy 130.983877 -111.361721)
			(xy 130.967226 -111.36122) (xy 127.782828 -111.36122) (xy 127.765048 -111.366554) (xy 127.732904 -111.375569)
			(xy 127.666855 -111.385267) (xy 127.600097 -111.385267) (xy 127.534048 -111.375569) (xy 127.501904 -111.366554)
			(xy 127.484124 -111.36122) (xy 127.125222 -111.36122) (xy 127.101552 -111.361715) (xy 127.055021 -111.370421)
			(xy 127.010906 -111.387593) (xy 126.970734 -111.412635) (xy 126.935893 -111.444683) (xy 126.907589 -111.482628)
			(xy 126.886799 -111.525157) (xy 126.874244 -111.5708) (xy 126.870357 -111.617979) (xy 126.875273 -111.665062)
			(xy 126.881636 -111.687864) (xy 126.890052 -111.715659) (xy 126.900603 -111.772769) (xy 126.903846 -111.830754)
			(xy 126.89973 -111.888684) (xy 126.888319 -111.945628) (xy 126.869798 -112.000671) (xy 126.844464 -112.05293)
			(xy 126.812724 -112.101566) (xy 126.79426 -112.123982) (xy 126.773935 -112.147083) (xy 126.72813 -112.188167)
			(xy 126.677234 -112.222745) (xy 126.622166 -112.250194) (xy 126.563916 -112.270019) (xy 126.503537 -112.281863)
			(xy 126.442114 -112.285513) (xy 126.380757 -112.280903) (xy 126.32057 -112.268115) (xy 126.262638 -112.247381)
			(xy 126.208005 -112.219074) (xy 126.157657 -112.183704) (xy 126.1125 -112.141908) (xy 126.073348 -112.094441)
			(xy 126.040907 -112.042157) (xy 126.027942 -112.014254) (xy 126.01839 -111.994024) (xy 125.993275 -111.957004)
			(xy 125.962065 -111.924956) (xy 125.925725 -111.898869) (xy 125.885377 -111.87955) (xy 125.842269 -111.867597)
			(xy 125.797734 -111.863378) (xy 125.753149 -111.867024) (xy 125.709891 -111.878423) (xy 125.669299 -111.897222)
			(xy 125.632626 -111.92284) (xy 125.616462 -111.938308) (xy 125.250702 -112.304068) (xy 125.250702 -112.724434)
			(xy 129.811 -112.724434) (xy 129.811 -112.664498) (xy 129.818823 -112.605076) (xy 129.834336 -112.547183)
			(xy 129.857272 -112.49181) (xy 129.887239 -112.439904) (xy 129.923726 -112.392354) (xy 129.966106 -112.349974)
			(xy 130.013656 -112.313487) (xy 130.065562 -112.28352) (xy 130.120935 -112.260584) (xy 130.178828 -112.245071)
			(xy 130.23825 -112.237248) (xy 130.298186 -112.237248) (xy 130.357608 -112.245071) (xy 130.415501 -112.260584)
			(xy 130.470874 -112.28352) (xy 130.52278 -112.313487) (xy 130.57033 -112.349974) (xy 130.61271 -112.392354)
			(xy 130.649197 -112.439904) (xy 130.679164 -112.49181) (xy 130.7021 -112.547183) (xy 130.717613 -112.605076)
			(xy 130.725436 -112.664498) (xy 130.725926 -112.694466) (xy 130.725436 -112.724434) (xy 130.717613 -112.783856)
			(xy 130.7021 -112.841749) (xy 130.679164 -112.897122) (xy 130.649197 -112.949028) (xy 130.61271 -112.996578)
			(xy 130.57033 -113.038958) (xy 130.52278 -113.075445) (xy 130.470874 -113.105412) (xy 130.415501 -113.128348)
			(xy 130.357608 -113.143861) (xy 130.298186 -113.151684) (xy 130.23825 -113.151684) (xy 130.178828 -113.143861)
			(xy 130.120935 -113.128348) (xy 130.065562 -113.105412) (xy 130.013656 -113.075445) (xy 129.966106 -113.038958)
			(xy 129.923726 -112.996578) (xy 129.887239 -112.949028) (xy 129.857272 -112.897122) (xy 129.834336 -112.841749)
			(xy 129.818823 -112.783856) (xy 129.811 -112.724434) (xy 125.250702 -112.724434) (xy 125.250702 -113.54968)
			(xy 128.182606 -113.54968) (xy 128.182606 -113.489744) (xy 128.190429 -113.430322) (xy 128.205942 -113.372429)
			(xy 128.228878 -113.317056) (xy 128.258845 -113.26515) (xy 128.295332 -113.2176) (xy 128.337712 -113.17522)
			(xy 128.385262 -113.138733) (xy 128.437168 -113.108766) (xy 128.492541 -113.08583) (xy 128.550434 -113.070317)
			(xy 128.609856 -113.062494) (xy 128.669792 -113.062494) (xy 128.729214 -113.070317) (xy 128.787107 -113.08583)
			(xy 128.84248 -113.108766) (xy 128.894386 -113.138733) (xy 128.941936 -113.17522) (xy 128.984316 -113.2176)
			(xy 129.020803 -113.26515) (xy 129.05077 -113.317056) (xy 129.073706 -113.372429) (xy 129.089219 -113.430322)
			(xy 129.097042 -113.489744) (xy 129.097532 -113.519712) (xy 129.097042 -113.54968) (xy 129.089219 -113.609102)
			(xy 129.073706 -113.666995) (xy 129.05077 -113.722368) (xy 129.020803 -113.774274) (xy 128.984316 -113.821824)
			(xy 128.941936 -113.864204) (xy 128.894386 -113.900691) (xy 128.84248 -113.930658) (xy 128.787107 -113.953594)
			(xy 128.729214 -113.969107) (xy 128.669792 -113.97693) (xy 128.609856 -113.97693) (xy 128.550434 -113.969107)
			(xy 128.492541 -113.953594) (xy 128.437168 -113.930658) (xy 128.385262 -113.900691) (xy 128.337712 -113.864204)
			(xy 128.295332 -113.821824) (xy 128.258845 -113.774274) (xy 128.228878 -113.722368) (xy 128.205942 -113.666995)
			(xy 128.190429 -113.609102) (xy 128.182606 -113.54968) (xy 125.250702 -113.54968) (xy 125.250702 -115.85321)
			(xy 126.003558 -116.606066) (xy 127.87503 -116.606066) (xy 127.890935 -116.605572) (xy 127.921755 -116.597694)
			(xy 127.949667 -116.582437) (xy 127.972937 -116.560748) (xy 127.990118 -116.533976) (xy 128.00014 -116.503785)
			(xy 128.001776 -116.487956) (xy 128.004147 -116.460783) (xy 128.015673 -116.407469) (xy 128.034676 -116.35634)
			(xy 128.060768 -116.30844) (xy 128.093417 -116.264746) (xy 128.131958 -116.226148) (xy 128.175604 -116.193433)
			(xy 128.223465 -116.16727) (xy 128.274565 -116.148191) (xy 128.327862 -116.136585) (xy 128.382268 -116.13269)
			(xy 128.436674 -116.136585) (xy 128.489971 -116.148191) (xy 128.541071 -116.16727) (xy 128.588932 -116.193433)
			(xy 128.632578 -116.226148) (xy 128.671119 -116.264746) (xy 128.703768 -116.30844) (xy 128.72986 -116.35634)
			(xy 128.748863 -116.407469) (xy 128.760389 -116.460783) (xy 128.76276 -116.487956) (xy 128.764361 -116.503792)
			(xy 128.774374 -116.533995) (xy 128.791555 -116.560776) (xy 128.814835 -116.582466) (xy 128.842762 -116.597714)
			(xy 128.873596 -116.60557) (xy 128.889506 -116.606066) (xy 129.201926 -116.606066) (xy 129.411222 -116.39677)
			(xy 129.411222 -114.817398) (xy 129.356866 -114.748564) (xy 129.314194 -114.73815) (xy 129.287895 -114.731294)
			(xy 129.237418 -114.71115) (xy 129.19031 -114.684047) (xy 129.147525 -114.650533) (xy 129.109929 -114.611288)
			(xy 129.078281 -114.567104) (xy 129.053224 -114.518877) (xy 129.035264 -114.467582) (xy 129.024764 -114.414258)
			(xy 129.021937 -114.359984) (xy 129.02684 -114.305857) (xy 129.039375 -114.252974) (xy 129.059286 -114.202405)
			(xy 129.086172 -114.155173) (xy 129.119488 -114.112234) (xy 129.13868 -114.09299) (xy 129.158161 -114.074776)
			(xy 129.201295 -114.04341) (xy 129.248377 -114.018357) (xy 129.298488 -114.000105) (xy 129.350654 -113.989009)
			(xy 129.403856 -113.985286) (xy 129.457058 -113.989009) (xy 129.509224 -114.000105) (xy 129.559335 -114.018357)
			(xy 129.606417 -114.04341) (xy 129.649551 -114.074776) (xy 129.669032 -114.09299) (xy 129.685239 -114.107201)
			(xy 129.721494 -114.130509) (xy 129.761164 -114.14736) (xy 129.80311 -114.15727) (xy 129.846127 -114.159954)
			(xy 129.88898 -114.155335) (xy 129.930437 -114.143547) (xy 129.969308 -114.124927) (xy 130.004477 -114.10001)
			(xy 130.02006 -114.085116) (xy 130.307842 -113.797334) (xy 135.827262 -113.797334) (xy 135.93064 -113.900712)
			(xy 137.636756 -113.900712) (xy 137.640827 -113.84509) (xy 137.652953 -113.790653) (xy 137.672876 -113.738562)
			(xy 137.700172 -113.689927) (xy 137.734258 -113.645784) (xy 137.774407 -113.607075) (xy 137.819765 -113.574624)
			(xy 137.869365 -113.549123) (xy 137.922149 -113.531116) (xy 137.976992 -113.520986) (xy 138.032726 -113.518949)
			(xy 138.088163 -113.525049) (xy 138.14212 -113.539155) (xy 138.193449 -113.560967) (xy 138.241055 -113.590021)
			(xy 138.283923 -113.625696) (xy 138.32114 -113.667233) (xy 138.351913 -113.713746) (xy 138.375585 -113.764243)
			(xy 138.391653 -113.81765) (xy 138.399773 -113.872826) (xy 138.400282 -113.900712) (xy 138.399773 -113.928598)
			(xy 138.391653 -113.983774) (xy 138.375585 -114.037181) (xy 138.351913 -114.087678) (xy 138.32114 -114.134191)
			(xy 138.283923 -114.175728) (xy 138.241055 -114.211403) (xy 138.193449 -114.240457) (xy 138.14212 -114.262269)
			(xy 138.088163 -114.276375) (xy 138.032726 -114.282475) (xy 137.976992 -114.280438) (xy 137.922149 -114.270308)
			(xy 137.869365 -114.252301) (xy 137.819765 -114.2268) (xy 137.774407 -114.194349) (xy 137.734258 -114.15564)
			(xy 137.700172 -114.111497) (xy 137.672876 -114.062862) (xy 137.652953 -114.010771) (xy 137.640827 -113.956334)
			(xy 137.636756 -113.900712) (xy 135.93064 -113.900712) (xy 136.63676 -114.606832) (xy 136.63676 -114.682778)
			(xy 136.668764 -114.715036) (xy 136.668764 -114.93271) (xy 138.604734 -114.93271) (xy 138.604734 -114.872774)
			(xy 138.612557 -114.813352) (xy 138.62807 -114.755459) (xy 138.651006 -114.700086) (xy 138.680973 -114.64818)
			(xy 138.71746 -114.60063) (xy 138.75984 -114.55825) (xy 138.80739 -114.521763) (xy 138.859296 -114.491796)
			(xy 138.914669 -114.46886) (xy 138.972562 -114.453347) (xy 139.031984 -114.445524) (xy 139.09192 -114.445524)
			(xy 139.151342 -114.453347) (xy 139.209235 -114.46886) (xy 139.264608 -114.491796) (xy 139.316514 -114.521763)
			(xy 139.364064 -114.55825) (xy 139.406444 -114.60063) (xy 139.442931 -114.64818) (xy 139.472898 -114.700086)
			(xy 139.495834 -114.755459) (xy 139.511347 -114.813352) (xy 139.51917 -114.872774) (xy 139.51966 -114.902742)
			(xy 139.51917 -114.93271) (xy 139.511347 -114.992132) (xy 139.495834 -115.050025) (xy 139.472898 -115.105398)
			(xy 139.442931 -115.157304) (xy 139.406444 -115.204854) (xy 139.364064 -115.247234) (xy 139.316514 -115.283721)
			(xy 139.264608 -115.313688) (xy 139.209235 -115.336624) (xy 139.151342 -115.352137) (xy 139.09192 -115.35996)
			(xy 139.031984 -115.35996) (xy 138.972562 -115.352137) (xy 138.914669 -115.336624) (xy 138.859296 -115.313688)
			(xy 138.80739 -115.283721) (xy 138.75984 -115.247234) (xy 138.71746 -115.204854) (xy 138.680973 -115.157304)
			(xy 138.651006 -115.105398) (xy 138.62807 -115.050025) (xy 138.612557 -114.992132) (xy 138.604734 -114.93271)
			(xy 136.668764 -114.93271) (xy 136.668764 -115.788475) (xy 137.473499 -115.788475) (xy 137.476057 -115.733987)
			(xy 137.486349 -115.680419) (xy 137.504166 -115.628862) (xy 137.529144 -115.580369) (xy 137.560775 -115.535928)
			(xy 137.598412 -115.496445) (xy 137.641289 -115.462725) (xy 137.688532 -115.435455) (xy 137.739177 -115.415192)
			(xy 137.792192 -115.402349) (xy 137.846495 -115.397187) (xy 137.90098 -115.399812) (xy 137.954536 -115.410171)
			(xy 138.00607 -115.428051) (xy 138.054532 -115.453089) (xy 138.098934 -115.484774) (xy 138.138371 -115.52246)
			(xy 138.172039 -115.565379) (xy 138.19925 -115.612655) (xy 138.209782 -115.637818) (xy 138.218225 -115.657969)
			(xy 138.241128 -115.695176) (xy 138.270054 -115.727919) (xy 138.304152 -115.755235) (xy 138.342419 -115.776319)
			(xy 138.383727 -115.79055) (xy 138.426859 -115.79751) (xy 138.470547 -115.796992) (xy 138.513503 -115.789014)
			(xy 138.53414 -115.781836) (xy 138.56296 -115.771671) (xy 138.622566 -115.758193) (xy 138.683436 -115.752767)
			(xy 138.744487 -115.755488) (xy 138.804632 -115.766309) (xy 138.862803 -115.785037) (xy 138.917965 -115.811338)
			(xy 138.969136 -115.844746) (xy 139.015408 -115.884665) (xy 139.055956 -115.930386) (xy 139.090059 -115.981097)
			(xy 139.117112 -116.035894) (xy 139.136633 -116.093804) (xy 139.148274 -116.153796) (xy 139.151829 -116.214803)
			(xy 139.147235 -116.275742) (xy 139.134573 -116.335527) (xy 139.114069 -116.393096) (xy 139.086087 -116.447424)
			(xy 139.051124 -116.497546) (xy 139.009803 -116.54257) (xy 138.962859 -116.581695) (xy 138.911126 -116.614226)
			(xy 138.855524 -116.639584) (xy 138.797042 -116.657318) (xy 138.736721 -116.667113) (xy 138.675633 -116.668794)
			(xy 138.614864 -116.662331) (xy 138.555496 -116.64784) (xy 138.498584 -116.625578) (xy 138.44514 -116.595942)
			(xy 138.396115 -116.559457) (xy 138.35238 -116.516773) (xy 138.314714 -116.46865) (xy 138.283787 -116.415943)
			(xy 138.260148 -116.359589) (xy 138.251692 -116.330222) (xy 138.24557 -116.309241) (xy 138.227166 -116.269602)
			(xy 138.202247 -116.233701) (xy 138.171547 -116.202597) (xy 138.135975 -116.177209) (xy 138.096581 -116.158288)
			(xy 138.054529 -116.146392) (xy 138.011061 -116.141873) (xy 137.967461 -116.144864) (xy 137.94613 -116.149628)
			(xy 137.919536 -116.155694) (xy 137.865245 -116.16099) (xy 137.810754 -116.158499) (xy 137.757173 -116.148272)
			(xy 137.705595 -116.130519) (xy 137.657071 -116.1056) (xy 137.612591 -116.074024) (xy 137.573061 -116.036435)
			(xy 137.539289 -115.9936) (xy 137.511961 -115.946391) (xy 137.491636 -115.895771) (xy 137.478727 -115.842772)
			(xy 137.473499 -115.788475) (xy 136.668764 -115.788475) (xy 136.668764 -117.504464) (xy 136.797542 -117.633242)
			(xy 137.473434 -117.633242) (xy 137.477505 -117.57762) (xy 137.489631 -117.523183) (xy 137.509554 -117.471092)
			(xy 137.53685 -117.422457) (xy 137.570936 -117.378314) (xy 137.611085 -117.339605) (xy 137.656443 -117.307154)
			(xy 137.706043 -117.281653) (xy 137.758827 -117.263646) (xy 137.81367 -117.253516) (xy 137.869404 -117.251479)
			(xy 137.924841 -117.257579) (xy 137.978798 -117.271685) (xy 138.030127 -117.293497) (xy 138.077733 -117.322551)
			(xy 138.120601 -117.358226) (xy 138.157818 -117.399763) (xy 138.188591 -117.446276) (xy 138.198959 -117.468392)
			(xy 138.642834 -117.468392) (xy 138.642834 -117.408456) (xy 138.650657 -117.349034) (xy 138.66617 -117.291141)
			(xy 138.689106 -117.235768) (xy 138.719073 -117.183862) (xy 138.75556 -117.136312) (xy 138.79794 -117.093932)
			(xy 138.84549 -117.057445) (xy 138.897396 -117.027478) (xy 138.952769 -117.004542) (xy 139.010662 -116.989029)
			(xy 139.070084 -116.981206) (xy 139.13002 -116.981206) (xy 139.189442 -116.989029) (xy 139.247335 -117.004542)
			(xy 139.302708 -117.027478) (xy 139.354614 -117.057445) (xy 139.402164 -117.093932) (xy 139.444544 -117.136312)
			(xy 139.481031 -117.183862) (xy 139.510998 -117.235768) (xy 139.533934 -117.291141) (xy 139.549447 -117.349034)
			(xy 139.55727 -117.408456) (xy 139.55776 -117.438424) (xy 139.55727 -117.468392) (xy 139.549447 -117.527814)
			(xy 139.533934 -117.585707) (xy 139.510998 -117.64108) (xy 139.481031 -117.692986) (xy 139.444544 -117.740536)
			(xy 139.402164 -117.782916) (xy 139.354614 -117.819403) (xy 139.302708 -117.84937) (xy 139.247335 -117.872306)
			(xy 139.189442 -117.887819) (xy 139.13002 -117.895642) (xy 139.070084 -117.895642) (xy 139.010662 -117.887819)
			(xy 138.952769 -117.872306) (xy 138.897396 -117.84937) (xy 138.84549 -117.819403) (xy 138.79794 -117.782916)
			(xy 138.75556 -117.740536) (xy 138.719073 -117.692986) (xy 138.689106 -117.64108) (xy 138.66617 -117.585707)
			(xy 138.650657 -117.527814) (xy 138.642834 -117.468392) (xy 138.198959 -117.468392) (xy 138.212263 -117.496773)
			(xy 138.228331 -117.55018) (xy 138.236451 -117.605356) (xy 138.23696 -117.633242) (xy 138.236451 -117.661128)
			(xy 138.228331 -117.716304) (xy 138.212263 -117.769711) (xy 138.188591 -117.820208) (xy 138.157818 -117.866721)
			(xy 138.120601 -117.908258) (xy 138.077733 -117.943933) (xy 138.030127 -117.972987) (xy 137.978798 -117.994799)
			(xy 137.924841 -118.008905) (xy 137.869404 -118.015005) (xy 137.81367 -118.012968) (xy 137.758827 -118.002838)
			(xy 137.706043 -117.984831) (xy 137.656443 -117.95933) (xy 137.611085 -117.926879) (xy 137.570936 -117.88817)
			(xy 137.53685 -117.844027) (xy 137.509554 -117.795392) (xy 137.489631 -117.743301) (xy 137.477505 -117.688864)
			(xy 137.473434 -117.633242) (xy 136.797542 -117.633242) (xy 137.982452 -118.818152) (xy 137.982452 -118.851934)
			(xy 137.982999 -118.868582) (xy 137.991622 -118.900741) (xy 138.008271 -118.929575) (xy 138.031813 -118.95312)
			(xy 138.060646 -118.969773) (xy 138.092804 -118.978399) (xy 138.109452 -118.978934) (xy 138.17473 -118.978934)
			(xy 138.211306 -118.94439) (xy 138.234652 -118.923005) (xy 138.285725 -118.885585) (xy 138.341049 -118.854798)
			(xy 138.399769 -118.831121) (xy 138.460974 -118.814921) (xy 138.523718 -118.806448) (xy 138.587029 -118.805834)
			(xy 138.649926 -118.813088) (xy 138.711434 -118.828098) (xy 138.770602 -118.850631) (xy 138.826514 -118.880338)
			(xy 138.878302 -118.91676) (xy 138.925166 -118.959332) (xy 138.966379 -119.007395) (xy 139.001304 -119.060205)
			(xy 139.029399 -119.116944) (xy 139.050229 -119.176733) (xy 139.063472 -119.238646) (xy 139.068923 -119.301724)
			(xy 139.066497 -119.364991) (xy 139.056231 -119.427467) (xy 139.038286 -119.488184) (xy 139.012938 -119.546202)
			(xy 138.98058 -119.600623) (xy 138.941714 -119.650603) (xy 138.919712 -119.67337) (xy 138.822684 -119.770398)
			(xy 138.742928 -119.850408) (xy 138.597386 -119.99595) (xy 138.05662 -119.99595) (xy 137.945368 -120.107202)
			(xy 137.945368 -120.156478) (xy 137.781538 -120.320308) (xy 137.774934 -120.360948) (xy 137.770259 -120.387067)
			(xy 137.754632 -120.437775) (xy 137.732129 -120.485827) (xy 137.703184 -120.530298) (xy 137.668355 -120.570328)
			(xy 137.628316 -120.605146) (xy 137.583837 -120.634079) (xy 137.535778 -120.656569) (xy 137.485067 -120.672182)
			(xy 137.458958 -120.676924) (xy 137.418318 -120.683528) (xy 135.478012 -122.623834) (xy 135.478012 -123.04522)
			(xy 135.725916 -123.293124) (xy 138.230356 -123.293124)
		)
		(stroke
			(width 0)
			(type solid)
		)
		(fill yes)
		(layer "B.Cu")
		(net "P3V3_CLK_NODE1")
	)
	(gr_poly
		(pts
			(xy 92.971112 -158.51632) (xy 92.971112 -150.102316) (xy 89.18194 -146.313144) (xy 89.18194 -139.937236)
			(xy 89.131394 -139.831064) (xy 89.098882 -135.754872) (xy 89.119964 -135.573008) (xy 89.121313 -135.556433)
			(xy 89.116429 -135.523552) (xy 89.103225 -135.493044) (xy 89.082597 -135.466976) (xy 89.05594 -135.447115)
			(xy 89.040716 -135.44042) (xy 89.014732 -135.429522) (xy 88.966028 -135.401192) (xy 88.922021 -135.366005)
			(xy 88.88367 -135.324726) (xy 88.851809 -135.278255) (xy 88.827131 -135.227602) (xy 88.810174 -135.173869)
			(xy 88.801306 -135.118227) (xy 88.800721 -135.061885) (xy 88.808431 -135.006071) (xy 88.824269 -134.951998)
			(xy 88.847889 -134.900843) (xy 88.878778 -134.85372) (xy 88.916263 -134.811654) (xy 88.95953 -134.77556)
			(xy 89.007635 -134.746225) (xy 89.059533 -134.724285) (xy 89.08669 -134.716774) (xy 89.102817 -134.712076)
			(xy 89.132011 -134.695481) (xy 89.155865 -134.671847) (xy 89.172728 -134.642807) (xy 89.181433 -134.610375)
			(xy 89.18194 -134.593584) (xy 89.18194 -132.84581) (xy 89.107772 -132.771642) (xy 89.09558 -132.771642)
			(xy 88.194388 -131.87045) (xy 88.182662 -131.859423) (xy 88.154914 -131.843127) (xy 88.123971 -131.834293)
			(xy 88.091802 -131.833482) (xy 88.076024 -131.836668) (xy 88.045786 -131.843136) (xy 87.984212 -131.848829)
			(xy 87.922433 -131.846181) (xy 87.861572 -131.835243) (xy 87.802737 -131.816212) (xy 87.746999 -131.789436)
			(xy 87.695372 -131.755401) (xy 87.648796 -131.714727) (xy 87.608119 -131.668154) (xy 87.57408 -131.61653)
			(xy 87.5473 -131.560794) (xy 87.528265 -131.50196) (xy 87.517322 -131.4411) (xy 87.514671 -131.379321)
			(xy 87.520359 -131.317747) (xy 87.526876 -131.28752) (xy 87.530057 -131.27174) (xy 87.529256 -131.239569)
			(xy 87.520427 -131.208623) (xy 87.504132 -131.180872) (xy 87.493094 -131.169156) (xy 86.961726 -130.637788)
			(xy 86.950098 -130.626784) (xy 86.922566 -130.610465) (xy 86.891838 -130.601512) (xy 86.859849 -130.60049)
			(xy 86.844124 -130.603498) (xy 86.814483 -130.609636) (xy 86.754185 -130.614963) (xy 86.693712 -130.612295)
			(xy 86.634118 -130.601678) (xy 86.576444 -130.583298) (xy 86.521696 -130.557475) (xy 86.470831 -130.52466)
			(xy 86.424735 -130.485426) (xy 86.384213 -130.440457) (xy 86.349973 -130.39054) (xy 86.322613 -130.336544)
			(xy 86.302609 -130.279412) (xy 86.290312 -130.220143) (xy 86.285935 -130.159769) (xy 86.289555 -130.099345)
			(xy 86.30111 -130.039926) (xy 86.320396 -129.982548) (xy 86.347078 -129.928214) (xy 86.38069 -129.877871)
			(xy 86.420646 -129.832399) (xy 86.466247 -129.792591) (xy 86.516698 -129.759142) (xy 86.571118 -129.732635)
			(xy 86.628557 -129.713534) (xy 86.658196 -129.707386) (xy 86.672497 -129.704229) (xy 86.699238 -129.692307)
			(xy 86.722555 -129.674599) (xy 86.741216 -129.652038) (xy 86.754238 -129.625814) (xy 86.760934 -129.597311)
			(xy 86.76132 -129.582672) (xy 86.76132 -128.65735) (xy 86.760815 -128.634229) (xy 86.752452 -128.588749)
			(xy 86.735994 -128.545535) (xy 86.711983 -128.506014) (xy 86.681215 -128.471494) (xy 86.644706 -128.443115)
			(xy 86.603661 -128.421814) (xy 86.559439 -128.408296) (xy 86.53653 -128.405128) (xy 86.506493 -128.401161)
			(xy 86.447751 -128.386321) (xy 86.391481 -128.363859) (xy 86.338667 -128.334169) (xy 86.290232 -128.29777)
			(xy 86.247023 -128.255299) (xy 86.209796 -128.207497) (xy 86.179202 -128.155201) (xy 86.155776 -128.099326)
			(xy 86.139927 -128.040848) (xy 86.131933 -127.98079) (xy 86.131934 -127.920203) (xy 86.139928 -127.860145)
			(xy 86.155778 -127.801667) (xy 86.179205 -127.745792) (xy 86.2098 -127.693497) (xy 86.247028 -127.645696)
			(xy 86.290237 -127.603225) (xy 86.338673 -127.566827) (xy 86.391488 -127.537138) (xy 86.447758 -127.514677)
			(xy 86.5065 -127.499838) (xy 86.53653 -127.495808) (xy 86.559433 -127.492636) (xy 86.603633 -127.479086)
			(xy 86.644656 -127.457767) (xy 86.681147 -127.429382) (xy 86.711906 -127.394868) (xy 86.735918 -127.355361)
			(xy 86.752391 -127.312164) (xy 86.760783 -127.266701) (xy 86.76132 -127.243586) (xy 86.76132 -126.94666)
			(xy 86.88832 -126.81966) (xy 86.88832 -126.789434) (xy 86.867622 -126.765637) (xy 86.832279 -126.7134)
			(xy 86.804446 -126.656804) (xy 86.784649 -126.596922) (xy 86.773264 -126.534889) (xy 86.770507 -126.471879)
			(xy 86.776429 -126.409088) (xy 86.790918 -126.347706) (xy 86.813701 -126.288895) (xy 86.844345 -126.23377)
			(xy 86.86292 -126.208282) (xy 86.88832 -126.1745) (xy 86.88832 -125.51537) (xy 85.178646 -123.805696)
			(xy 84.8614 -123.805696) (xy 84.54136 -123.485656) (xy 84.54136 -116.311426) (xy 81.99374 -113.763806)
			(xy 81.99374 -112.620044) (xy 81.172304 -111.798608) (xy 80.554322 -111.62157) (xy 80.527144 -111.603536)
			(xy 80.457294 -111.599726) (xy 80.426306 -111.615982) (xy 80.402089 -111.628171) (xy 80.351012 -111.646344)
			(xy 80.297877 -111.657105) (xy 80.243753 -111.660236) (xy 80.189731 -111.655676) (xy 80.136899 -111.643516)
			(xy 80.086319 -111.624) (xy 80.039011 -111.597521) (xy 79.995927 -111.564614) (xy 79.957935 -111.525939)
			(xy 79.925798 -111.482277) (xy 79.900165 -111.434505) (xy 79.890366 -111.409226) (xy 79.882145 -111.388177)
			(xy 79.859373 -111.34915) (xy 79.830067 -111.314758) (xy 79.795148 -111.286081) (xy 79.755714 -111.264022)
			(xy 79.713004 -111.249274) (xy 79.668361 -111.2423) (xy 79.645764 -111.242348) (xy 79.617913 -111.242511)
			(xy 79.562631 -111.23574) (xy 79.508922 -111.221004) (xy 79.457925 -111.198615) (xy 79.410726 -111.169051)
			(xy 79.368325 -111.132939) (xy 79.331626 -111.091046) (xy 79.301407 -111.044263) (xy 79.27831 -110.993583)
			(xy 79.262827 -110.940084) (xy 79.255286 -110.884902) (xy 79.255848 -110.829211) (xy 79.2645 -110.774192)
			(xy 79.28106 -110.721017) (xy 79.305174 -110.670813) (xy 79.33633 -110.624649) (xy 79.373867 -110.583505)
			(xy 79.395066 -110.565438) (xy 79.427578 -110.539022) (xy 79.448152 -110.45825) (xy 79.386938 -110.308136)
			(xy 79.380837 -110.294326) (xy 79.363187 -110.269841) (xy 79.34028 -110.250186) (xy 79.313398 -110.236459)
			(xy 79.284045 -110.229428) (xy 79.253861 -110.229487) (xy 79.23911 -110.232698) (xy 79.213151 -110.238559)
			(xy 79.1602 -110.243867) (xy 79.107026 -110.241759) (xy 79.054662 -110.232274) (xy 79.004126 -110.215597)
			(xy 78.956401 -110.192053) (xy 78.912415 -110.162099) (xy 78.8924 -110.14456) (xy 78.874534 -110.129049)
			(xy 78.834227 -110.104282) (xy 78.790033 -110.087402) (xy 78.743478 -110.078992) (xy 78.696171 -110.079342)
			(xy 78.649746 -110.08844) (xy 78.605807 -110.105973) (xy 78.565871 -110.131333) (xy 78.54823 -110.1471)
			(xy 78.527816 -110.1655) (xy 78.482676 -110.196847) (xy 78.433506 -110.221394) (xy 78.381322 -110.238631)
			(xy 78.327205 -110.248202) (xy 78.272275 -110.24991) (xy 78.217668 -110.243718) (xy 78.164514 -110.229756)
			(xy 78.113914 -110.208311) (xy 78.066914 -110.179828) (xy 78.024488 -110.144896) (xy 77.987512 -110.104238)
			(xy 77.956753 -110.058695) (xy 77.932847 -110.009211) (xy 77.916288 -109.956808) (xy 77.90742 -109.902571)
			(xy 77.906425 -109.847623) (xy 77.913324 -109.793101) (xy 77.927976 -109.740133) (xy 77.950075 -109.689816)
			(xy 77.979166 -109.643189) (xy 78.014645 -109.60122) (xy 78.05578 -109.564775) (xy 78.101717 -109.534609)
			(xy 78.151508 -109.511347) (xy 78.204122 -109.49547) (xy 78.258469 -109.487306) (xy 78.313425 -109.487024)
			(xy 78.367853 -109.49463) (xy 78.420626 -109.509968) (xy 78.470653 -109.532718) (xy 78.516898 -109.562411)
			(xy 78.558403 -109.598432) (xy 78.594311 -109.640036) (xy 78.609444 -109.662976) (xy 78.618469 -109.676275)
			(xy 78.641957 -109.6982) (xy 78.670182 -109.713555) (xy 78.701349 -109.721365) (xy 78.73348 -109.721133)
			(xy 78.764531 -109.712873) (xy 78.79253 -109.697111) (xy 78.815699 -109.674849) (xy 78.824582 -109.661452)
			(xy 78.84668 -109.629448) (xy 78.855646 -109.61706) (xy 78.86799 -109.589092) (xy 78.873317 -109.558988)
			(xy 78.87132 -109.528483) (xy 78.862113 -109.499331) (xy 78.846227 -109.473211) (xy 78.835758 -109.462062)
			(xy 75.456288 -106.082592) (xy 70.950836 -106.082592) (xy 67.257676 -106.06405) (xy 67.241964 -106.064433)
			(xy 67.211457 -106.071951) (xy 67.183713 -106.086698) (xy 67.160415 -106.10778) (xy 67.142978 -106.133918)
			(xy 67.132459 -106.163525) (xy 67.130422 -106.179112) (xy 67.127376 -106.206056) (xy 67.114643 -106.258763)
			(xy 67.094578 -106.309137) (xy 67.067585 -106.356164) (xy 67.034208 -106.398896) (xy 66.995118 -106.436475)
			(xy 66.951103 -106.468142) (xy 66.90305 -106.493261) (xy 66.851924 -106.511326) (xy 66.798756 -106.521972)
			(xy 66.744617 -106.524986) (xy 66.690596 -106.520307) (xy 66.664078 -106.514646) (xy 66.641688 -106.509924)
			(xy 66.595987 -106.507679) (xy 66.550623 -106.513653) (xy 66.507062 -106.527651) (xy 66.46671 -106.549223)
			(xy 66.430873 -106.57767) (xy 66.400708 -106.612073) (xy 66.377189 -106.651322) (xy 66.361077 -106.694147)
			(xy 66.352893 -106.739164) (xy 66.35242 -106.762042) (xy 66.35242 -107.352592) (xy 67.06311 -107.352592)
			(xy 67.067181 -107.29697) (xy 67.079307 -107.242533) (xy 67.09923 -107.190442) (xy 67.126526 -107.141807)
			(xy 67.160612 -107.097664) (xy 67.200761 -107.058955) (xy 67.246119 -107.026504) (xy 67.295719 -107.001003)
			(xy 67.348503 -106.982996) (xy 67.403346 -106.972866) (xy 67.45908 -106.970829) (xy 67.514517 -106.976929)
			(xy 67.568474 -106.991035) (xy 67.619803 -107.012847) (xy 67.667409 -107.041901) (xy 67.710277 -107.077576)
			(xy 67.747494 -107.119113) (xy 67.778267 -107.165626) (xy 67.801939 -107.216123) (xy 67.818007 -107.26953)
			(xy 67.826127 -107.324706) (xy 67.826636 -107.352592) (xy 67.826127 -107.380478) (xy 67.818007 -107.435654)
			(xy 67.801939 -107.489061) (xy 67.778267 -107.539558) (xy 67.747494 -107.586071) (xy 67.710277 -107.627608)
			(xy 67.667409 -107.663283) (xy 67.619803 -107.692337) (xy 67.568474 -107.714149) (xy 67.514517 -107.728255)
			(xy 67.45908 -107.734355) (xy 67.403346 -107.732318) (xy 67.348503 -107.722188) (xy 67.295719 -107.704181)
			(xy 67.246119 -107.67868) (xy 67.200761 -107.646229) (xy 67.160612 -107.60752) (xy 67.126526 -107.563377)
			(xy 67.09923 -107.514742) (xy 67.079307 -107.462651) (xy 67.067181 -107.408214) (xy 67.06311 -107.352592)
			(xy 66.35242 -107.352592) (xy 66.35242 -111.06277) (xy 66.6623 -111.37265) (xy 74.365104 -111.37265)
			(xy 77.799184 -114.80673) (xy 77.799184 -116.004086) (xy 81.24266 -116.004086) (xy 81.246731 -115.948464)
			(xy 81.258857 -115.894027) (xy 81.27878 -115.841936) (xy 81.306076 -115.793301) (xy 81.340162 -115.749158)
			(xy 81.380311 -115.710449) (xy 81.425669 -115.677998) (xy 81.475269 -115.652497) (xy 81.528053 -115.63449)
			(xy 81.582896 -115.62436) (xy 81.63863 -115.622323) (xy 81.694067 -115.628423) (xy 81.748024 -115.642529)
			(xy 81.799353 -115.664341) (xy 81.846959 -115.693395) (xy 81.889827 -115.72907) (xy 81.927044 -115.770607)
			(xy 81.957817 -115.81712) (xy 81.981489 -115.867617) (xy 81.997557 -115.921024) (xy 82.005677 -115.9762)
			(xy 82.006186 -116.004086) (xy 82.005677 -116.031972) (xy 81.997557 -116.087148) (xy 81.981489 -116.140555)
			(xy 81.957817 -116.191052) (xy 81.927044 -116.237565) (xy 81.889827 -116.279102) (xy 81.846959 -116.314777)
			(xy 81.799353 -116.343831) (xy 81.748024 -116.365643) (xy 81.694067 -116.379749) (xy 81.63863 -116.385849)
			(xy 81.582896 -116.383812) (xy 81.528053 -116.373682) (xy 81.475269 -116.355675) (xy 81.425669 -116.330174)
			(xy 81.380311 -116.297723) (xy 81.340162 -116.259014) (xy 81.306076 -116.214871) (xy 81.27878 -116.166236)
			(xy 81.258857 -116.114145) (xy 81.246731 -116.059708) (xy 81.24266 -116.004086) (xy 77.799184 -116.004086)
			(xy 77.799184 -118.213632) (xy 77.799673 -118.236169) (xy 77.807626 -118.280536) (xy 77.823277 -118.322805)
			(xy 77.846136 -118.361652) (xy 77.875487 -118.39586) (xy 77.91041 -118.424357) (xy 77.94981 -118.44625)
			(xy 77.992453 -118.460852) (xy 78.037002 -118.467707) (xy 78.082062 -118.4666) (xy 78.104238 -118.462552)
			(xy 78.131972 -118.457358) (xy 78.188309 -118.454239) (xy 78.24449 -118.459452) (xy 78.299291 -118.472883)
			(xy 78.351516 -118.49424) (xy 78.400026 -118.523055) (xy 78.443762 -118.558702) (xy 78.481772 -118.600401)
			(xy 78.513224 -118.647244) (xy 78.537434 -118.698209) (xy 78.553874 -118.752184) (xy 78.558667 -118.78437)
			(xy 80.126584 -118.78437) (xy 80.130655 -118.728748) (xy 80.142781 -118.674311) (xy 80.162704 -118.62222)
			(xy 80.19 -118.573585) (xy 80.224086 -118.529442) (xy 80.264235 -118.490733) (xy 80.309593 -118.458282)
			(xy 80.359193 -118.432781) (xy 80.411977 -118.414774) (xy 80.46682 -118.404644) (xy 80.522554 -118.402607)
			(xy 80.577991 -118.408707) (xy 80.631948 -118.422813) (xy 80.683277 -118.444625) (xy 80.730883 -118.473679)
			(xy 80.773751 -118.509354) (xy 80.810968 -118.550891) (xy 80.841741 -118.597404) (xy 80.865413 -118.647901)
			(xy 80.873763 -118.675654) (xy 81.581226 -118.675654) (xy 81.581226 -118.615718) (xy 81.589049 -118.556296)
			(xy 81.604562 -118.498403) (xy 81.627498 -118.44303) (xy 81.657465 -118.391124) (xy 81.693952 -118.343574)
			(xy 81.736332 -118.301194) (xy 81.783882 -118.264707) (xy 81.835788 -118.23474) (xy 81.891161 -118.211804)
			(xy 81.949054 -118.196291) (xy 82.008476 -118.188468) (xy 82.068412 -118.188468) (xy 82.127834 -118.196291)
			(xy 82.185727 -118.211804) (xy 82.2411 -118.23474) (xy 82.293006 -118.264707) (xy 82.340556 -118.301194)
			(xy 82.382936 -118.343574) (xy 82.419423 -118.391124) (xy 82.44939 -118.44303) (xy 82.472326 -118.498403)
			(xy 82.487839 -118.556296) (xy 82.495662 -118.615718) (xy 82.496152 -118.645686) (xy 82.495662 -118.675654)
			(xy 82.487839 -118.735076) (xy 82.472326 -118.792969) (xy 82.44939 -118.848342) (xy 82.419423 -118.900248)
			(xy 82.382936 -118.947798) (xy 82.340556 -118.990178) (xy 82.293006 -119.026665) (xy 82.2411 -119.056632)
			(xy 82.185727 -119.079568) (xy 82.127834 -119.095081) (xy 82.068412 -119.102904) (xy 82.008476 -119.102904)
			(xy 81.949054 -119.095081) (xy 81.891161 -119.079568) (xy 81.835788 -119.056632) (xy 81.783882 -119.026665)
			(xy 81.736332 -118.990178) (xy 81.693952 -118.947798) (xy 81.657465 -118.900248) (xy 81.627498 -118.848342)
			(xy 81.604562 -118.792969) (xy 81.589049 -118.735076) (xy 81.581226 -118.675654) (xy 80.873763 -118.675654)
			(xy 80.881481 -118.701308) (xy 80.889601 -118.756484) (xy 80.89011 -118.78437) (xy 80.889601 -118.812256)
			(xy 80.881481 -118.867432) (xy 80.865413 -118.920839) (xy 80.841741 -118.971336) (xy 80.810968 -119.017849)
			(xy 80.773751 -119.059386) (xy 80.730883 -119.095061) (xy 80.683277 -119.124115) (xy 80.631948 -119.145927)
			(xy 80.577991 -119.160033) (xy 80.522554 -119.166133) (xy 80.46682 -119.164096) (xy 80.411977 -119.153966)
			(xy 80.359193 -119.135959) (xy 80.309593 -119.110458) (xy 80.264235 -119.078007) (xy 80.224086 -119.039298)
			(xy 80.19 -118.995155) (xy 80.162704 -118.94652) (xy 80.142781 -118.894429) (xy 80.130655 -118.839992)
			(xy 80.126584 -118.78437) (xy 78.558667 -118.78437) (xy 78.562184 -118.807991) (xy 78.562183 -118.864414)
			(xy 78.553873 -118.920222) (xy 78.537432 -118.974196) (xy 78.513221 -119.025161) (xy 78.481768 -119.072003)
			(xy 78.443758 -119.113702) (xy 78.400021 -119.149348) (xy 78.351511 -119.178163) (xy 78.299286 -119.199518)
			(xy 78.244485 -119.212949) (xy 78.188303 -119.218161) (xy 78.131966 -119.215041) (xy 78.104238 -119.20982)
			(xy 78.082057 -119.205758) (xy 78.036981 -119.204616) (xy 77.992411 -119.211447) (xy 77.949746 -119.226037)
			(xy 77.910326 -119.247927) (xy 77.875388 -119.27643) (xy 77.846028 -119.310652) (xy 77.823168 -119.349518)
			(xy 77.807526 -119.391808) (xy 77.799593 -119.436195) (xy 77.799184 -119.45874) (xy 77.799184 -119.667274)
			(xy 77.799646 -119.689133) (xy 77.807141 -119.732204) (xy 77.821896 -119.773357) (xy 77.843478 -119.811378)
			(xy 77.871248 -119.845144) (xy 77.904387 -119.873659) (xy 77.941917 -119.896082) (xy 77.982731 -119.91175)
			(xy 78.025625 -119.920203) (xy 78.069332 -119.921189) (xy 78.09103 -119.91848) (xy 78.118718 -119.914778)
			(xy 78.174579 -119.914551) (xy 78.21622 -119.920512) (xy 79.876902 -119.920512) (xy 79.880973 -119.86489)
			(xy 79.893099 -119.810453) (xy 79.913022 -119.758362) (xy 79.940318 -119.709727) (xy 79.974404 -119.665584)
			(xy 80.014553 -119.626875) (xy 80.059911 -119.594424) (xy 80.109511 -119.568923) (xy 80.162295 -119.550916)
			(xy 80.217138 -119.540786) (xy 80.272872 -119.538749) (xy 80.328309 -119.544849) (xy 80.382266 -119.558955)
			(xy 80.433595 -119.580767) (xy 80.481201 -119.609821) (xy 80.524069 -119.645496) (xy 80.561286 -119.687033)
			(xy 80.592059 -119.733546) (xy 80.615731 -119.784043) (xy 80.631799 -119.83745) (xy 80.639919 -119.892626)
			(xy 80.640428 -119.920512) (xy 80.639919 -119.948398) (xy 80.631799 -120.003574) (xy 80.615731 -120.056981)
			(xy 80.615288 -120.057926) (xy 81.214466 -120.057926) (xy 81.218537 -120.002304) (xy 81.230663 -119.947867)
			(xy 81.250586 -119.895776) (xy 81.277882 -119.847141) (xy 81.311968 -119.802998) (xy 81.352117 -119.764289)
			(xy 81.397475 -119.731838) (xy 81.447075 -119.706337) (xy 81.499859 -119.68833) (xy 81.554702 -119.6782)
			(xy 81.610436 -119.676163) (xy 81.665873 -119.682263) (xy 81.71983 -119.696369) (xy 81.771159 -119.718181)
			(xy 81.818765 -119.747235) (xy 81.861633 -119.78291) (xy 81.89885 -119.824447) (xy 81.929623 -119.87096)
			(xy 81.953295 -119.921457) (xy 81.969363 -119.974864) (xy 81.977483 -120.03004) (xy 81.977992 -120.057926)
			(xy 81.977483 -120.085812) (xy 81.969363 -120.140988) (xy 81.953295 -120.194395) (xy 81.929623 -120.244892)
			(xy 81.89885 -120.291405) (xy 81.861633 -120.332942) (xy 81.818765 -120.368617) (xy 81.771159 -120.397671)
			(xy 81.71983 -120.419483) (xy 81.665873 -120.433589) (xy 81.610436 -120.439689) (xy 81.554702 -120.437652)
			(xy 81.499859 -120.427522) (xy 81.447075 -120.409515) (xy 81.397475 -120.384014) (xy 81.352117 -120.351563)
			(xy 81.311968 -120.312854) (xy 81.277882 -120.268711) (xy 81.250586 -120.220076) (xy 81.230663 -120.167985)
			(xy 81.218537 -120.113548) (xy 81.214466 -120.057926) (xy 80.615288 -120.057926) (xy 80.592059 -120.107478)
			(xy 80.561286 -120.153991) (xy 80.524069 -120.195528) (xy 80.481201 -120.231203) (xy 80.433595 -120.260257)
			(xy 80.382266 -120.282069) (xy 80.328309 -120.296175) (xy 80.272872 -120.302275) (xy 80.217138 -120.300238)
			(xy 80.162295 -120.290108) (xy 80.109511 -120.272101) (xy 80.059911 -120.2466) (xy 80.014553 -120.214149)
			(xy 79.974404 -120.17544) (xy 79.940318 -120.131297) (xy 79.913022 -120.082662) (xy 79.893099 -120.030571)
			(xy 79.880973 -119.976134) (xy 79.876902 -119.920512) (xy 78.21622 -119.920512) (xy 78.229877 -119.922467)
			(xy 78.28343 -119.938359) (xy 78.334095 -119.961885) (xy 78.380791 -119.992544) (xy 78.422519 -120.029682)
			(xy 78.440788 -120.050814) (xy 78.451358 -120.06272) (xy 78.477162 -120.081353) (xy 78.506777 -120.093012)
			(xy 78.538357 -120.096971) (xy 78.569934 -120.092984) (xy 78.599539 -120.081298) (xy 78.612746 -120.072404)
			(xy 78.635461 -120.056566) (xy 78.684535 -120.030914) (xy 78.736802 -120.012626) (xy 78.791164 -120.002087)
			(xy 78.846478 -119.999518) (xy 78.901583 -120.004972) (xy 78.95532 -120.018336) (xy 79.006561 -120.039328)
			(xy 79.054228 -120.067508) (xy 79.097321 -120.102283) (xy 79.134933 -120.142923) (xy 79.166275 -120.188573)
			(xy 79.190688 -120.238275) (xy 79.207659 -120.290985) (xy 79.216831 -120.345594) (xy 79.218012 -120.400955)
			(xy 79.211177 -120.455906) (xy 79.196469 -120.509291) (xy 79.174198 -120.559989) (xy 79.144831 -120.606934)
			(xy 79.108986 -120.649141) (xy 79.067415 -120.685722) (xy 79.020993 -120.715909) (xy 78.970694 -120.739067)
			(xy 78.917576 -120.75471) (xy 78.862754 -120.76251) (xy 78.80738 -120.762301) (xy 78.752618 -120.75409)
			(xy 78.699619 -120.738047) (xy 78.649496 -120.714511) (xy 78.603302 -120.683976) (xy 78.562008 -120.647084)
			(xy 78.543912 -120.626124) (xy 78.533343 -120.614214) (xy 78.507541 -120.595576) (xy 78.477925 -120.583913)
			(xy 78.446342 -120.579953) (xy 78.414763 -120.583942) (xy 78.385157 -120.595632) (xy 78.371954 -120.604534)
			(xy 78.347562 -120.621537) (xy 78.294617 -120.648587) (xy 78.266544 -120.658382) (xy 78.245821 -120.66567)
			(xy 78.207061 -120.686333) (xy 78.172427 -120.713349) (xy 78.142951 -120.745913) (xy 78.119509 -120.783059)
			(xy 78.102798 -120.82368) (xy 78.093315 -120.866568) (xy 78.091343 -120.910448) (xy 78.09694 -120.954014)
			(xy 78.10994 -120.99597) (xy 78.119478 -121.01576) (xy 78.131762 -121.040783) (xy 78.149699 -121.09356)
			(xy 78.15976 -121.148387) (xy 78.16173 -121.204094) (xy 78.155568 -121.259495) (xy 78.141405 -121.313408)
			(xy 78.119542 -121.364684) (xy 78.090446 -121.41223) (xy 78.054738 -121.455033) (xy 78.013177 -121.49218)
			(xy 77.96665 -121.52288) (xy 77.916149 -121.546478) (xy 77.889608 -121.555002) (xy 77.874164 -121.560154)
			(xy 77.846375 -121.577096) (xy 77.823781 -121.600522) (xy 77.810841 -121.623582) (xy 80.124806 -121.623582)
			(xy 80.128877 -121.56796) (xy 80.141003 -121.513523) (xy 80.160926 -121.461432) (xy 80.188222 -121.412797)
			(xy 80.222308 -121.368654) (xy 80.262457 -121.329945) (xy 80.307815 -121.297494) (xy 80.357415 -121.271993)
			(xy 80.410199 -121.253986) (xy 80.465042 -121.243856) (xy 80.520776 -121.241819) (xy 80.576213 -121.247919)
			(xy 80.63017 -121.262025) (xy 80.681499 -121.283837) (xy 80.729105 -121.312891) (xy 80.771973 -121.348566)
			(xy 80.80919 -121.390103) (xy 80.839963 -121.436616) (xy 80.863635 -121.487113) (xy 80.879703 -121.54052)
			(xy 80.887823 -121.595696) (xy 80.888332 -121.623582) (xy 80.887823 -121.651468) (xy 80.879703 -121.706644)
			(xy 80.863635 -121.760051) (xy 80.839963 -121.810548) (xy 80.80919 -121.857061) (xy 80.771973 -121.898598)
			(xy 80.729105 -121.934273) (xy 80.698804 -121.952766) (xy 82.178142 -121.952766) (xy 82.182213 -121.897144)
			(xy 82.194339 -121.842707) (xy 82.214262 -121.790616) (xy 82.241558 -121.741981) (xy 82.275644 -121.697838)
			(xy 82.315793 -121.659129) (xy 82.361151 -121.626678) (xy 82.410751 -121.601177) (xy 82.463535 -121.58317)
			(xy 82.518378 -121.57304) (xy 82.574112 -121.571003) (xy 82.629549 -121.577103) (xy 82.683506 -121.591209)
			(xy 82.734835 -121.613021) (xy 82.782441 -121.642075) (xy 82.825309 -121.67775) (xy 82.862526 -121.719287)
			(xy 82.893299 -121.7658) (xy 82.916971 -121.816297) (xy 82.933039 -121.869704) (xy 82.941159 -121.92488)
			(xy 82.941668 -121.952766) (xy 82.941159 -121.980652) (xy 82.933039 -122.035828) (xy 82.916971 -122.089235)
			(xy 82.893299 -122.139732) (xy 82.862526 -122.186245) (xy 82.825309 -122.227782) (xy 82.782441 -122.263457)
			(xy 82.734835 -122.292511) (xy 82.683506 -122.314323) (xy 82.629549 -122.328429) (xy 82.574112 -122.334529)
			(xy 82.518378 -122.332492) (xy 82.463535 -122.322362) (xy 82.410751 -122.304355) (xy 82.361151 -122.278854)
			(xy 82.315793 -122.246403) (xy 82.275644 -122.207694) (xy 82.241558 -122.163551) (xy 82.214262 -122.114916)
			(xy 82.194339 -122.062825) (xy 82.182213 -122.008388) (xy 82.178142 -121.952766) (xy 80.698804 -121.952766)
			(xy 80.681499 -121.963327) (xy 80.63017 -121.985139) (xy 80.576213 -121.999245) (xy 80.520776 -122.005345)
			(xy 80.465042 -122.003308) (xy 80.410199 -121.993178) (xy 80.357415 -121.975171) (xy 80.307815 -121.94967)
			(xy 80.262457 -121.917219) (xy 80.222308 -121.87851) (xy 80.188222 -121.834367) (xy 80.160926 -121.785732)
			(xy 80.141003 -121.733641) (xy 80.128877 -121.679204) (xy 80.124806 -121.623582) (xy 77.810841 -121.623582)
			(xy 77.807854 -121.628904) (xy 77.799631 -121.660395) (xy 77.799184 -121.676668) (xy 77.799184 -122.556524)
			(xy 78.634844 -123.392184) (xy 78.634844 -124.56693) (xy 83.391992 -124.56693) (xy 83.391992 -124.506994)
			(xy 83.399815 -124.447572) (xy 83.415328 -124.389679) (xy 83.438264 -124.334306) (xy 83.468231 -124.2824)
			(xy 83.504718 -124.23485) (xy 83.547098 -124.19247) (xy 83.594648 -124.155983) (xy 83.646554 -124.126016)
			(xy 83.701927 -124.10308) (xy 83.75982 -124.087567) (xy 83.819242 -124.079744) (xy 83.879178 -124.079744)
			(xy 83.9386 -124.087567) (xy 83.996493 -124.10308) (xy 84.051866 -124.126016) (xy 84.103772 -124.155983)
			(xy 84.151322 -124.19247) (xy 84.193702 -124.23485) (xy 84.230189 -124.2824) (xy 84.260156 -124.334306)
			(xy 84.283092 -124.389679) (xy 84.298605 -124.447572) (xy 84.306428 -124.506994) (xy 84.306918 -124.536962)
			(xy 84.306428 -124.56693) (xy 84.298605 -124.626352) (xy 84.283092 -124.684245) (xy 84.260156 -124.739618)
			(xy 84.230189 -124.791524) (xy 84.193702 -124.839074) (xy 84.151322 -124.881454) (xy 84.103772 -124.917941)
			(xy 84.051866 -124.947908) (xy 83.996493 -124.970844) (xy 83.9386 -124.986357) (xy 83.879178 -124.99418)
			(xy 83.819242 -124.99418) (xy 83.75982 -124.986357) (xy 83.701927 -124.970844) (xy 83.646554 -124.947908)
			(xy 83.594648 -124.917941) (xy 83.547098 -124.881454) (xy 83.504718 -124.839074) (xy 83.468231 -124.791524)
			(xy 83.438264 -124.739618) (xy 83.415328 -124.684245) (xy 83.399815 -124.626352) (xy 83.391992 -124.56693)
			(xy 78.634844 -124.56693) (xy 78.634844 -125.95377) (xy 82.534742 -125.95377) (xy 82.534742 -125.893834)
			(xy 82.542565 -125.834412) (xy 82.558078 -125.776519) (xy 82.581014 -125.721146) (xy 82.610981 -125.66924)
			(xy 82.647468 -125.62169) (xy 82.689848 -125.57931) (xy 82.737398 -125.542823) (xy 82.789304 -125.512856)
			(xy 82.844677 -125.48992) (xy 82.90257 -125.474407) (xy 82.961992 -125.466584) (xy 83.021928 -125.466584)
			(xy 83.08135 -125.474407) (xy 83.139243 -125.48992) (xy 83.194616 -125.512856) (xy 83.246522 -125.542823)
			(xy 83.294072 -125.57931) (xy 83.336452 -125.62169) (xy 83.372939 -125.66924) (xy 83.402906 -125.721146)
			(xy 83.425842 -125.776519) (xy 83.441355 -125.834412) (xy 83.449178 -125.893834) (xy 83.449668 -125.923802)
			(xy 83.449178 -125.95377) (xy 83.441355 -126.013192) (xy 83.425842 -126.071085) (xy 83.402906 -126.126458)
			(xy 83.372939 -126.178364) (xy 83.336452 -126.225914) (xy 83.294072 -126.268294) (xy 83.246522 -126.304781)
			(xy 83.194616 -126.334748) (xy 83.139243 -126.357684) (xy 83.08135 -126.373197) (xy 83.021928 -126.38102)
			(xy 82.961992 -126.38102) (xy 82.90257 -126.373197) (xy 82.844677 -126.357684) (xy 82.789304 -126.334748)
			(xy 82.737398 -126.304781) (xy 82.689848 -126.268294) (xy 82.647468 -126.225914) (xy 82.610981 -126.178364)
			(xy 82.581014 -126.126458) (xy 82.558078 -126.071085) (xy 82.542565 -126.013192) (xy 82.534742 -125.95377)
			(xy 78.634844 -125.95377) (xy 78.634844 -127.552446) (xy 83.27947 -127.552446) (xy 83.27947 -127.49251)
			(xy 83.287293 -127.433088) (xy 83.302806 -127.375195) (xy 83.325742 -127.319822) (xy 83.355709 -127.267916)
			(xy 83.392196 -127.220366) (xy 83.434576 -127.177986) (xy 83.482126 -127.141499) (xy 83.534032 -127.111532)
			(xy 83.589405 -127.088596) (xy 83.647298 -127.073083) (xy 83.70672 -127.06526) (xy 83.766656 -127.06526)
			(xy 83.826078 -127.073083) (xy 83.883971 -127.088596) (xy 83.939344 -127.111532) (xy 83.99125 -127.141499)
			(xy 84.0388 -127.177986) (xy 84.08118 -127.220366) (xy 84.117667 -127.267916) (xy 84.147634 -127.319822)
			(xy 84.17057 -127.375195) (xy 84.186083 -127.433088) (xy 84.193906 -127.49251) (xy 84.194396 -127.522478)
			(xy 84.193906 -127.552446) (xy 84.186083 -127.611868) (xy 84.17057 -127.669761) (xy 84.147634 -127.725134)
			(xy 84.139697 -127.738882) (xy 84.67393 -127.738882) (xy 84.67393 -127.678946) (xy 84.681753 -127.619524)
			(xy 84.697266 -127.561631) (xy 84.720202 -127.506258) (xy 84.750169 -127.454352) (xy 84.786656 -127.406802)
			(xy 84.829036 -127.364422) (xy 84.876586 -127.327935) (xy 84.928492 -127.297968) (xy 84.983865 -127.275032)
			(xy 85.041758 -127.259519) (xy 85.10118 -127.251696) (xy 85.161116 -127.251696) (xy 85.220538 -127.259519)
			(xy 85.278431 -127.275032) (xy 85.333804 -127.297968) (xy 85.38571 -127.327935) (xy 85.43326 -127.364422)
			(xy 85.47564 -127.406802) (xy 85.512127 -127.454352) (xy 85.542094 -127.506258) (xy 85.56503 -127.561631)
			(xy 85.580543 -127.619524) (xy 85.588366 -127.678946) (xy 85.588856 -127.708914) (xy 85.588366 -127.738882)
			(xy 85.580543 -127.798304) (xy 85.56503 -127.856197) (xy 85.542094 -127.91157) (xy 85.512127 -127.963476)
			(xy 85.47564 -128.011026) (xy 85.43326 -128.053406) (xy 85.38571 -128.089893) (xy 85.333804 -128.11986)
			(xy 85.278431 -128.142796) (xy 85.220538 -128.158309) (xy 85.161116 -128.166132) (xy 85.10118 -128.166132)
			(xy 85.041758 -128.158309) (xy 84.983865 -128.142796) (xy 84.928492 -128.11986) (xy 84.876586 -128.089893)
			(xy 84.829036 -128.053406) (xy 84.786656 -128.011026) (xy 84.750169 -127.963476) (xy 84.720202 -127.91157)
			(xy 84.697266 -127.856197) (xy 84.681753 -127.798304) (xy 84.67393 -127.738882) (xy 84.139697 -127.738882)
			(xy 84.117667 -127.77704) (xy 84.08118 -127.82459) (xy 84.0388 -127.86697) (xy 83.99125 -127.903457)
			(xy 83.939344 -127.933424) (xy 83.883971 -127.95636) (xy 83.826078 -127.971873) (xy 83.766656 -127.979696)
			(xy 83.70672 -127.979696) (xy 83.647298 -127.971873) (xy 83.589405 -127.95636) (xy 83.534032 -127.933424)
			(xy 83.482126 -127.903457) (xy 83.434576 -127.86697) (xy 83.392196 -127.82459) (xy 83.355709 -127.77704)
			(xy 83.325742 -127.725134) (xy 83.302806 -127.669761) (xy 83.287293 -127.611868) (xy 83.27947 -127.552446)
			(xy 78.634844 -127.552446) (xy 78.634844 -130.264912) (xy 80.843102 -130.264912) (xy 80.843102 -130.204976)
			(xy 80.850925 -130.145554) (xy 80.866438 -130.087661) (xy 80.889374 -130.032288) (xy 80.919341 -129.980382)
			(xy 80.955828 -129.932832) (xy 80.998208 -129.890452) (xy 81.045758 -129.853965) (xy 81.097664 -129.823998)
			(xy 81.153037 -129.801062) (xy 81.21093 -129.785549) (xy 81.270352 -129.777726) (xy 81.330288 -129.777726)
			(xy 81.38971 -129.785549) (xy 81.447603 -129.801062) (xy 81.502976 -129.823998) (xy 81.554882 -129.853965)
			(xy 81.602432 -129.890452) (xy 81.644812 -129.932832) (xy 81.681299 -129.980382) (xy 81.711266 -130.032288)
			(xy 81.734202 -130.087661) (xy 81.749715 -130.145554) (xy 81.757538 -130.204976) (xy 81.758028 -130.234944)
			(xy 81.757538 -130.264912) (xy 81.749715 -130.324334) (xy 81.734202 -130.382227) (xy 81.711266 -130.4376)
			(xy 81.681299 -130.489506) (xy 81.644812 -130.537056) (xy 81.602432 -130.579436) (xy 81.554882 -130.615923)
			(xy 81.502976 -130.64589) (xy 81.447603 -130.668826) (xy 81.38971 -130.684339) (xy 81.330288 -130.692162)
			(xy 81.270352 -130.692162) (xy 81.21093 -130.684339) (xy 81.153037 -130.668826) (xy 81.097664 -130.64589)
			(xy 81.045758 -130.615923) (xy 80.998208 -130.579436) (xy 80.955828 -130.537056) (xy 80.919341 -130.489506)
			(xy 80.889374 -130.4376) (xy 80.866438 -130.382227) (xy 80.850925 -130.324334) (xy 80.843102 -130.264912)
			(xy 78.634844 -130.264912) (xy 78.634844 -131.700012) (xy 82.389962 -131.700012) (xy 82.389962 -131.640076)
			(xy 82.397785 -131.580654) (xy 82.413298 -131.522761) (xy 82.436234 -131.467388) (xy 82.466201 -131.415482)
			(xy 82.502688 -131.367932) (xy 82.545068 -131.325552) (xy 82.592618 -131.289065) (xy 82.644524 -131.259098)
			(xy 82.699897 -131.236162) (xy 82.75779 -131.220649) (xy 82.817212 -131.212826) (xy 82.877148 -131.212826)
			(xy 82.911982 -131.217412) (xy 84.851222 -131.217412) (xy 84.851222 -131.157476) (xy 84.859045 -131.098054)
			(xy 84.874558 -131.040161) (xy 84.897494 -130.984788) (xy 84.927461 -130.932882) (xy 84.963948 -130.885332)
			(xy 85.006328 -130.842952) (xy 85.053878 -130.806465) (xy 85.105784 -130.776498) (xy 85.161157 -130.753562)
			(xy 85.21905 -130.738049) (xy 85.278472 -130.730226) (xy 85.338408 -130.730226) (xy 85.39783 -130.738049)
			(xy 85.455723 -130.753562) (xy 85.511096 -130.776498) (xy 85.563002 -130.806465) (xy 85.610552 -130.842952)
			(xy 85.652932 -130.885332) (xy 85.689419 -130.932882) (xy 85.719386 -130.984788) (xy 85.742322 -131.040161)
			(xy 85.757835 -131.098054) (xy 85.765658 -131.157476) (xy 85.766148 -131.187444) (xy 85.765658 -131.217412)
			(xy 85.757835 -131.276834) (xy 85.742322 -131.334727) (xy 85.719386 -131.3901) (xy 85.689419 -131.442006)
			(xy 85.652932 -131.489556) (xy 85.610552 -131.531936) (xy 85.563002 -131.568423) (xy 85.511096 -131.59839)
			(xy 85.455723 -131.621326) (xy 85.39783 -131.636839) (xy 85.338408 -131.644662) (xy 85.278472 -131.644662)
			(xy 85.21905 -131.636839) (xy 85.161157 -131.621326) (xy 85.105784 -131.59839) (xy 85.053878 -131.568423)
			(xy 85.006328 -131.531936) (xy 84.963948 -131.489556) (xy 84.927461 -131.442006) (xy 84.897494 -131.3901)
			(xy 84.874558 -131.334727) (xy 84.859045 -131.276834) (xy 84.851222 -131.217412) (xy 82.911982 -131.217412)
			(xy 82.93657 -131.220649) (xy 82.994463 -131.236162) (xy 83.049836 -131.259098) (xy 83.101742 -131.289065)
			(xy 83.149292 -131.325552) (xy 83.191672 -131.367932) (xy 83.228159 -131.415482) (xy 83.258126 -131.467388)
			(xy 83.281062 -131.522761) (xy 83.296575 -131.580654) (xy 83.304398 -131.640076) (xy 83.304888 -131.670044)
			(xy 83.304398 -131.700012) (xy 83.296575 -131.759434) (xy 83.281062 -131.817327) (xy 83.258126 -131.8727)
			(xy 83.228159 -131.924606) (xy 83.191672 -131.972156) (xy 83.149292 -132.014536) (xy 83.101742 -132.051023)
			(xy 83.049836 -132.08099) (xy 82.994463 -132.103926) (xy 82.93657 -132.119439) (xy 82.877148 -132.127262)
			(xy 82.817212 -132.127262) (xy 82.75779 -132.119439) (xy 82.699897 -132.103926) (xy 82.644524 -132.08099)
			(xy 82.592618 -132.051023) (xy 82.545068 -132.014536) (xy 82.502688 -131.972156) (xy 82.466201 -131.924606)
			(xy 82.436234 -131.8727) (xy 82.413298 -131.817327) (xy 82.397785 -131.759434) (xy 82.389962 -131.700012)
			(xy 78.634844 -131.700012) (xy 78.634844 -133.239002) (xy 80.42192 -135.025892) (xy 84.964522 -135.025892)
			(xy 84.968593 -134.97027) (xy 84.980719 -134.915833) (xy 85.000642 -134.863742) (xy 85.027938 -134.815107)
			(xy 85.062024 -134.770964) (xy 85.102173 -134.732255) (xy 85.147531 -134.699804) (xy 85.197131 -134.674303)
			(xy 85.249915 -134.656296) (xy 85.304758 -134.646166) (xy 85.360492 -134.644129) (xy 85.415929 -134.650229)
			(xy 85.469886 -134.664335) (xy 85.521215 -134.686147) (xy 85.568821 -134.715201) (xy 85.611689 -134.750876)
			(xy 85.648906 -134.792413) (xy 85.679679 -134.838926) (xy 85.703351 -134.889423) (xy 85.719419 -134.94283)
			(xy 85.727539 -134.998006) (xy 85.728048 -135.025892) (xy 85.727539 -135.053778) (xy 85.724578 -135.073898)
			(xy 86.02421 -135.073898) (xy 86.028281 -135.018276) (xy 86.040407 -134.963839) (xy 86.06033 -134.911748)
			(xy 86.087626 -134.863113) (xy 86.121712 -134.81897) (xy 86.161861 -134.780261) (xy 86.207219 -134.74781)
			(xy 86.256819 -134.722309) (xy 86.309603 -134.704302) (xy 86.364446 -134.694172) (xy 86.42018 -134.692135)
			(xy 86.475617 -134.698235) (xy 86.529574 -134.712341) (xy 86.580903 -134.734153) (xy 86.628509 -134.763207)
			(xy 86.671377 -134.798882) (xy 86.708594 -134.840419) (xy 86.739367 -134.886932) (xy 86.763039 -134.937429)
			(xy 86.779107 -134.990836) (xy 86.787227 -135.046012) (xy 86.787736 -135.073898) (xy 86.787227 -135.101784)
			(xy 86.779107 -135.15696) (xy 86.763039 -135.210367) (xy 86.739367 -135.260864) (xy 86.708594 -135.307377)
			(xy 86.671377 -135.348914) (xy 86.628509 -135.384589) (xy 86.580903 -135.413643) (xy 86.529574 -135.435455)
			(xy 86.475617 -135.449561) (xy 86.42018 -135.455661) (xy 86.364446 -135.453624) (xy 86.309603 -135.443494)
			(xy 86.256819 -135.425487) (xy 86.207219 -135.399986) (xy 86.161861 -135.367535) (xy 86.121712 -135.328826)
			(xy 86.087626 -135.284683) (xy 86.06033 -135.236048) (xy 86.040407 -135.183957) (xy 86.028281 -135.12952)
			(xy 86.02421 -135.073898) (xy 85.724578 -135.073898) (xy 85.719419 -135.108954) (xy 85.703351 -135.162361)
			(xy 85.679679 -135.212858) (xy 85.648906 -135.259371) (xy 85.611689 -135.300908) (xy 85.568821 -135.336583)
			(xy 85.521215 -135.365637) (xy 85.469886 -135.387449) (xy 85.415929 -135.401555) (xy 85.360492 -135.407655)
			(xy 85.304758 -135.405618) (xy 85.249915 -135.395488) (xy 85.197131 -135.377481) (xy 85.147531 -135.35198)
			(xy 85.102173 -135.319529) (xy 85.062024 -135.28082) (xy 85.027938 -135.236677) (xy 85.000642 -135.188042)
			(xy 84.980719 -135.135951) (xy 84.968593 -135.081514) (xy 84.964522 -135.025892) (xy 80.42192 -135.025892)
			(xy 81.070196 -135.6741) (xy 81.784698 -135.6741) (xy 81.81536 -135.674584) (xy 81.876187 -135.68237)
			(xy 81.935536 -135.697803) (xy 81.992451 -135.720636) (xy 82.046012 -135.750498) (xy 82.070956 -135.768334)
			(xy 82.104484 -135.792972) (xy 82.944716 -135.792972) (xy 82.967985 -135.792449) (xy 83.013743 -135.783972)
			(xy 83.057194 -135.767306) (xy 83.096883 -135.743006) (xy 83.131485 -135.711886) (xy 83.159842 -135.674986)
			(xy 83.181006 -135.63354) (xy 83.19427 -135.588933) (xy 83.19919 -135.542657) (xy 83.197954 -135.519414)
			(xy 83.196091 -135.488655) (xy 83.19965 -135.427135) (xy 83.211432 -135.366649) (xy 83.231222 -135.30829)
			(xy 83.258664 -135.253115) (xy 83.293261 -135.202121) (xy 83.334387 -135.15623) (xy 83.381299 -135.116272)
			(xy 83.433148 -135.08297) (xy 83.488997 -135.056925) (xy 83.547835 -135.03861) (xy 83.608599 -135.028355)
			(xy 83.670189 -135.026346) (xy 83.731491 -135.032619) (xy 83.791398 -135.04706) (xy 83.848825 -135.069409)
			(xy 83.902734 -135.099262) (xy 83.952151 -135.136077) (xy 83.996181 -135.17919) (xy 84.034028 -135.227821)
			(xy 84.065007 -135.281091) (xy 84.088559 -135.338035) (xy 84.104257 -135.397625) (xy 84.111818 -135.458782)
			(xy 84.111105 -135.520401) (xy 84.102131 -135.581367) (xy 84.094066 -135.611108) (xy 84.084414 -135.644636)
			(xy 84.101686 -135.711438) (xy 84.99856 -136.608312) (xy 86.234776 -136.608312) (xy 86.238847 -136.55269)
			(xy 86.250973 -136.498253) (xy 86.270896 -136.446162) (xy 86.298192 -136.397527) (xy 86.332278 -136.353384)
			(xy 86.372427 -136.314675) (xy 86.417785 -136.282224) (xy 86.467385 -136.256723) (xy 86.520169 -136.238716)
			(xy 86.575012 -136.228586) (xy 86.630746 -136.226549) (xy 86.686183 -136.232649) (xy 86.74014 -136.246755)
			(xy 86.791469 -136.268567) (xy 86.839075 -136.297621) (xy 86.881943 -136.333296) (xy 86.91916 -136.374833)
			(xy 86.949933 -136.421346) (xy 86.973605 -136.471843) (xy 86.989673 -136.52525) (xy 86.997793 -136.580426)
			(xy 86.998302 -136.608312) (xy 86.997793 -136.636198) (xy 86.989673 -136.691374) (xy 86.973605 -136.744781)
			(xy 86.949933 -136.795278) (xy 86.91916 -136.841791) (xy 86.881943 -136.883328) (xy 86.839075 -136.919003)
			(xy 86.791469 -136.948057) (xy 86.74014 -136.969869) (xy 86.686183 -136.983975) (xy 86.630746 -136.990075)
			(xy 86.575012 -136.988038) (xy 86.520169 -136.977908) (xy 86.467385 -136.959901) (xy 86.417785 -136.9344)
			(xy 86.372427 -136.901949) (xy 86.332278 -136.86324) (xy 86.298192 -136.819097) (xy 86.270896 -136.770462)
			(xy 86.250973 -136.718371) (xy 86.238847 -136.663934) (xy 86.234776 -136.608312) (xy 84.99856 -136.608312)
			(xy 85.69706 -137.306812) (xy 85.69706 -137.650474) (xy 86.061802 -137.650474) (xy 86.065873 -137.594852)
			(xy 86.077999 -137.540415) (xy 86.097922 -137.488324) (xy 86.125218 -137.439689) (xy 86.159304 -137.395546)
			(xy 86.199453 -137.356837) (xy 86.244811 -137.324386) (xy 86.294411 -137.298885) (xy 86.347195 -137.280878)
			(xy 86.402038 -137.270748) (xy 86.457772 -137.268711) (xy 86.513209 -137.274811) (xy 86.567166 -137.288917)
			(xy 86.618495 -137.310729) (xy 86.666101 -137.339783) (xy 86.708969 -137.375458) (xy 86.746186 -137.416995)
			(xy 86.776959 -137.463508) (xy 86.800631 -137.514005) (xy 86.816699 -137.567412) (xy 86.824819 -137.622588)
			(xy 86.825328 -137.650474) (xy 86.824819 -137.67836) (xy 86.816699 -137.733536) (xy 86.800631 -137.786943)
			(xy 86.776959 -137.83744) (xy 86.746186 -137.883953) (xy 86.708969 -137.92549) (xy 86.666101 -137.961165)
			(xy 86.618495 -137.990219) (xy 86.567166 -138.012031) (xy 86.513209 -138.026137) (xy 86.457772 -138.032237)
			(xy 86.402038 -138.0302) (xy 86.347195 -138.02007) (xy 86.294411 -138.002063) (xy 86.244811 -137.976562)
			(xy 86.199453 -137.944111) (xy 86.159304 -137.905402) (xy 86.125218 -137.861259) (xy 86.097922 -137.812624)
			(xy 86.077999 -137.760533) (xy 86.065873 -137.706096) (xy 86.061802 -137.650474) (xy 85.69706 -137.650474)
			(xy 85.69706 -140.11783) (xy 85.697462 -140.132671) (xy 85.704326 -140.161548) (xy 85.717676 -140.188058)
			(xy 85.736789 -140.210767) (xy 85.760631 -140.228446) (xy 85.787913 -140.240139) (xy 85.80247 -140.243052)
			(xy 85.830252 -140.248359) (xy 85.883962 -140.266087) (xy 85.934466 -140.29155) (xy 85.980657 -140.324191)
			(xy 86.021523 -140.363295) (xy 86.056166 -140.408003) (xy 86.083829 -140.457337) (xy 86.103905 -140.510214)
			(xy 86.115953 -140.565476) (xy 86.119711 -140.621911) (xy 86.115094 -140.678282) (xy 86.102205 -140.733354)
			(xy 86.081325 -140.785919) (xy 86.052914 -140.834826) (xy 86.035642 -140.857224) (xy 86.025386 -140.870974)
			(xy 86.011903 -140.9025) (xy 86.007294 -140.936478) (xy 86.011891 -140.970457) (xy 86.025363 -141.001989)
			(xy 86.035642 -141.01572) (xy 86.053111 -141.038381) (xy 86.081774 -141.087901) (xy 86.10272 -141.141146)
			(xy 86.11548 -141.196922) (xy 86.119767 -141.253978) (xy 86.115486 -141.311035) (xy 86.102733 -141.366812)
			(xy 86.081793 -141.420059) (xy 86.053136 -141.469583) (xy 86.035642 -141.492224) (xy 86.025386 -141.505974)
			(xy 86.011903 -141.5375) (xy 86.007294 -141.571478) (xy 86.011891 -141.605457) (xy 86.025363 -141.636989)
			(xy 86.035642 -141.65072) (xy 86.052906 -141.673128) (xy 86.081325 -141.722036) (xy 86.102212 -141.774604)
			(xy 86.115107 -141.82968) (xy 86.11973 -141.886056) (xy 86.115977 -141.942497) (xy 86.103931 -141.997765)
			(xy 86.083858 -142.050648) (xy 86.056195 -142.099988) (xy 86.021551 -142.144703) (xy 85.980684 -142.183812)
			(xy 85.93449 -142.216458) (xy 85.883982 -142.241926) (xy 85.830267 -142.259657) (xy 85.80247 -142.264892)
			(xy 85.75675 -142.272766) (xy 85.69706 -142.343632) (xy 85.69706 -143.725392) (xy 86.534242 -143.725392)
			(xy 86.538313 -143.66977) (xy 86.550439 -143.615333) (xy 86.570362 -143.563242) (xy 86.597658 -143.514607)
			(xy 86.631744 -143.470464) (xy 86.671893 -143.431755) (xy 86.717251 -143.399304) (xy 86.766851 -143.373803)
			(xy 86.819635 -143.355796) (xy 86.874478 -143.345666) (xy 86.930212 -143.343629) (xy 86.985649 -143.349729)
			(xy 87.039606 -143.363835) (xy 87.090935 -143.385647) (xy 87.138541 -143.414701) (xy 87.181409 -143.450376)
			(xy 87.218626 -143.491913) (xy 87.249399 -143.538426) (xy 87.273071 -143.588923) (xy 87.289139 -143.64233)
			(xy 87.297259 -143.697506) (xy 87.297768 -143.725392) (xy 87.297259 -143.753278) (xy 87.289139 -143.808454)
			(xy 87.273071 -143.861861) (xy 87.249399 -143.912358) (xy 87.218626 -143.958871) (xy 87.181409 -144.000408)
			(xy 87.138541 -144.036083) (xy 87.090935 -144.065137) (xy 87.039606 -144.086949) (xy 86.985649 -144.101055)
			(xy 86.930212 -144.107155) (xy 86.874478 -144.105118) (xy 86.819635 -144.094988) (xy 86.766851 -144.076981)
			(xy 86.717251 -144.05148) (xy 86.671893 -144.019029) (xy 86.631744 -143.98032) (xy 86.597658 -143.936177)
			(xy 86.570362 -143.887542) (xy 86.550439 -143.835451) (xy 86.538313 -143.781014) (xy 86.534242 -143.725392)
			(xy 85.69706 -143.725392) (xy 85.69706 -145.905982) (xy 85.722968 -145.940018) (xy 85.740583 -145.963991)
			(xy 85.77013 -146.015626) (xy 85.792738 -146.070654) (xy 85.808026 -146.128148) (xy 85.815736 -146.187137)
			(xy 85.815738 -146.246628) (xy 85.808032 -146.305618) (xy 85.792749 -146.363112) (xy 85.770145 -146.418142)
			(xy 85.740603 -146.469779) (xy 85.722968 -146.493738) (xy 85.69706 -146.527774) (xy 85.69706 -148.943568)
			(xy 88.413082 -151.65959) (xy 88.265254 -151.807418) (xy 88.265254 -158.446216) (xy 88.55075 -158.731712)
			(xy 92.75572 -158.731712)
		)
		(stroke
			(width 0)
			(type solid)
		)
		(fill yes)
		(layer "B.Cu")
		(net "P1V8_STB_NODE1")
	)
	(gr_poly
		(pts
			(xy 99.43084 -138.036808) (xy 99.43084 -126.827026) (xy 99.430333 -126.804522) (xy 99.422358 -126.760226)
			(xy 99.406706 -126.718026) (xy 99.383867 -126.679243) (xy 99.354554 -126.645088) (xy 99.319684 -126.61663)
			(xy 99.280347 -126.594759) (xy 99.237773 -126.580157) (xy 99.193293 -126.573281) (xy 99.148297 -126.574347)
			(xy 99.104192 -126.583321) (xy 99.062357 -126.599923) (xy 99.042982 -126.61138) (xy 99.016864 -126.627017)
			(xy 98.961354 -126.652004) (xy 98.903023 -126.669414) (xy 98.842898 -126.678939) (xy 98.782042 -126.680413)
			(xy 98.721527 -126.673808) (xy 98.662421 -126.659242) (xy 98.605767 -126.636972) (xy 98.552564 -126.607389)
			(xy 98.503751 -126.571017) (xy 98.460188 -126.528496) (xy 98.422645 -126.480578) (xy 98.391784 -126.428106)
			(xy 98.368149 -126.372007) (xy 98.352157 -126.313271) (xy 98.34409 -126.252934) (xy 98.34409 -126.19206)
			(xy 98.352158 -126.131722) (xy 98.368151 -126.072987) (xy 98.391787 -126.016888) (xy 98.422649 -125.964417)
			(xy 98.460193 -125.916499) (xy 98.503756 -125.873979) (xy 98.552569 -125.837607) (xy 98.605773 -125.808026)
			(xy 98.662427 -125.785756) (xy 98.721533 -125.77119) (xy 98.782048 -125.764587) (xy 98.842905 -125.766061)
			(xy 98.903029 -125.775588) (xy 98.96136 -125.792998) (xy 99.01687 -125.817986) (xy 99.042982 -125.833632)
			(xy 99.062361 -125.845078) (xy 99.104189 -125.861684) (xy 99.148289 -125.870661) (xy 99.19328 -125.871729)
			(xy 99.237755 -125.864855) (xy 99.280324 -125.850253) (xy 99.319655 -125.82838) (xy 99.354518 -125.79992)
			(xy 99.383822 -125.765765) (xy 99.40665 -125.726981) (xy 99.422289 -125.684782) (xy 99.43025 -125.640487)
			(xy 99.43084 -125.617986) (xy 99.43084 -125.527308) (xy 99.430358 -125.504608) (xy 99.42233 -125.459924)
			(xy 99.406492 -125.417377) (xy 99.383348 -125.37832) (xy 99.353635 -125.343996) (xy 99.318296 -125.315496)
			(xy 99.278457 -125.293726) (xy 99.235384 -125.27938) (xy 99.190448 -125.272913) (xy 99.145078 -125.274531)
			(xy 99.100716 -125.284183) (xy 99.058775 -125.301561) (xy 99.039426 -125.31344) (xy 99.016255 -125.327783)
			(xy 98.966687 -125.350424) (xy 98.914402 -125.36578) (xy 98.860463 -125.373538) (xy 98.805969 -125.37354)
			(xy 98.752029 -125.365786) (xy 98.699743 -125.350435) (xy 98.650173 -125.327798) (xy 98.604329 -125.298337)
			(xy 98.563146 -125.262651) (xy 98.52746 -125.221467) (xy 98.498 -125.175623) (xy 98.475363 -125.126053)
			(xy 98.460013 -125.073766) (xy 98.45226 -125.019826) (xy 98.452263 -124.965333) (xy 98.460021 -124.911394)
			(xy 98.475378 -124.859108) (xy 98.498019 -124.809541) (xy 98.527485 -124.7637) (xy 98.563175 -124.72252)
			(xy 98.604362 -124.686838) (xy 98.650209 -124.657382) (xy 98.699781 -124.634751) (xy 98.75207 -124.619405)
			(xy 98.80601 -124.611657) (xy 98.860504 -124.611665) (xy 98.914442 -124.619429) (xy 98.966726 -124.634791)
			(xy 99.016291 -124.657437) (xy 99.039426 -124.671836) (xy 99.058787 -124.683691) (xy 99.100723 -124.701069)
			(xy 99.145078 -124.710721) (xy 99.190443 -124.71234) (xy 99.235374 -124.705874) (xy 99.278441 -124.691528)
			(xy 99.318275 -124.669761) (xy 99.353608 -124.641262) (xy 99.383317 -124.606941) (xy 99.406456 -124.567887)
			(xy 99.422289 -124.525344) (xy 99.430312 -124.480665) (xy 99.43084 -124.457968) (xy 99.43084 -121.613422)
			(xy 99.4303 -121.59677) (xy 99.421686 -121.564599) (xy 99.40504 -121.535753) (xy 99.381497 -121.512198)
			(xy 99.352659 -121.495538) (xy 99.320492 -121.486909) (xy 99.30384 -121.486422) (xy 99.257358 -121.486422)
			(xy 99.222052 -121.516394) (xy 99.19716 -121.535698) (xy 99.179003 -121.549204) (xy 99.147339 -121.581528)
			(xy 99.121897 -121.618946) (xy 99.103483 -121.660278) (xy 99.092677 -121.704218) (xy 99.089821 -121.749376)
			(xy 99.095006 -121.794326) (xy 99.108067 -121.837649) (xy 99.117912 -121.858024) (xy 99.130385 -121.883616)
			(xy 99.148449 -121.937605) (xy 99.15829 -121.993679) (xy 99.159689 -122.050592) (xy 99.152616 -122.107081)
			(xy 99.137227 -122.161892) (xy 99.113865 -122.213809) (xy 99.083048 -122.261677) (xy 99.04546 -122.304435)
			(xy 99.001936 -122.341132) (xy 98.953442 -122.370955) (xy 98.901054 -122.393241) (xy 98.845937 -122.407496)
			(xy 98.789314 -122.413402) (xy 98.732442 -122.410828) (xy 98.7044 -122.405902) (xy 98.682166 -122.402028)
			(xy 98.637044 -122.40128) (xy 98.5925 -122.408513) (xy 98.549933 -122.4235) (xy 98.510684 -122.44577)
			(xy 98.475985 -122.474623) (xy 98.446927 -122.509152) (xy 98.424426 -122.54827) (xy 98.409188 -122.590747)
			(xy 98.404934 -122.612912) (xy 98.399903 -122.639864) (xy 98.383133 -122.692063) (xy 98.359064 -122.741324)
			(xy 98.328193 -122.786633) (xy 98.291154 -122.827057) (xy 98.24871 -122.861764) (xy 98.201736 -122.890038)
			(xy 98.151199 -122.911297) (xy 98.09814 -122.925104) (xy 98.04365 -122.931175) (xy 97.988852 -122.929384)
			(xy 97.934875 -122.919768) (xy 97.882831 -122.902526) (xy 97.833789 -122.878011) (xy 97.788762 -122.84673)
			(xy 97.748675 -122.809327) (xy 97.714355 -122.76657) (xy 97.686508 -122.719342) (xy 97.665707 -122.668614)
			(xy 97.652382 -122.615432) (xy 97.646805 -122.560889) (xy 97.649093 -122.50611) (xy 97.659197 -122.452223)
			(xy 97.676911 -122.400336) (xy 97.701868 -122.351519) (xy 97.733556 -122.306777) (xy 97.771322 -122.267031)
			(xy 97.814387 -122.2331) (xy 97.861866 -122.205682) (xy 97.91278 -122.185342) (xy 97.966082 -122.172499)
			(xy 98.020672 -122.167417) (xy 98.075428 -122.170201) (xy 98.10242 -122.175016) (xy 98.124654 -122.178888)
			(xy 98.169774 -122.179633) (xy 98.214316 -122.172398) (xy 98.25688 -122.157409) (xy 98.296128 -122.135138)
			(xy 98.330825 -122.106286) (xy 98.359882 -122.07176) (xy 98.382383 -122.032644) (xy 98.397622 -121.990169)
			(xy 98.401886 -121.968006) (xy 98.408333 -121.934289) (xy 98.431712 -121.869752) (xy 98.448368 -121.839736)
			(xy 98.45587 -121.825847) (xy 98.46451 -121.795497) (xy 98.465439 -121.763955) (xy 98.458598 -121.733149)
			(xy 98.444408 -121.704964) (xy 98.423735 -121.681122) (xy 98.397844 -121.663083) (xy 98.368318 -121.651948)
			(xy 98.336962 -121.6484) (xy 98.305694 -121.652654) (xy 98.290888 -121.658126) (xy 98.265425 -121.667892)
			(xy 98.212457 -121.680875) (xy 98.158181 -121.686187) (xy 98.103701 -121.683717) (xy 98.050128 -121.673517)
			(xy 97.998552 -121.655795) (xy 97.950025 -121.630911) (xy 97.905534 -121.599372) (xy 97.865986 -121.561821)
			(xy 97.832186 -121.519023) (xy 97.804824 -121.471848) (xy 97.784455 -121.421259) (xy 97.771495 -121.368286)
			(xy 97.766209 -121.314007) (xy 97.768703 -121.259529) (xy 97.778927 -121.20596) (xy 97.796673 -121.154392)
			(xy 97.821579 -121.105876) (xy 97.853138 -121.0614) (xy 97.890707 -121.021869) (xy 97.933521 -120.988089)
			(xy 97.980708 -120.960747) (xy 98.031306 -120.940402) (xy 98.084285 -120.927466) (xy 98.138567 -120.922205)
			(xy 98.193044 -120.924724) (xy 98.246608 -120.934972) (xy 98.298167 -120.952741) (xy 98.346672 -120.97767)
			(xy 98.36912 -120.993154) (xy 98.387891 -121.005865) (xy 98.428922 -121.025129) (xy 98.472718 -121.036813)
			(xy 98.517892 -121.040547) (xy 98.563013 -121.036213) (xy 98.60665 -121.023948) (xy 98.647421 -121.004141)
			(xy 98.684035 -120.977419) (xy 98.700082 -120.961404) (xy 98.719024 -120.942214) (xy 98.761358 -120.908819)
			(xy 98.807972 -120.881717) (xy 98.857938 -120.861448) (xy 98.91026 -120.848415) (xy 98.963895 -120.84288)
			(xy 99.017776 -120.844951) (xy 99.070828 -120.854587) (xy 99.096576 -120.862598) (xy 99.117468 -120.86908)
			(xy 99.160718 -120.875602) (xy 99.204446 -120.874621) (xy 99.247361 -120.866169) (xy 99.288194 -120.850493)
			(xy 99.325741 -120.828058) (xy 99.358892 -120.799525) (xy 99.386669 -120.765738) (xy 99.40825 -120.727694)
			(xy 99.422999 -120.686516) (xy 99.430479 -120.643422) (xy 99.43084 -120.621552) (xy 99.43084 -120.137682)
			(xy 99.430272 -120.120758) (xy 99.421313 -120.088115) (xy 99.404107 -120.058964) (xy 99.379858 -120.035346)
			(xy 99.365308 -120.026684) (xy 99.338178 -120.011053) (xy 99.288073 -119.973506) (xy 99.243553 -119.92948)
			(xy 99.205449 -119.879796) (xy 99.174473 -119.825382) (xy 99.151204 -119.767254) (xy 99.136075 -119.706497)
			(xy 99.129368 -119.644244) (xy 99.13121 -119.581659) (xy 99.141565 -119.519908) (xy 99.160241 -119.460146)
			(xy 99.186888 -119.403487) (xy 99.20351 -119.376952) (xy 99.212447 -119.362103) (xy 99.222791 -119.329043)
			(xy 99.223868 -119.294419) (xy 99.215597 -119.260779) (xy 99.198587 -119.230602) (xy 99.186746 -119.217948)
			(xy 98.203004 -118.234206) (xy 98.203004 -109.143546) (xy 97.256854 -108.197396) (xy 93.014292 -108.197396)
			(xy 92.60078 -108.610908) (xy 92.60078 -109.342557) (xy 95.160553 -109.342557) (xy 95.161772 -109.286632)
			(xy 95.171145 -109.231485) (xy 95.18847 -109.178297) (xy 95.213375 -109.128209) (xy 95.245328 -109.082295)
			(xy 95.283642 -109.041539) (xy 95.327497 -109.006814) (xy 95.375953 -108.978866) (xy 95.42797 -108.958292)
			(xy 95.482434 -108.945535) (xy 95.538177 -108.940867) (xy 95.594004 -108.944389) (xy 95.648719 -108.956025)
			(xy 95.701148 -108.975526) (xy 95.750167 -109.002474) (xy 95.794726 -109.036291) (xy 95.833869 -109.076252)
			(xy 95.85071 -109.098588) (xy 95.860746 -109.111607) (xy 95.886222 -109.132368) (xy 95.916152 -109.145941)
			(xy 95.948554 -109.151427) (xy 95.981284 -109.148465) (xy 96.012175 -109.137248) (xy 96.02597 -109.128306)
			(xy 96.049267 -109.112829) (xy 96.09941 -109.088054) (xy 96.152632 -109.070866) (xy 96.207794 -109.061634)
			(xy 96.263712 -109.060556) (xy 96.319189 -109.067654) (xy 96.373035 -109.082777) (xy 96.424095 -109.1056)
			(xy 96.471276 -109.135634) (xy 96.513565 -109.172235) (xy 96.550057 -109.214619) (xy 96.579968 -109.261877)
			(xy 96.602659 -109.312997) (xy 96.617642 -109.366881) (xy 96.624596 -109.422376) (xy 96.623373 -109.478292)
			(xy 96.613998 -109.533429) (xy 96.596672 -109.586607) (xy 96.571767 -109.636685) (xy 96.539817 -109.68259)
			(xy 96.501507 -109.723337) (xy 96.457657 -109.758054) (xy 96.409208 -109.785995) (xy 96.357198 -109.806563)
			(xy 96.302742 -109.819316) (xy 96.247008 -109.823981) (xy 96.191191 -109.820457) (xy 96.136485 -109.808821)
			(xy 96.084066 -109.789322) (xy 96.035055 -109.762378) (xy 95.990504 -109.728566) (xy 95.951368 -109.688611)
			(xy 95.93453 -109.666278) (xy 95.924458 -109.65329) (xy 95.898989 -109.632533) (xy 95.869068 -109.61896)
			(xy 95.836675 -109.613469) (xy 95.803952 -109.616422) (xy 95.773065 -109.627625) (xy 95.75927 -109.63656)
			(xy 95.736004 -109.65209) (xy 95.685856 -109.676875) (xy 95.632627 -109.694073) (xy 95.577458 -109.703313)
			(xy 95.52153 -109.704399) (xy 95.466044 -109.697306) (xy 95.412187 -109.682187) (xy 95.361116 -109.659366)
			(xy 95.313925 -109.629332) (xy 95.271625 -109.592729) (xy 95.235123 -109.550341) (xy 95.205202 -109.503078)
			(xy 95.182503 -109.451953) (xy 95.167513 -109.39806) (xy 95.160553 -109.342557) (xy 92.60078 -109.342557)
			(xy 92.60078 -111.012732) (xy 97.090482 -111.012732) (xy 97.094553 -110.95711) (xy 97.106679 -110.902673)
			(xy 97.126602 -110.850582) (xy 97.153898 -110.801947) (xy 97.187984 -110.757804) (xy 97.228133 -110.719095)
			(xy 97.273491 -110.686644) (xy 97.323091 -110.661143) (xy 97.375875 -110.643136) (xy 97.430718 -110.633006)
			(xy 97.486452 -110.630969) (xy 97.541889 -110.637069) (xy 97.595846 -110.651175) (xy 97.647175 -110.672987)
			(xy 97.694781 -110.702041) (xy 97.737649 -110.737716) (xy 97.774866 -110.779253) (xy 97.805639 -110.825766)
			(xy 97.829311 -110.876263) (xy 97.845379 -110.92967) (xy 97.853499 -110.984846) (xy 97.854008 -111.012732)
			(xy 97.853499 -111.040618) (xy 97.845379 -111.095794) (xy 97.829311 -111.149201) (xy 97.805639 -111.199698)
			(xy 97.774866 -111.246211) (xy 97.737649 -111.287748) (xy 97.694781 -111.323423) (xy 97.647175 -111.352477)
			(xy 97.595846 -111.374289) (xy 97.541889 -111.388395) (xy 97.486452 -111.394495) (xy 97.430718 -111.392458)
			(xy 97.375875 -111.382328) (xy 97.323091 -111.364321) (xy 97.273491 -111.33882) (xy 97.228133 -111.306369)
			(xy 97.187984 -111.26766) (xy 97.153898 -111.223517) (xy 97.126602 -111.174882) (xy 97.106679 -111.122791)
			(xy 97.094553 -111.068354) (xy 97.090482 -111.012732) (xy 92.60078 -111.012732) (xy 92.60078 -116.480844)
			(xy 92.98686 -116.866924) (xy 92.98686 -117.985282) (xy 93.39756 -117.985282) (xy 93.39756 -117.925346)
			(xy 93.405383 -117.865924) (xy 93.420896 -117.808031) (xy 93.443832 -117.752658) (xy 93.473799 -117.700752)
			(xy 93.510286 -117.653202) (xy 93.552666 -117.610822) (xy 93.600216 -117.574335) (xy 93.652122 -117.544368)
			(xy 93.707495 -117.521432) (xy 93.765388 -117.505919) (xy 93.82481 -117.498096) (xy 93.884746 -117.498096)
			(xy 93.944168 -117.505919) (xy 94.002061 -117.521432) (xy 94.057434 -117.544368) (xy 94.10934 -117.574335)
			(xy 94.15689 -117.610822) (xy 94.19927 -117.653202) (xy 94.235757 -117.700752) (xy 94.265724 -117.752658)
			(xy 94.28866 -117.808031) (xy 94.304173 -117.865924) (xy 94.306678 -117.884952) (xy 94.841042 -117.884952)
			(xy 94.841042 -117.825016) (xy 94.848865 -117.765594) (xy 94.864378 -117.707701) (xy 94.887314 -117.652328)
			(xy 94.917281 -117.600422) (xy 94.953768 -117.552872) (xy 94.996148 -117.510492) (xy 95.043698 -117.474005)
			(xy 95.095604 -117.444038) (xy 95.150977 -117.421102) (xy 95.20887 -117.405589) (xy 95.268292 -117.397766)
			(xy 95.328228 -117.397766) (xy 95.38765 -117.405589) (xy 95.445543 -117.421102) (xy 95.500916 -117.444038)
			(xy 95.552822 -117.474005) (xy 95.600372 -117.510492) (xy 95.642752 -117.552872) (xy 95.679239 -117.600422)
			(xy 95.709206 -117.652328) (xy 95.732142 -117.707701) (xy 95.747655 -117.765594) (xy 95.755478 -117.825016)
			(xy 95.755968 -117.854984) (xy 95.755478 -117.884952) (xy 95.747655 -117.944374) (xy 95.732142 -118.002267)
			(xy 95.709206 -118.05764) (xy 95.679239 -118.109546) (xy 95.642752 -118.157096) (xy 95.600372 -118.199476)
			(xy 95.552822 -118.235963) (xy 95.500916 -118.26593) (xy 95.445543 -118.288866) (xy 95.38765 -118.304379)
			(xy 95.328228 -118.312202) (xy 95.268292 -118.312202) (xy 95.20887 -118.304379) (xy 95.150977 -118.288866)
			(xy 95.095604 -118.26593) (xy 95.043698 -118.235963) (xy 94.996148 -118.199476) (xy 94.953768 -118.157096)
			(xy 94.917281 -118.109546) (xy 94.887314 -118.05764) (xy 94.864378 -118.002267) (xy 94.848865 -117.944374)
			(xy 94.841042 -117.884952) (xy 94.306678 -117.884952) (xy 94.311996 -117.925346) (xy 94.312486 -117.955314)
			(xy 94.311996 -117.985282) (xy 94.304173 -118.044704) (xy 94.28866 -118.102597) (xy 94.265724 -118.15797)
			(xy 94.235757 -118.209876) (xy 94.19927 -118.257426) (xy 94.15689 -118.299806) (xy 94.10934 -118.336293)
			(xy 94.057434 -118.36626) (xy 94.002061 -118.389196) (xy 93.944168 -118.404709) (xy 93.884746 -118.412532)
			(xy 93.82481 -118.412532) (xy 93.765388 -118.404709) (xy 93.707495 -118.389196) (xy 93.652122 -118.36626)
			(xy 93.600216 -118.336293) (xy 93.552666 -118.299806) (xy 93.510286 -118.257426) (xy 93.473799 -118.209876)
			(xy 93.443832 -118.15797) (xy 93.420896 -118.102597) (xy 93.405383 -118.044704) (xy 93.39756 -117.985282)
			(xy 92.98686 -117.985282) (xy 92.98686 -118.691402) (xy 96.377488 -118.691402) (xy 96.377488 -118.631466)
			(xy 96.385311 -118.572044) (xy 96.400824 -118.514151) (xy 96.42376 -118.458778) (xy 96.453727 -118.406872)
			(xy 96.490214 -118.359322) (xy 96.532594 -118.316942) (xy 96.580144 -118.280455) (xy 96.63205 -118.250488)
			(xy 96.687423 -118.227552) (xy 96.745316 -118.212039) (xy 96.804738 -118.204216) (xy 96.864674 -118.204216)
			(xy 96.924096 -118.212039) (xy 96.981989 -118.227552) (xy 97.037362 -118.250488) (xy 97.089268 -118.280455)
			(xy 97.136818 -118.316942) (xy 97.179198 -118.359322) (xy 97.215685 -118.406872) (xy 97.245652 -118.458778)
			(xy 97.268588 -118.514151) (xy 97.284101 -118.572044) (xy 97.291924 -118.631466) (xy 97.292414 -118.661434)
			(xy 97.291924 -118.691402) (xy 97.284101 -118.750824) (xy 97.268588 -118.808717) (xy 97.245652 -118.86409)
			(xy 97.215685 -118.915996) (xy 97.179198 -118.963546) (xy 97.136818 -119.005926) (xy 97.089268 -119.042413)
			(xy 97.037362 -119.07238) (xy 96.981989 -119.095316) (xy 96.924096 -119.110829) (xy 96.864674 -119.118652)
			(xy 96.804738 -119.118652) (xy 96.745316 -119.110829) (xy 96.687423 -119.095316) (xy 96.63205 -119.07238)
			(xy 96.580144 -119.042413) (xy 96.532594 -119.005926) (xy 96.490214 -118.963546) (xy 96.453727 -118.915996)
			(xy 96.42376 -118.86409) (xy 96.400824 -118.808717) (xy 96.385311 -118.750824) (xy 96.377488 -118.691402)
			(xy 92.98686 -118.691402) (xy 92.98686 -120.141492) (xy 93.28988 -120.141492) (xy 93.293951 -120.08587)
			(xy 93.306077 -120.031433) (xy 93.326 -119.979342) (xy 93.353296 -119.930707) (xy 93.387382 -119.886564)
			(xy 93.427531 -119.847855) (xy 93.472889 -119.815404) (xy 93.522489 -119.789903) (xy 93.575273 -119.771896)
			(xy 93.630116 -119.761766) (xy 93.68585 -119.759729) (xy 93.741287 -119.765829) (xy 93.795244 -119.779935)
			(xy 93.846573 -119.801747) (xy 93.894179 -119.830801) (xy 93.937047 -119.866476) (xy 93.974264 -119.908013)
			(xy 94.005037 -119.954526) (xy 94.028709 -120.005023) (xy 94.044777 -120.05843) (xy 94.052897 -120.113606)
			(xy 94.053406 -120.141492) (xy 94.052897 -120.169378) (xy 94.044777 -120.224554) (xy 94.041034 -120.236996)
			(xy 95.448118 -120.236996) (xy 95.452189 -120.181374) (xy 95.464315 -120.126937) (xy 95.484238 -120.074846)
			(xy 95.511534 -120.026211) (xy 95.54562 -119.982068) (xy 95.585769 -119.943359) (xy 95.631127 -119.910908)
			(xy 95.680727 -119.885407) (xy 95.733511 -119.8674) (xy 95.788354 -119.85727) (xy 95.844088 -119.855233)
			(xy 95.899525 -119.861333) (xy 95.953482 -119.875439) (xy 96.004811 -119.897251) (xy 96.052417 -119.926305)
			(xy 96.095285 -119.96198) (xy 96.132502 -120.003517) (xy 96.163275 -120.05003) (xy 96.186947 -120.100527)
			(xy 96.203015 -120.153934) (xy 96.211135 -120.20911) (xy 96.211644 -120.236996) (xy 96.211135 -120.264882)
			(xy 96.203015 -120.320058) (xy 96.186947 -120.373465) (xy 96.163275 -120.423962) (xy 96.132502 -120.470475)
			(xy 96.095285 -120.512012) (xy 96.052417 -120.547687) (xy 96.004811 -120.576741) (xy 95.953482 -120.598553)
			(xy 95.899525 -120.612659) (xy 95.844088 -120.618759) (xy 95.788354 -120.616722) (xy 95.733511 -120.606592)
			(xy 95.680727 -120.588585) (xy 95.631127 -120.563084) (xy 95.585769 -120.530633) (xy 95.54562 -120.491924)
			(xy 95.511534 -120.447781) (xy 95.484238 -120.399146) (xy 95.464315 -120.347055) (xy 95.452189 -120.292618)
			(xy 95.448118 -120.236996) (xy 94.041034 -120.236996) (xy 94.028709 -120.277961) (xy 94.005037 -120.328458)
			(xy 93.974264 -120.374971) (xy 93.937047 -120.416508) (xy 93.894179 -120.452183) (xy 93.846573 -120.481237)
			(xy 93.795244 -120.503049) (xy 93.741287 -120.517155) (xy 93.68585 -120.523255) (xy 93.630116 -120.521218)
			(xy 93.575273 -120.511088) (xy 93.522489 -120.493081) (xy 93.472889 -120.46758) (xy 93.427531 -120.435129)
			(xy 93.387382 -120.39642) (xy 93.353296 -120.352277) (xy 93.326 -120.303642) (xy 93.306077 -120.251551)
			(xy 93.293951 -120.197114) (xy 93.28988 -120.141492) (xy 92.98686 -120.141492) (xy 92.98686 -120.418606)
			(xy 93.309186 -121.283984) (xy 93.293438 -121.727722) (xy 93.272778 -122.305916) (xy 93.796439 -122.305916)
			(xy 93.80271 -122.246106) (xy 93.816758 -122.187632) (xy 93.838342 -122.131501) (xy 93.867089 -122.07868)
			(xy 93.902505 -122.030077) (xy 93.94398 -121.986529) (xy 93.990799 -121.948787) (xy 94.042158 -121.9175)
			(xy 94.09717 -121.893208) (xy 94.15489 -121.876327) (xy 94.214324 -121.867149) (xy 94.274447 -121.865832)
			(xy 94.334225 -121.872399) (xy 94.36354 -121.879106) (xy 94.38595 -121.884156) (xy 94.431802 -121.886916)
			(xy 94.477403 -121.881387) (xy 94.521267 -121.867748) (xy 94.561964 -121.846445) (xy 94.598167 -121.818171)
			(xy 94.628697 -121.783849) (xy 94.652557 -121.744597) (xy 94.668971 -121.701694) (xy 94.673674 -121.679208)
			(xy 94.679236 -121.652518) (xy 94.696821 -121.600917) (xy 94.721575 -121.552345) (xy 94.752992 -121.507792)
			(xy 94.790433 -121.468167) (xy 94.833134 -121.434276) (xy 94.880225 -121.40681) (xy 94.930748 -121.386329)
			(xy 94.983671 -121.37325) (xy 95.037918 -121.36784) (xy 95.092382 -121.370208) (xy 95.145954 -121.380307)
			(xy 95.197543 -121.397931) (xy 95.246097 -121.422721) (xy 95.290626 -121.454171) (xy 95.330224 -121.49164)
			(xy 95.364083 -121.534367) (xy 95.391514 -121.581478) (xy 95.411958 -121.632016) (xy 95.424998 -121.684949)
			(xy 95.430368 -121.7392) (xy 95.427959 -121.793662) (xy 95.417821 -121.847227) (xy 95.400159 -121.898802)
			(xy 95.375334 -121.947338) (xy 95.343851 -121.991844) (xy 95.325438 -122.011948) (xy 95.314698 -122.023896)
			(xy 95.299126 -122.051988) (xy 95.291063 -122.083079) (xy 95.291022 -122.115198) (xy 95.299005 -122.14631)
			(xy 95.314506 -122.174441) (xy 95.325184 -122.186446) (xy 95.343831 -122.206861) (xy 95.375551 -122.252149)
			(xy 95.400402 -122.301541) (xy 95.417863 -122.354003) (xy 95.427568 -122.408437) (xy 95.429314 -122.463701)
			(xy 95.423064 -122.518638) (xy 95.40895 -122.572098) (xy 95.387266 -122.62296) (xy 95.358467 -122.67016)
			(xy 95.323157 -122.712708) (xy 95.282075 -122.749713) (xy 95.236081 -122.780401) (xy 95.186139 -122.804128)
			(xy 95.133295 -122.820397) (xy 95.078656 -122.828868) (xy 95.023367 -122.829363) (xy 94.968585 -122.821872)
			(xy 94.915458 -122.806552) (xy 94.865099 -122.783723) (xy 94.818563 -122.753863) (xy 94.797372 -122.736102)
			(xy 94.779573 -122.721347) (xy 94.739789 -122.697811) (xy 94.696403 -122.681863) (xy 94.650846 -122.67403)
			(xy 94.604624 -122.674571) (xy 94.559264 -122.683468) (xy 94.516262 -122.700427) (xy 94.496382 -122.712226)
			(xy 94.470647 -122.727782) (xy 94.415877 -122.752617) (xy 94.358327 -122.770068) (xy 94.298987 -122.779833)
			(xy 94.23888 -122.781744) (xy 94.179039 -122.775768) (xy 94.120497 -122.762009) (xy 94.06426 -122.740703)
			(xy 94.011297 -122.712217) (xy 93.962519 -122.677042) (xy 93.918767 -122.635783) (xy 93.880795 -122.58915)
			(xy 93.849254 -122.537947) (xy 93.82469 -122.483055) (xy 93.807524 -122.425419) (xy 93.798053 -122.366032)
			(xy 93.796439 -122.305916) (xy 93.272778 -122.305916) (xy 93.228482 -123.5456) (xy 97.936302 -123.5456)
			(xy 97.940373 -123.489978) (xy 97.952499 -123.435541) (xy 97.972422 -123.38345) (xy 97.999718 -123.334815)
			(xy 98.033804 -123.290672) (xy 98.073953 -123.251963) (xy 98.119311 -123.219512) (xy 98.168911 -123.194011)
			(xy 98.221695 -123.176004) (xy 98.276538 -123.165874) (xy 98.332272 -123.163837) (xy 98.387709 -123.169937)
			(xy 98.441666 -123.184043) (xy 98.492995 -123.205855) (xy 98.540601 -123.234909) (xy 98.583469 -123.270584)
			(xy 98.620686 -123.312121) (xy 98.651459 -123.358634) (xy 98.675131 -123.409131) (xy 98.691199 -123.462538)
			(xy 98.699319 -123.517714) (xy 98.699828 -123.5456) (xy 98.699319 -123.573486) (xy 98.691199 -123.628662)
			(xy 98.675131 -123.682069) (xy 98.651459 -123.732566) (xy 98.620686 -123.779079) (xy 98.583469 -123.820616)
			(xy 98.540601 -123.856291) (xy 98.492995 -123.885345) (xy 98.441666 -123.907157) (xy 98.387709 -123.921263)
			(xy 98.332272 -123.927363) (xy 98.276538 -123.925326) (xy 98.221695 -123.915196) (xy 98.168911 -123.897189)
			(xy 98.119311 -123.871688) (xy 98.073953 -123.839237) (xy 98.033804 -123.800528) (xy 97.999718 -123.756385)
			(xy 97.972422 -123.70775) (xy 97.952499 -123.655659) (xy 97.940373 -123.601222) (xy 97.936302 -123.5456)
			(xy 93.228482 -123.5456) (xy 93.186469 -124.721366) (xy 94.665544 -124.721366) (xy 94.669615 -124.665744)
			(xy 94.681741 -124.611307) (xy 94.701664 -124.559216) (xy 94.72896 -124.510581) (xy 94.763046 -124.466438)
			(xy 94.803195 -124.427729) (xy 94.848553 -124.395278) (xy 94.898153 -124.369777) (xy 94.950937 -124.35177)
			(xy 95.00578 -124.34164) (xy 95.061514 -124.339603) (xy 95.116951 -124.345703) (xy 95.170908 -124.359809)
			(xy 95.222237 -124.381621) (xy 95.269843 -124.410675) (xy 95.312711 -124.44635) (xy 95.349928 -124.487887)
			(xy 95.380701 -124.5344) (xy 95.404373 -124.584897) (xy 95.420441 -124.638304) (xy 95.428561 -124.69348)
			(xy 95.42907 -124.721366) (xy 95.428561 -124.749252) (xy 95.420441 -124.804428) (xy 95.404373 -124.857835)
			(xy 95.380701 -124.908332) (xy 95.349928 -124.954845) (xy 95.312711 -124.996382) (xy 95.269843 -125.032057)
			(xy 95.222237 -125.061111) (xy 95.170908 -125.082923) (xy 95.116951 -125.097029) (xy 95.061514 -125.103129)
			(xy 95.00578 -125.101092) (xy 94.950937 -125.090962) (xy 94.898153 -125.072955) (xy 94.848553 -125.047454)
			(xy 94.803195 -125.015003) (xy 94.763046 -124.976294) (xy 94.72896 -124.932151) (xy 94.701664 -124.883516)
			(xy 94.681741 -124.831425) (xy 94.669615 -124.776988) (xy 94.665544 -124.721366) (xy 93.186469 -124.721366)
			(xy 93.135281 -126.153908) (xy 94.576521 -126.153908) (xy 94.577405 -126.09918) (xy 94.586103 -126.04514)
			(xy 94.602435 -125.992898) (xy 94.626066 -125.943527) (xy 94.656512 -125.89804) (xy 94.693146 -125.857372)
			(xy 94.735217 -125.822358) (xy 94.78186 -125.793716) (xy 94.832119 -125.772035) (xy 94.88496 -125.75776)
			(xy 94.939299 -125.751185) (xy 94.99402 -125.752443) (xy 95.047999 -125.76151) (xy 95.100128 -125.778199)
			(xy 95.149337 -125.802167) (xy 95.194614 -125.832923) (xy 95.235031 -125.869834) (xy 95.269757 -125.912143)
			(xy 95.298079 -125.958981) (xy 95.309182 -125.984) (xy 95.309643 -125.985016) (xy 96.585022 -125.985016)
			(xy 96.589093 -125.929394) (xy 96.601219 -125.874957) (xy 96.621142 -125.822866) (xy 96.648438 -125.774231)
			(xy 96.682524 -125.730088) (xy 96.722673 -125.691379) (xy 96.768031 -125.658928) (xy 96.817631 -125.633427)
			(xy 96.870415 -125.61542) (xy 96.925258 -125.60529) (xy 96.980992 -125.603253) (xy 97.036429 -125.609353)
			(xy 97.090386 -125.623459) (xy 97.141715 -125.645271) (xy 97.189321 -125.674325) (xy 97.232189 -125.71)
			(xy 97.269406 -125.751537) (xy 97.300179 -125.79805) (xy 97.323851 -125.848547) (xy 97.339919 -125.901954)
			(xy 97.348039 -125.95713) (xy 97.348548 -125.985016) (xy 97.348039 -126.012902) (xy 97.339919 -126.068078)
			(xy 97.323851 -126.121485) (xy 97.300179 -126.171982) (xy 97.269406 -126.218495) (xy 97.232189 -126.260032)
			(xy 97.189321 -126.295707) (xy 97.141715 -126.324761) (xy 97.090386 -126.346573) (xy 97.036429 -126.360679)
			(xy 96.980992 -126.366779) (xy 96.925258 -126.364742) (xy 96.870415 -126.354612) (xy 96.817631 -126.336605)
			(xy 96.768031 -126.311104) (xy 96.722673 -126.278653) (xy 96.682524 -126.239944) (xy 96.648438 -126.195801)
			(xy 96.621142 -126.147166) (xy 96.601219 -126.095075) (xy 96.589093 -126.040638) (xy 96.585022 -125.985016)
			(xy 95.309643 -125.985016) (xy 95.318992 -126.005642) (xy 95.345361 -126.045161) (xy 95.378608 -126.079099)
			(xy 95.417578 -126.106274) (xy 95.460915 -126.125742) (xy 95.507113 -126.136826) (xy 95.554566 -126.139141)
			(xy 95.578168 -126.1364) (xy 95.60802 -126.13266) (xy 95.668184 -126.132252) (xy 95.727883 -126.139729)
			(xy 95.786088 -126.15496) (xy 95.841797 -126.177685) (xy 95.894049 -126.20751) (xy 95.941944 -126.243923)
			(xy 95.984658 -126.286296) (xy 96.021453 -126.333898) (xy 96.051696 -126.38591) (xy 96.074866 -126.441435)
			(xy 96.090563 -126.499516) (xy 96.098517 -126.559153) (xy 96.098591 -126.619318) (xy 96.090784 -126.678975)
			(xy 96.07523 -126.737095) (xy 96.052198 -126.792677) (xy 96.022083 -126.844763) (xy 95.985405 -126.892456)
			(xy 95.942797 -126.934934) (xy 95.894991 -126.971465) (xy 95.842813 -127.001419) (xy 95.78716 -127.024281)
			(xy 95.728993 -127.039656) (xy 95.669313 -127.04728) (xy 95.609148 -127.047021) (xy 95.549535 -127.038883)
			(xy 95.491502 -127.023008) (xy 95.436049 -126.999667) (xy 95.38413 -126.969265) (xy 95.336641 -126.932323)
			(xy 95.2944 -126.88948) (xy 95.258135 -126.841473) (xy 95.22847 -126.789129) (xy 95.205917 -126.733351)
			(xy 95.19793 -126.704344) (xy 95.191498 -126.681471) (xy 95.171234 -126.6385) (xy 95.143338 -126.600041)
			(xy 95.108783 -126.567435) (xy 95.068771 -126.541818) (xy 95.024696 -126.52408) (xy 94.978093 -126.514841)
			(xy 94.954344 -126.514098) (xy 94.926981 -126.513415) (xy 94.872883 -126.505087) (xy 94.820531 -126.489112)
			(xy 94.770999 -126.465819) (xy 94.725306 -126.435685) (xy 94.684388 -126.39933) (xy 94.649087 -126.357499)
			(xy 94.620127 -126.311052) (xy 94.598103 -126.260944) (xy 94.583468 -126.208201) (xy 94.576521 -126.153908)
			(xy 93.135281 -126.153908) (xy 93.047361 -128.614424) (xy 93.329504 -128.614424) (xy 93.333575 -128.558802)
			(xy 93.345701 -128.504365) (xy 93.365624 -128.452274) (xy 93.39292 -128.403639) (xy 93.427006 -128.359496)
			(xy 93.467155 -128.320787) (xy 93.512513 -128.288336) (xy 93.562113 -128.262835) (xy 93.614897 -128.244828)
			(xy 93.66974 -128.234698) (xy 93.725474 -128.232661) (xy 93.780911 -128.238761) (xy 93.834868 -128.252867)
			(xy 93.886197 -128.274679) (xy 93.933803 -128.303733) (xy 93.976671 -128.339408) (xy 94.013888 -128.380945)
			(xy 94.044661 -128.427458) (xy 94.068333 -128.477955) (xy 94.084401 -128.531362) (xy 94.092521 -128.586538)
			(xy 94.09303 -128.614424) (xy 94.092521 -128.64231) (xy 94.084401 -128.697486) (xy 94.068333 -128.750893)
			(xy 94.044661 -128.80139) (xy 94.013888 -128.847903) (xy 93.976671 -128.88944) (xy 93.933803 -128.925115)
			(xy 93.886197 -128.954169) (xy 93.834868 -128.975981) (xy 93.780911 -128.990087) (xy 93.725474 -128.996187)
			(xy 93.66974 -128.99415) (xy 93.614897 -128.98402) (xy 93.562113 -128.966013) (xy 93.512513 -128.940512)
			(xy 93.467155 -128.908061) (xy 93.427006 -128.869352) (xy 93.39292 -128.825209) (xy 93.365624 -128.776574)
			(xy 93.345701 -128.724483) (xy 93.333575 -128.670046) (xy 93.329504 -128.614424) (xy 93.047361 -128.614424)
			(xy 93.016121 -129.488692) (xy 95.92894 -129.488692) (xy 95.933011 -129.43307) (xy 95.945137 -129.378633)
			(xy 95.96506 -129.326542) (xy 95.992356 -129.277907) (xy 96.026442 -129.233764) (xy 96.066591 -129.195055)
			(xy 96.111949 -129.162604) (xy 96.161549 -129.137103) (xy 96.214333 -129.119096) (xy 96.269176 -129.108966)
			(xy 96.32491 -129.106929) (xy 96.380347 -129.113029) (xy 96.434304 -129.127135) (xy 96.485633 -129.148947)
			(xy 96.533239 -129.178001) (xy 96.576107 -129.213676) (xy 96.613324 -129.255213) (xy 96.644097 -129.301726)
			(xy 96.667769 -129.352223) (xy 96.683837 -129.40563) (xy 96.691957 -129.460806) (xy 96.692466 -129.488692)
			(xy 96.691957 -129.516578) (xy 96.683837 -129.571754) (xy 96.667769 -129.625161) (xy 96.644097 -129.675658)
			(xy 96.613324 -129.722171) (xy 96.576107 -129.763708) (xy 96.533239 -129.799383) (xy 96.485633 -129.828437)
			(xy 96.434304 -129.850249) (xy 96.380347 -129.864355) (xy 96.32491 -129.870455) (xy 96.269176 -129.868418)
			(xy 96.214333 -129.858288) (xy 96.161549 -129.840281) (xy 96.111949 -129.81478) (xy 96.066591 -129.782329)
			(xy 96.026442 -129.74362) (xy 95.992356 -129.699477) (xy 95.96506 -129.650842) (xy 95.945137 -129.598751)
			(xy 95.933011 -129.544314) (xy 95.92894 -129.488692) (xy 93.016121 -129.488692) (xy 92.98686 -130.307588)
			(xy 92.98686 -131.560514) (xy 96.980962 -131.560514) (xy 96.981781 -131.500749) (xy 96.990374 -131.441599)
			(xy 97.006595 -131.384071) (xy 97.030166 -131.329144) (xy 97.060688 -131.277753) (xy 97.09764 -131.230774)
			(xy 97.118678 -131.209542) (xy 97.134394 -131.193548) (xy 97.160483 -131.157085) (xy 97.179763 -131.116607)
			(xy 97.191637 -131.073372) (xy 97.195733 -131.028724) (xy 97.191926 -130.98405) (xy 97.180333 -130.940739)
			(xy 97.171256 -130.920236) (xy 97.159879 -130.894916) (xy 97.143862 -130.841768) (xy 97.135717 -130.786859)
			(xy 97.135614 -130.731349) (xy 97.143557 -130.676411) (xy 97.159377 -130.623203) (xy 97.18274 -130.572849)
			(xy 97.213154 -130.526413) (xy 97.249976 -130.484874) (xy 97.292428 -130.44911) (xy 97.339616 -130.419875)
			(xy 97.390541 -130.397786) (xy 97.44413 -130.383311) (xy 97.499252 -130.376754) (xy 97.554741 -130.378254)
			(xy 97.609427 -130.387779) (xy 97.662156 -130.405129) (xy 97.711814 -130.429936) (xy 97.757353 -130.461677)
			(xy 97.797812 -130.499683) (xy 97.832336 -130.543151) (xy 97.860196 -130.591162) (xy 97.880805 -130.642704)
			(xy 97.893728 -130.696689) (xy 97.898691 -130.751976) (xy 97.89559 -130.807399) (xy 97.88449 -130.861788)
			(xy 97.865625 -130.913994) (xy 97.839395 -130.962915) (xy 97.823274 -130.985514) (xy 97.81032 -131.003827)
			(xy 97.79033 -131.043979) (xy 97.777699 -131.087017) (xy 97.772819 -131.131603) (xy 97.77584 -131.176353)
			(xy 97.786669 -131.219879) (xy 97.80497 -131.260828) (xy 97.817178 -131.279646) (xy 97.833762 -131.304895)
			(xy 97.860872 -131.358877) (xy 97.880643 -131.415957) (xy 97.892731 -131.475143) (xy 97.896924 -131.535405)
			(xy 97.89315 -131.595695) (xy 97.881476 -131.654963) (xy 97.862103 -131.71218) (xy 97.835368 -131.76635)
			(xy 97.818956 -131.79171) (xy 97.806677 -131.810878) (xy 97.788509 -131.852614) (xy 97.778061 -131.896917)
			(xy 97.775664 -131.942372) (xy 97.781397 -131.987529) (xy 97.795076 -132.030943) (xy 97.816264 -132.07123)
			(xy 97.844284 -132.107102) (xy 97.878242 -132.137414) (xy 97.917053 -132.161197) (xy 97.938082 -132.169916)
			(xy 97.964001 -132.180513) (xy 98.01268 -132.208184) (xy 98.05679 -132.242675) (xy 98.095383 -132.283245)
			(xy 98.127629 -132.329021) (xy 98.152837 -132.37902) (xy 98.170463 -132.432168) (xy 98.180129 -132.487321)
			(xy 98.181627 -132.543295) (xy 98.174925 -132.598886) (xy 98.160167 -132.652901) (xy 98.137671 -132.704177)
			(xy 98.107919 -132.751612) (xy 98.071551 -132.794188) (xy 98.02935 -132.83099) (xy 97.982221 -132.861225)
			(xy 97.931178 -132.884245) (xy 97.877317 -132.899555) (xy 97.821797 -132.906825) (xy 97.765811 -132.905899)
			(xy 97.710562 -132.896798) (xy 97.657237 -132.879717) (xy 97.606982 -132.855022) (xy 97.560878 -132.823246)
			(xy 97.519916 -132.78507) (xy 97.484976 -132.741315) (xy 97.456808 -132.692922) (xy 97.436019 -132.64093)
			(xy 97.423054 -132.586458) (xy 97.418193 -132.530675) (xy 97.421541 -132.474781) (xy 97.433025 -132.419977)
			(xy 97.452398 -132.367442) (xy 97.465388 -132.342636) (xy 97.475885 -132.322441) (xy 97.490195 -132.279238)
			(xy 97.496585 -132.234177) (xy 97.494851 -132.188699) (xy 97.485048 -132.144255) (xy 97.46749 -132.102267)
			(xy 97.442737 -132.064075) (xy 97.411581 -132.030901) (xy 97.375016 -132.003802) (xy 97.334211 -131.983646)
			(xy 97.31248 -131.976876) (xy 97.283886 -131.96817) (xy 97.229058 -131.944371) (xy 97.177793 -131.913637)
			(xy 97.130967 -131.876491) (xy 97.089374 -131.833565) (xy 97.053724 -131.78559) (xy 97.024623 -131.733382)
			(xy 97.002567 -131.677829) (xy 96.98793 -131.619878) (xy 96.980962 -131.560514) (xy 92.98686 -131.560514)
			(xy 92.98686 -132.143672) (xy 94.496765 -132.143672) (xy 94.49944 -132.087978) (xy 94.510192 -132.033265)
			(xy 94.528794 -131.980701) (xy 94.554848 -131.931403) (xy 94.587801 -131.886424) (xy 94.62695 -131.846719)
			(xy 94.671461 -131.813136) (xy 94.720386 -131.78639) (xy 94.772683 -131.767049) (xy 94.827239 -131.755527)
			(xy 94.88289 -131.752068) (xy 94.938453 -131.756747) (xy 94.992742 -131.769463) (xy 95.044603 -131.789946)
			(xy 95.092929 -131.817759) (xy 95.115126 -131.834636) (xy 95.128142 -131.844367) (xy 95.157884 -131.857447)
			(xy 95.189966 -131.862582) (xy 95.222305 -131.859436) (xy 95.252797 -131.848216) (xy 95.27946 -131.829651)
			(xy 95.290386 -131.817618) (xy 95.310683 -131.794668) (xy 95.356368 -131.753845) (xy 95.407091 -131.719483)
			(xy 95.461946 -131.692196) (xy 95.519951 -131.672473) (xy 95.580069 -131.660665) (xy 95.641226 -131.656986)
			(xy 95.702326 -131.6615) (xy 95.762277 -131.674126) (xy 95.820008 -131.694639) (xy 95.874486 -131.722671)
			(xy 95.924735 -131.757723) (xy 95.969859 -131.799166) (xy 96.009048 -131.846259) (xy 96.041604 -131.89816)
			(xy 96.066943 -131.953942) (xy 96.084612 -132.012605) (xy 96.094296 -132.073102) (xy 96.09582 -132.13435)
			(xy 96.089158 -132.195253) (xy 96.07443 -132.254723) (xy 96.051897 -132.311696) (xy 96.021964 -132.365153)
			(xy 95.985166 -132.414138) (xy 95.94216 -132.457774) (xy 95.893717 -132.495282) (xy 95.840701 -132.52599)
			(xy 95.784063 -132.54935) (xy 95.724813 -132.564943) (xy 95.664013 -132.572491) (xy 95.60275 -132.571859)
			(xy 95.542119 -132.563057) (xy 95.483204 -132.546244) (xy 95.427059 -132.52172) (xy 95.374689 -132.489924)
			(xy 95.32703 -132.451424) (xy 95.305626 -132.429504) (xy 95.294094 -132.418087) (xy 95.266536 -132.400971)
			(xy 95.235555 -132.391353) (xy 95.203149 -132.389853) (xy 95.171412 -132.39657) (xy 95.142392 -132.411069)
			(xy 95.129858 -132.421376) (xy 95.108507 -132.439312) (xy 95.061634 -132.469511) (xy 95.010865 -132.492566)
			(xy 94.957281 -132.507986) (xy 94.902022 -132.515442) (xy 94.846267 -132.514776) (xy 94.791203 -132.506001)
			(xy 94.738003 -132.489304) (xy 94.687799 -132.465042) (xy 94.641662 -132.433731) (xy 94.600573 -132.396038)
			(xy 94.565409 -132.352765) (xy 94.536917 -132.304835) (xy 94.515706 -132.253268) (xy 94.502226 -132.199163)
			(xy 94.496765 -132.143672) (xy 92.98686 -132.143672) (xy 92.98686 -132.1943) (xy 92.987293 -132.215992)
			(xy 92.994646 -132.258747) (xy 93.009157 -132.299631) (xy 93.030402 -132.337456) (xy 93.057765 -132.371121)
			(xy 93.09045 -132.399648) (xy 93.127506 -132.422208) (xy 93.167856 -132.438144) (xy 93.210326 -132.446993)
			(xy 93.253683 -132.448499) (xy 93.296665 -132.442616) (xy 93.338023 -132.429516) (xy 93.357446 -132.419852)
			(xy 93.382473 -132.407477) (xy 93.435283 -132.389367) (xy 93.490169 -132.379145) (xy 93.545958 -132.37703)
			(xy 93.60146 -132.383067) (xy 93.65549 -132.397127) (xy 93.706895 -132.418911) (xy 93.754576 -132.447953)
			(xy 93.797517 -132.483632) (xy 93.8348 -132.525189) (xy 93.865629 -132.571734) (xy 93.889347 -132.622275)
			(xy 93.905447 -132.675733) (xy 93.913585 -132.730966) (xy 93.913588 -132.786796) (xy 93.905455 -132.842029)
			(xy 93.889361 -132.895489) (xy 93.865648 -132.946032) (xy 93.834823 -132.992581) (xy 93.797544 -133.034141)
			(xy 93.754607 -133.069825) (xy 93.706929 -133.098871) (xy 93.655527 -133.12066) (xy 93.601498 -133.134726)
			(xy 93.545997 -133.140769) (xy 93.490207 -133.13866) (xy 93.43532 -133.128443) (xy 93.382508 -133.110338)
			(xy 93.357446 -133.098032) (xy 93.337983 -133.088475) (xy 93.296641 -133.075409) (xy 93.253682 -133.06955)
			(xy 93.210351 -133.071069) (xy 93.167907 -133.079922) (xy 93.127582 -133.095852) (xy 93.090547 -133.118396)
			(xy 93.057877 -133.1469) (xy 93.03052 -133.180537) (xy 93.009269 -133.21833) (xy 92.994744 -133.259181)
			(xy 92.987364 -133.301906) (xy 92.98686 -133.323584) (xy 92.98686 -133.534658) (xy 92.987331 -133.550432)
			(xy 92.995076 -133.581013) (xy 93.010101 -133.608753) (xy 93.031484 -133.631947) (xy 93.057912 -133.649174)
			(xy 93.087765 -133.659375) (xy 93.103446 -133.66115) (xy 93.130839 -133.663885) (xy 93.184488 -133.676232)
			(xy 93.235804 -133.696161) (xy 93.283724 -133.723259) (xy 93.327251 -133.756962) (xy 93.365483 -133.796571)
			(xy 93.397626 -133.841264) (xy 93.423011 -133.890113) (xy 93.441112 -133.942102) (xy 93.451553 -133.996154)
			(xy 93.454118 -134.051144) (xy 93.448752 -134.105933) (xy 93.435568 -134.159382) (xy 93.414839 -134.21038)
			(xy 93.386996 -134.257871) (xy 93.370146 -134.27964) (xy 93.359892 -134.29339) (xy 93.346412 -134.324915)
			(xy 93.341807 -134.358891) (xy 93.346407 -134.392867) (xy 93.359882 -134.424394) (xy 93.370146 -134.438136)
			(xy 93.387614 -134.460797) (xy 93.416274 -134.510317) (xy 93.437217 -134.563561) (xy 93.449975 -134.619336)
			(xy 93.454261 -134.676391) (xy 93.452354 -134.701791) (xy 96.806464 -134.701791) (xy 96.81075 -134.644735)
			(xy 96.823509 -134.58896) (xy 96.844455 -134.535716) (xy 96.873117 -134.486197) (xy 96.890586 -134.463536)
			(xy 96.900854 -134.449796) (xy 96.914337 -134.418269) (xy 96.91894 -134.384291) (xy 96.914332 -134.350313)
			(xy 96.900845 -134.318788) (xy 96.890586 -134.30504) (xy 96.873312 -134.282524) (xy 96.844817 -134.233451)
			(xy 96.823907 -134.180697) (xy 96.811042 -134.125429) (xy 96.806507 -134.068864) (xy 96.810401 -134.012252)
			(xy 96.822639 -133.956841) (xy 96.84295 -133.903854) (xy 96.870887 -133.854461) (xy 96.905833 -133.809751)
			(xy 96.947016 -133.770712) (xy 96.993528 -133.738204) (xy 97.044343 -133.712946) (xy 97.098339 -133.695493)
			(xy 97.154324 -133.686233) (xy 97.182686 -133.68528) (xy 97.197853 -133.684603) (xy 97.227234 -133.676996)
			(xy 97.253986 -133.662662) (xy 97.276594 -133.642414) (xy 97.293778 -133.617398) (xy 97.304566 -133.58903)
			(xy 97.306892 -133.574028) (xy 97.310761 -133.547034) (xy 97.325196 -133.494447) (xy 97.346972 -133.444451)
			(xy 97.375646 -133.398066) (xy 97.410633 -133.356237) (xy 97.451219 -133.319815) (xy 97.496578 -133.289544)
			(xy 97.545785 -133.266041) (xy 97.597837 -133.249783) (xy 97.651674 -133.241104) (xy 97.706199 -133.240179)
			(xy 97.760299 -133.247027) (xy 97.812873 -133.261509) (xy 97.862849 -133.28333) (xy 97.909209 -133.312045)
			(xy 97.951007 -133.347068) (xy 97.987393 -133.387687) (xy 98.017623 -133.433073) (xy 98.041083 -133.482301)
			(xy 98.057294 -133.534367) (xy 98.065926 -133.588212) (xy 98.066803 -133.642737) (xy 98.059906 -133.696832)
			(xy 98.045378 -133.749393) (xy 98.023512 -133.799349) (xy 97.994756 -133.845684) (xy 97.959696 -133.887451)
			(xy 97.919045 -133.9238) (xy 97.873632 -133.953991) (xy 97.824383 -133.977407) (xy 97.772302 -133.993572)
			(xy 97.71845 -134.002156) (xy 97.691194 -134.003034) (xy 97.676025 -134.003681) (xy 97.646642 -134.011294)
			(xy 97.619888 -134.025633) (xy 97.59728 -134.045887) (xy 97.580097 -134.070909) (xy 97.569312 -134.099282)
			(xy 97.566988 -134.114286) (xy 97.563305 -134.140253) (xy 97.549737 -134.190912) (xy 97.529343 -134.23923)
			(xy 97.50251 -134.284291) (xy 97.48647 -134.30504) (xy 97.476227 -134.318797) (xy 97.462746 -134.350318)
			(xy 97.45814 -134.384291) (xy 97.462741 -134.418264) (xy 97.476217 -134.449787) (xy 97.48647 -134.463536)
			(xy 97.503924 -134.486206) (xy 97.532581 -134.535724) (xy 97.553523 -134.588966) (xy 97.566279 -134.644739)
			(xy 97.570564 -134.701791) (xy 97.566282 -134.758843) (xy 97.553529 -134.814616) (xy 97.53259 -134.867859)
			(xy 97.503935 -134.917378) (xy 97.48647 -134.94004) (xy 97.476227 -134.953797) (xy 97.462746 -134.985318)
			(xy 97.45814 -135.019291) (xy 97.462741 -135.053264) (xy 97.476217 -135.084787) (xy 97.48647 -135.098536)
			(xy 97.503351 -135.120433) (xy 97.531285 -135.168145) (xy 97.552039 -135.219389) (xy 97.565179 -135.273093)
			(xy 97.570428 -135.328131) (xy 97.567678 -135.383351) (xy 97.556985 -135.437595) (xy 97.538574 -135.489727)
			(xy 97.512831 -135.538656) (xy 97.480293 -135.583356) (xy 97.441644 -135.622891) (xy 97.397693 -135.656433)
			(xy 97.349361 -135.683279) (xy 97.297659 -135.702866) (xy 97.243671 -135.714785) (xy 97.188528 -135.718786)
			(xy 97.133385 -135.714785) (xy 97.079397 -135.702866) (xy 97.027695 -135.683279) (xy 96.979363 -135.656433)
			(xy 96.935412 -135.622891) (xy 96.896763 -135.583356) (xy 96.864225 -135.538656) (xy 96.838482 -135.489727)
			(xy 96.820071 -135.437595) (xy 96.809378 -135.383351) (xy 96.806628 -135.328131) (xy 96.811877 -135.273093)
			(xy 96.825017 -135.219389) (xy 96.845771 -135.168145) (xy 96.873705 -135.120433) (xy 96.890586 -135.098536)
			(xy 96.900854 -135.084796) (xy 96.914337 -135.053269) (xy 96.91894 -135.019291) (xy 96.914332 -134.985313)
			(xy 96.900845 -134.953788) (xy 96.890586 -134.94004) (xy 96.873106 -134.917388) (xy 96.844446 -134.867867)
			(xy 96.823504 -134.814622) (xy 96.810748 -134.758846) (xy 96.806464 -134.701791) (xy 93.452354 -134.701791)
			(xy 93.449978 -134.733445) (xy 93.437223 -134.789221) (xy 93.416282 -134.842466) (xy 93.387624 -134.891987)
			(xy 93.370146 -134.91464) (xy 93.359892 -134.92839) (xy 93.346412 -134.959915) (xy 93.341807 -134.993891)
			(xy 93.346407 -135.027867) (xy 93.359882 -135.059394) (xy 93.370146 -135.073136) (xy 93.387272 -135.095346)
			(xy 93.415509 -135.143802) (xy 93.436347 -135.19587) (xy 93.449337 -135.250428) (xy 93.4542 -135.3063)
			(xy 93.450831 -135.362282) (xy 93.439301 -135.417167) (xy 93.419861 -135.469773) (xy 93.392928 -135.518966)
			(xy 93.359083 -135.563686) (xy 93.339412 -135.583676) (xy 93.339158 -135.58393) (xy 93.33865 -135.584438)
			(xy 93.327218 -135.596557) (xy 93.310554 -135.625395) (xy 93.30193 -135.657566) (xy 93.301935 -135.690872)
			(xy 93.310569 -135.72304) (xy 93.327241 -135.751873) (xy 93.33865 -135.764016) (xy 93.78315 -136.208516)
			(xy 93.78315 -136.648952) (xy 93.788738 -136.658096) (xy 93.817957 -136.665631) (xy 93.874255 -136.687348)
			(xy 93.927213 -136.716273) (xy 93.975912 -136.751904) (xy 94.019508 -136.793624) (xy 94.057246 -136.840709)
			(xy 94.088472 -136.892343) (xy 94.112645 -136.947632) (xy 94.129344 -137.005617) (xy 94.138282 -137.065293)
			(xy 94.139304 -137.125627) (xy 94.13239 -137.185571) (xy 94.117662 -137.244089) (xy 94.095375 -137.300164)
			(xy 94.065914 -137.352825) (xy 94.029791 -137.40116) (xy 93.987632 -137.444331) (xy 93.940166 -137.48159)
			(xy 93.888218 -137.51229) (xy 93.86062 -137.52449) (xy 93.825314 -137.539476) (xy 93.78315 -137.602976)
			(xy 93.78315 -138.288268) (xy 93.783618 -138.30465) (xy 93.791897 -138.336348) (xy 93.807991 -138.364884)
			(xy 93.830836 -138.388367) (xy 93.844618 -138.397234) (xy 93.868466 -138.412135) (xy 93.911911 -138.447837)
			(xy 93.949651 -138.489523) (xy 93.980873 -138.536291) (xy 94.004899 -138.587132) (xy 94.013528 -138.613896)
			(xy 94.021656 -138.646154) (xy 94.02953 -138.683238) (xy 94.196154 -138.849862) (xy 98.617786 -138.849862)
		)
		(stroke
			(width 0)
			(type solid)
		)
		(fill yes)
		(layer "B.Cu")
		(net "P1V05_SUS_NODE1")
	)
	(gr_poly
		(pts
			(xy 192.84188 -153.293572) (xy 192.84188 -143.278352) (xy 192.841331 -143.261709) (xy 192.832705 -143.229559)
			(xy 192.816053 -143.200737) (xy 192.792509 -143.177206) (xy 192.763678 -143.160569) (xy 192.731524 -143.15196)
			(xy 192.71488 -143.151352) (xy 181.263036 -143.151352) (xy 181.243198 -143.138597) (xy 181.199907 -143.119897)
			(xy 181.153909 -143.109508) (xy 181.106783 -143.107787) (xy 181.060149 -143.114793) (xy 181.015609 -143.130285)
			(xy 180.974693 -143.153731) (xy 180.938807 -143.184326) (xy 180.909185 -143.221018) (xy 180.89753 -143.241522)
			(xy 180.884143 -143.265357) (xy 180.851593 -143.309276) (xy 180.813108 -143.348099) (xy 180.769476 -143.381034)
			(xy 180.721591 -143.407404) (xy 180.670433 -143.42667) (xy 180.617049 -143.438439) (xy 180.562531 -143.442468)
			(xy 180.507997 -143.438676) (xy 180.454562 -143.42714) (xy 180.40332 -143.408096) (xy 180.355321 -143.381935)
			(xy 180.311546 -143.349191) (xy 180.272893 -143.310535) (xy 180.240152 -143.266758) (xy 180.213993 -143.218757)
			(xy 180.194953 -143.167514) (xy 180.18342 -143.114078) (xy 180.179632 -143.059544) (xy 180.183665 -143.005027)
			(xy 180.195437 -142.951643) (xy 180.214707 -142.900486) (xy 180.24108 -142.852603) (xy 180.274017 -142.808973)
			(xy 180.312844 -142.770491) (xy 180.356764 -142.737944) (xy 180.38064 -142.724632) (xy 180.401226 -142.712949)
			(xy 180.438021 -142.683183) (xy 180.46867 -142.64712) (xy 180.492114 -142.606007) (xy 180.507544 -142.561265)
			(xy 180.514425 -142.51444) (xy 180.512519 -142.467151) (xy 180.501894 -142.421032) (xy 180.482915 -142.377676)
			(xy 180.456239 -142.338582) (xy 180.439822 -142.321534) (xy 179.66563 -141.547342) (xy 172.804328 -141.547342)
			(xy 172.789516 -141.547703) (xy 172.76068 -141.554478) (xy 172.734193 -141.567738) (xy 172.711489 -141.586764)
			(xy 172.6938 -141.610523) (xy 172.682086 -141.63773) (xy 172.679106 -141.652244) (xy 172.67376 -141.679789)
			(xy 172.656054 -141.733031) (xy 172.630739 -141.783105) (xy 172.598362 -141.82893) (xy 172.559621 -141.869518)
			(xy 172.515351 -141.903991) (xy 172.466509 -141.931608) (xy 172.414148 -141.951771) (xy 172.359398 -141.964045)
			(xy 172.30344 -141.968166) (xy 172.247482 -141.964045) (xy 172.192732 -141.951771) (xy 172.140371 -141.931608)
			(xy 172.091529 -141.903991) (xy 172.047259 -141.869518) (xy 172.008518 -141.82893) (xy 171.976141 -141.783105)
			(xy 171.950826 -141.733031) (xy 171.93312 -141.679789) (xy 171.927774 -141.652244) (xy 171.924771 -141.63774)
			(xy 171.913026 -141.610559) (xy 171.895331 -141.586818) (xy 171.872639 -141.567797) (xy 171.846172 -141.554521)
			(xy 171.817357 -141.547704) (xy 171.802552 -141.547342) (xy 171.633896 -141.547342) (xy 171.564808 -141.601952)
			(xy 171.554648 -141.645132) (xy 171.547633 -141.672664) (xy 171.526562 -141.725427) (xy 171.497899 -141.774481)
			(xy 171.462279 -141.818741) (xy 171.420488 -141.85723) (xy 171.37345 -141.889094) (xy 171.322208 -141.913631)
			(xy 171.267893 -141.930296) (xy 171.211707 -141.938722) (xy 171.154893 -141.938722) (xy 171.098707 -141.930296)
			(xy 171.044392 -141.913631) (xy 170.99315 -141.889094) (xy 170.946112 -141.85723) (xy 170.904321 -141.818741)
			(xy 170.868701 -141.774481) (xy 170.840038 -141.725427) (xy 170.818967 -141.672664) (xy 170.811952 -141.645132)
			(xy 170.807512 -141.628669) (xy 170.791184 -141.598749) (xy 170.767509 -141.574228) (xy 170.738181 -141.55686)
			(xy 170.705298 -141.547888) (xy 170.688254 -141.547342) (xy 168.402508 -141.547342) (xy 167.07104 -142.87881)
			(xy 170.737782 -142.87881) (xy 170.741853 -142.823188) (xy 170.753979 -142.768751) (xy 170.773902 -142.71666)
			(xy 170.801198 -142.668025) (xy 170.835284 -142.623882) (xy 170.875433 -142.585173) (xy 170.920791 -142.552722)
			(xy 170.970391 -142.527221) (xy 171.023175 -142.509214) (xy 171.078018 -142.499084) (xy 171.133752 -142.497047)
			(xy 171.189189 -142.503147) (xy 171.243146 -142.517253) (xy 171.294475 -142.539065) (xy 171.342081 -142.568119)
			(xy 171.384949 -142.603794) (xy 171.422166 -142.645331) (xy 171.452939 -142.691844) (xy 171.476611 -142.742341)
			(xy 171.492679 -142.795748) (xy 171.500799 -142.850924) (xy 171.501308 -142.87881) (xy 171.791882 -142.87881)
			(xy 171.795953 -142.823188) (xy 171.808079 -142.768751) (xy 171.828002 -142.71666) (xy 171.855298 -142.668025)
			(xy 171.889384 -142.623882) (xy 171.929533 -142.585173) (xy 171.974891 -142.552722) (xy 172.024491 -142.527221)
			(xy 172.077275 -142.509214) (xy 172.132118 -142.499084) (xy 172.187852 -142.497047) (xy 172.243289 -142.503147)
			(xy 172.297246 -142.517253) (xy 172.348575 -142.539065) (xy 172.396181 -142.568119) (xy 172.439049 -142.603794)
			(xy 172.476266 -142.645331) (xy 172.507039 -142.691844) (xy 172.530711 -142.742341) (xy 172.546779 -142.795748)
			(xy 172.554899 -142.850924) (xy 172.555408 -142.87881) (xy 172.554899 -142.906696) (xy 172.546779 -142.961872)
			(xy 172.530711 -143.015279) (xy 172.507039 -143.065776) (xy 172.476266 -143.112289) (xy 172.439049 -143.153826)
			(xy 172.396181 -143.189501) (xy 172.348575 -143.218555) (xy 172.297246 -143.240367) (xy 172.243289 -143.254473)
			(xy 172.187852 -143.260573) (xy 172.132118 -143.258536) (xy 172.077275 -143.248406) (xy 172.024491 -143.230399)
			(xy 171.974891 -143.204898) (xy 171.929533 -143.172447) (xy 171.889384 -143.133738) (xy 171.855298 -143.089595)
			(xy 171.828002 -143.04096) (xy 171.808079 -142.988869) (xy 171.795953 -142.934432) (xy 171.791882 -142.87881)
			(xy 171.501308 -142.87881) (xy 171.500799 -142.906696) (xy 171.492679 -142.961872) (xy 171.476611 -143.015279)
			(xy 171.452939 -143.065776) (xy 171.422166 -143.112289) (xy 171.384949 -143.153826) (xy 171.342081 -143.189501)
			(xy 171.294475 -143.218555) (xy 171.243146 -143.240367) (xy 171.189189 -143.254473) (xy 171.133752 -143.260573)
			(xy 171.078018 -143.258536) (xy 171.023175 -143.248406) (xy 170.970391 -143.230399) (xy 170.920791 -143.204898)
			(xy 170.875433 -143.172447) (xy 170.835284 -143.133738) (xy 170.801198 -143.089595) (xy 170.773902 -143.04096)
			(xy 170.753979 -142.988869) (xy 170.741853 -142.934432) (xy 170.737782 -142.87881) (xy 167.07104 -142.87881)
			(xy 165.802056 -144.147794) (xy 165.786583 -144.163942) (xy 165.765062 -144.194784) (xy 170.709842 -144.194784)
			(xy 170.713913 -144.139162) (xy 170.726039 -144.084725) (xy 170.745962 -144.032634) (xy 170.773258 -143.983999)
			(xy 170.807344 -143.939856) (xy 170.847493 -143.901147) (xy 170.892851 -143.868696) (xy 170.942451 -143.843195)
			(xy 170.995235 -143.825188) (xy 171.050078 -143.815058) (xy 171.105812 -143.813021) (xy 171.161249 -143.819121)
			(xy 171.215206 -143.833227) (xy 171.266535 -143.855039) (xy 171.314141 -143.884093) (xy 171.357009 -143.919768)
			(xy 171.394226 -143.961305) (xy 171.424999 -144.007818) (xy 171.448671 -144.058315) (xy 171.464739 -144.111722)
			(xy 171.472859 -144.166898) (xy 171.473368 -144.194784) (xy 171.473322 -144.197324) (xy 171.761402 -144.197324)
			(xy 171.765473 -144.141702) (xy 171.777599 -144.087265) (xy 171.797522 -144.035174) (xy 171.824818 -143.986539)
			(xy 171.858904 -143.942396) (xy 171.899053 -143.903687) (xy 171.944411 -143.871236) (xy 171.994011 -143.845735)
			(xy 172.046795 -143.827728) (xy 172.101638 -143.817598) (xy 172.157372 -143.815561) (xy 172.212809 -143.821661)
			(xy 172.266766 -143.835767) (xy 172.318095 -143.857579) (xy 172.365701 -143.886633) (xy 172.408569 -143.922308)
			(xy 172.445786 -143.963845) (xy 172.476559 -144.010358) (xy 172.500231 -144.060855) (xy 172.516299 -144.114262)
			(xy 172.524419 -144.169438) (xy 172.524928 -144.197324) (xy 172.524419 -144.22521) (xy 172.516299 -144.280386)
			(xy 172.500231 -144.333793) (xy 172.476559 -144.38429) (xy 172.445786 -144.430803) (xy 172.408569 -144.47234)
			(xy 172.365701 -144.508015) (xy 172.318095 -144.537069) (xy 172.266766 -144.558881) (xy 172.212809 -144.572987)
			(xy 172.157372 -144.579087) (xy 172.101638 -144.57705) (xy 172.046795 -144.56692) (xy 171.994011 -144.548913)
			(xy 171.944411 -144.523412) (xy 171.899053 -144.490961) (xy 171.858904 -144.452252) (xy 171.824818 -144.408109)
			(xy 171.797522 -144.359474) (xy 171.777599 -144.307383) (xy 171.765473 -144.252946) (xy 171.761402 -144.197324)
			(xy 171.473322 -144.197324) (xy 171.472859 -144.22267) (xy 171.464739 -144.277846) (xy 171.448671 -144.331253)
			(xy 171.424999 -144.38175) (xy 171.394226 -144.428263) (xy 171.357009 -144.4698) (xy 171.314141 -144.505475)
			(xy 171.266535 -144.534529) (xy 171.215206 -144.556341) (xy 171.161249 -144.570447) (xy 171.105812 -144.576547)
			(xy 171.050078 -144.57451) (xy 170.995235 -144.56438) (xy 170.942451 -144.546373) (xy 170.892851 -144.520872)
			(xy 170.847493 -144.488421) (xy 170.807344 -144.449712) (xy 170.773258 -144.405569) (xy 170.745962 -144.356934)
			(xy 170.726039 -144.304843) (xy 170.713913 -144.250406) (xy 170.709842 -144.194784) (xy 165.765062 -144.194784)
			(xy 165.760993 -144.200615) (xy 165.742209 -144.241197) (xy 165.730811 -144.284439) (xy 165.72715 -144.329008)
			(xy 165.731339 -144.37353) (xy 165.743248 -144.416634) (xy 165.762511 -144.456991) (xy 165.775132 -144.475454)
			(xy 165.787457 -144.49316) (xy 165.808465 -144.530843) (xy 165.817042 -144.550638) (xy 165.826694 -144.572307)
			(xy 165.852819 -144.611895) (xy 165.885835 -144.64595) (xy 165.924595 -144.673288) (xy 165.967754 -144.692961)
			(xy 166.013813 -144.704286) (xy 166.061174 -144.70687) (xy 166.084758 -144.704308) (xy 166.116125 -144.700612)
			(xy 166.179284 -144.700091) (xy 166.242022 -144.707395) (xy 166.303371 -144.722412) (xy 166.36239 -144.744911)
			(xy 166.418167 -144.774545) (xy 166.469845 -144.810859) (xy 166.516629 -144.853293) (xy 166.557797 -144.901194)
			(xy 166.592717 -144.953824) (xy 166.62085 -145.010374) (xy 166.641763 -145.069972) (xy 166.655135 -145.131701)
			(xy 166.66076 -145.194611) (xy 166.65855 -145.257734) (xy 166.648541 -145.320097) (xy 166.630885 -145.38074)
			(xy 166.605856 -145.43873) (xy 166.573838 -145.493175) (xy 166.535324 -145.543235) (xy 166.490907 -145.58814)
			(xy 166.441271 -145.627199) (xy 166.387181 -145.65981) (xy 166.329468 -145.685472) (xy 166.269021 -145.70379)
			(xy 166.206771 -145.71448) (xy 166.143677 -145.71738) (xy 166.080709 -145.712444) (xy 166.018837 -145.699747)
			(xy 165.959013 -145.679487) (xy 165.902159 -145.651974) (xy 165.84915 -145.617632) (xy 165.800802 -145.57699)
			(xy 165.778942 -145.554192) (xy 165.7667 -145.54177) (xy 165.736967 -145.523567) (xy 165.70341 -145.514114)
			(xy 165.685978 -145.513552) (xy 165.588696 -145.513552) (xy 164.68471 -146.417538) (xy 164.676328 -146.452844)
			(xy 164.676328 -146.453098) (xy 164.669449 -146.480216) (xy 164.648828 -146.532221) (xy 164.620833 -146.580657)
			(xy 164.586063 -146.624484) (xy 164.545264 -146.662763) (xy 164.499312 -146.694672) (xy 164.449192 -146.719526)
			(xy 164.39598 -146.736794) (xy 164.340815 -146.746104) (xy 164.284883 -146.747257) (xy 164.229382 -146.740227)
			(xy 164.175503 -146.725167) (xy 164.124401 -146.702398) (xy 164.077174 -146.672409) (xy 164.034833 -146.635844)
			(xy 163.998287 -146.593486) (xy 163.96832 -146.546245) (xy 163.945574 -146.495133) (xy 163.930538 -146.441247)
			(xy 163.923534 -146.385743) (xy 163.924712 -146.329811) (xy 163.934048 -146.274651) (xy 163.951339 -146.221446)
			(xy 163.976217 -146.171337) (xy 164.008147 -146.1254) (xy 164.046444 -146.084619) (xy 164.090287 -146.049869)
			(xy 164.138736 -146.021896) (xy 164.190751 -146.001299) (xy 164.217858 -145.994374) (xy 164.253164 -145.985992)
			(xy 165.142164 -145.096738) (xy 165.154205 -145.083906) (xy 165.171348 -145.053191) (xy 165.179446 -145.018961)
			(xy 165.177884 -144.983821) (xy 165.172898 -144.966944) (xy 165.15969 -144.927066) (xy 165.14953 -144.912334)
			(xy 165.134248 -144.889016) (xy 165.109929 -144.838848) (xy 165.093174 -144.785674) (xy 165.084339 -144.730628)
			(xy 165.083614 -144.674881) (xy 165.091013 -144.619624) (xy 165.10638 -144.566032) (xy 165.129385 -144.515249)
			(xy 165.15954 -144.468357) (xy 165.17747 -144.447006) (xy 165.21049 -144.40916) (xy 165.206934 -144.309338)
			(xy 165.117272 -144.219676) (xy 164.918644 -144.219676) (xy 164.895363 -144.220222) (xy 164.849588 -144.22875)
			(xy 164.806131 -144.245472) (xy 164.766448 -144.269829) (xy 164.731864 -144.301008) (xy 164.703538 -144.337964)
			(xy 164.682418 -144.379461) (xy 164.669209 -144.424111) (xy 164.664353 -144.47042) (xy 164.668014 -144.516838)
			(xy 164.673534 -144.539462) (xy 164.680258 -144.56636) (xy 164.686763 -144.62142) (xy 164.685231 -144.676842)
			(xy 164.675693 -144.731458) (xy 164.658351 -144.784119) (xy 164.633569 -144.833715) (xy 164.60187 -144.879202)
			(xy 164.563921 -144.919622) (xy 164.520521 -144.954124) (xy 164.472584 -144.981981) (xy 164.421121 -145.002607)
			(xy 164.367214 -145.015566) (xy 164.311999 -145.020587) (xy 164.256638 -145.017563) (xy 164.202299 -145.006559)
			(xy 164.150124 -144.987805) (xy 164.101213 -144.961697) (xy 164.056595 -144.928785) (xy 164.017212 -144.889761)
			(xy 164.00018 -144.867884) (xy 163.990998 -144.85635) (xy 163.968366 -144.837469) (xy 163.942002 -144.824293)
			(xy 163.913317 -144.817527) (xy 163.89858 -144.817084) (xy 163.894008 -144.817084) (xy 163.87654 -144.817639)
			(xy 163.84291 -144.827104) (xy 163.813089 -144.845306) (xy 163.80079 -144.857724) (xy 163.778192 -144.881373)
			(xy 163.727952 -144.923262) (xy 163.672754 -144.958362) (xy 163.613511 -144.986093) (xy 163.551201 -145.005997)
			(xy 163.486852 -145.017745) (xy 163.421528 -145.021144) (xy 163.356308 -145.016137) (xy 163.292268 -145.002806)
			(xy 163.230467 -144.981373) (xy 163.171925 -144.95219) (xy 163.144454 -144.934432) (xy 163.129722 -144.924526)
			(xy 163.090606 -144.911826) (xy 163.073832 -144.906964) (xy 163.038947 -144.905611) (xy 163.005004 -144.913778)
			(xy 162.974552 -144.930852) (xy 162.961828 -144.942814) (xy 161.871914 -146.032728) (xy 161.860457 -146.044863)
			(xy 161.843751 -146.073742) (xy 161.835096 -146.105963) (xy 161.834576 -146.122644) (xy 161.834576 -146.2532)
			(xy 161.835077 -146.269903) (xy 161.843746 -146.302164) (xy 161.860489 -146.33107) (xy 161.884161 -146.354641)
			(xy 161.913138 -146.371262) (xy 161.945435 -146.379793) (xy 161.978841 -146.379651) (xy 162.011064 -146.370845)
			(xy 162.039899 -146.353979) (xy 162.063369 -146.330207) (xy 162.072066 -146.315938) (xy 162.08677 -146.289145)
			(xy 162.12222 -146.239361) (xy 162.163978 -146.194736) (xy 162.211303 -146.156063) (xy 162.263352 -146.124032)
			(xy 162.319201 -146.09921) (xy 162.377856 -146.08204) (xy 162.438273 -146.072827) (xy 162.49938 -146.071735)
			(xy 162.560088 -146.078783) (xy 162.619319 -146.093845) (xy 162.676019 -146.116655) (xy 162.72918 -146.146806)
			(xy 162.777857 -146.183762) (xy 162.821184 -146.226866) (xy 162.85839 -146.275352) (xy 162.888814 -146.328357)
			(xy 162.911916 -146.384938) (xy 162.927283 -146.444091) (xy 162.934644 -146.504762) (xy 162.933866 -146.565873)
			(xy 162.924965 -146.626338) (xy 162.908097 -146.68508) (xy 162.883564 -146.741056) (xy 162.8518 -146.79327)
			(xy 162.813373 -146.840793) (xy 162.768963 -146.882781) (xy 162.719362 -146.918487) (xy 162.665451 -146.947275)
			(xy 162.608189 -146.968635) (xy 162.548594 -146.982185) (xy 162.487726 -146.987686) (xy 162.426667 -146.98504)
			(xy 162.366503 -146.974292) (xy 162.308305 -146.955636) (xy 162.253106 -146.929401) (xy 162.22726 -146.913092)
			(xy 162.207921 -146.901094) (xy 162.165979 -146.883439) (xy 162.121564 -146.873535) (xy 162.076096 -146.871698)
			(xy 162.031027 -146.877988) (xy 161.987798 -146.892204) (xy 161.947792 -146.91389) (xy 161.912288 -146.942355)
			(xy 161.88242 -146.976687) (xy 161.859143 -147.015789) (xy 161.843202 -147.058411) (xy 161.839029 -147.08149)
			(xy 165.00778 -147.08149) (xy 165.00778 -147.021554) (xy 165.015603 -146.962132) (xy 165.031116 -146.904239)
			(xy 165.054052 -146.848866) (xy 165.084019 -146.79696) (xy 165.120506 -146.74941) (xy 165.162886 -146.70703)
			(xy 165.210436 -146.670543) (xy 165.262342 -146.640576) (xy 165.317715 -146.61764) (xy 165.375608 -146.602127)
			(xy 165.43503 -146.594304) (xy 165.494966 -146.594304) (xy 165.554388 -146.602127) (xy 165.612281 -146.61764)
			(xy 165.667654 -146.640576) (xy 165.71956 -146.670543) (xy 165.76711 -146.70703) (xy 165.80949 -146.74941)
			(xy 165.845977 -146.79696) (xy 165.875944 -146.848866) (xy 165.89888 -146.904239) (xy 165.914393 -146.962132)
			(xy 165.922216 -147.021554) (xy 165.922706 -147.051522) (xy 165.922216 -147.08149) (xy 165.914393 -147.140912)
			(xy 165.89888 -147.198805) (xy 165.875944 -147.254178) (xy 165.845977 -147.306084) (xy 165.80949 -147.353634)
			(xy 165.76711 -147.396014) (xy 165.71956 -147.432501) (xy 165.667654 -147.462468) (xy 165.612281 -147.485404)
			(xy 165.554388 -147.500917) (xy 165.494966 -147.50874) (xy 165.43503 -147.50874) (xy 165.375608 -147.500917)
			(xy 165.317715 -147.485404) (xy 165.262342 -147.462468) (xy 165.210436 -147.432501) (xy 165.162886 -147.396014)
			(xy 165.120506 -147.353634) (xy 165.084019 -147.306084) (xy 165.054052 -147.254178) (xy 165.031116 -147.198805)
			(xy 165.015603 -147.140912) (xy 165.00778 -147.08149) (xy 161.839029 -147.08149) (xy 161.835106 -147.103191)
			(xy 161.834576 -147.125944) (xy 161.834576 -147.866354) (xy 161.448033 -148.252897) (xy 175.191882 -148.252897)
			(xy 175.199467 -148.194372) (xy 175.214512 -148.137308) (xy 175.236767 -148.08265) (xy 175.265863 -148.031307)
			(xy 175.301317 -147.98413) (xy 175.34254 -147.941901) (xy 175.36541 -147.92325) (xy 175.382144 -147.909453)
			(xy 175.411105 -147.877174) (xy 175.434167 -147.840449) (xy 175.450663 -147.800342) (xy 175.460113 -147.758018)
			(xy 175.462243 -147.714704) (xy 175.456991 -147.671656) (xy 175.444511 -147.630124) (xy 175.425163 -147.591313)
			(xy 175.399509 -147.556348) (xy 175.384206 -147.54098) (xy 175.364503 -147.521255) (xy 175.330441 -147.47712)
			(xy 175.303166 -147.428498) (xy 175.283257 -147.376423) (xy 175.271139 -147.322006) (xy 175.267071 -147.266404)
			(xy 175.271138 -147.210802) (xy 175.283255 -147.156385) (xy 175.303162 -147.10431) (xy 175.330437 -147.055687)
			(xy 175.364498 -147.011552) (xy 175.384206 -146.991832) (xy 175.399521 -146.97647) (xy 175.425197 -146.941511)
			(xy 175.444562 -146.9027) (xy 175.457056 -146.861163) (xy 175.462314 -146.818108) (xy 175.460183 -146.774786)
			(xy 175.450727 -146.732455) (xy 175.434219 -146.692344) (xy 175.411139 -146.65562) (xy 175.382157 -146.623348)
			(xy 175.36541 -146.609562) (xy 175.342546 -146.590904) (xy 175.301321 -146.548676) (xy 175.265867 -146.501499)
			(xy 175.23677 -146.450156) (xy 175.214515 -146.3955) (xy 175.199469 -146.338435) (xy 175.191883 -146.279911)
			(xy 175.191882 -146.220897) (xy 175.199467 -146.162372) (xy 175.214512 -146.105308) (xy 175.236767 -146.05065)
			(xy 175.265863 -145.999307) (xy 175.301317 -145.95213) (xy 175.34254 -145.909901) (xy 175.36541 -145.89125)
			(xy 175.382144 -145.877453) (xy 175.411105 -145.845174) (xy 175.434167 -145.808449) (xy 175.450663 -145.768342)
			(xy 175.460113 -145.726018) (xy 175.462243 -145.682704) (xy 175.456991 -145.639656) (xy 175.444511 -145.598124)
			(xy 175.425163 -145.559313) (xy 175.399509 -145.524348) (xy 175.384206 -145.50898) (xy 175.36478 -145.489494)
			(xy 175.331088 -145.445995) (xy 175.303994 -145.398108) (xy 175.284059 -145.346826) (xy 175.271697 -145.293212)
			(xy 175.267164 -145.238379) (xy 175.270554 -145.183463) (xy 175.281797 -145.129603) (xy 175.300659 -145.077917)
			(xy 175.32675 -145.029476) (xy 175.359529 -144.985285) (xy 175.398315 -144.946261) (xy 175.42002 -144.929352)
			(xy 175.438515 -144.91479) (xy 175.470279 -144.880059) (xy 175.495105 -144.840073) (xy 175.512143 -144.796198)
			(xy 175.520811 -144.749937) (xy 175.520812 -144.70287) (xy 175.512145 -144.656609) (xy 175.495108 -144.612734)
			(xy 175.470284 -144.572747) (xy 175.43852 -144.538014) (xy 175.42002 -144.52346) (xy 175.398294 -144.506571)
			(xy 175.359494 -144.467548) (xy 175.326704 -144.423356) (xy 175.300602 -144.374911) (xy 175.281732 -144.323218)
			(xy 175.270484 -144.269351) (xy 175.267092 -144.214427) (xy 175.271625 -144.159585) (xy 175.283991 -144.105963)
			(xy 175.303933 -144.054675) (xy 175.331036 -144.006783) (xy 175.364739 -143.963282) (xy 175.384206 -143.943832)
			(xy 175.399521 -143.92847) (xy 175.425197 -143.893511) (xy 175.444562 -143.8547) (xy 175.457056 -143.813163)
			(xy 175.462314 -143.770108) (xy 175.460183 -143.726786) (xy 175.450727 -143.684455) (xy 175.434219 -143.644344)
			(xy 175.411139 -143.60762) (xy 175.382157 -143.575348) (xy 175.36541 -143.561562) (xy 175.342546 -143.542904)
			(xy 175.301321 -143.500676) (xy 175.265867 -143.453499) (xy 175.23677 -143.402156) (xy 175.214515 -143.3475)
			(xy 175.199469 -143.290435) (xy 175.191883 -143.231911) (xy 175.191882 -143.172897) (xy 175.199467 -143.114372)
			(xy 175.214512 -143.057308) (xy 175.236767 -143.00265) (xy 175.265863 -142.951307) (xy 175.301317 -142.90413)
			(xy 175.34254 -142.861901) (xy 175.36541 -142.84325) (xy 175.382144 -142.829453) (xy 175.411105 -142.797174)
			(xy 175.434167 -142.760449) (xy 175.450663 -142.720342) (xy 175.460113 -142.678018) (xy 175.462243 -142.634704)
			(xy 175.456991 -142.591656) (xy 175.444511 -142.550124) (xy 175.425163 -142.511313) (xy 175.399509 -142.476348)
			(xy 175.384206 -142.46098) (xy 175.364775 -142.441568) (xy 175.331126 -142.398159) (xy 175.304049 -142.350373)
			(xy 175.284104 -142.299198) (xy 175.271703 -142.245693) (xy 175.267102 -142.190962) (xy 175.270397 -142.136137)
			(xy 175.281518 -142.082351) (xy 175.300237 -142.030716) (xy 175.326166 -141.982298) (xy 175.35877 -141.938098)
			(xy 175.397375 -141.89903) (xy 175.441183 -141.865901) (xy 175.489288 -141.839397) (xy 175.540697 -141.820063)
			(xy 175.594346 -141.808301) (xy 175.649128 -141.804353) (xy 175.70391 -141.808301) (xy 175.757559 -141.820063)
			(xy 175.808968 -141.839397) (xy 175.857073 -141.865901) (xy 175.900881 -141.89903) (xy 175.939486 -141.938098)
			(xy 175.97209 -141.982298) (xy 175.998019 -142.030716) (xy 176.016738 -142.082351) (xy 176.027859 -142.136137)
			(xy 176.031154 -142.190962) (xy 176.026553 -142.245693) (xy 176.014152 -142.299198) (xy 175.994207 -142.350373)
			(xy 175.96713 -142.398159) (xy 175.933481 -142.441568) (xy 175.91405 -142.46098) (xy 175.898716 -142.476325)
			(xy 175.873035 -142.511285) (xy 175.853665 -142.550099) (xy 175.84117 -142.591639) (xy 175.835912 -142.634698)
			(xy 175.838044 -142.678024) (xy 175.847504 -142.720359) (xy 175.864018 -142.760471) (xy 175.887105 -142.797196)
			(xy 175.916095 -142.829466) (xy 175.932846 -142.84325) (xy 175.95572 -142.861896) (xy 175.996939 -142.904127)
			(xy 176.03239 -142.951307) (xy 176.061482 -143.002651) (xy 176.083735 -143.057308) (xy 176.098778 -143.114373)
			(xy 176.106362 -143.172897) (xy 176.106361 -143.231911) (xy 176.098776 -143.290435) (xy 176.083732 -143.347499)
			(xy 176.061479 -143.402156) (xy 176.032386 -143.4535) (xy 175.996935 -143.500678) (xy 175.955714 -143.542909)
			(xy 175.932846 -143.561562) (xy 175.916101 -143.575347) (xy 175.887134 -143.607625) (xy 175.864067 -143.644351)
			(xy 175.847568 -143.684461) (xy 175.838117 -143.726788) (xy 175.835988 -143.770106) (xy 175.841242 -143.813156)
			(xy 175.853728 -143.85469) (xy 175.873082 -143.893502) (xy 175.898743 -143.928465) (xy 175.91405 -143.943832)
			(xy 175.933494 -143.963302) (xy 175.967189 -144.006802) (xy 175.994287 -144.05469) (xy 176.014224 -144.105975)
			(xy 176.026587 -144.159592) (xy 176.03112 -144.214428) (xy 176.027728 -144.269347) (xy 176.016482 -144.323209)
			(xy 175.997616 -144.374897) (xy 175.97152 -144.423339) (xy 175.938736 -144.467529) (xy 175.899944 -144.506552)
			(xy 175.878236 -144.52346) (xy 175.859732 -144.538009) (xy 175.827973 -144.572744) (xy 175.803151 -144.612733)
			(xy 175.786117 -144.656609) (xy 175.777452 -144.702871) (xy 175.777453 -144.749937) (xy 175.786119 -144.796198)
			(xy 175.803155 -144.840073) (xy 175.827977 -144.880061) (xy 175.859738 -144.914796) (xy 175.878236 -144.929352)
			(xy 175.899972 -144.946229) (xy 175.938776 -144.985252) (xy 175.97157 -145.029445) (xy 175.997674 -145.077891)
			(xy 176.016546 -145.129585) (xy 176.027794 -145.183455) (xy 176.031186 -145.238382) (xy 176.02665 -145.293226)
			(xy 176.014281 -145.346849) (xy 175.994336 -145.398139) (xy 175.967228 -145.446031) (xy 175.933519 -145.48953)
			(xy 175.91405 -145.50898) (xy 175.898716 -145.524325) (xy 175.873035 -145.559285) (xy 175.853665 -145.598099)
			(xy 175.84117 -145.639639) (xy 175.835912 -145.682698) (xy 175.838044 -145.726024) (xy 175.847504 -145.768359)
			(xy 175.864018 -145.808471) (xy 175.887105 -145.845196) (xy 175.916095 -145.877466) (xy 175.932846 -145.89125)
			(xy 175.95572 -145.909896) (xy 175.996939 -145.952127) (xy 176.03239 -145.999307) (xy 176.061482 -146.050651)
			(xy 176.083735 -146.105308) (xy 176.098778 -146.162373) (xy 176.106362 -146.220897) (xy 176.106361 -146.279911)
			(xy 176.098776 -146.338435) (xy 176.083732 -146.395499) (xy 176.061479 -146.450156) (xy 176.032386 -146.5015)
			(xy 175.996935 -146.548678) (xy 175.955714 -146.590909) (xy 175.932846 -146.609562) (xy 175.916101 -146.623347)
			(xy 175.887134 -146.655625) (xy 175.864067 -146.692351) (xy 175.847568 -146.732461) (xy 175.838117 -146.774788)
			(xy 175.835988 -146.818106) (xy 175.841242 -146.861156) (xy 175.853728 -146.90269) (xy 175.873082 -146.941502)
			(xy 175.898743 -146.976465) (xy 175.91405 -146.991832) (xy 175.933762 -147.011547) (xy 175.967819 -147.055685)
			(xy 175.972892 -147.06473) (xy 180.796182 -147.06473) (xy 180.800253 -147.009108) (xy 180.812379 -146.954671)
			(xy 180.832302 -146.90258) (xy 180.859598 -146.853945) (xy 180.893684 -146.809802) (xy 180.933833 -146.771093)
			(xy 180.979191 -146.738642) (xy 181.028791 -146.713141) (xy 181.081575 -146.695134) (xy 181.136418 -146.685004)
			(xy 181.192152 -146.682967) (xy 181.247589 -146.689067) (xy 181.301546 -146.703173) (xy 181.352875 -146.724985)
			(xy 181.400481 -146.754039) (xy 181.443349 -146.789714) (xy 181.480566 -146.831251) (xy 181.511339 -146.877764)
			(xy 181.535011 -146.928261) (xy 181.551079 -146.981668) (xy 181.559199 -147.036844) (xy 181.559708 -147.06473)
			(xy 181.559199 -147.092616) (xy 181.551079 -147.147792) (xy 181.535011 -147.201199) (xy 181.511339 -147.251696)
			(xy 181.480566 -147.298209) (xy 181.443349 -147.339746) (xy 181.400481 -147.375421) (xy 181.352875 -147.404475)
			(xy 181.301546 -147.426287) (xy 181.247589 -147.440393) (xy 181.192152 -147.446493) (xy 181.136418 -147.444456)
			(xy 181.081575 -147.434326) (xy 181.028791 -147.416319) (xy 180.979191 -147.390818) (xy 180.933833 -147.358367)
			(xy 180.893684 -147.319658) (xy 180.859598 -147.275515) (xy 180.832302 -147.22688) (xy 180.812379 -147.174789)
			(xy 180.800253 -147.120352) (xy 180.796182 -147.06473) (xy 175.972892 -147.06473) (xy 175.99509 -147.10431)
			(xy 176.014995 -147.156385) (xy 176.02711 -147.210803) (xy 176.031177 -147.266404) (xy 176.027109 -147.322005)
			(xy 176.014993 -147.376423) (xy 175.995087 -147.428498) (xy 175.967815 -147.477122) (xy 175.933757 -147.521259)
			(xy 175.91405 -147.54098) (xy 175.898716 -147.556325) (xy 175.873035 -147.591285) (xy 175.853665 -147.630099)
			(xy 175.84117 -147.671639) (xy 175.835912 -147.714698) (xy 175.838044 -147.758024) (xy 175.847504 -147.800359)
			(xy 175.864018 -147.840471) (xy 175.887105 -147.877196) (xy 175.916095 -147.909466) (xy 175.932846 -147.92325)
			(xy 175.95572 -147.941896) (xy 175.996939 -147.984127) (xy 176.03239 -148.031307) (xy 176.061482 -148.082651)
			(xy 176.064526 -148.090128) (xy 180.768242 -148.090128) (xy 180.772313 -148.034506) (xy 180.784439 -147.980069)
			(xy 180.804362 -147.927978) (xy 180.831658 -147.879343) (xy 180.865744 -147.8352) (xy 180.905893 -147.796491)
			(xy 180.951251 -147.76404) (xy 181.000851 -147.738539) (xy 181.053635 -147.720532) (xy 181.108478 -147.710402)
			(xy 181.164212 -147.708365) (xy 181.219649 -147.714465) (xy 181.273606 -147.728571) (xy 181.324935 -147.750383)
			(xy 181.372541 -147.779437) (xy 181.415409 -147.815112) (xy 181.452626 -147.856649) (xy 181.483399 -147.903162)
			(xy 181.507071 -147.953659) (xy 181.523139 -148.007066) (xy 181.531259 -148.062242) (xy 181.531768 -148.090128)
			(xy 181.531259 -148.118014) (xy 181.523139 -148.17319) (xy 181.507071 -148.226597) (xy 181.483399 -148.277094)
			(xy 181.452626 -148.323607) (xy 181.415409 -148.365144) (xy 181.372541 -148.400819) (xy 181.324935 -148.429873)
			(xy 181.273606 -148.451685) (xy 181.219649 -148.465791) (xy 181.164212 -148.471891) (xy 181.108478 -148.469854)
			(xy 181.053635 -148.459724) (xy 181.000851 -148.441717) (xy 180.951251 -148.416216) (xy 180.905893 -148.383765)
			(xy 180.865744 -148.345056) (xy 180.831658 -148.300913) (xy 180.804362 -148.252278) (xy 180.784439 -148.200187)
			(xy 180.772313 -148.14575) (xy 180.768242 -148.090128) (xy 176.064526 -148.090128) (xy 176.083735 -148.137308)
			(xy 176.098778 -148.194373) (xy 176.106362 -148.252897) (xy 176.106361 -148.311911) (xy 176.098776 -148.370435)
			(xy 176.083732 -148.427499) (xy 176.061479 -148.482156) (xy 176.032386 -148.5335) (xy 175.996935 -148.580678)
			(xy 175.955714 -148.622909) (xy 175.932846 -148.641562) (xy 175.916101 -148.655347) (xy 175.887134 -148.687625)
			(xy 175.864067 -148.724351) (xy 175.847568 -148.764461) (xy 175.838117 -148.806788) (xy 175.835988 -148.850106)
			(xy 175.841242 -148.893156) (xy 175.853728 -148.93469) (xy 175.873082 -148.973502) (xy 175.898743 -149.008465)
			(xy 175.91405 -149.023832) (xy 175.933481 -149.043244) (xy 175.96713 -149.086653) (xy 175.994207 -149.134439)
			(xy 176.014152 -149.185614) (xy 176.026553 -149.239119) (xy 176.031154 -149.29385) (xy 176.027859 -149.348675)
			(xy 176.016738 -149.402461) (xy 175.998019 -149.454096) (xy 175.97209 -149.502514) (xy 175.939486 -149.546714)
			(xy 175.900881 -149.585782) (xy 175.857073 -149.618911) (xy 175.808968 -149.645415) (xy 175.757559 -149.664749)
			(xy 175.70391 -149.676511) (xy 175.649128 -149.680459) (xy 175.594346 -149.676511) (xy 175.540697 -149.664749)
			(xy 175.489288 -149.645415) (xy 175.441183 -149.618911) (xy 175.397375 -149.585782) (xy 175.35877 -149.546714)
			(xy 175.326166 -149.502514) (xy 175.300237 -149.454096) (xy 175.281518 -149.402461) (xy 175.270397 -149.348675)
			(xy 175.267102 -149.29385) (xy 175.271703 -149.239119) (xy 175.284104 -149.185614) (xy 175.304049 -149.134439)
			(xy 175.331126 -149.086653) (xy 175.364775 -149.043244) (xy 175.384206 -149.023832) (xy 175.399521 -149.00847)
			(xy 175.425197 -148.973511) (xy 175.444562 -148.9347) (xy 175.457056 -148.893163) (xy 175.462314 -148.850108)
			(xy 175.460183 -148.806786) (xy 175.450727 -148.764455) (xy 175.434219 -148.724344) (xy 175.411139 -148.68762)
			(xy 175.382157 -148.655348) (xy 175.36541 -148.641562) (xy 175.342546 -148.622904) (xy 175.301321 -148.580676)
			(xy 175.265867 -148.533499) (xy 175.23677 -148.482156) (xy 175.214515 -148.4275) (xy 175.199469 -148.370435)
			(xy 175.191883 -148.311911) (xy 175.191882 -148.252897) (xy 161.448033 -148.252897) (xy 161.291778 -148.409152)
			(xy 161.280335 -148.42128) (xy 161.263655 -148.450141) (xy 161.255021 -148.482338) (xy 161.255022 -148.515672)
			(xy 161.263659 -148.547868) (xy 161.280341 -148.576728) (xy 161.303931 -148.60028) (xy 161.332816 -148.616918)
			(xy 161.365026 -148.625504) (xy 161.381694 -148.626068) (xy 161.55162 -148.626068) (xy 161.63417 -148.67255)
			(xy 161.65411 -148.68395) (xy 161.697086 -148.700146) (xy 161.74227 -148.708375) (xy 161.765234 -148.708872)
			(xy 162.680904 -148.708872) (xy 162.738054 -148.72462) (xy 162.739832 -148.725382) (xy 162.760981 -148.730629)
			(xy 162.804366 -148.734652) (xy 162.847802 -148.731221) (xy 162.890016 -148.720435) (xy 162.929775 -148.70261)
			(xy 162.948112 -148.690838) (xy 163.044632 -148.626068) (xy 163.67633 -148.626068) (xy 163.764214 -148.676106)
			(xy 163.785869 -148.687747) (xy 163.832479 -148.703369) (xy 163.881221 -148.709753) (xy 163.930282 -148.706663)
			(xy 163.954206 -148.700998) (xy 163.985956 -148.692616) (xy 163.98748 -148.692616) (xy 164.003482 -148.688552)
			(xy 164.949632 -148.688552) (xy 164.963399 -148.688323) (xy 164.990763 -148.685268) (xy 165.004242 -148.682456)
			(xy 165.100254 -148.66112) (xy 165.28796 -148.716238) (xy 165.473888 -148.901912) (xy 165.473888 -149.597003)
			(xy 167.486048 -149.597003) (xy 167.488008 -149.533072) (xy 167.497973 -149.469893) (xy 167.515786 -149.408462)
			(xy 167.541164 -149.349752) (xy 167.573708 -149.29469) (xy 167.612903 -149.244146) (xy 167.635174 -149.22119)
			(xy 167.67302 -149.183344) (xy 167.695656 -149.161398) (xy 167.745415 -149.122677) (xy 167.79958 -149.090408)
			(xy 167.857321 -149.065086) (xy 167.91775 -149.047099) (xy 167.979939 -149.036725) (xy 168.042935 -149.034123)
			(xy 168.105768 -149.039331) (xy 168.167475 -149.052271) (xy 168.227108 -149.072744) (xy 168.28375 -149.100435)
			(xy 168.336533 -149.134919) (xy 168.384646 -149.175667) (xy 168.427349 -149.222052) (xy 168.463987 -149.273363)
			(xy 168.493998 -149.328812) (xy 168.51692 -149.387547) (xy 168.532402 -149.448665) (xy 168.540206 -149.51123)
			(xy 168.540684 -149.542754) (xy 168.540684 -150.060152) (xy 176.300382 -150.060152) (xy 176.304453 -150.00453)
			(xy 176.316579 -149.950093) (xy 176.336502 -149.898002) (xy 176.363798 -149.849367) (xy 176.397884 -149.805224)
			(xy 176.438033 -149.766515) (xy 176.483391 -149.734064) (xy 176.532991 -149.708563) (xy 176.585775 -149.690556)
			(xy 176.640618 -149.680426) (xy 176.696352 -149.678389) (xy 176.751789 -149.684489) (xy 176.805746 -149.698595)
			(xy 176.857075 -149.720407) (xy 176.904681 -149.749461) (xy 176.947549 -149.785136) (xy 176.984766 -149.826673)
			(xy 177.015539 -149.873186) (xy 177.039211 -149.923683) (xy 177.055279 -149.97709) (xy 177.063399 -150.032266)
			(xy 177.063908 -150.060152) (xy 177.063399 -150.088038) (xy 177.055279 -150.143214) (xy 177.039211 -150.196621)
			(xy 177.015539 -150.247118) (xy 176.984766 -150.293631) (xy 176.947549 -150.335168) (xy 176.904681 -150.370843)
			(xy 176.857075 -150.399897) (xy 176.805746 -150.421709) (xy 176.751789 -150.435815) (xy 176.696352 -150.441915)
			(xy 176.640618 -150.439878) (xy 176.585775 -150.429748) (xy 176.532991 -150.411741) (xy 176.483391 -150.38624)
			(xy 176.438033 -150.353789) (xy 176.397884 -150.31508) (xy 176.363798 -150.270937) (xy 176.336502 -150.222302)
			(xy 176.316579 -150.170211) (xy 176.304453 -150.115774) (xy 176.300382 -150.060152) (xy 168.540684 -150.060152)
			(xy 168.540684 -150.404322) (xy 168.540278 -150.434286) (xy 168.533233 -150.493798) (xy 168.519233 -150.552067)
			(xy 168.498472 -150.608283) (xy 168.471238 -150.661664) (xy 168.46056 -150.677622) (xy 180.578742 -150.677622)
			(xy 180.578742 -150.617686) (xy 180.586565 -150.558264) (xy 180.602078 -150.500371) (xy 180.625014 -150.444998)
			(xy 180.654981 -150.393092) (xy 180.691468 -150.345542) (xy 180.733848 -150.303162) (xy 180.781398 -150.266675)
			(xy 180.833304 -150.236708) (xy 180.888677 -150.213772) (xy 180.94657 -150.198259) (xy 181.005992 -150.190436)
			(xy 181.065928 -150.190436) (xy 181.12535 -150.198259) (xy 181.183243 -150.213772) (xy 181.238616 -150.236708)
			(xy 181.290522 -150.266675) (xy 181.338072 -150.303162) (xy 181.380452 -150.345542) (xy 181.416939 -150.393092)
			(xy 181.446906 -150.444998) (xy 181.469842 -150.500371) (xy 181.485355 -150.558264) (xy 181.493178 -150.617686)
			(xy 181.493668 -150.647654) (xy 181.493178 -150.677622) (xy 181.485355 -150.737044) (xy 181.469842 -150.794937)
			(xy 181.446906 -150.85031) (xy 181.416939 -150.902216) (xy 181.380452 -150.949766) (xy 181.338072 -150.992146)
			(xy 181.290522 -151.028633) (xy 181.238616 -151.0586) (xy 181.183243 -151.081536) (xy 181.12535 -151.097049)
			(xy 181.065928 -151.104872) (xy 181.005992 -151.104872) (xy 180.94657 -151.097049) (xy 180.888677 -151.081536)
			(xy 180.833304 -151.0586) (xy 180.781398 -151.028633) (xy 180.733848 -150.992146) (xy 180.691468 -150.949766)
			(xy 180.654981 -150.902216) (xy 180.625014 -150.85031) (xy 180.602078 -150.794937) (xy 180.586565 -150.737044)
			(xy 180.578742 -150.677622) (xy 168.46056 -150.677622) (xy 168.437911 -150.711469) (xy 168.418764 -150.734522)
			(xy 168.388284 -150.770336) (xy 168.388284 -150.861268) (xy 168.388829 -150.877903) (xy 168.397521 -150.91002)
			(xy 168.414197 -150.938812) (xy 168.437729 -150.962335) (xy 168.466529 -150.978999) (xy 168.498649 -150.987678)
			(xy 168.515284 -150.988268) (xy 168.614344 -150.988268) (xy 168.648126 -150.962868) (xy 168.673841 -150.944221)
			(xy 168.729038 -150.912781) (xy 168.787722 -150.888463) (xy 168.848978 -150.871647) (xy 168.911852 -150.862593)
			(xy 168.975364 -150.861443) (xy 169.038524 -150.868215) (xy 169.100349 -150.882804) (xy 169.159874 -150.904982)
			(xy 169.216172 -150.934403) (xy 169.268366 -150.970609) (xy 169.315643 -151.013036) (xy 169.357265 -151.061022)
			(xy 169.392584 -151.11382) (xy 169.42105 -151.170608) (xy 169.442219 -151.230499) (xy 169.455761 -151.292561)
			(xy 169.461465 -151.355827) (xy 169.459243 -151.419311) (xy 169.449128 -151.482023) (xy 169.431279 -151.542986)
			(xy 169.405974 -151.60125) (xy 169.373606 -151.655908) (xy 169.334681 -151.706107) (xy 169.31259 -151.728932)
			(xy 169.036746 -152.004776) (xy 168.03243 -152.004776) (xy 167.999704 -152.00427) (xy 167.934792 -151.995878)
			(xy 167.871492 -151.97923) (xy 167.810851 -151.954599) (xy 167.75387 -151.922394) (xy 167.727376 -151.903176)
			(xy 167.693594 -151.877776) (xy 167.676576 -151.877776) (xy 167.676576 -151.862536) (xy 167.646096 -151.826722)
			(xy 167.625264 -151.801529) (xy 167.589509 -151.7468) (xy 167.561068 -151.687938) (xy 167.54041 -151.625915)
			(xy 167.527876 -151.561755) (xy 167.523674 -151.496517) (xy 167.527872 -151.431279) (xy 167.540401 -151.367118)
			(xy 167.561055 -151.305093) (xy 167.589492 -151.246229) (xy 167.625244 -151.191498) (xy 167.646096 -151.166322)
			(xy 167.676576 -151.130508) (xy 167.676576 -151.115268) (xy 167.693594 -151.115268) (xy 167.727376 -151.089868)
			(xy 167.738321 -151.081788) (xy 167.760938 -151.066666) (xy 167.772588 -151.059642) (xy 167.786442 -151.050756)
			(xy 167.809478 -151.027266) (xy 167.825742 -150.998667) (xy 167.834156 -150.966861) (xy 167.834159 -150.933961)
			(xy 167.825751 -150.902154) (xy 167.809491 -150.873553) (xy 167.78646 -150.850058) (xy 167.772588 -150.841202)
			(xy 167.760935 -150.834183) (xy 167.738317 -150.81906) (xy 167.727376 -150.810976) (xy 167.693594 -150.785576)
			(xy 167.676576 -150.785576) (xy 167.676576 -150.770336) (xy 167.646096 -150.734522) (xy 167.626948 -150.711473)
			(xy 167.593638 -150.661659) (xy 167.566417 -150.608275) (xy 167.545662 -150.552059) (xy 167.531663 -150.493793)
			(xy 167.524613 -150.434284) (xy 167.524176 -150.404322) (xy 167.524176 -149.774402) (xy 167.516556 -149.75332)
			(xy 167.506139 -149.72308) (xy 167.492123 -149.660674) (xy 167.486048 -149.597003) (xy 165.473888 -149.597003)
			(xy 165.473888 -150.08098) (xy 165.340284 -150.214838) (xy 165.340284 -151.369776) (xy 165.340803 -151.393317)
			(xy 165.349479 -151.439592) (xy 165.366522 -151.483481) (xy 165.391349 -151.523485) (xy 165.406832 -151.541226)
			(xy 165.473888 -151.614124) (xy 165.473888 -152.597612) (xy 165.403784 -152.696418) (xy 165.391239 -152.714953)
			(xy 165.372176 -152.755443) (xy 165.360499 -152.798645) (xy 165.356569 -152.843225) (xy 165.360508 -152.887803)
			(xy 165.364322 -152.901903) (xy 167.549568 -152.901903) (xy 167.553768 -152.836663) (xy 167.5663 -152.772501)
			(xy 167.586956 -152.710476) (xy 167.615396 -152.651611) (xy 167.65115 -152.59688) (xy 167.672004 -152.571704)
			(xy 167.702484 -152.53589) (xy 167.702484 -152.520396) (xy 167.719502 -152.520396) (xy 167.753284 -152.49525)
			(xy 167.77977 -152.476006) (xy 167.836738 -152.443742) (xy 167.897375 -152.419056) (xy 167.960679 -152.402357)
			(xy 168.025603 -152.393921) (xy 168.058338 -152.393396) (xy 168.809162 -152.393396) (xy 168.841126 -152.393867)
			(xy 168.904551 -152.401875) (xy 168.966472 -152.417769) (xy 169.025912 -152.441299) (xy 169.081934 -152.472094)
			(xy 169.133655 -152.509668) (xy 169.180258 -152.553428) (xy 169.221009 -152.602684) (xy 169.255265 -152.65666)
			(xy 169.282486 -152.714503) (xy 169.302242 -152.775302) (xy 169.314221 -152.838098) (xy 169.318236 -152.9019)
			(xy 169.314221 -152.965702) (xy 169.302242 -153.028498) (xy 169.282486 -153.089297) (xy 169.255265 -153.14714)
			(xy 169.221009 -153.201116) (xy 169.180258 -153.250372) (xy 169.133655 -153.294132) (xy 169.081934 -153.331706)
			(xy 169.025912 -153.362501) (xy 168.966472 -153.386031) (xy 168.904551 -153.401925) (xy 168.841126 -153.409933)
			(xy 168.809162 -153.410412) (xy 168.058338 -153.410412) (xy 168.025603 -153.409891) (xy 167.960679 -153.401455)
			(xy 167.897374 -153.384756) (xy 167.836736 -153.36007) (xy 167.779767 -153.327806) (xy 167.753284 -153.308558)
			(xy 167.719502 -153.283412) (xy 167.702484 -153.283412) (xy 167.702484 -153.267918) (xy 167.672004 -153.232104)
			(xy 167.651154 -153.206925) (xy 167.615399 -153.152194) (xy 167.586959 -153.09333) (xy 167.566301 -153.031305)
			(xy 167.553769 -152.967143) (xy 167.549568 -152.901903) (xy 165.364322 -152.901903) (xy 165.372193 -152.931004)
			(xy 165.391264 -152.971489) (xy 165.403784 -152.990042) (xy 165.473888 -153.088848) (xy 165.473888 -153.680668)
			(xy 165.474379 -153.697326) (xy 165.482994 -153.729509) (xy 165.499646 -153.758365) (xy 165.5232 -153.781927)
			(xy 165.55205 -153.798589) (xy 165.58423 -153.807215) (xy 165.600888 -153.807668) (xy 166.29761 -153.807668)
			(xy 166.977822 -154.48788) (xy 166.990014 -154.50058) (xy 167.007032 -154.518868) (xy 167.103044 -154.563318)
			(xy 167.162734 -154.548078) (xy 167.17518 -154.541982) (xy 167.20053 -154.529734) (xy 167.253562 -154.510825)
			(xy 167.30851 -154.498556) (xy 167.364548 -154.493112) (xy 167.42083 -154.494574) (xy 167.448738 -154.498294)
			(xy 167.458136 -154.499564) (xy 168.303702 -154.499564) (xy 168.379902 -154.423364) (xy 169.198036 -154.423364)
			(xy 169.221296 -154.403464) (xy 169.271743 -154.368788) (xy 169.32599 -154.340424) (xy 169.383252 -154.318783)
			(xy 169.442699 -154.304178) (xy 169.503471 -154.296821) (xy 169.534078 -154.296364) (xy 169.968418 -154.296364)
			(xy 170.77817 -155.10637) (xy 170.800405 -155.129314) (xy 170.839566 -155.1798) (xy 170.872091 -155.234796)
			(xy 170.897466 -155.293435) (xy 170.915292 -155.354792) (xy 170.925287 -155.417899) (xy 170.927294 -155.481761)
			(xy 170.921281 -155.545372) (xy 170.907343 -155.607726) (xy 170.8857 -155.667843) (xy 170.856693 -155.724773)
			(xy 170.820779 -155.777618) (xy 170.778525 -155.825545) (xy 170.730598 -155.867799) (xy 170.677753 -155.903713)
			(xy 170.620823 -155.93272) (xy 170.560706 -155.954363) (xy 170.498352 -155.968301) (xy 170.434741 -155.974314)
			(xy 170.370879 -155.972307) (xy 170.307772 -155.962312) (xy 170.246415 -155.944486) (xy 170.187776 -155.919111)
			(xy 170.13278 -155.886586) (xy 170.082294 -155.847425) (xy 170.05935 -155.82519) (xy 169.549318 -155.315158)
			(xy 169.501566 -155.31211) (xy 169.472216 -155.309821) (xy 169.414287 -155.299322) (xy 169.35796 -155.282198)
			(xy 169.303989 -155.258679) (xy 169.253098 -155.22908) (xy 169.229278 -155.21178) (xy 169.195242 -155.18638)
			(xy 168.37787 -155.18638) (xy 168.37787 -155.184348) (xy 168.303702 -155.11018) (xy 167.890698 -155.11018)
			(xy 167.781732 -155.173934) (xy 167.765222 -155.199334) (xy 167.748393 -155.224468) (xy 167.709149 -155.270497)
			(xy 167.664184 -155.310956) (xy 167.614283 -155.345141) (xy 167.560313 -155.372456) (xy 167.503217 -155.392425)
			(xy 167.443988 -155.404701) (xy 167.383658 -155.409069) (xy 167.323278 -155.405454) (xy 167.263901 -155.393918)
			(xy 167.20656 -155.374662) (xy 167.152254 -155.348023) (xy 167.10193 -155.314463) (xy 167.078914 -155.294838)
			(xy 167.062658 -155.280614) (xy 166.97579 -155.245562) (xy 166.905432 -155.267406) (xy 166.890954 -155.27655)
			(xy 166.864326 -155.292871) (xy 166.80788 -155.319605) (xy 166.748585 -155.339225) (xy 166.687334 -155.351438)
			(xy 166.625049 -155.356058) (xy 166.562667 -155.353017) (xy 166.501126 -155.34236) (xy 166.441353 -155.324248)
			(xy 166.384248 -155.298953) (xy 166.330671 -155.266855) (xy 166.281426 -155.228439) (xy 166.259002 -155.2067)
			(xy 165.876478 -154.824176) (xy 165.600888 -154.824176) (xy 165.58424 -154.824721) (xy 165.552078 -154.83334)
			(xy 165.523241 -154.849988) (xy 165.499696 -154.873532) (xy 165.483045 -154.902366) (xy 165.474422 -154.934528)
			(xy 165.473888 -154.951176) (xy 165.473888 -157.109411) (xy 167.566082 -157.109411) (xy 167.570281 -157.044172)
			(xy 167.582812 -156.98001) (xy 167.603468 -156.917985) (xy 167.631907 -156.859121) (xy 167.66766 -156.80439)
			(xy 167.688514 -156.779214) (xy 167.71874 -156.7434) (xy 167.71874 -156.72816) (xy 167.727376 -156.72816)
			(xy 167.727376 -156.459936) (xy 167.696896 -156.424122) (xy 167.676064 -156.398929) (xy 167.640309 -156.3442)
			(xy 167.611868 -156.285338) (xy 167.59121 -156.223315) (xy 167.578676 -156.159155) (xy 167.574474 -156.093917)
			(xy 167.578672 -156.028679) (xy 167.591201 -155.964518) (xy 167.611855 -155.902493) (xy 167.640292 -155.843629)
			(xy 167.676044 -155.788898) (xy 167.696896 -155.763722) (xy 167.727376 -155.727908) (xy 167.727376 -155.712668)
			(xy 167.744394 -155.712668) (xy 167.778176 -155.687268) (xy 167.804666 -155.668041) (xy 167.861637 -155.635811)
			(xy 167.922278 -155.61117) (xy 167.985583 -155.594527) (xy 168.050502 -155.586157) (xy 168.08323 -155.585668)
			(xy 168.87698 -155.585668) (xy 168.907873 -155.586121) (xy 168.969202 -155.593617) (xy 169.029172 -155.608487)
			(xy 169.086898 -155.630514) (xy 169.14153 -155.659373) (xy 169.192263 -155.694638) (xy 169.238349 -155.73579)
			(xy 169.279111 -155.782223) (xy 169.313946 -155.833252) (xy 169.342342 -155.888125) (xy 169.363881 -155.946035)
			(xy 169.378245 -156.006128) (xy 169.382186 -156.036772) (xy 169.385118 -156.058453) (xy 169.397437 -156.10043)
			(xy 169.416761 -156.139678) (xy 169.442517 -156.17504) (xy 169.473946 -156.205471) (xy 169.51012 -156.230073)
			(xy 169.549971 -156.24812) (xy 169.592323 -156.25908) (xy 169.614088 -156.261308) (xy 169.646082 -156.264372)
			(xy 169.708974 -156.277624) (xy 169.769694 -156.298698) (xy 169.827274 -156.327257) (xy 169.880796 -156.362845)
			(xy 169.929405 -156.404896) (xy 169.972326 -156.452737) (xy 170.008875 -156.505607) (xy 170.038469 -156.562662)
			(xy 170.060636 -156.622992) (xy 170.075023 -156.685634) (xy 170.081399 -156.749591) (xy 170.079663 -156.813841)
			(xy 170.069843 -156.87736) (xy 170.052096 -156.939134) (xy 170.026704 -156.998179) (xy 169.994073 -157.053553)
			(xy 169.954723 -157.104373) (xy 169.93235 -157.127448) (xy 169.723054 -157.336744) (xy 173.042072 -157.336744)
			(xy 175.205136 -157.336744) (xy 175.405288 -157.536896) (xy 175.405288 -159.1818) (xy 175.404845 -159.209054)
			(xy 175.397087 -159.263006) (xy 175.394679 -159.271208) (xy 180.01742 -159.271208) (xy 180.01742 -157.306772)
			(xy 180.677566 -156.64688) (xy 183.836818 -156.64688) (xy 184.117996 -156.927804) (xy 184.117996 -159.266636)
			(xy 183.857646 -159.526732) (xy 180.273198 -159.526732) (xy 180.01742 -159.271208) (xy 175.394679 -159.271208)
			(xy 175.38173 -159.315306) (xy 175.359086 -159.364887) (xy 175.329616 -159.410741) (xy 175.29392 -159.451935)
			(xy 175.252725 -159.487628) (xy 175.20687 -159.517096) (xy 175.157287 -159.539737) (xy 175.104987 -159.555091)
			(xy 175.051034 -159.562846) (xy 175.02378 -159.563308) (xy 173.042072 -159.563308) (xy 173.042072 -157.336744)
			(xy 169.723054 -157.336744) (xy 169.44213 -157.617668) (xy 168.074848 -157.617668) (xy 168.042122 -157.617154)
			(xy 167.97721 -157.608764) (xy 167.913911 -157.592118) (xy 167.853269 -157.567489) (xy 167.796288 -157.535285)
			(xy 167.769794 -157.516068) (xy 167.736012 -157.490668) (xy 167.71874 -157.490668) (xy 167.71874 -157.475428)
			(xy 167.688514 -157.439614) (xy 167.667673 -157.414427) (xy 167.631918 -157.359698) (xy 167.603476 -157.300835)
			(xy 167.582818 -157.238811) (xy 167.570284 -157.17465) (xy 167.566082 -157.109411) (xy 165.473888 -157.109411)
			(xy 165.473888 -157.245812) (xy 165.992302 -157.764226) (xy 167.417242 -157.764226) (xy 167.716454 -158.063438)
			(xy 168.642538 -158.063438) (xy 169.21226 -158.63316) (xy 169.21226 -161.055812) (xy 170.27906 -162.122612)
			(xy 184.01284 -162.122612)
		)
		(stroke
			(width 0)
			(type solid)
		)
		(fill yes)
		(layer "B.Cu")
		(net "P1V9_LAN2")
	)
	(gr_poly
		(pts
			(xy 32.210502 -124.984002) (xy 32.226642 -124.967154) (xy 32.253097 -124.92873) (xy 32.272096 -124.886124)
			(xy 32.283 -124.840766) (xy 32.285442 -124.794179) (xy 32.279342 -124.747929) (xy 32.264903 -124.70357)
			(xy 32.242611 -124.66259) (xy 32.213215 -124.626367) (xy 32.19577 -124.610876) (xy 32.18942 -124.605542)
			(xy 32.17775 -124.596113) (xy 32.151031 -124.582483) (xy 32.121867 -124.575475) (xy 32.091873 -124.575475)
			(xy 32.062709 -124.582483) (xy 32.03599 -124.596113) (xy 32.02432 -124.605542) (xy 32.00268 -124.623366)
			(xy 31.955173 -124.653132) (xy 31.90382 -124.675623) (xy 31.849727 -124.690353) (xy 31.794061 -124.697006)
			(xy 31.738021 -124.695437) (xy 31.682815 -124.68568) (xy 31.629631 -124.667947) (xy 31.579617 -124.642618)
			(xy 31.53385 -124.61024) (xy 31.493316 -124.571511) (xy 31.458889 -124.527264) (xy 31.431311 -124.478455)
			(xy 31.411175 -124.426133) (xy 31.398917 -124.371428) (xy 31.3948 -124.315517) (xy 31.398912 -124.259606)
			(xy 31.411166 -124.204899) (xy 31.431296 -124.152576) (xy 31.45887 -124.103764) (xy 31.493293 -124.059514)
			(xy 31.533824 -124.020781) (xy 31.579588 -123.988399) (xy 31.6296 -123.963066) (xy 31.682782 -123.945328)
			(xy 31.737988 -123.935567) (xy 31.794028 -123.933993) (xy 31.849694 -123.94064) (xy 31.903788 -123.955366)
			(xy 31.955143 -123.977852) (xy 32.002652 -124.007614) (xy 32.02432 -124.025406) (xy 32.03599 -124.034835)
			(xy 32.062709 -124.048465) (xy 32.091873 -124.055473) (xy 32.121867 -124.055473) (xy 32.151031 -124.048465)
			(xy 32.17775 -124.034835) (xy 32.18942 -124.025406) (xy 32.210746 -124.007842) (xy 32.257498 -123.978406)
			(xy 32.308007 -123.956022) (xy 32.361217 -123.941159) (xy 32.416014 -123.934128) (xy 32.471252 -123.935075)
			(xy 32.525777 -123.943982) (xy 32.578445 -123.960661) (xy 32.628157 -123.984764) (xy 32.673871 -124.015786)
			(xy 32.714632 -124.053079) (xy 32.732472 -124.074174) (xy 32.748005 -124.091568) (xy 32.784233 -124.120926)
			(xy 32.825205 -124.143187) (xy 32.869549 -124.157605) (xy 32.915779 -124.163697) (xy 32.962344 -124.161259)
			(xy 33.007685 -124.150372) (xy 33.050281 -124.131402) (xy 33.088704 -124.104984) (xy 33.105598 -124.088906)
			(xy 34.392616 -122.801888) (xy 34.397696 -122.704606) (xy 34.366962 -122.66676) (xy 34.349718 -122.644703)
			(xy 34.3212 -122.596524) (xy 34.300028 -122.544695) (xy 34.286658 -122.490328) (xy 34.281375 -122.434592)
			(xy 34.284293 -122.378681) (xy 34.29535 -122.323797) (xy 34.314308 -122.271118) (xy 34.34076 -122.221775)
			(xy 34.374139 -122.176827) (xy 34.413727 -122.137238) (xy 34.458676 -122.10386) (xy 34.508019 -122.077407)
			(xy 34.560698 -122.058449) (xy 34.615582 -122.047393) (xy 34.671492 -122.044475) (xy 34.727229 -122.049758)
			(xy 34.781595 -122.063129) (xy 34.833425 -122.0843) (xy 34.881603 -122.112818) (xy 34.903664 -122.130058)
			(xy 34.916011 -122.139505) (xy 34.944168 -122.152666) (xy 34.974674 -122.158612) (xy 35.005712 -122.156991)
			(xy 35.035433 -122.147898) (xy 35.062065 -122.131875) (xy 35.073336 -122.121168) (xy 35.165284 -122.02922)
			(xy 35.177476 -122.02922) (xy 35.194134 -122.028728) (xy 35.226316 -122.020112) (xy 35.255171 -122.003459)
			(xy 35.278732 -121.979906) (xy 35.295395 -121.951056) (xy 35.304023 -121.918878) (xy 35.304476 -121.90222)
			(xy 35.304069 -121.88758) (xy 35.297399 -121.85907) (xy 35.284407 -121.83283) (xy 35.265776 -121.810243)
			(xy 35.242487 -121.792497) (xy 35.229292 -121.786142) (xy 35.204006 -121.774303) (xy 35.156905 -121.744328)
			(xy 35.114675 -121.707808) (xy 35.07822 -121.665522) (xy 35.048317 -121.618374) (xy 35.025607 -121.56737)
			(xy 35.010574 -121.513602) (xy 35.003538 -121.458216) (xy 35.004651 -121.402396) (xy 35.013888 -121.347334)
			(xy 35.031053 -121.294208) (xy 35.055778 -121.24415) (xy 35.087536 -121.198231) (xy 35.125648 -121.157432)
			(xy 35.1693 -121.122624) (xy 35.217559 -121.09455) (xy 35.269395 -121.07381) (xy 35.3237 -121.060848)
			(xy 35.351466 -121.057924) (xy 35.378434 -121.056038) (xy 35.432414 -121.058979) (xy 35.485438 -121.069512)
			(xy 35.536443 -121.087426) (xy 35.584408 -121.112362) (xy 35.628371 -121.143821) (xy 35.667453 -121.181172)
			(xy 35.700868 -121.223668) (xy 35.72795 -121.270455) (xy 35.748153 -121.320598) (xy 35.757522 -121.35866)
			(xy 42.383962 -121.35866) (xy 42.388033 -121.303038) (xy 42.400159 -121.248601) (xy 42.420082 -121.19651)
			(xy 42.447378 -121.147875) (xy 42.481464 -121.103732) (xy 42.521613 -121.065023) (xy 42.566971 -121.032572)
			(xy 42.616571 -121.007071) (xy 42.669355 -120.989064) (xy 42.724198 -120.978934) (xy 42.779932 -120.976897)
			(xy 42.835369 -120.982997) (xy 42.889326 -120.997103) (xy 42.940655 -121.018915) (xy 42.988261 -121.047969)
			(xy 43.031129 -121.083644) (xy 43.068346 -121.125181) (xy 43.099119 -121.171694) (xy 43.122791 -121.222191)
			(xy 43.138859 -121.275598) (xy 43.146979 -121.330774) (xy 43.147488 -121.35866) (xy 45.30166 -121.35866)
			(xy 45.305731 -121.303038) (xy 45.317857 -121.248601) (xy 45.33778 -121.19651) (xy 45.365076 -121.147875)
			(xy 45.399162 -121.103732) (xy 45.439311 -121.065023) (xy 45.484669 -121.032572) (xy 45.534269 -121.007071)
			(xy 45.587053 -120.989064) (xy 45.641896 -120.978934) (xy 45.69763 -120.976897) (xy 45.753067 -120.982997)
			(xy 45.807024 -120.997103) (xy 45.858353 -121.018915) (xy 45.905959 -121.047969) (xy 45.948827 -121.083644)
			(xy 45.986044 -121.125181) (xy 46.016817 -121.171694) (xy 46.040489 -121.222191) (xy 46.056557 -121.275598)
			(xy 46.064677 -121.330774) (xy 46.065186 -121.35866) (xy 46.064677 -121.386546) (xy 46.056557 -121.441722)
			(xy 46.040489 -121.495129) (xy 46.016817 -121.545626) (xy 45.986044 -121.592139) (xy 45.948827 -121.633676)
			(xy 45.905959 -121.669351) (xy 45.858353 -121.698405) (xy 45.807024 -121.720217) (xy 45.753067 -121.734323)
			(xy 45.69763 -121.740423) (xy 45.641896 -121.738386) (xy 45.587053 -121.728256) (xy 45.534269 -121.710249)
			(xy 45.484669 -121.684748) (xy 45.439311 -121.652297) (xy 45.399162 -121.613588) (xy 45.365076 -121.569445)
			(xy 45.33778 -121.52081) (xy 45.317857 -121.468719) (xy 45.305731 -121.414282) (xy 45.30166 -121.35866)
			(xy 43.147488 -121.35866) (xy 43.146979 -121.386546) (xy 43.138859 -121.441722) (xy 43.122791 -121.495129)
			(xy 43.099119 -121.545626) (xy 43.068346 -121.592139) (xy 43.031129 -121.633676) (xy 42.988261 -121.669351)
			(xy 42.940655 -121.698405) (xy 42.889326 -121.720217) (xy 42.835369 -121.734323) (xy 42.779932 -121.740423)
			(xy 42.724198 -121.738386) (xy 42.669355 -121.728256) (xy 42.616571 -121.710249) (xy 42.566971 -121.684748)
			(xy 42.521613 -121.652297) (xy 42.481464 -121.613588) (xy 42.447378 -121.569445) (xy 42.420082 -121.52081)
			(xy 42.400159 -121.468719) (xy 42.388033 -121.414282) (xy 42.383962 -121.35866) (xy 35.757522 -121.35866)
			(xy 35.761074 -121.37309) (xy 35.766455 -121.426882) (xy 35.764186 -121.480894) (xy 35.754314 -121.534045)
			(xy 35.746182 -121.559828) (xy 35.738485 -121.581517) (xy 35.718618 -121.623031) (xy 35.706558 -121.642632)
			(xy 35.695248 -121.662032) (xy 35.678907 -121.703857) (xy 35.67017 -121.747902) (xy 35.669311 -121.792797)
			(xy 35.676356 -121.837144) (xy 35.691085 -121.879563) (xy 35.713039 -121.918733) (xy 35.741536 -121.953434)
			(xy 35.775689 -121.982587) (xy 35.814433 -122.005285) (xy 35.856564 -122.020819) (xy 35.900768 -122.028707)
			(xy 35.92322 -122.02922) (xy 42.45356 -122.02922) (xy 42.884852 -122.460512) (xy 46.370748 -122.460512)
			(xy 46.402752 -122.428508) (xy 50.937668 -122.428508) (xy 50.960219 -122.427998) (xy 51.004608 -122.419996)
			(xy 51.046889 -122.40429) (xy 51.085737 -122.381374) (xy 51.119934 -122.351965) (xy 51.148408 -122.316985)
			(xy 51.170266 -122.277532) (xy 51.184823 -122.234842) (xy 51.18862 -122.212608) (xy 51.19243 -122.191018)
			(xy 51.19473 -122.179867) (xy 51.200192 -122.15776) (xy 51.203352 -122.146822) (xy 51.208432 -122.129296)
			(xy 51.208432 -121.97842) (xy 51.207891 -121.961768) (xy 51.199277 -121.929599) (xy 51.182631 -121.900754)
			(xy 51.159087 -121.8772) (xy 51.13025 -121.860543) (xy 51.098083 -121.851916) (xy 51.081432 -121.85142)
			(xy 51.059334 -121.85142) (xy 51.038506 -121.858786) (xy 51.013814 -121.867177) (xy 50.962779 -121.877903)
			(xy 50.910758 -121.88157) (xy 50.858723 -121.87811) (xy 50.807646 -121.867587) (xy 50.758481 -121.850197)
			(xy 50.712146 -121.826267) (xy 50.669506 -121.796241) (xy 50.65014 -121.778776) (xy 50.630232 -121.759558)
			(xy 50.595618 -121.716391) (xy 50.567602 -121.668676) (xy 50.546772 -121.617415) (xy 50.533565 -121.563683)
			(xy 50.528259 -121.508607) (xy 50.530963 -121.453341) (xy 50.541623 -121.399046) (xy 50.560013 -121.34686)
			(xy 50.585749 -121.297878) (xy 50.61829 -121.253127) (xy 50.656954 -121.213546) (xy 50.70093 -121.179965)
			(xy 50.749296 -121.153089) (xy 50.801036 -121.13348) (xy 50.82794 -121.127012) (xy 50.851997 -121.122086)
			(xy 50.90091 -121.117734) (xy 50.949977 -121.1197) (xy 50.974244 -121.123456) (xy 50.997374 -121.126272)
			(xy 51.043928 -121.124424) (xy 51.089365 -121.114121) (xy 51.132162 -121.095709) (xy 51.170886 -121.069803)
			(xy 51.204239 -121.037273) (xy 51.231104 -120.999207) (xy 51.250579 -120.956883) (xy 51.262013 -120.911718)
			(xy 51.264058 -120.888506) (xy 51.265428 -120.858522) (xy 51.275052 -120.799274) (xy 51.292339 -120.741793)
			(xy 51.316992 -120.687066) (xy 51.348588 -120.636031) (xy 51.386584 -120.589564) (xy 51.430329 -120.548464)
			(xy 51.479072 -120.513435) (xy 51.531976 -120.485079) (xy 51.588132 -120.463882) (xy 51.646578 -120.450209)
			(xy 51.70631 -120.444293) (xy 51.766302 -120.446237) (xy 51.825526 -120.456007) (xy 51.882964 -120.473435)
			(xy 51.910488 -120.485408) (xy 51.937501 -120.498192) (xy 51.988251 -120.52975) (xy 52.034463 -120.567644)
			(xy 52.075351 -120.61123) (xy 52.110219 -120.659766) (xy 52.138474 -120.712426) (xy 52.159637 -120.768316)
			(xy 52.173346 -120.826485) (xy 52.179369 -120.885942) (xy 52.177603 -120.945678) (xy 52.168079 -121.004677)
			(xy 52.150958 -121.061934) (xy 52.126532 -121.116476) (xy 52.095215 -121.167376) (xy 52.057541 -121.213768)
			(xy 52.036218 -121.234708) (xy 52.024059 -121.246947) (xy 52.006212 -121.276454) (xy 51.996936 -121.309668)
			(xy 51.99634 -121.32691) (xy 51.99634 -121.633996) (xy 51.99748 -121.649696) (xy 52.006486 -121.679849)
			(xy 52.022609 -121.706874) (xy 52.044865 -121.729122) (xy 52.071897 -121.745234) (xy 52.102053 -121.754228)
			(xy 52.117752 -121.755408) (xy 52.17414 -121.755408) (xy 52.17414 -121.780808) (xy 52.632102 -121.780808)
			(xy 52.886356 -122.034808) (xy 53.095652 -122.244104) (xy 53.499258 -122.244104) (xy 53.521072 -122.243655)
			(xy 53.564058 -122.236205) (xy 53.605138 -122.221516) (xy 53.643103 -122.200022) (xy 53.676835 -122.172354)
			(xy 53.705342 -122.139328) (xy 53.727783 -122.101916) (xy 53.743499 -122.061217) (xy 53.752028 -122.018432)
			(xy 53.753117 -121.974818) (xy 53.746735 -121.93166) (xy 53.73307 -121.890228) (xy 53.723286 -121.870724)
			(xy 53.709908 -121.846681) (xy 53.689442 -121.795609) (xy 53.676524 -121.742127) (xy 53.671422 -121.687344)
			(xy 53.674242 -121.632396) (xy 53.684925 -121.578423) (xy 53.70325 -121.526544) (xy 53.728836 -121.477836)
			(xy 53.761153 -121.433307) (xy 53.799531 -121.393882) (xy 53.843174 -121.360378) (xy 53.891177 -121.33349)
			(xy 53.942544 -121.313776) (xy 53.99621 -121.301645) (xy 54.051062 -121.297347) (xy 54.105962 -121.300973)
			(xy 54.159772 -121.312447) (xy 54.211377 -121.33153) (xy 54.259705 -121.357829) (xy 54.303755 -121.390796)
			(xy 54.323488 -121.409968) (xy 54.334403 -121.420301) (xy 54.360024 -121.436001) (xy 54.38861 -121.445262)
			(xy 54.41857 -121.447568) (xy 54.448237 -121.442793) (xy 54.47596 -121.4312) (xy 54.488334 -121.422668)
			(xy 54.510088 -121.407292) (xy 54.557012 -121.382077) (xy 54.606989 -121.363635) (xy 54.659045 -121.352326)
			(xy 54.712168 -121.34837) (xy 54.765325 -121.351844) (xy 54.817481 -121.36268) (xy 54.867622 -121.380668)
			(xy 54.914774 -121.405457) (xy 54.958017 -121.436565) (xy 54.996511 -121.473388) (xy 55.029508 -121.515208)
			(xy 55.043324 -121.537984) (xy 55.055989 -121.560555) (xy 55.075787 -121.608375) (xy 55.088946 -121.658431)
			(xy 55.095225 -121.709805) (xy 55.094509 -121.761557) (xy 55.08681 -121.812737) (xy 55.072271 -121.862409)
			(xy 55.06212 -121.886218) (xy 55.053163 -121.907421) (xy 55.04221 -121.952122) (xy 55.039486 -121.998064)
			(xy 55.045078 -122.043746) (xy 55.058806 -122.087674) (xy 55.080219 -122.128413) (xy 55.108617 -122.164629)
			(xy 55.143073 -122.19514) (xy 55.18246 -122.218948) (xy 55.22549 -122.235274) (xy 55.270757 -122.243585)
			(xy 55.293768 -122.244104) (xy 55.666386 -122.244104) (xy 55.70474 -122.206004) (xy 55.79237 -122.206004)
			(xy 55.815058 -122.204781) (xy 55.859486 -122.195288) (xy 55.901519 -122.178049) (xy 55.939819 -122.153613)
			(xy 55.973164 -122.122758) (xy 56.000493 -122.086466) (xy 56.020935 -122.045894) (xy 56.03384 -122.002334)
			(xy 56.038795 -121.957175) (xy 56.037734 -121.934478) (xy 56.036109 -121.903664) (xy 56.040164 -121.842091)
			(xy 56.052461 -121.781623) (xy 56.072776 -121.723357) (xy 56.100741 -121.668352) (xy 56.135848 -121.617607)
			(xy 56.177459 -121.572042) (xy 56.224819 -121.532486) (xy 56.277067 -121.499657) (xy 56.304942 -121.486422)
			(xy 56.326024 -121.477532) (xy 56.34712 -121.468499) (xy 56.385909 -121.443986) (xy 56.419671 -121.412912)
			(xy 56.44731 -121.376284) (xy 56.467929 -121.335292) (xy 56.480859 -121.291265) (xy 56.485679 -121.245634)
			(xy 56.482234 -121.199877) (xy 56.4769 -121.177558) (xy 56.469103 -121.150252) (xy 56.460744 -121.094085)
			(xy 56.460805 -121.0373) (xy 56.469283 -120.981151) (xy 56.485992 -120.92688) (xy 56.510562 -120.875685)
			(xy 56.542449 -120.828699) (xy 56.58095 -120.786958) (xy 56.625214 -120.751387) (xy 56.674262 -120.722771)
			(xy 56.72701 -120.701742) (xy 56.754522 -120.694704) (xy 56.789828 -120.686322) (xy 57.085484 -120.390666)
			(xy 57.096406 -120.30456) (xy 57.074308 -120.267222) (xy 57.059468 -120.241064) (xy 57.03602 -120.185683)
			(xy 57.020027 -120.127708) (xy 57.011764 -120.068138) (xy 57.011373 -120.007999) (xy 57.018862 -119.948327)
			(xy 57.034102 -119.890149) (xy 57.056829 -119.834468) (xy 57.086652 -119.782243) (xy 57.123058 -119.734374)
			(xy 57.16542 -119.691685) (xy 57.213007 -119.654911) (xy 57.265001 -119.624686) (xy 57.320505 -119.601531)
			(xy 57.378564 -119.585844) (xy 57.438177 -119.577896) (xy 57.498317 -119.577823) (xy 57.528206 -119.581168)
			(xy 57.549679 -119.583518) (xy 57.592838 -119.581754) (xy 57.635077 -119.572719) (xy 57.67518 -119.556673)
			(xy 57.711993 -119.534077) (xy 57.744456 -119.505583) (xy 57.771634 -119.472011) (xy 57.792745 -119.434327)
			(xy 57.807181 -119.393616) (xy 57.814526 -119.351051) (xy 57.814972 -119.329454) (xy 57.814972 -119.20982)
			(xy 57.78246 -119.125746) (xy 57.768998 -119.109744) (xy 57.748649 -119.084492) (xy 57.714524 -119.029344)
			(xy 57.688519 -118.969934) (xy 57.671154 -118.90745) (xy 57.662776 -118.843142) (xy 57.663554 -118.778295)
			(xy 57.67347 -118.714205) (xy 57.682384 -118.683024) (xy 57.691333 -118.655195) (xy 57.715323 -118.601887)
			(xy 57.745894 -118.55206) (xy 57.782551 -118.506524) (xy 57.803288 -118.48592) (xy 57.818961 -118.469653)
			(xy 57.844861 -118.43265) (xy 57.863808 -118.391649) (xy 57.875201 -118.347942) (xy 57.878683 -118.302909)
			(xy 57.874143 -118.257971) (xy 57.861725 -118.214545) (xy 57.84182 -118.174) (xy 57.815056 -118.137617)
			(xy 57.782277 -118.106542) (xy 57.763664 -118.093744) (xy 57.741311 -118.078476) (xy 57.700748 -118.042631)
			(xy 57.665665 -118.001409) (xy 57.636767 -117.955637) (xy 57.614635 -117.906237) (xy 57.599716 -117.854202)
			(xy 57.592308 -117.80058) (xy 57.592562 -117.74645) (xy 57.596024 -117.719602) (xy 57.600596 -117.694202)
			(xy 57.604705 -117.672222) (xy 57.606042 -117.62753) (xy 57.599533 -117.583294) (xy 57.585379 -117.540881)
			(xy 57.564017 -117.501602) (xy 57.536108 -117.46667) (xy 57.502514 -117.437165) (xy 57.464272 -117.413997)
			(xy 57.422564 -117.397883) (xy 57.400698 -117.393212) (xy 57.394094 -117.391942) (xy 57.370218 -117.385846)
			(xy 57.354275 -117.381878) (xy 57.321437 -117.381318) (xy 57.289544 -117.38916) (xy 57.26071 -117.404884)
			(xy 57.236845 -117.427448) (xy 57.219531 -117.455357) (xy 57.209916 -117.48676) (xy 57.208636 -117.519578)
			(xy 57.215776 -117.551636) (xy 57.222898 -117.56644) (xy 57.234658 -117.590152) (xy 57.252244 -117.640072)
			(xy 57.262753 -117.691945) (xy 57.264808 -117.718332) (xy 57.266002 -117.746081) (xy 57.261317 -117.801424)
			(xy 57.248658 -117.855503) (xy 57.228294 -117.907175) (xy 57.200654 -117.95535) (xy 57.166323 -117.999009)
			(xy 57.126025 -118.037231) (xy 57.080613 -118.069207) (xy 57.031045 -118.094262) (xy 56.978368 -118.111867)
			(xy 56.923696 -118.121651) (xy 56.868183 -118.123405) (xy 56.813002 -118.117094) (xy 56.786018 -118.110508)
			(xy 56.763787 -118.105097) (xy 56.718183 -118.101438) (xy 56.67266 -118.105998) (xy 56.628688 -118.118628)
			(xy 56.587685 -118.138923) (xy 56.550975 -118.166225) (xy 56.519742 -118.199656) (xy 56.494994 -118.238135)
			(xy 56.47753 -118.280421) (xy 56.467914 -118.325149) (xy 56.46674 -118.347998) (xy 56.46674 -119.876062)
			(xy 56.46628 -119.903298) (xy 56.458532 -119.957217) (xy 56.44319 -120.009483) (xy 56.420564 -120.059034)
			(xy 56.391117 -120.104861) (xy 56.355447 -120.14603) (xy 56.31428 -120.181702) (xy 56.268456 -120.211153)
			(xy 56.218906 -120.233781) (xy 56.16664 -120.249127) (xy 56.112722 -120.256878) (xy 56.085486 -120.257316)
			(xy 55.96636 -120.257316) (xy 55.95017 -120.257803) (xy 55.918834 -120.265955) (xy 55.890553 -120.281724)
			(xy 55.867147 -120.304098) (xy 55.850119 -120.331639) (xy 55.840563 -120.362576) (xy 55.83936 -120.378728)
			(xy 55.837531 -120.409071) (xy 55.826849 -120.468912) (xy 55.808339 -120.526813) (xy 55.782327 -120.581754)
			(xy 55.74927 -120.632767) (xy 55.709751 -120.678955) (xy 55.664465 -120.719505) (xy 55.614209 -120.753702)
			(xy 55.559868 -120.780945) (xy 55.502399 -120.800755) (xy 55.442813 -120.812782) (xy 55.38216 -120.816814)
			(xy 55.321507 -120.812782) (xy 55.261921 -120.800755) (xy 55.204452 -120.780945) (xy 55.150111 -120.753702)
			(xy 55.099855 -120.719505) (xy 55.054569 -120.678955) (xy 55.01505 -120.632767) (xy 54.981993 -120.581754)
			(xy 54.955981 -120.526813) (xy 54.937471 -120.468912) (xy 54.926789 -120.409071) (xy 54.92496 -120.378728)
			(xy 54.923776 -120.362566) (xy 54.914262 -120.331599) (xy 54.897246 -120.304031) (xy 54.873829 -120.281645)
			(xy 54.845523 -120.265888) (xy 54.814159 -120.257778) (xy 54.79796 -120.257316) (xy 52.453286 -120.257316)
			(xy 52.426053 -120.256852) (xy 52.372141 -120.249099) (xy 52.319882 -120.233751) (xy 52.270339 -120.211123)
			(xy 52.224521 -120.181673) (xy 52.183361 -120.146003) (xy 52.147696 -120.104837) (xy 52.118253 -120.059015)
			(xy 52.095631 -120.009469) (xy 52.08029 -119.957208) (xy 52.072544 -119.903295) (xy 52.072032 -119.876062)
			(xy 52.072032 -118.053866) (xy 52.07153 -118.037552) (xy 52.063251 -118.00599) (xy 52.047244 -117.977558)
			(xy 52.024552 -117.954111) (xy 51.996659 -117.937181) (xy 51.965386 -117.927874) (xy 51.949096 -117.926866)
			(xy 51.90998 -117.923818) (xy 51.879846 -117.919694) (xy 51.820952 -117.904501) (xy 51.764589 -117.881642)
			(xy 51.711751 -117.851519) (xy 51.663367 -117.814664) (xy 51.620292 -117.771724) (xy 51.583283 -117.723458)
			(xy 51.552993 -117.670715) (xy 51.529956 -117.614425) (xy 51.514577 -117.555579) (xy 51.507127 -117.495216)
			(xy 51.507738 -117.434397) (xy 51.516399 -117.374195) (xy 51.532958 -117.31567) (xy 51.557122 -117.259854)
			(xy 51.588465 -117.207731) (xy 51.626437 -117.160218) (xy 51.670366 -117.118153) (xy 51.719481 -117.082277)
			(xy 51.772914 -117.053222) (xy 51.829724 -117.0315) (xy 51.888912 -117.017494) (xy 51.919124 -117.01399)
			(xy 51.95824 -117.009926) (xy 52.07635 -116.910612) (xy 52.087018 -116.873782) (xy 52.095545 -116.846459)
			(xy 52.11965 -116.794547) (xy 52.135024 -116.770404) (xy 52.150241 -116.748213) (xy 52.185918 -116.707935)
			(xy 52.226899 -116.673068) (xy 52.272371 -116.644302) (xy 52.321433 -116.62221) (xy 52.373112 -116.607228)
			(xy 52.426383 -116.599654) (xy 52.453286 -116.599208) (xy 54.557676 -116.599208) (xy 54.56174 -116.595144)
			(xy 56.242204 -116.595144) (xy 56.46674 -116.81968) (xy 56.46674 -117.135402) (xy 56.467954 -117.158251)
			(xy 56.477568 -117.202981) (xy 56.495029 -117.245269) (xy 56.519773 -117.283753) (xy 56.551002 -117.317189)
			(xy 56.587708 -117.3445) (xy 56.628707 -117.364804) (xy 56.672677 -117.377447) (xy 56.7182 -117.38202)
			(xy 56.763806 -117.378377) (xy 56.786018 -117.372892) (xy 56.800361 -117.369234) (xy 56.829477 -117.363897)
			(xy 56.844184 -117.362224) (xy 56.863488 -117.3607) (xy 56.886204 -117.358521) (xy 56.930385 -117.347114)
			(xy 56.97182 -117.328003) (xy 57.009178 -117.301802) (xy 57.041259 -117.269354) (xy 57.067033 -117.2317)
			(xy 57.085671 -117.190051) (xy 57.096575 -117.145743) (xy 57.099395 -117.1002) (xy 57.097168 -117.07749)
			(xy 57.093619 -117.051906) (xy 57.092631 -117.000266) (xy 57.098619 -116.948964) (xy 57.111472 -116.898938)
			(xy 57.130956 -116.851104) (xy 57.156715 -116.806335) (xy 57.188277 -116.76545) (xy 57.206388 -116.747036)
			(xy 57.226722 -116.727702) (xy 57.272029 -116.694607) (xy 57.321695 -116.668505) (xy 57.374649 -116.649959)
			(xy 57.429748 -116.63937) (xy 57.485804 -116.636966) (xy 57.541608 -116.642799) (xy 57.595955 -116.656743)
			(xy 57.647674 -116.678497) (xy 57.695648 -116.707592) (xy 57.738843 -116.7434) (xy 57.776327 -116.785149)
			(xy 57.807292 -116.831939) (xy 57.831069 -116.882759) (xy 57.847145 -116.936514) (xy 57.855175 -116.992044)
			(xy 57.854984 -117.048151) (xy 57.851294 -117.075966) (xy 57.846976 -117.099588) (xy 57.842875 -117.121565)
			(xy 57.841553 -117.166247) (xy 57.848073 -117.210471) (xy 57.862234 -117.252871) (xy 57.883598 -117.292138)
			(xy 57.911506 -117.327058) (xy 57.945096 -117.356554) (xy 57.983331 -117.379714) (xy 58.025029 -117.395824)
			(xy 58.046874 -117.400578) (xy 58.057542 -117.402864) (xy 58.089292 -117.4115) (xy 58.11036 -117.4172)
			(xy 58.153722 -117.422132) (xy 58.197289 -117.419584) (xy 58.23978 -117.409631) (xy 58.279947 -117.392565)
			(xy 58.316607 -117.368889) (xy 58.348685 -117.339298) (xy 58.375236 -117.304662) (xy 58.38571 -117.285516)
			(xy 58.397394 -117.264942) (xy 58.417206 -117.234208) (xy 58.44032 -117.201442) (xy 58.44032 -117.089428)
			(xy 58.912252 -116.617496) (xy 60.170822 -116.617496) (xy 60.254388 -116.585492) (xy 60.27039 -116.572284)
			(xy 60.295073 -116.552663) (xy 60.348805 -116.519669) (xy 60.406557 -116.494361) (xy 60.467236 -116.477219)
			(xy 60.529693 -116.468565) (xy 60.592747 -116.468565) (xy 60.655204 -116.477219) (xy 60.715883 -116.494361)
			(xy 60.773635 -116.519669) (xy 60.827367 -116.552663) (xy 60.85205 -116.572284) (xy 60.868052 -116.585492)
			(xy 60.951618 -116.617496) (xy 61.43879 -116.617496) (xy 61.524896 -116.582952) (xy 61.541152 -116.568982)
			(xy 61.563952 -116.549771) (xy 61.613626 -116.516796) (xy 61.667161 -116.490551) (xy 61.72365 -116.471481)
			(xy 61.782138 -116.459908) (xy 61.841634 -116.456028) (xy 61.90113 -116.459908) (xy 61.959618 -116.471481)
			(xy 62.016107 -116.490551) (xy 62.069642 -116.516796) (xy 62.119316 -116.549771) (xy 62.142116 -116.568982)
			(xy 62.158372 -116.582952) (xy 62.244478 -116.617496) (xy 63.852044 -116.617496) (xy 63.863982 -116.61521)
			(xy 63.893093 -116.60997) (xy 63.95212 -116.606151) (xy 64.011147 -116.60997) (xy 64.040258 -116.61521)
			(xy 64.052196 -116.617496) (xy 69.680836 -116.617496) (xy 69.697743 -116.616963) (xy 69.730367 -116.608072)
			(xy 69.75951 -116.590923) (xy 69.783125 -116.566721) (xy 69.791834 -116.552218) (xy 69.807047 -116.52582)
			(xy 69.843404 -116.476927) (xy 69.885926 -116.43329) (xy 69.933861 -116.39568) (xy 69.986362 -116.364762)
			(xy 70.0425 -116.341082) (xy 70.101284 -116.325059) (xy 70.161674 -116.316976) (xy 70.222602 -116.316976)
			(xy 70.282992 -116.325059) (xy 70.341776 -116.341082) (xy 70.397914 -116.364762) (xy 70.450415 -116.39568)
			(xy 70.49835 -116.43329) (xy 70.540872 -116.476927) (xy 70.577229 -116.52582) (xy 70.592442 -116.552218)
			(xy 70.601123 -116.566737) (xy 70.624748 -116.590932) (xy 70.653901 -116.608069) (xy 70.686532 -116.616944)
			(xy 70.70344 -116.617496) (xy 71.859902 -116.617496) (xy 72.044556 -116.80215) (xy 75.752942 -116.80215)
			(xy 75.752942 -116.742214) (xy 75.760765 -116.682792) (xy 75.776278 -116.624899) (xy 75.799214 -116.569526)
			(xy 75.829181 -116.51762) (xy 75.865668 -116.47007) (xy 75.908048 -116.42769) (xy 75.955598 -116.391203)
			(xy 76.007504 -116.361236) (xy 76.062877 -116.3383) (xy 76.12077 -116.322787) (xy 76.180192 -116.314964)
			(xy 76.240128 -116.314964) (xy 76.29955 -116.322787) (xy 76.357443 -116.3383) (xy 76.412816 -116.361236)
			(xy 76.464722 -116.391203) (xy 76.512272 -116.42769) (xy 76.554652 -116.47007) (xy 76.591139 -116.51762)
			(xy 76.621106 -116.569526) (xy 76.644042 -116.624899) (xy 76.659555 -116.682792) (xy 76.667378 -116.742214)
			(xy 76.667868 -116.772182) (xy 76.667378 -116.80215) (xy 76.659555 -116.861572) (xy 76.644042 -116.919465)
			(xy 76.621106 -116.974838) (xy 76.591139 -117.026744) (xy 76.554652 -117.074294) (xy 76.512272 -117.116674)
			(xy 76.464722 -117.153161) (xy 76.412816 -117.183128) (xy 76.357443 -117.206064) (xy 76.29955 -117.221577)
			(xy 76.240128 -117.2294) (xy 76.180192 -117.2294) (xy 76.12077 -117.221577) (xy 76.062877 -117.206064)
			(xy 76.007504 -117.183128) (xy 75.955598 -117.153161) (xy 75.908048 -117.116674) (xy 75.865668 -117.074294)
			(xy 75.829181 -117.026744) (xy 75.799214 -116.974838) (xy 75.776278 -116.919465) (xy 75.760765 -116.861572)
			(xy 75.752942 -116.80215) (xy 72.044556 -116.80215) (xy 72.10298 -116.860574) (xy 72.10298 -119.591328)
			(xy 72.225154 -119.715788) (xy 72.268842 -119.721376) (xy 72.285213 -119.723641) (xy 72.317518 -119.730632)
			(xy 72.333358 -119.735346) (xy 72.355227 -119.741626) (xy 72.400378 -119.747195) (xy 72.445799 -119.744628)
			(xy 72.490036 -119.734007) (xy 72.531671 -119.715671) (xy 72.569371 -119.690209) (xy 72.601931 -119.658435)
			(xy 72.628305 -119.621367) (xy 72.647652 -119.580192) (xy 72.65935 -119.536228) (xy 72.66178 -119.513604)
			(xy 72.664066 -119.492268) (xy 72.667869 -119.467782) (xy 72.680996 -119.42) (xy 72.700206 -119.374323)
			(xy 72.725177 -119.331522) (xy 72.740012 -119.311674) (xy 72.752749 -119.293048) (xy 72.772126 -119.252303)
			(xy 72.784004 -119.208777) (xy 72.788009 -119.163837) (xy 72.784017 -119.118897) (xy 72.772152 -119.075367)
			(xy 72.752787 -119.034616) (xy 72.740012 -119.016018) (xy 72.723493 -118.993822) (xy 72.696354 -118.945607)
			(xy 72.676464 -118.893977) (xy 72.664239 -118.840016) (xy 72.659936 -118.784855) (xy 72.663645 -118.729651)
			(xy 72.675289 -118.675562) (xy 72.694622 -118.623721) (xy 72.721241 -118.575217) (xy 72.754586 -118.531066)
			(xy 72.793958 -118.492193) (xy 72.838532 -118.459415) (xy 72.887372 -118.433418) (xy 72.939456 -118.414749)
			(xy 72.993689 -118.403797) (xy 73.048936 -118.400793) (xy 73.104038 -118.405801) (xy 73.157838 -118.418714)
			(xy 73.209209 -118.439262) (xy 73.257074 -118.467015) (xy 73.279 -118.483888) (xy 73.296843 -118.496646)
			(xy 73.335962 -118.516485) (xy 73.377903 -118.529319) (xy 73.421424 -118.534769) (xy 73.465235 -118.532673)
			(xy 73.508037 -118.523093) (xy 73.548562 -118.506313) (xy 73.585607 -118.482831) (xy 73.618076 -118.453342)
			(xy 73.645005 -118.418721) (xy 73.655682 -118.39956) (xy 73.668449 -118.375065) (xy 73.699978 -118.329711)
			(xy 73.737718 -118.289378) (xy 73.780879 -118.254908) (xy 73.828559 -118.227021) (xy 73.879762 -118.206302)
			(xy 73.933418 -118.193182) (xy 73.988404 -118.187936) (xy 74.043573 -118.190674) (xy 74.09777 -118.201339)
			(xy 74.149863 -118.219707) (xy 74.198763 -118.245394) (xy 74.243448 -118.277865) (xy 74.282983 -118.316439)
			(xy 74.316544 -118.360311) (xy 74.343427 -118.408564) (xy 74.363072 -118.460189) (xy 74.375067 -118.514107)
			(xy 74.379162 -118.569191) (xy 74.375271 -118.62429) (xy 74.363476 -118.678253) (xy 74.344023 -118.72995)
			(xy 74.317319 -118.778302) (xy 74.283922 -118.822299) (xy 74.244529 -118.861019) (xy 74.199965 -118.893655)
			(xy 74.151161 -118.919524) (xy 74.099137 -118.938085) (xy 74.044979 -118.948951) (xy 73.989821 -118.951893)
			(xy 73.934816 -118.946852) (xy 73.881112 -118.933931) (xy 73.829832 -118.913402) (xy 73.782049 -118.885692)
			(xy 73.760076 -118.868952) (xy 73.742234 -118.856194) (xy 73.703118 -118.836357) (xy 73.661179 -118.823525)
			(xy 73.617661 -118.818077) (xy 73.573853 -118.820176) (xy 73.531054 -118.829759) (xy 73.490534 -118.846542)
			(xy 73.453494 -118.870027) (xy 73.421032 -118.899518) (xy 73.39411 -118.934141) (xy 73.383394 -118.95328)
			(xy 73.374913 -118.96978) (xy 73.355195 -119.001207) (xy 73.344024 -119.016018) (xy 73.331294 -119.034643)
			(xy 73.311931 -119.075385) (xy 73.300066 -119.118905) (xy 73.296074 -119.163837) (xy 73.300079 -119.208768)
			(xy 73.311957 -119.252286) (xy 73.331332 -119.293021) (xy 73.344024 -119.311674) (xy 73.359738 -119.332776)
			(xy 73.385835 -119.378458) (xy 73.40541 -119.427293) (xy 73.418091 -119.478354) (xy 73.423637 -119.530672)
			(xy 73.421944 -119.583257) (xy 73.413044 -119.635111) (xy 73.397106 -119.68525) (xy 73.374431 -119.732725)
			(xy 73.36028 -119.754904) (xy 73.344855 -119.777447) (xy 73.308589 -119.818294) (xy 73.266868 -119.85355)
			(xy 73.220545 -119.882496) (xy 73.170567 -119.904538) (xy 73.117956 -119.919227) (xy 73.063788 -119.926262)
			(xy 73.00917 -119.925499) (xy 72.95522 -119.916954) (xy 72.928988 -119.909336) (xy 72.907117 -119.903052)
			(xy 72.861959 -119.897475) (xy 72.81653 -119.900037) (xy 72.772286 -119.910654) (xy 72.730642 -119.928987)
			(xy 72.692932 -119.954448) (xy 72.660364 -119.986224) (xy 72.633981 -120.023295) (xy 72.614628 -120.064474)
			(xy 72.602924 -120.108444) (xy 72.600566 -120.131078) (xy 72.597671 -120.159808) (xy 72.584324 -120.215985)
			(xy 72.562667 -120.269511) (xy 72.533194 -120.319163) (xy 72.496577 -120.363809) (xy 72.453653 -120.40243)
			(xy 72.405401 -120.434144) (xy 72.352923 -120.458227) (xy 72.297415 -120.474131) (xy 72.268842 -120.478296)
			(xy 72.225154 -120.483884) (xy 72.10298 -120.608344) (xy 72.10298 -121.81586) (xy 72.0979 -121.81586)
			(xy 72.0979 -122.60453) (xy 72.116442 -122.63501) (xy 72.133113 -122.663496) (xy 72.15942 -122.724028)
			(xy 72.177241 -122.787577) (xy 72.186245 -122.852962) (xy 72.1868 -122.885962) (xy 72.1868 -123.45416)
			(xy 72.18807 -123.462796) (xy 72.191952 -123.494447) (xy 72.192344 -123.558214) (xy 72.184345 -123.621479)
			(xy 72.168093 -123.683141) (xy 72.143871 -123.74213) (xy 72.112099 -123.79742) (xy 72.073331 -123.84805)
			(xy 72.051164 -123.870974) (xy 71.879968 -124.04217) (xy 71.868566 -124.054297) (xy 71.851869 -124.083078)
			(xy 71.843178 -124.115197) (xy 71.84263 -124.131832) (xy 71.84263 -124.705872) (xy 71.978266 -124.841508)
			(xy 74.257916 -124.841508) (xy 74.311764 -124.78766) (xy 74.311764 -123.75515) (xy 74.876152 -123.190762)
			(xy 75.836272 -123.190762) (xy 75.845416 -123.20016) (xy 76.902564 -123.20016) (xy 77.1779 -122.924824)
			(xy 77.1779 -121.307606) (xy 77.177463 -121.292448) (xy 77.170306 -121.26299) (xy 77.156394 -121.236055)
			(xy 77.136516 -121.213167) (xy 77.111796 -121.19562) (xy 77.08363 -121.184407) (xy 77.06868 -121.181876)
			(xy 77.040582 -121.177357) (xy 76.98605 -121.161079) (xy 76.934541 -121.136883) (xy 76.887196 -121.105305)
			(xy 76.845067 -121.067045) (xy 76.809088 -121.022953) (xy 76.780057 -120.974005) (xy 76.758617 -120.921289)
			(xy 76.745246 -120.865973) (xy 76.740238 -120.809285) (xy 76.743705 -120.752481) (xy 76.755571 -120.696823)
			(xy 76.775572 -120.643544) (xy 76.803265 -120.593827) (xy 76.820268 -120.571006) (xy 76.833 -120.552381)
			(xy 76.852369 -120.511639) (xy 76.864238 -120.468116) (xy 76.868234 -120.423182) (xy 76.864231 -120.378248)
			(xy 76.852356 -120.334728) (xy 76.832982 -120.293988) (xy 76.820268 -120.27535) (xy 76.800354 -120.248386)
			(xy 76.769302 -120.188987) (xy 76.758546 -120.15724) (xy 76.7507 -120.136062) (xy 76.728623 -120.096667)
			(xy 76.699932 -120.061794) (xy 76.66553 -120.03254) (xy 76.626499 -120.009826) (xy 76.584069 -119.994367)
			(xy 76.539574 -119.986651) (xy 76.516992 -119.986298) (xy 76.489132 -119.985936) (xy 76.433967 -119.97812)
			(xy 76.380527 -119.962363) (xy 76.329946 -119.938999) (xy 76.283302 -119.908527) (xy 76.241587 -119.871594)
			(xy 76.205687 -119.828986) (xy 76.176367 -119.78161) (xy 76.15425 -119.730472) (xy 76.139807 -119.676661)
			(xy 76.133344 -119.621322) (xy 76.135 -119.565631) (xy 76.144739 -119.510773) (xy 76.162354 -119.457916)
			(xy 76.18747 -119.408182) (xy 76.203048 -119.38508) (xy 76.218999 -119.363248) (xy 76.256063 -119.32388)
			(xy 76.298314 -119.290142) (xy 76.344907 -119.262708) (xy 76.394907 -119.242129) (xy 76.447311 -119.228817)
			(xy 76.501071 -119.223039) (xy 76.555108 -119.224911) (xy 76.608339 -119.234395) (xy 76.659697 -119.251302)
			(xy 76.708153 -119.275292) (xy 76.752735 -119.305884) (xy 76.79255 -119.342466) (xy 76.8268 -119.384304)
			(xy 76.854799 -119.430559) (xy 76.875985 -119.480305) (xy 76.889933 -119.532544) (xy 76.893674 -119.559324)
			(xy 76.895883 -119.574187) (xy 76.906348 -119.602347) (xy 76.923115 -119.627273) (xy 76.945253 -119.64758)
			(xy 76.97153 -119.662138) (xy 77.000486 -119.670139) (xy 77.03051 -119.671137) (xy 77.045312 -119.668544)
			(xy 77.06868 -119.66448) (xy 77.083627 -119.661925) (xy 77.111793 -119.650716) (xy 77.136516 -119.633174)
			(xy 77.156399 -119.610292) (xy 77.170319 -119.583362) (xy 77.177487 -119.553907) (xy 77.1779 -119.53875)
			(xy 77.1779 -114.96548) (xy 74.090784 -111.878364) (xy 62.69736 -111.878364) (xy 61.903356 -112.672368)
			(xy 63.796162 -112.672368) (xy 63.800233 -112.616746) (xy 63.812359 -112.562309) (xy 63.832282 -112.510218)
			(xy 63.859578 -112.461583) (xy 63.893664 -112.41744) (xy 63.933813 -112.378731) (xy 63.979171 -112.34628)
			(xy 64.028771 -112.320779) (xy 64.081555 -112.302772) (xy 64.136398 -112.292642) (xy 64.192132 -112.290605)
			(xy 64.247569 -112.296705) (xy 64.301526 -112.310811) (xy 64.352855 -112.332623) (xy 64.400461 -112.361677)
			(xy 64.443329 -112.397352) (xy 64.480546 -112.438889) (xy 64.511319 -112.485402) (xy 64.534991 -112.535899)
			(xy 64.551059 -112.589306) (xy 64.556666 -112.627406) (xy 67.31557 -112.627406) (xy 67.31557 -112.56747)
			(xy 67.323393 -112.508048) (xy 67.338906 -112.450155) (xy 67.361842 -112.394782) (xy 67.391809 -112.342876)
			(xy 67.428296 -112.295326) (xy 67.470676 -112.252946) (xy 67.518226 -112.216459) (xy 67.570132 -112.186492)
			(xy 67.625505 -112.163556) (xy 67.683398 -112.148043) (xy 67.74282 -112.14022) (xy 67.802756 -112.14022)
			(xy 67.862178 -112.148043) (xy 67.920071 -112.163556) (xy 67.975444 -112.186492) (xy 68.02735 -112.216459)
			(xy 68.0749 -112.252946) (xy 68.11728 -112.295326) (xy 68.153767 -112.342876) (xy 68.183734 -112.394782)
			(xy 68.20667 -112.450155) (xy 68.222183 -112.508048) (xy 68.230006 -112.56747) (xy 68.230496 -112.597438)
			(xy 68.230006 -112.627406) (xy 68.222183 -112.686828) (xy 68.20667 -112.744721) (xy 68.183734 -112.800094)
			(xy 68.153767 -112.852) (xy 68.11728 -112.89955) (xy 68.0749 -112.94193) (xy 68.02735 -112.978417)
			(xy 67.975444 -113.008384) (xy 67.920071 -113.03132) (xy 67.862178 -113.046833) (xy 67.802756 -113.054656)
			(xy 67.74282 -113.054656) (xy 67.683398 -113.046833) (xy 67.625505 -113.03132) (xy 67.570132 -113.008384)
			(xy 67.518226 -112.978417) (xy 67.470676 -112.94193) (xy 67.428296 -112.89955) (xy 67.391809 -112.852)
			(xy 67.361842 -112.800094) (xy 67.338906 -112.744721) (xy 67.323393 -112.686828) (xy 67.31557 -112.627406)
			(xy 64.556666 -112.627406) (xy 64.559179 -112.644482) (xy 64.559688 -112.672368) (xy 64.559179 -112.700254)
			(xy 64.551059 -112.75543) (xy 64.534991 -112.808837) (xy 64.511319 -112.859334) (xy 64.480546 -112.905847)
			(xy 64.443329 -112.947384) (xy 64.400461 -112.983059) (xy 64.352855 -113.012113) (xy 64.301526 -113.033925)
			(xy 64.247569 -113.048031) (xy 64.192132 -113.054131) (xy 64.136398 -113.052094) (xy 64.081555 -113.041964)
			(xy 64.028771 -113.023957) (xy 63.979171 -112.998456) (xy 63.933813 -112.966005) (xy 63.893664 -112.927296)
			(xy 63.859578 -112.883153) (xy 63.832282 -112.834518) (xy 63.812359 -112.782427) (xy 63.800233 -112.72799)
			(xy 63.796162 -112.672368) (xy 61.903356 -112.672368) (xy 61.191902 -113.383822) (xy 52.15382 -113.383822)
			(xy 51.410616 -114.127026) (xy 51.399259 -114.139171) (xy 51.382654 -114.167965) (xy 51.374044 -114.200069)
			(xy 51.373532 -114.216688) (xy 51.373532 -114.82324) (xy 50.88636 -115.310158) (xy 50.64125 -115.555268)
			(xy 49.98212 -115.555268) (xy 48.161448 -117.37594) (xy 33.391856 -117.37594) (xy 33.357312 -117.410484)
			(xy 33.233868 -117.410484) (xy 33.017206 -117.627146) (xy 32.445452 -118.1989) (xy 32.414464 -118.229888)
			(xy 32.405918 -118.29948) (xy 49.621676 -118.29948) (xy 49.621676 -118.239544) (xy 49.629499 -118.180122)
			(xy 49.645012 -118.122229) (xy 49.667948 -118.066856) (xy 49.697915 -118.01495) (xy 49.734402 -117.9674)
			(xy 49.776782 -117.92502) (xy 49.824332 -117.888533) (xy 49.876238 -117.858566) (xy 49.931611 -117.83563)
			(xy 49.989504 -117.820117) (xy 50.048926 -117.812294) (xy 50.108862 -117.812294) (xy 50.168284 -117.820117)
			(xy 50.226177 -117.83563) (xy 50.28155 -117.858566) (xy 50.333456 -117.888533) (xy 50.381006 -117.92502)
			(xy 50.423386 -117.9674) (xy 50.459873 -118.01495) (xy 50.48984 -118.066856) (xy 50.512776 -118.122229)
			(xy 50.528289 -118.180122) (xy 50.536112 -118.239544) (xy 50.536602 -118.269512) (xy 50.536112 -118.29948)
			(xy 50.528289 -118.358902) (xy 50.512776 -118.416795) (xy 50.48984 -118.472168) (xy 50.459873 -118.524074)
			(xy 50.423386 -118.571624) (xy 50.381006 -118.614004) (xy 50.333456 -118.650491) (xy 50.28155 -118.680458)
			(xy 50.226177 -118.703394) (xy 50.168284 -118.718907) (xy 50.108862 -118.72673) (xy 50.048926 -118.72673)
			(xy 49.989504 -118.718907) (xy 49.931611 -118.703394) (xy 49.876238 -118.680458) (xy 49.824332 -118.650491)
			(xy 49.776782 -118.614004) (xy 49.734402 -118.571624) (xy 49.697915 -118.524074) (xy 49.667948 -118.472168)
			(xy 49.645012 -118.416795) (xy 49.629499 -118.358902) (xy 49.621676 -118.29948) (xy 32.405918 -118.29948)
			(xy 32.403796 -118.316756) (xy 32.426402 -118.354348) (xy 32.43072 -118.361714) (xy 32.444393 -118.386564)
			(xy 32.465042 -118.439389) (xy 32.477638 -118.494689) (xy 32.481904 -118.551245) (xy 32.477744 -118.60781)
			(xy 32.46525 -118.663133) (xy 32.444698 -118.715996) (xy 32.416543 -118.765231) (xy 32.381404 -118.809751)
			(xy 32.361124 -118.829582) (xy 32.345334 -118.845069) (xy 32.318831 -118.880472) (xy 32.298862 -118.919931)
			(xy 32.28603 -118.962253) (xy 32.280725 -119.006158) (xy 32.281188 -119.014744) (xy 33.908982 -119.014744)
			(xy 33.908982 -118.954808) (xy 33.916805 -118.895386) (xy 33.932318 -118.837493) (xy 33.955254 -118.78212)
			(xy 33.985221 -118.730214) (xy 34.021708 -118.682664) (xy 34.064088 -118.640284) (xy 34.111638 -118.603797)
			(xy 34.163544 -118.57383) (xy 34.218917 -118.550894) (xy 34.27681 -118.535381) (xy 34.336232 -118.527558)
			(xy 34.396168 -118.527558) (xy 34.45559 -118.535381) (xy 34.513483 -118.550894) (xy 34.568856 -118.57383)
			(xy 34.620762 -118.603797) (xy 34.668312 -118.640284) (xy 34.710692 -118.682664) (xy 34.747179 -118.730214)
			(xy 34.777146 -118.78212) (xy 34.793754 -118.822216) (xy 43.208446 -118.822216) (xy 43.212517 -118.766594)
			(xy 43.224643 -118.712157) (xy 43.244566 -118.660066) (xy 43.271862 -118.611431) (xy 43.305948 -118.567288)
			(xy 43.346097 -118.528579) (xy 43.391455 -118.496128) (xy 43.441055 -118.470627) (xy 43.493839 -118.45262)
			(xy 43.548682 -118.44249) (xy 43.604416 -118.440453) (xy 43.659853 -118.446553) (xy 43.71381 -118.460659)
			(xy 43.765139 -118.482471) (xy 43.812745 -118.511525) (xy 43.855613 -118.5472) (xy 43.89283 -118.588737)
			(xy 43.923603 -118.63525) (xy 43.947275 -118.685747) (xy 43.963343 -118.739154) (xy 43.971463 -118.79433)
			(xy 43.971972 -118.822216) (xy 43.971463 -118.850102) (xy 43.963343 -118.905278) (xy 43.947275 -118.958685)
			(xy 43.923603 -119.009182) (xy 43.89283 -119.055695) (xy 43.855613 -119.097232) (xy 43.812745 -119.132907)
			(xy 43.765139 -119.161961) (xy 43.71381 -119.183773) (xy 43.659853 -119.197879) (xy 43.604416 -119.203979)
			(xy 43.548682 -119.201942) (xy 43.493839 -119.191812) (xy 43.441055 -119.173805) (xy 43.391455 -119.148304)
			(xy 43.346097 -119.115853) (xy 43.305948 -119.077144) (xy 43.271862 -119.033001) (xy 43.244566 -118.984366)
			(xy 43.224643 -118.932275) (xy 43.212517 -118.877838) (xy 43.208446 -118.822216) (xy 34.793754 -118.822216)
			(xy 34.800082 -118.837493) (xy 34.815595 -118.895386) (xy 34.823418 -118.954808) (xy 34.823908 -118.984776)
			(xy 34.823418 -119.014744) (xy 34.815595 -119.074166) (xy 34.800082 -119.132059) (xy 34.777146 -119.187432)
			(xy 34.747179 -119.239338) (xy 34.745271 -119.241824) (xy 38.008812 -119.241824) (xy 38.012883 -119.186202)
			(xy 38.025009 -119.131765) (xy 38.044932 -119.079674) (xy 38.072228 -119.031039) (xy 38.106314 -118.986896)
			(xy 38.146463 -118.948187) (xy 38.191821 -118.915736) (xy 38.241421 -118.890235) (xy 38.294205 -118.872228)
			(xy 38.349048 -118.862098) (xy 38.404782 -118.860061) (xy 38.460219 -118.866161) (xy 38.514176 -118.880267)
			(xy 38.565505 -118.902079) (xy 38.613111 -118.931133) (xy 38.655979 -118.966808) (xy 38.693196 -119.008345)
			(xy 38.723969 -119.054858) (xy 38.747641 -119.105355) (xy 38.763709 -119.158762) (xy 38.771829 -119.213938)
			(xy 38.772338 -119.241824) (xy 38.771829 -119.26971) (xy 38.763709 -119.324886) (xy 38.750719 -119.368062)
			(xy 49.861468 -119.368062) (xy 49.865539 -119.31244) (xy 49.877665 -119.258003) (xy 49.897588 -119.205912)
			(xy 49.924884 -119.157277) (xy 49.95897 -119.113134) (xy 49.999119 -119.074425) (xy 50.044477 -119.041974)
			(xy 50.094077 -119.016473) (xy 50.146861 -118.998466) (xy 50.201704 -118.988336) (xy 50.257438 -118.986299)
			(xy 50.312875 -118.992399) (xy 50.366832 -119.006505) (xy 50.418161 -119.028317) (xy 50.465767 -119.057371)
			(xy 50.508635 -119.093046) (xy 50.545852 -119.134583) (xy 50.576625 -119.181096) (xy 50.600297 -119.231593)
			(xy 50.616365 -119.285) (xy 50.624485 -119.340176) (xy 50.624994 -119.368062) (xy 50.624485 -119.395948)
			(xy 50.616365 -119.451124) (xy 50.600297 -119.504531) (xy 50.576625 -119.555028) (xy 50.545852 -119.601541)
			(xy 50.508635 -119.643078) (xy 50.465767 -119.678753) (xy 50.418161 -119.707807) (xy 50.366832 -119.729619)
			(xy 50.312875 -119.743725) (xy 50.257438 -119.749825) (xy 50.201704 -119.747788) (xy 50.146861 -119.737658)
			(xy 50.094077 -119.719651) (xy 50.044477 -119.69415) (xy 49.999119 -119.661699) (xy 49.95897 -119.62299)
			(xy 49.924884 -119.578847) (xy 49.897588 -119.530212) (xy 49.877665 -119.478121) (xy 49.865539 -119.423684)
			(xy 49.861468 -119.368062) (xy 38.750719 -119.368062) (xy 38.747641 -119.378293) (xy 38.723969 -119.42879)
			(xy 38.693196 -119.475303) (xy 38.655979 -119.51684) (xy 38.613111 -119.552515) (xy 38.565505 -119.581569)
			(xy 38.514176 -119.603381) (xy 38.460219 -119.617487) (xy 38.404782 -119.623587) (xy 38.349048 -119.62155)
			(xy 38.294205 -119.61142) (xy 38.241421 -119.593413) (xy 38.191821 -119.567912) (xy 38.146463 -119.535461)
			(xy 38.106314 -119.496752) (xy 38.072228 -119.452609) (xy 38.044932 -119.403974) (xy 38.025009 -119.351883)
			(xy 38.012883 -119.297446) (xy 38.008812 -119.241824) (xy 34.745271 -119.241824) (xy 34.710692 -119.286888)
			(xy 34.668312 -119.329268) (xy 34.620762 -119.365755) (xy 34.568856 -119.395722) (xy 34.513483 -119.418658)
			(xy 34.45559 -119.434171) (xy 34.396168 -119.441994) (xy 34.336232 -119.441994) (xy 34.27681 -119.434171)
			(xy 34.218917 -119.418658) (xy 34.163544 -119.395722) (xy 34.111638 -119.365755) (xy 34.064088 -119.329268)
			(xy 34.021708 -119.286888) (xy 33.985221 -119.239338) (xy 33.955254 -119.187432) (xy 33.932318 -119.132059)
			(xy 33.916805 -119.074166) (xy 33.908982 -119.014744) (xy 32.281188 -119.014744) (xy 32.283106 -119.050319)
			(xy 32.293101 -119.093399) (xy 32.310407 -119.134096) (xy 32.334503 -119.17118) (xy 32.349186 -119.187722)
			(xy 32.367808 -119.208449) (xy 32.39946 -119.254304) (xy 32.424105 -119.304275) (xy 32.441218 -119.357301)
			(xy 32.450436 -119.412251) (xy 32.451561 -119.467958) (xy 32.444571 -119.523236) (xy 32.429613 -119.576909)
			(xy 32.407007 -119.627835) (xy 32.377233 -119.674931) (xy 32.340924 -119.717195) (xy 32.32023 -119.735854)
			(xy 32.29979 -119.753014) (xy 32.255013 -119.782051) (xy 32.206627 -119.804566) (xy 32.155576 -119.82012)
			(xy 32.102856 -119.828411) (xy 32.049494 -119.829275) (xy 31.996533 -119.822697) (xy 31.945005 -119.808804)
			(xy 31.895915 -119.787868) (xy 31.850221 -119.760297) (xy 31.808813 -119.726629) (xy 31.7725 -119.68752)
			(xy 31.741989 -119.643733) (xy 31.717877 -119.596123) (xy 31.708852 -119.571008) (xy 31.700497 -119.549322)
			(xy 31.677075 -119.509189) (xy 31.646746 -119.473984) (xy 31.610521 -119.44488) (xy 31.569609 -119.422848)
			(xy 31.525373 -119.408621) (xy 31.479287 -119.402675) (xy 31.432888 -119.405208) (xy 31.387724 -119.416134)
			(xy 31.345298 -119.435091) (xy 31.307027 -119.461445) (xy 31.29026 -119.477536) (xy 31.161228 -119.606568)
			(xy 31.148274 -119.68734) (xy 31.166562 -119.72417) (xy 31.178536 -119.749172) (xy 31.19594 -119.801803)
			(xy 31.205542 -119.856399) (xy 31.207142 -119.91181) (xy 31.203126 -119.946162) (xy 36.687742 -119.946162)
			(xy 36.687742 -119.886226) (xy 36.695565 -119.826804) (xy 36.711078 -119.768911) (xy 36.734014 -119.713538)
			(xy 36.763981 -119.661632) (xy 36.800468 -119.614082) (xy 36.842848 -119.571702) (xy 36.890398 -119.535215)
			(xy 36.942304 -119.505248) (xy 36.997677 -119.482312) (xy 37.05557 -119.466799) (xy 37.114992 -119.458976)
			(xy 37.174928 -119.458976) (xy 37.23435 -119.466799) (xy 37.292243 -119.482312) (xy 37.347616 -119.505248)
			(xy 37.399522 -119.535215) (xy 37.447072 -119.571702) (xy 37.489452 -119.614082) (xy 37.525939 -119.661632)
			(xy 37.555906 -119.713538) (xy 37.578842 -119.768911) (xy 37.594355 -119.826804) (xy 37.602178 -119.886226)
			(xy 37.602668 -119.916194) (xy 37.602178 -119.946162) (xy 37.594355 -120.005584) (xy 37.578842 -120.063477)
			(xy 37.555906 -120.11885) (xy 37.525939 -120.170756) (xy 37.489452 -120.218306) (xy 37.447072 -120.260686)
			(xy 37.399522 -120.297173) (xy 37.347616 -120.32714) (xy 37.292243 -120.350076) (xy 37.23435 -120.365589)
			(xy 37.174928 -120.373412) (xy 37.114992 -120.373412) (xy 37.05557 -120.365589) (xy 36.997677 -120.350076)
			(xy 36.942304 -120.32714) (xy 36.890398 -120.297173) (xy 36.842848 -120.260686) (xy 36.800468 -120.218306)
			(xy 36.763981 -120.170756) (xy 36.734014 -120.11885) (xy 36.711078 -120.063477) (xy 36.695565 -120.005584)
			(xy 36.687742 -119.946162) (xy 31.203126 -119.946162) (xy 31.200705 -119.966869) (xy 31.186368 -120.020417)
			(xy 31.164431 -120.071326) (xy 31.135357 -120.118524) (xy 31.099759 -120.161017) (xy 31.058385 -120.197911)
			(xy 31.012107 -120.228428) (xy 30.9619 -120.251926) (xy 30.908821 -120.26791) (xy 30.853987 -120.276044)
			(xy 30.798553 -120.276156) (xy 30.743686 -120.268244) (xy 30.690543 -120.252474) (xy 30.665166 -120.241314)
			(xy 30.653482 -120.23598) (xy 30.624018 -120.229122) (xy 30.608149 -120.225875) (xy 30.575776 -120.226599)
			(xy 30.544621 -120.235428) (xy 30.516682 -120.251798) (xy 30.504892 -120.262904) (xy 29.23794 -121.529856)
			(xy 29.222449 -121.546016) (xy 29.196832 -121.582723) (xy 29.17804 -121.623349) (xy 29.166654 -121.666639)
			(xy 29.163026 -121.711253) (xy 29.167268 -121.755814) (xy 29.17925 -121.798942) (xy 29.198599 -121.839306)
			(xy 29.224719 -121.875656) (xy 29.24048 -121.891552) (xy 29.248354 -121.899426) (xy 29.267524 -121.919937)
			(xy 29.300248 -121.965553) (xy 29.325934 -122.015472) (xy 29.344028 -122.068616) (xy 29.35414 -122.123838)
			(xy 29.354672 -122.139456) (xy 31.64027 -122.139456) (xy 31.644341 -122.083834) (xy 31.656467 -122.029397)
			(xy 31.67639 -121.977306) (xy 31.703686 -121.928671) (xy 31.737772 -121.884528) (xy 31.777921 -121.845819)
			(xy 31.823279 -121.813368) (xy 31.872879 -121.787867) (xy 31.925663 -121.76986) (xy 31.980506 -121.75973)
			(xy 32.03624 -121.757693) (xy 32.091677 -121.763793) (xy 32.145634 -121.777899) (xy 32.196963 -121.799711)
			(xy 32.244569 -121.828765) (xy 32.287437 -121.86444) (xy 32.324654 -121.905977) (xy 32.355427 -121.95249)
			(xy 32.379099 -122.002987) (xy 32.395167 -122.056394) (xy 32.403287 -122.11157) (xy 32.403796 -122.139456)
			(xy 32.403287 -122.167342) (xy 32.395167 -122.222518) (xy 32.379099 -122.275925) (xy 32.355427 -122.326422)
			(xy 32.324654 -122.372935) (xy 32.287437 -122.414472) (xy 32.244569 -122.450147) (xy 32.196963 -122.479201)
			(xy 32.145634 -122.501013) (xy 32.091677 -122.515119) (xy 32.03624 -122.521219) (xy 31.980506 -122.519182)
			(xy 31.925663 -122.509052) (xy 31.872879 -122.491045) (xy 31.823279 -122.465544) (xy 31.777921 -122.433093)
			(xy 31.737772 -122.394384) (xy 31.703686 -122.350241) (xy 31.67639 -122.301606) (xy 31.656467 -122.249515)
			(xy 31.644341 -122.195078) (xy 31.64027 -122.139456) (xy 29.354672 -122.139456) (xy 29.35605 -122.179946)
			(xy 29.349718 -122.235728) (xy 29.335281 -122.289979) (xy 29.31305 -122.34153) (xy 29.283505 -122.389267)
			(xy 29.247285 -122.432159) (xy 29.205169 -122.469281) (xy 29.158069 -122.499831) (xy 29.107001 -122.523149)
			(xy 29.053067 -122.538733) (xy 28.997432 -122.546245) (xy 28.941297 -122.545524) (xy 28.885873 -122.536584)
			(xy 28.832358 -122.51962) (xy 28.781905 -122.494998) (xy 28.735606 -122.463248) (xy 28.7147 -122.44451)
			(xy 28.70073 -122.430794) (xy 28.684783 -122.415129) (xy 28.64845 -122.389095) (xy 28.608127 -122.369811)
			(xy 28.565053 -122.357871) (xy 28.520556 -122.353643) (xy 28.476005 -122.357257) (xy 28.432771 -122.368602)
			(xy 28.392186 -122.387328) (xy 28.355497 -122.412859) (xy 28.339288 -122.428254) (xy 28.24226 -122.525282)
			(xy 28.24226 -125.083316) (xy 28.242805 -125.099965) (xy 28.251425 -125.132128) (xy 28.268073 -125.160965)
			(xy 28.291616 -125.184512) (xy 28.32045 -125.201166) (xy 28.352611 -125.209792) (xy 28.36926 -125.210316)
			(xy 31.984188 -125.210316)
		)
		(stroke
			(width 0)
			(type solid)
		)
		(fill yes)
		(layer "B.Cu")
		(net "P1V8_NODE1")
	)
	(gr_poly
		(pts
			(xy 123.65355 -30.03931) (xy 123.678236 -30.03648) (xy 123.727924 -30.03648) (xy 123.75261 -30.03931)
			(xy 123.760992 -30.040326) (xy 131.758182 -30.040326) (xy 132.314188 -29.48432) (xy 132.329838 -29.467973)
			(xy 132.355662 -29.430815) (xy 132.374494 -29.38967) (xy 132.385738 -29.345839) (xy 132.389037 -29.30071)
			(xy 132.384288 -29.255709) (xy 132.371641 -29.212263) (xy 132.351495 -29.171744) (xy 132.32449 -29.135437)
			(xy 132.308346 -29.119576) (xy 132.285821 -29.098428) (xy 132.246093 -29.051111) (xy 132.213089 -28.99888)
			(xy 132.187409 -28.942686) (xy 132.169519 -28.883548) (xy 132.159746 -28.822541) (xy 132.158265 -28.760775)
			(xy 132.165105 -28.69937) (xy 132.180141 -28.639443) (xy 132.203099 -28.582083) (xy 132.233563 -28.528331)
			(xy 132.270979 -28.479165) (xy 132.314667 -28.435477) (xy 132.363834 -28.398061) (xy 132.417586 -28.367598)
			(xy 132.474946 -28.34464) (xy 132.534873 -28.329604) (xy 132.596278 -28.322765) (xy 132.658045 -28.324246)
			(xy 132.719051 -28.33402) (xy 132.778188 -28.35191) (xy 132.834383 -28.37759) (xy 132.886613 -28.410595)
			(xy 132.93393 -28.450324) (xy 132.95503 -28.472892) (xy 132.970872 -28.489048) (xy 133.007188 -28.516033)
			(xy 133.047708 -28.53616) (xy 133.091152 -28.548793) (xy 133.136147 -28.553533) (xy 133.18127 -28.550229)
			(xy 133.225095 -28.538986) (xy 133.266236 -28.520159) (xy 133.303393 -28.494345) (xy 133.319774 -28.478734)
			(xy 133.585712 -28.212796) (xy 133.585712 -27.944826) (xy 133.559804 -27.892248) (xy 133.536436 -27.87396)
			(xy 133.536182 -27.873706) (xy 133.512863 -27.855065) (xy 133.470785 -27.812715) (xy 133.434572 -27.765252)
			(xy 133.404839 -27.713483) (xy 133.382091 -27.658287) (xy 133.366713 -27.600602) (xy 133.358968 -27.541406)
			(xy 133.358987 -27.481706) (xy 133.366769 -27.422516) (xy 133.382183 -27.36484) (xy 133.404966 -27.309658)
			(xy 133.434732 -27.257908) (xy 133.470975 -27.210468) (xy 133.513079 -27.168144) (xy 133.536436 -27.149552)
			(xy 133.54766 -27.140343) (xy 133.56598 -27.117828) (xy 133.578743 -27.091759) (xy 133.58529 -27.063481)
			(xy 133.585712 -27.048968) (xy 133.585712 -26.117804) (xy 133.83006 -25.873456) (xy 133.83006 -24.007826)
			(xy 137.790682 -20.047458) (xy 137.802138 -20.035323) (xy 137.818841 -20.006443) (xy 137.827493 -19.974223)
			(xy 137.82802 -19.957542) (xy 137.82802 -19.897852) (xy 137.88771 -19.897852) (xy 137.904392 -19.897351)
			(xy 137.936612 -19.888689) (xy 137.96548 -19.871962) (xy 137.977626 -19.860514) (xy 143.280892 -14.556994)
			(xy 143.280892 -6.659626) (xy 144.595596 -5.345176) (xy 144.606952 -5.33303) (xy 144.623557 -5.304237)
			(xy 144.632165 -5.272133) (xy 144.63268 -5.255514) (xy 144.63268 -2.064004) (xy 144.56156 -1.992884)
			(xy 112.58042 -1.992884) (xy 112.563763 -1.993376) (xy 112.531582 -2.001994) (xy 112.502729 -2.018647)
			(xy 112.479169 -2.0422) (xy 112.462507 -2.071049) (xy 112.453881 -2.103227) (xy 112.45342 -2.119884)
			(xy 112.45342 -8.7701) (xy 117.198913 -8.7701) (xy 117.202867 -8.571278) (xy 117.214722 -8.37277)
			(xy 117.23446 -8.174891) (xy 117.262049 -7.977953) (xy 117.297446 -7.782267) (xy 117.340595 -7.588143)
			(xy 117.391427 -7.395889) (xy 117.449863 -7.205807) (xy 117.515809 -7.018198) (xy 117.589162 -6.83336)
			(xy 117.669805 -6.651584) (xy 117.757612 -6.473158) (xy 117.852442 -6.298364) (xy 117.954147 -6.127478)
			(xy 118.062565 -5.960771) (xy 118.177526 -5.798506) (xy 118.298846 -5.64094) (xy 118.426335 -5.488321)
			(xy 118.559791 -5.340892) (xy 118.699002 -5.198885) (xy 118.843749 -5.062524) (xy 118.993803 -4.932027)
			(xy 119.148926 -4.807598) (xy 119.308874 -4.689434) (xy 119.473393 -4.577723) (xy 119.642223 -4.472641)
			(xy 119.815097 -4.374354) (xy 119.991742 -4.283018) (xy 120.171879 -4.198777) (xy 120.355222 -4.121764)
			(xy 120.541482 -4.052101) (xy 120.730365 -3.989898) (xy 120.921571 -3.935253) (xy 121.114799 -3.888254)
			(xy 121.309742 -3.848974) (xy 121.506093 -3.817475) (xy 121.703541 -3.793807) (xy 121.901773 -3.778008)
			(xy 122.100477 -3.770102) (xy 122.199908 -3.769614) (xy 122.199908 -3.76936) (xy 122.299344 -3.76983)
			(xy 122.498058 -3.777737) (xy 122.696301 -3.793538) (xy 122.893759 -3.817207) (xy 123.09012 -3.848709)
			(xy 123.285074 -3.887991) (xy 123.478311 -3.934994) (xy 123.669527 -3.989642) (xy 123.85842 -4.051848)
			(xy 124.044689 -4.121515) (xy 124.228042 -4.198533) (xy 124.408188 -4.282779) (xy 124.584842 -4.37412)
			(xy 124.757726 -4.472413) (xy 124.926564 -4.577501) (xy 125.091091 -4.689218) (xy 125.251047 -4.807388)
			(xy 125.406178 -4.931824) (xy 125.55624 -5.062329) (xy 125.700994 -5.198696) (xy 125.840213 -5.340711)
			(xy 125.973675 -5.488148) (xy 126.10117 -5.640775) (xy 126.222497 -5.79835) (xy 126.337463 -5.960623)
			(xy 126.445887 -6.127339) (xy 126.547597 -6.298234) (xy 126.642432 -6.473038) (xy 126.730243 -6.651473)
			(xy 126.81089 -6.833259) (xy 126.884247 -7.018107) (xy 126.950197 -7.205725) (xy 126.984086 -7.315962)
			(xy 129.787911 -7.315962) (xy 129.791914 -7.2281) (xy 129.80389 -7.140966) (xy 129.823741 -7.055282)
			(xy 129.8513 -6.971758) (xy 129.886341 -6.891086) (xy 129.928572 -6.813935) (xy 129.977644 -6.740944)
			(xy 130.033151 -6.672718) (xy 130.094631 -6.609822) (xy 130.161576 -6.552777) (xy 130.233431 -6.502056)
			(xy 130.309601 -6.458079) (xy 130.389454 -6.421211) (xy 130.472329 -6.391758) (xy 130.557539 -6.369962)
			(xy 130.644378 -6.356006) (xy 130.732126 -6.350003) (xy 130.820056 -6.352005) (xy 130.907441 -6.361995)
			(xy 130.993554 -6.37989) (xy 131.077684 -6.405541) (xy 131.159132 -6.438736) (xy 131.237225 -6.4792)
			(xy 131.311314 -6.526598) (xy 131.380786 -6.580537) (xy 131.445065 -6.64057) (xy 131.503619 -6.706199)
			(xy 131.555963 -6.776881) (xy 131.601662 -6.85203) (xy 131.640338 -6.931023) (xy 131.67167 -7.013206)
			(xy 131.6954 -7.097898) (xy 131.71133 -7.184397) (xy 131.719328 -7.271985) (xy 131.719828 -7.315962)
			(xy 132.327911 -7.315962) (xy 132.331914 -7.2281) (xy 132.34389 -7.140966) (xy 132.363741 -7.055282)
			(xy 132.3913 -6.971758) (xy 132.426341 -6.891086) (xy 132.468572 -6.813935) (xy 132.517644 -6.740944)
			(xy 132.573151 -6.672718) (xy 132.634631 -6.609822) (xy 132.701576 -6.552777) (xy 132.773431 -6.502056)
			(xy 132.849601 -6.458079) (xy 132.929454 -6.421211) (xy 133.012329 -6.391758) (xy 133.097539 -6.369962)
			(xy 133.184378 -6.356006) (xy 133.272126 -6.350003) (xy 133.360056 -6.352005) (xy 133.447441 -6.361995)
			(xy 133.533554 -6.37989) (xy 133.617684 -6.405541) (xy 133.699132 -6.438736) (xy 133.777225 -6.4792)
			(xy 133.851314 -6.526598) (xy 133.920786 -6.580537) (xy 133.985065 -6.64057) (xy 134.043619 -6.706199)
			(xy 134.095963 -6.776881) (xy 134.141662 -6.85203) (xy 134.180338 -6.931023) (xy 134.21167 -7.013206)
			(xy 134.2354 -7.097898) (xy 134.25133 -7.184397) (xy 134.259328 -7.271985) (xy 134.259828 -7.315962)
			(xy 134.867911 -7.315962) (xy 134.871914 -7.2281) (xy 134.88389 -7.140966) (xy 134.903741 -7.055282)
			(xy 134.9313 -6.971758) (xy 134.966341 -6.891086) (xy 135.008572 -6.813935) (xy 135.057644 -6.740944)
			(xy 135.113151 -6.672718) (xy 135.174631 -6.609822) (xy 135.241576 -6.552777) (xy 135.313431 -6.502056)
			(xy 135.389601 -6.458079) (xy 135.469454 -6.421211) (xy 135.552329 -6.391758) (xy 135.637539 -6.369962)
			(xy 135.724378 -6.356006) (xy 135.812126 -6.350003) (xy 135.900056 -6.352005) (xy 135.987441 -6.361995)
			(xy 136.073554 -6.37989) (xy 136.157684 -6.405541) (xy 136.239132 -6.438736) (xy 136.317225 -6.4792)
			(xy 136.391314 -6.526598) (xy 136.460786 -6.580537) (xy 136.525065 -6.64057) (xy 136.583619 -6.706199)
			(xy 136.635963 -6.776881) (xy 136.681662 -6.85203) (xy 136.720338 -6.931023) (xy 136.75167 -7.013206)
			(xy 136.7754 -7.097898) (xy 136.79133 -7.184397) (xy 136.799328 -7.271985) (xy 136.799828 -7.315962)
			(xy 139.947911 -7.315962) (xy 139.951914 -7.2281) (xy 139.96389 -7.140966) (xy 139.983741 -7.055282)
			(xy 140.0113 -6.971758) (xy 140.046341 -6.891086) (xy 140.088572 -6.813935) (xy 140.137644 -6.740944)
			(xy 140.193151 -6.672718) (xy 140.254631 -6.609822) (xy 140.321576 -6.552777) (xy 140.393431 -6.502056)
			(xy 140.469601 -6.458079) (xy 140.549454 -6.421211) (xy 140.632329 -6.391758) (xy 140.717539 -6.369962)
			(xy 140.804378 -6.356006) (xy 140.892126 -6.350003) (xy 140.980056 -6.352005) (xy 141.067441 -6.361995)
			(xy 141.153554 -6.37989) (xy 141.237684 -6.405541) (xy 141.319132 -6.438736) (xy 141.397225 -6.4792)
			(xy 141.471314 -6.526598) (xy 141.540786 -6.580537) (xy 141.605065 -6.64057) (xy 141.663619 -6.706199)
			(xy 141.715963 -6.776881) (xy 141.761662 -6.85203) (xy 141.800338 -6.931023) (xy 141.83167 -7.013206)
			(xy 141.8554 -7.097898) (xy 141.87133 -7.184397) (xy 141.879328 -7.271985) (xy 141.879828 -7.315962)
			(xy 141.879328 -7.359939) (xy 141.87133 -7.447527) (xy 141.8554 -7.534026) (xy 141.83167 -7.618718)
			(xy 141.800338 -7.700901) (xy 141.761662 -7.779894) (xy 141.715963 -7.855043) (xy 141.663619 -7.925725)
			(xy 141.605065 -7.991354) (xy 141.540786 -8.051387) (xy 141.471314 -8.105326) (xy 141.397225 -8.152724)
			(xy 141.319132 -8.193188) (xy 141.237684 -8.226383) (xy 141.153554 -8.252034) (xy 141.067441 -8.269929)
			(xy 140.980056 -8.279919) (xy 140.892126 -8.281921) (xy 140.804378 -8.275918) (xy 140.717539 -8.261962)
			(xy 140.632329 -8.240166) (xy 140.549454 -8.210713) (xy 140.469601 -8.173845) (xy 140.393431 -8.129868)
			(xy 140.321576 -8.079147) (xy 140.254631 -8.022102) (xy 140.193151 -7.959206) (xy 140.137644 -7.89098)
			(xy 140.088572 -7.817989) (xy 140.046341 -7.740838) (xy 140.0113 -7.660166) (xy 139.983741 -7.576642)
			(xy 139.96389 -7.490958) (xy 139.951914 -7.403824) (xy 139.947911 -7.315962) (xy 136.799828 -7.315962)
			(xy 136.799328 -7.359939) (xy 136.79133 -7.447527) (xy 136.7754 -7.534026) (xy 136.75167 -7.618718)
			(xy 136.720338 -7.700901) (xy 136.681662 -7.779894) (xy 136.635963 -7.855043) (xy 136.583619 -7.925725)
			(xy 136.525065 -7.991354) (xy 136.460786 -8.051387) (xy 136.391314 -8.105326) (xy 136.317225 -8.152724)
			(xy 136.239132 -8.193188) (xy 136.157684 -8.226383) (xy 136.073554 -8.252034) (xy 135.987441 -8.269929)
			(xy 135.900056 -8.279919) (xy 135.812126 -8.281921) (xy 135.724378 -8.275918) (xy 135.637539 -8.261962)
			(xy 135.552329 -8.240166) (xy 135.469454 -8.210713) (xy 135.389601 -8.173845) (xy 135.313431 -8.129868)
			(xy 135.241576 -8.079147) (xy 135.174631 -8.022102) (xy 135.113151 -7.959206) (xy 135.057644 -7.89098)
			(xy 135.008572 -7.817989) (xy 134.966341 -7.740838) (xy 134.9313 -7.660166) (xy 134.903741 -7.576642)
			(xy 134.88389 -7.490958) (xy 134.871914 -7.403824) (xy 134.867911 -7.315962) (xy 134.259828 -7.315962)
			(xy 134.259328 -7.359939) (xy 134.25133 -7.447527) (xy 134.2354 -7.534026) (xy 134.21167 -7.618718)
			(xy 134.180338 -7.700901) (xy 134.141662 -7.779894) (xy 134.095963 -7.855043) (xy 134.043619 -7.925725)
			(xy 133.985065 -7.991354) (xy 133.920786 -8.051387) (xy 133.851314 -8.105326) (xy 133.777225 -8.152724)
			(xy 133.699132 -8.193188) (xy 133.617684 -8.226383) (xy 133.533554 -8.252034) (xy 133.447441 -8.269929)
			(xy 133.360056 -8.279919) (xy 133.272126 -8.281921) (xy 133.184378 -8.275918) (xy 133.097539 -8.261962)
			(xy 133.012329 -8.240166) (xy 132.929454 -8.210713) (xy 132.849601 -8.173845) (xy 132.773431 -8.129868)
			(xy 132.701576 -8.079147) (xy 132.634631 -8.022102) (xy 132.573151 -7.959206) (xy 132.517644 -7.89098)
			(xy 132.468572 -7.817989) (xy 132.426341 -7.740838) (xy 132.3913 -7.660166) (xy 132.363741 -7.576642)
			(xy 132.34389 -7.490958) (xy 132.331914 -7.403824) (xy 132.327911 -7.315962) (xy 131.719828 -7.315962)
			(xy 131.719328 -7.359939) (xy 131.71133 -7.447527) (xy 131.6954 -7.534026) (xy 131.67167 -7.618718)
			(xy 131.640338 -7.700901) (xy 131.601662 -7.779894) (xy 131.555963 -7.855043) (xy 131.503619 -7.925725)
			(xy 131.445065 -7.991354) (xy 131.380786 -8.051387) (xy 131.311314 -8.105326) (xy 131.237225 -8.152724)
			(xy 131.159132 -8.193188) (xy 131.077684 -8.226383) (xy 130.993554 -8.252034) (xy 130.907441 -8.269929)
			(xy 130.820056 -8.279919) (xy 130.732126 -8.281921) (xy 130.644378 -8.275918) (xy 130.557539 -8.261962)
			(xy 130.472329 -8.240166) (xy 130.389454 -8.210713) (xy 130.309601 -8.173845) (xy 130.233431 -8.129868)
			(xy 130.161576 -8.079147) (xy 130.094631 -8.022102) (xy 130.033151 -7.959206) (xy 129.977644 -7.89098)
			(xy 129.928572 -7.817989) (xy 129.886341 -7.740838) (xy 129.8513 -7.660166) (xy 129.823741 -7.576642)
			(xy 129.80389 -7.490958) (xy 129.791914 -7.403824) (xy 129.787911 -7.315962) (xy 126.984086 -7.315962)
			(xy 127.008635 -7.395817) (xy 127.05947 -7.588082) (xy 127.102621 -7.782215) (xy 127.138019 -7.977911)
			(xy 127.16561 -8.17486) (xy 127.185349 -8.37275) (xy 127.197204 -8.571268) (xy 127.201159 -8.7701)
			(xy 127.197204 -8.968932) (xy 127.185349 -9.16745) (xy 127.16561 -9.36534) (xy 127.138019 -9.562289)
			(xy 127.102621 -9.757985) (xy 127.080843 -9.855962) (xy 129.787911 -9.855962) (xy 129.791914 -9.7681)
			(xy 129.80389 -9.680966) (xy 129.823741 -9.595282) (xy 129.8513 -9.511758) (xy 129.886341 -9.431086)
			(xy 129.928572 -9.353935) (xy 129.977644 -9.280944) (xy 130.033151 -9.212718) (xy 130.094631 -9.149822)
			(xy 130.161576 -9.092777) (xy 130.233431 -9.042056) (xy 130.309601 -8.998079) (xy 130.389454 -8.961211)
			(xy 130.472329 -8.931758) (xy 130.557539 -8.909962) (xy 130.644378 -8.896006) (xy 130.732126 -8.890003)
			(xy 130.820056 -8.892005) (xy 130.907441 -8.901995) (xy 130.993554 -8.91989) (xy 131.077684 -8.945541)
			(xy 131.159132 -8.978736) (xy 131.237225 -9.0192) (xy 131.311314 -9.066598) (xy 131.380786 -9.120537)
			(xy 131.445065 -9.18057) (xy 131.503619 -9.246199) (xy 131.555963 -9.316881) (xy 131.601662 -9.39203)
			(xy 131.640338 -9.471023) (xy 131.67167 -9.553206) (xy 131.6954 -9.637898) (xy 131.71133 -9.724397)
			(xy 131.719328 -9.811985) (xy 131.719828 -9.855962) (xy 132.327911 -9.855962) (xy 132.331914 -9.7681)
			(xy 132.34389 -9.680966) (xy 132.363741 -9.595282) (xy 132.3913 -9.511758) (xy 132.426341 -9.431086)
			(xy 132.468572 -9.353935) (xy 132.517644 -9.280944) (xy 132.573151 -9.212718) (xy 132.634631 -9.149822)
			(xy 132.701576 -9.092777) (xy 132.773431 -9.042056) (xy 132.849601 -8.998079) (xy 132.929454 -8.961211)
			(xy 133.012329 -8.931758) (xy 133.097539 -8.909962) (xy 133.184378 -8.896006) (xy 133.272126 -8.890003)
			(xy 133.360056 -8.892005) (xy 133.447441 -8.901995) (xy 133.533554 -8.91989) (xy 133.617684 -8.945541)
			(xy 133.699132 -8.978736) (xy 133.777225 -9.0192) (xy 133.851314 -9.066598) (xy 133.920786 -9.120537)
			(xy 133.985065 -9.18057) (xy 134.043619 -9.246199) (xy 134.095963 -9.316881) (xy 134.141662 -9.39203)
			(xy 134.180338 -9.471023) (xy 134.21167 -9.553206) (xy 134.2354 -9.637898) (xy 134.25133 -9.724397)
			(xy 134.259328 -9.811985) (xy 134.259828 -9.855962) (xy 134.867911 -9.855962) (xy 134.871914 -9.7681)
			(xy 134.88389 -9.680966) (xy 134.903741 -9.595282) (xy 134.9313 -9.511758) (xy 134.966341 -9.431086)
			(xy 135.008572 -9.353935) (xy 135.057644 -9.280944) (xy 135.113151 -9.212718) (xy 135.174631 -9.149822)
			(xy 135.241576 -9.092777) (xy 135.313431 -9.042056) (xy 135.389601 -8.998079) (xy 135.469454 -8.961211)
			(xy 135.552329 -8.931758) (xy 135.637539 -8.909962) (xy 135.724378 -8.896006) (xy 135.812126 -8.890003)
			(xy 135.900056 -8.892005) (xy 135.987441 -8.901995) (xy 136.073554 -8.91989) (xy 136.157684 -8.945541)
			(xy 136.239132 -8.978736) (xy 136.317225 -9.0192) (xy 136.391314 -9.066598) (xy 136.460786 -9.120537)
			(xy 136.525065 -9.18057) (xy 136.583619 -9.246199) (xy 136.635963 -9.316881) (xy 136.681662 -9.39203)
			(xy 136.720338 -9.471023) (xy 136.75167 -9.553206) (xy 136.7754 -9.637898) (xy 136.79133 -9.724397)
			(xy 136.799328 -9.811985) (xy 136.799828 -9.855962) (xy 137.407911 -9.855962) (xy 137.411914 -9.7681)
			(xy 137.42389 -9.680966) (xy 137.443741 -9.595282) (xy 137.4713 -9.511758) (xy 137.506341 -9.431086)
			(xy 137.548572 -9.353935) (xy 137.597644 -9.280944) (xy 137.653151 -9.212718) (xy 137.714631 -9.149822)
			(xy 137.781576 -9.092777) (xy 137.853431 -9.042056) (xy 137.929601 -8.998079) (xy 138.009454 -8.961211)
			(xy 138.092329 -8.931758) (xy 138.177539 -8.909962) (xy 138.264378 -8.896006) (xy 138.352126 -8.890003)
			(xy 138.374306 -8.890508) (xy 139.948412 -8.890508) (xy 141.879828 -8.890508) (xy 141.879828 -10.821416)
			(xy 139.948412 -10.821416) (xy 139.948412 -8.890508) (xy 138.374306 -8.890508) (xy 138.440056 -8.892005)
			(xy 138.527441 -8.901995) (xy 138.613554 -8.91989) (xy 138.697684 -8.945541) (xy 138.779132 -8.978736)
			(xy 138.857225 -9.0192) (xy 138.931314 -9.066598) (xy 139.000786 -9.120537) (xy 139.065065 -9.18057)
			(xy 139.123619 -9.246199) (xy 139.175963 -9.316881) (xy 139.221662 -9.39203) (xy 139.260338 -9.471023)
			(xy 139.29167 -9.553206) (xy 139.3154 -9.637898) (xy 139.33133 -9.724397) (xy 139.339328 -9.811985)
			(xy 139.339828 -9.855962) (xy 139.339328 -9.899939) (xy 139.33133 -9.987527) (xy 139.3154 -10.074026)
			(xy 139.29167 -10.158718) (xy 139.260338 -10.240901) (xy 139.221662 -10.319894) (xy 139.175963 -10.395043)
			(xy 139.123619 -10.465725) (xy 139.065065 -10.531354) (xy 139.000786 -10.591387) (xy 138.931314 -10.645326)
			(xy 138.857225 -10.692724) (xy 138.779132 -10.733188) (xy 138.697684 -10.766383) (xy 138.613554 -10.792034)
			(xy 138.527441 -10.809929) (xy 138.440056 -10.819919) (xy 138.352126 -10.821921) (xy 138.264378 -10.815918)
			(xy 138.177539 -10.801962) (xy 138.092329 -10.780166) (xy 138.009454 -10.750713) (xy 137.929601 -10.713845)
			(xy 137.853431 -10.669868) (xy 137.781576 -10.619147) (xy 137.714631 -10.562102) (xy 137.653151 -10.499206)
			(xy 137.597644 -10.43098) (xy 137.548572 -10.357989) (xy 137.506341 -10.280838) (xy 137.4713 -10.200166)
			(xy 137.443741 -10.116642) (xy 137.42389 -10.030958) (xy 137.411914 -9.943824) (xy 137.407911 -9.855962)
			(xy 136.799828 -9.855962) (xy 136.799328 -9.899939) (xy 136.79133 -9.987527) (xy 136.7754 -10.074026)
			(xy 136.75167 -10.158718) (xy 136.720338 -10.240901) (xy 136.681662 -10.319894) (xy 136.635963 -10.395043)
			(xy 136.583619 -10.465725) (xy 136.525065 -10.531354) (xy 136.460786 -10.591387) (xy 136.391314 -10.645326)
			(xy 136.317225 -10.692724) (xy 136.239132 -10.733188) (xy 136.157684 -10.766383) (xy 136.073554 -10.792034)
			(xy 135.987441 -10.809929) (xy 135.900056 -10.819919) (xy 135.812126 -10.821921) (xy 135.724378 -10.815918)
			(xy 135.637539 -10.801962) (xy 135.552329 -10.780166) (xy 135.469454 -10.750713) (xy 135.389601 -10.713845)
			(xy 135.313431 -10.669868) (xy 135.241576 -10.619147) (xy 135.174631 -10.562102) (xy 135.113151 -10.499206)
			(xy 135.057644 -10.43098) (xy 135.008572 -10.357989) (xy 134.966341 -10.280838) (xy 134.9313 -10.200166)
			(xy 134.903741 -10.116642) (xy 134.88389 -10.030958) (xy 134.871914 -9.943824) (xy 134.867911 -9.855962)
			(xy 134.259828 -9.855962) (xy 134.259328 -9.899939) (xy 134.25133 -9.987527) (xy 134.2354 -10.074026)
			(xy 134.21167 -10.158718) (xy 134.180338 -10.240901) (xy 134.141662 -10.319894) (xy 134.095963 -10.395043)
			(xy 134.043619 -10.465725) (xy 133.985065 -10.531354) (xy 133.920786 -10.591387) (xy 133.851314 -10.645326)
			(xy 133.777225 -10.692724) (xy 133.699132 -10.733188) (xy 133.617684 -10.766383) (xy 133.533554 -10.792034)
			(xy 133.447441 -10.809929) (xy 133.360056 -10.819919) (xy 133.272126 -10.821921) (xy 133.184378 -10.815918)
			(xy 133.097539 -10.801962) (xy 133.012329 -10.780166) (xy 132.929454 -10.750713) (xy 132.849601 -10.713845)
			(xy 132.773431 -10.669868) (xy 132.701576 -10.619147) (xy 132.634631 -10.562102) (xy 132.573151 -10.499206)
			(xy 132.517644 -10.43098) (xy 132.468572 -10.357989) (xy 132.426341 -10.280838) (xy 132.3913 -10.200166)
			(xy 132.363741 -10.116642) (xy 132.34389 -10.030958) (xy 132.331914 -9.943824) (xy 132.327911 -9.855962)
			(xy 131.719828 -9.855962) (xy 131.719328 -9.899939) (xy 131.71133 -9.987527) (xy 131.6954 -10.074026)
			(xy 131.67167 -10.158718) (xy 131.640338 -10.240901) (xy 131.601662 -10.319894) (xy 131.555963 -10.395043)
			(xy 131.503619 -10.465725) (xy 131.445065 -10.531354) (xy 131.380786 -10.591387) (xy 131.311314 -10.645326)
			(xy 131.237225 -10.692724) (xy 131.159132 -10.733188) (xy 131.077684 -10.766383) (xy 130.993554 -10.792034)
			(xy 130.907441 -10.809929) (xy 130.820056 -10.819919) (xy 130.732126 -10.821921) (xy 130.644378 -10.815918)
			(xy 130.557539 -10.801962) (xy 130.472329 -10.780166) (xy 130.389454 -10.750713) (xy 130.309601 -10.713845)
			(xy 130.233431 -10.669868) (xy 130.161576 -10.619147) (xy 130.094631 -10.562102) (xy 130.033151 -10.499206)
			(xy 129.977644 -10.43098) (xy 129.928572 -10.357989) (xy 129.886341 -10.280838) (xy 129.8513 -10.200166)
			(xy 129.823741 -10.116642) (xy 129.80389 -10.030958) (xy 129.791914 -9.943824) (xy 129.787911 -9.855962)
			(xy 127.080843 -9.855962) (xy 127.05947 -9.952118) (xy 127.008635 -10.144383) (xy 126.950197 -10.334475)
			(xy 126.884247 -10.522093) (xy 126.81089 -10.706941) (xy 126.730243 -10.888727) (xy 126.642432 -11.067162)
			(xy 126.547597 -11.241966) (xy 126.445887 -11.412861) (xy 126.337463 -11.579577) (xy 126.222497 -11.74185)
			(xy 126.10117 -11.899425) (xy 125.973675 -12.052052) (xy 125.840213 -12.199489) (xy 125.700994 -12.341504)
			(xy 125.55624 -12.477871) (xy 125.406178 -12.608376) (xy 125.251047 -12.732812) (xy 125.091091 -12.850982)
			(xy 124.926564 -12.962699) (xy 124.757726 -13.067787) (xy 124.584842 -13.16608) (xy 124.408188 -13.257421)
			(xy 124.228042 -13.341667) (xy 124.044689 -13.418685) (xy 123.85842 -13.488352) (xy 123.669527 -13.550558)
			(xy 123.478311 -13.605206) (xy 123.285074 -13.652209) (xy 123.09012 -13.691491) (xy 122.893759 -13.722993)
			(xy 122.696301 -13.746662) (xy 122.498058 -13.762463) (xy 122.299344 -13.77037) (xy 122.199908 -13.770864)
			(xy 122.199908 -13.77061) (xy 122.100477 -13.770098) (xy 121.901773 -13.762192) (xy 121.703541 -13.746393)
			(xy 121.506093 -13.722725) (xy 121.309742 -13.691226) (xy 121.114799 -13.651946) (xy 120.921571 -13.604947)
			(xy 120.730365 -13.550302) (xy 120.541482 -13.488099) (xy 120.355222 -13.418436) (xy 120.171879 -13.341423)
			(xy 119.991742 -13.257182) (xy 119.815097 -13.165846) (xy 119.642223 -13.067559) (xy 119.473393 -12.962477)
			(xy 119.308874 -12.850766) (xy 119.148926 -12.732602) (xy 118.993803 -12.608173) (xy 118.843749 -12.477676)
			(xy 118.699002 -12.341315) (xy 118.559791 -12.199308) (xy 118.426335 -12.051879) (xy 118.298846 -11.89926)
			(xy 118.177526 -11.741694) (xy 118.062565 -11.579429) (xy 117.954147 -11.412722) (xy 117.852442 -11.241836)
			(xy 117.757612 -11.067042) (xy 117.669805 -10.888616) (xy 117.589162 -10.70684) (xy 117.515809 -10.522002)
			(xy 117.449863 -10.334393) (xy 117.391427 -10.144311) (xy 117.340595 -9.952057) (xy 117.297446 -9.757933)
			(xy 117.262049 -9.562247) (xy 117.23446 -9.365309) (xy 117.214722 -9.16743) (xy 117.202867 -8.968922)
			(xy 117.198913 -8.7701) (xy 112.45342 -8.7701) (xy 112.45342 -11.389102) (xy 115.905262 -11.389102)
			(xy 115.905262 -11.329166) (xy 115.913085 -11.269744) (xy 115.928598 -11.211851) (xy 115.951534 -11.156478)
			(xy 115.981501 -11.104572) (xy 116.017988 -11.057022) (xy 116.060368 -11.014642) (xy 116.107918 -10.978155)
			(xy 116.159824 -10.948188) (xy 116.215197 -10.925252) (xy 116.27309 -10.909739) (xy 116.332512 -10.901916)
			(xy 116.392448 -10.901916) (xy 116.45187 -10.909739) (xy 116.509763 -10.925252) (xy 116.565136 -10.948188)
			(xy 116.617042 -10.978155) (xy 116.664592 -11.014642) (xy 116.706972 -11.057022) (xy 116.743459 -11.104572)
			(xy 116.773426 -11.156478) (xy 116.796362 -11.211851) (xy 116.811875 -11.269744) (xy 116.819698 -11.329166)
			(xy 116.820188 -11.359134) (xy 116.819698 -11.389102) (xy 116.811875 -11.448524) (xy 116.796362 -11.506417)
			(xy 116.773426 -11.56179) (xy 116.743459 -11.613696) (xy 116.706972 -11.661246) (xy 116.664592 -11.703626)
			(xy 116.617042 -11.740113) (xy 116.565136 -11.77008) (xy 116.509763 -11.793016) (xy 116.45187 -11.808529)
			(xy 116.392448 -11.816352) (xy 116.332512 -11.816352) (xy 116.27309 -11.808529) (xy 116.215197 -11.793016)
			(xy 116.159824 -11.77008) (xy 116.107918 -11.740113) (xy 116.060368 -11.703626) (xy 116.017988 -11.661246)
			(xy 115.981501 -11.613696) (xy 115.951534 -11.56179) (xy 115.928598 -11.506417) (xy 115.913085 -11.448524)
			(xy 115.905262 -11.389102) (xy 112.45342 -11.389102) (xy 112.45342 -14.003274) (xy 112.814858 -14.364712)
			(xy 117.441962 -14.364712) (xy 117.441962 -14.304776) (xy 117.449785 -14.245354) (xy 117.465298 -14.187461)
			(xy 117.488234 -14.132088) (xy 117.518201 -14.080182) (xy 117.554688 -14.032632) (xy 117.597068 -13.990252)
			(xy 117.644618 -13.953765) (xy 117.696524 -13.923798) (xy 117.751897 -13.900862) (xy 117.80979 -13.885349)
			(xy 117.869212 -13.877526) (xy 117.929148 -13.877526) (xy 117.98857 -13.885349) (xy 118.046463 -13.900862)
			(xy 118.101836 -13.923798) (xy 118.153742 -13.953765) (xy 118.201292 -13.990252) (xy 118.243672 -14.032632)
			(xy 118.280159 -14.080182) (xy 118.310126 -14.132088) (xy 118.333062 -14.187461) (xy 118.348575 -14.245354)
			(xy 118.356398 -14.304776) (xy 118.356888 -14.334744) (xy 118.356398 -14.364712) (xy 118.348575 -14.424134)
			(xy 118.333062 -14.482027) (xy 118.310126 -14.5374) (xy 118.280159 -14.589306) (xy 118.243672 -14.636856)
			(xy 118.20238 -14.678148) (xy 127.279382 -14.678148) (xy 127.279382 -14.618212) (xy 127.287205 -14.55879)
			(xy 127.302718 -14.500897) (xy 127.325654 -14.445524) (xy 127.355621 -14.393618) (xy 127.392108 -14.346068)
			(xy 127.434488 -14.303688) (xy 127.482038 -14.267201) (xy 127.533944 -14.237234) (xy 127.589317 -14.214298)
			(xy 127.64721 -14.198785) (xy 127.706632 -14.190962) (xy 127.766568 -14.190962) (xy 127.82599 -14.198785)
			(xy 127.883883 -14.214298) (xy 127.939256 -14.237234) (xy 127.991162 -14.267201) (xy 128.038712 -14.303688)
			(xy 128.081092 -14.346068) (xy 128.117579 -14.393618) (xy 128.147546 -14.445524) (xy 128.170482 -14.500897)
			(xy 128.185995 -14.55879) (xy 128.193818 -14.618212) (xy 128.194308 -14.64818) (xy 128.193818 -14.678148)
			(xy 128.185995 -14.73757) (xy 128.170482 -14.795463) (xy 128.147546 -14.850836) (xy 128.117579 -14.902742)
			(xy 128.081092 -14.950292) (xy 128.038712 -14.992672) (xy 127.991162 -15.029159) (xy 127.939256 -15.059126)
			(xy 127.883883 -15.082062) (xy 127.82599 -15.097575) (xy 127.766568 -15.105398) (xy 127.706632 -15.105398)
			(xy 127.64721 -15.097575) (xy 127.589317 -15.082062) (xy 127.533944 -15.059126) (xy 127.482038 -15.029159)
			(xy 127.434488 -14.992672) (xy 127.392108 -14.950292) (xy 127.355621 -14.902742) (xy 127.325654 -14.850836)
			(xy 127.302718 -14.795463) (xy 127.287205 -14.73757) (xy 127.279382 -14.678148) (xy 118.20238 -14.678148)
			(xy 118.201292 -14.679236) (xy 118.153742 -14.715723) (xy 118.101836 -14.74569) (xy 118.046463 -14.768626)
			(xy 117.98857 -14.784139) (xy 117.929148 -14.791962) (xy 117.869212 -14.791962) (xy 117.80979 -14.784139)
			(xy 117.751897 -14.768626) (xy 117.696524 -14.74569) (xy 117.644618 -14.715723) (xy 117.597068 -14.679236)
			(xy 117.554688 -14.636856) (xy 117.518201 -14.589306) (xy 117.488234 -14.5374) (xy 117.465298 -14.482027)
			(xy 117.449785 -14.424134) (xy 117.441962 -14.364712) (xy 112.814858 -14.364712) (xy 114.667684 -16.217538)
			(xy 120.199406 -16.217538) (xy 120.20441 -16.157243) (xy 120.217316 -16.098132) (xy 120.237897 -16.041238)
			(xy 120.265797 -15.987551) (xy 120.300527 -15.938009) (xy 120.341482 -15.893475) (xy 120.387949 -15.854727)
			(xy 120.413272 -15.83817) (xy 120.432264 -15.825615) (xy 120.46584 -15.794875) (xy 120.493402 -15.758646)
			(xy 120.514068 -15.718085) (xy 120.527177 -15.674491) (xy 120.532309 -15.629259) (xy 120.5293 -15.583836)
			(xy 120.518247 -15.539677) (xy 120.499502 -15.498193) (xy 120.473667 -15.460712) (xy 120.457976 -15.444216)
			(xy 120.438597 -15.424004) (xy 120.405391 -15.378918) (xy 120.379132 -15.329462) (xy 120.360384 -15.2767)
			(xy 120.349549 -15.221764) (xy 120.34686 -15.165834) (xy 120.352374 -15.110112) (xy 120.365974 -15.055794)
			(xy 120.387368 -15.004048) (xy 120.416095 -14.955984) (xy 120.451539 -14.912635) (xy 120.492938 -14.874932)
			(xy 120.539403 -14.843686) (xy 120.589936 -14.819566) (xy 120.643452 -14.803092) (xy 120.698802 -14.794617)
			(xy 120.754795 -14.794323) (xy 120.810231 -14.802216) (xy 120.863917 -14.818127) (xy 120.914701 -14.841715)
			(xy 120.961492 -14.872471) (xy 121.003285 -14.909737) (xy 121.039182 -14.952711) (xy 121.068412 -15.00047)
			(xy 121.090348 -15.051989) (xy 121.104518 -15.106161) (xy 121.110618 -15.161822) (xy 121.108516 -15.217777)
			(xy 121.098259 -15.272824) (xy 121.080066 -15.325781) (xy 121.066047 -15.352866) (xy 122.361877 -15.352866)
			(xy 122.36958 -15.298069) (xy 122.385119 -15.244959) (xy 122.408169 -15.194652) (xy 122.438246 -15.148203)
			(xy 122.474718 -15.106587) (xy 122.516821 -15.070677) (xy 122.56367 -15.041228) (xy 122.614283 -15.018856)
			(xy 122.667597 -15.004032) (xy 122.722493 -14.997067) (xy 122.77782 -14.998106) (xy 122.832416 -15.007129)
			(xy 122.885135 -15.023945) (xy 122.934872 -15.048202) (xy 122.980582 -15.07939) (xy 123.001278 -15.09776)
			(xy 123.018914 -15.113233) (xy 123.058691 -15.138101) (xy 123.102355 -15.15525) (xy 123.148425 -15.164096)
			(xy 123.195335 -15.164341) (xy 123.241494 -15.155974) (xy 123.285334 -15.139282) (xy 123.325368 -15.114829)
			(xy 123.343162 -15.099538) (xy 123.365887 -15.07971) (xy 123.415585 -15.045542) (xy 123.469341 -15.018199)
			(xy 123.526223 -14.998155) (xy 123.585246 -14.985758) (xy 123.645385 -14.981221) (xy 123.705599 -14.984624)
			(xy 123.764845 -14.995908) (xy 123.822094 -15.014877) (xy 123.876356 -15.041202) (xy 123.926689 -15.074427)
			(xy 123.972221 -15.113977) (xy 124.012163 -15.159165) (xy 124.045823 -15.209209) (xy 124.072616 -15.26324)
			(xy 124.09208 -15.320324) (xy 124.103876 -15.379469) (xy 124.107799 -15.439652) (xy 124.103783 -15.499828)
			(xy 124.091896 -15.558956) (xy 124.072345 -15.616009) (xy 124.045469 -15.67) (xy 124.011732 -15.719992)
			(xy 123.971721 -15.765119) (xy 123.926128 -15.804598) (xy 123.875744 -15.837746) (xy 123.821442 -15.863988)
			(xy 123.764163 -15.882869) (xy 123.704901 -15.894061) (xy 123.644681 -15.897372) (xy 123.584549 -15.892743)
			(xy 123.525546 -15.880254) (xy 123.468694 -15.860123) (xy 123.41498 -15.832698) (xy 123.365335 -15.798454)
			(xy 123.320618 -15.757985) (xy 123.300744 -15.7353) (xy 123.285109 -15.717779) (xy 123.248682 -15.688155)
			(xy 123.207437 -15.665721) (xy 123.162774 -15.651241) (xy 123.116211 -15.645206) (xy 123.069333 -15.647822)
			(xy 123.023731 -15.659) (xy 122.980956 -15.678359) (xy 122.9614 -15.691358) (xy 122.938388 -15.70673)
			(xy 122.888914 -15.731517) (xy 122.836377 -15.748895) (xy 122.78188 -15.7585) (xy 122.726568 -15.76013)
			(xy 122.6716 -15.753752) (xy 122.618131 -15.739498) (xy 122.567282 -15.717668) (xy 122.520121 -15.688721)
			(xy 122.477638 -15.653263) (xy 122.440723 -15.612039) (xy 122.410152 -15.565914) (xy 122.386566 -15.515855)
			(xy 122.37046 -15.462914) (xy 122.362172 -15.408202) (xy 122.361877 -15.352866) (xy 121.066047 -15.352866)
			(xy 121.054328 -15.375509) (xy 121.021597 -15.420942) (xy 120.982578 -15.461102) (xy 120.960642 -15.478506)
			(xy 120.942898 -15.492747) (xy 120.912281 -15.526394) (xy 120.888141 -15.564954) (xy 120.871251 -15.607195)
			(xy 120.86215 -15.651767) (xy 120.861129 -15.697248) (xy 120.86822 -15.742185) (xy 120.883196 -15.785141)
			(xy 120.90558 -15.824745) (xy 120.934657 -15.859733) (xy 120.951752 -15.874746) (xy 120.974632 -15.894541)
			(xy 121.015438 -15.939212) (xy 121.050001 -15.988871) (xy 121.077719 -16.042651) (xy 121.098109 -16.099614)
			(xy 121.110816 -16.158768) (xy 121.112915 -16.185134) (xy 121.398282 -16.185134) (xy 121.402353 -16.129512)
			(xy 121.414479 -16.075075) (xy 121.434402 -16.022984) (xy 121.461698 -15.974349) (xy 121.495784 -15.930206)
			(xy 121.535933 -15.891497) (xy 121.581291 -15.859046) (xy 121.630891 -15.833545) (xy 121.683675 -15.815538)
			(xy 121.738518 -15.805408) (xy 121.794252 -15.803371) (xy 121.849689 -15.809471) (xy 121.903646 -15.823577)
			(xy 121.954975 -15.845389) (xy 122.002581 -15.874443) (xy 122.045449 -15.910118) (xy 122.082666 -15.951655)
			(xy 122.113439 -15.998168) (xy 122.137111 -16.048665) (xy 122.153179 -16.102072) (xy 122.161299 -16.157248)
			(xy 122.161808 -16.185134) (xy 122.161299 -16.21302) (xy 122.153179 -16.268196) (xy 122.137111 -16.321603)
			(xy 122.113439 -16.3721) (xy 122.082666 -16.418613) (xy 122.045449 -16.46015) (xy 122.002581 -16.495825)
			(xy 121.954975 -16.524879) (xy 121.903646 -16.546691) (xy 121.849689 -16.560797) (xy 121.794252 -16.566897)
			(xy 121.738518 -16.56486) (xy 121.683675 -16.55473) (xy 121.630891 -16.536723) (xy 121.581291 -16.511222)
			(xy 121.535933 -16.478771) (xy 121.495784 -16.440062) (xy 121.461698 -16.395919) (xy 121.434402 -16.347284)
			(xy 121.414479 -16.295193) (xy 121.402353 -16.240756) (xy 121.398282 -16.185134) (xy 121.112915 -16.185134)
			(xy 121.115617 -16.21908) (xy 121.112429 -16.279499) (xy 121.101307 -16.338971) (xy 121.082446 -16.396459)
			(xy 121.056174 -16.45096) (xy 121.022949 -16.501524) (xy 120.983352 -16.54727) (xy 120.938072 -16.587399)
			(xy 120.887899 -16.621211) (xy 120.833708 -16.648117) (xy 120.776445 -16.667648) (xy 120.717106 -16.679464)
			(xy 120.656729 -16.683357) (xy 120.596365 -16.67926) (xy 120.537067 -16.667246) (xy 120.479869 -16.647522)
			(xy 120.425769 -16.620433) (xy 120.375711 -16.586452) (xy 120.330566 -16.546171) (xy 120.291123 -16.500293)
			(xy 120.258069 -16.449617) (xy 120.23198 -16.395028) (xy 120.213313 -16.337477) (xy 120.202391 -16.277968)
			(xy 120.199406 -16.217538) (xy 114.667684 -16.217538) (xy 115.311682 -16.861536) (xy 115.844064 -16.861536)
			(xy 115.848135 -16.805914) (xy 115.860261 -16.751477) (xy 115.880184 -16.699386) (xy 115.90748 -16.650751)
			(xy 115.941566 -16.606608) (xy 115.981715 -16.567899) (xy 116.027073 -16.535448) (xy 116.076673 -16.509947)
			(xy 116.129457 -16.49194) (xy 116.1843 -16.48181) (xy 116.240034 -16.479773) (xy 116.295471 -16.485873)
			(xy 116.349428 -16.499979) (xy 116.400757 -16.521791) (xy 116.448363 -16.550845) (xy 116.491231 -16.58652)
			(xy 116.528448 -16.628057) (xy 116.559221 -16.67457) (xy 116.582893 -16.725067) (xy 116.598961 -16.778474)
			(xy 116.607081 -16.83365) (xy 116.60759 -16.861536) (xy 116.607081 -16.889422) (xy 116.598961 -16.944598)
			(xy 116.582893 -16.998005) (xy 116.559221 -17.048502) (xy 116.528448 -17.095015) (xy 116.491231 -17.136552)
			(xy 116.448363 -17.172227) (xy 116.400757 -17.201281) (xy 116.349428 -17.223093) (xy 116.295471 -17.237199)
			(xy 116.240034 -17.243299) (xy 116.1843 -17.241262) (xy 116.129457 -17.231132) (xy 116.076673 -17.213125)
			(xy 116.027073 -17.187624) (xy 115.981715 -17.155173) (xy 115.941566 -17.116464) (xy 115.90748 -17.072321)
			(xy 115.880184 -17.023686) (xy 115.860261 -16.971595) (xy 115.848135 -16.917158) (xy 115.844064 -16.861536)
			(xy 115.311682 -16.861536) (xy 115.741196 -17.29105) (xy 123.323602 -17.29105) (xy 123.327673 -17.235428)
			(xy 123.339799 -17.180991) (xy 123.359722 -17.1289) (xy 123.387018 -17.080265) (xy 123.421104 -17.036122)
			(xy 123.461253 -16.997413) (xy 123.506611 -16.964962) (xy 123.556211 -16.939461) (xy 123.608995 -16.921454)
			(xy 123.663838 -16.911324) (xy 123.719572 -16.909287) (xy 123.775009 -16.915387) (xy 123.828966 -16.929493)
			(xy 123.880295 -16.951305) (xy 123.927901 -16.980359) (xy 123.970769 -17.016034) (xy 124.007986 -17.057571)
			(xy 124.038759 -17.104084) (xy 124.062431 -17.154581) (xy 124.078499 -17.207988) (xy 124.086619 -17.263164)
			(xy 124.087128 -17.29105) (xy 124.086619 -17.318936) (xy 124.078499 -17.374112) (xy 124.062431 -17.427519)
			(xy 124.038759 -17.478016) (xy 124.007986 -17.524529) (xy 123.970769 -17.566066) (xy 123.927901 -17.601741)
			(xy 123.880295 -17.630795) (xy 123.828966 -17.652607) (xy 123.775009 -17.666713) (xy 123.719572 -17.672813)
			(xy 123.663838 -17.670776) (xy 123.608995 -17.660646) (xy 123.556211 -17.642639) (xy 123.506611 -17.617138)
			(xy 123.461253 -17.584687) (xy 123.421104 -17.545978) (xy 123.387018 -17.501835) (xy 123.359722 -17.4532)
			(xy 123.339799 -17.401109) (xy 123.327673 -17.346672) (xy 123.323602 -17.29105) (xy 115.741196 -17.29105)
			(xy 115.98656 -17.536414) (xy 115.98656 -18.335494) (xy 129.875262 -18.335494) (xy 129.875262 -18.275558)
			(xy 129.883085 -18.216136) (xy 129.898598 -18.158243) (xy 129.921534 -18.10287) (xy 129.951501 -18.050964)
			(xy 129.987988 -18.003414) (xy 130.030368 -17.961034) (xy 130.077918 -17.924547) (xy 130.129824 -17.89458)
			(xy 130.185197 -17.871644) (xy 130.24309 -17.856131) (xy 130.302512 -17.848308) (xy 130.362448 -17.848308)
			(xy 130.42187 -17.856131) (xy 130.479763 -17.871644) (xy 130.535136 -17.89458) (xy 130.587042 -17.924547)
			(xy 130.634592 -17.961034) (xy 130.676972 -18.003414) (xy 130.713459 -18.050964) (xy 130.743426 -18.10287)
			(xy 130.766362 -18.158243) (xy 130.781875 -18.216136) (xy 130.789698 -18.275558) (xy 130.790188 -18.305526)
			(xy 130.789698 -18.335494) (xy 130.781875 -18.394916) (xy 130.766362 -18.452809) (xy 130.743426 -18.508182)
			(xy 130.713459 -18.560088) (xy 130.676972 -18.607638) (xy 130.634592 -18.650018) (xy 130.587042 -18.686505)
			(xy 130.535136 -18.716472) (xy 130.479763 -18.739408) (xy 130.42187 -18.754921) (xy 130.362448 -18.762744)
			(xy 130.302512 -18.762744) (xy 130.24309 -18.754921) (xy 130.185197 -18.739408) (xy 130.129824 -18.716472)
			(xy 130.077918 -18.686505) (xy 130.030368 -18.650018) (xy 129.987988 -18.607638) (xy 129.951501 -18.560088)
			(xy 129.921534 -18.508182) (xy 129.898598 -18.452809) (xy 129.883085 -18.394916) (xy 129.875262 -18.335494)
			(xy 115.98656 -18.335494) (xy 115.98656 -19.84883) (xy 117.6688 -19.84883) (xy 117.672871 -19.793208)
			(xy 117.684997 -19.738771) (xy 117.70492 -19.68668) (xy 117.732216 -19.638045) (xy 117.766302 -19.593902)
			(xy 117.806451 -19.555193) (xy 117.851809 -19.522742) (xy 117.901409 -19.497241) (xy 117.954193 -19.479234)
			(xy 118.009036 -19.469104) (xy 118.06477 -19.467067) (xy 118.120207 -19.473167) (xy 118.174164 -19.487273)
			(xy 118.225493 -19.509085) (xy 118.273099 -19.538139) (xy 118.315967 -19.573814) (xy 118.353184 -19.615351)
			(xy 118.383957 -19.661864) (xy 118.407629 -19.712361) (xy 118.423697 -19.765768) (xy 118.431817 -19.820944)
			(xy 118.432326 -19.84883) (xy 118.431817 -19.876716) (xy 118.423697 -19.931892) (xy 118.407629 -19.985299)
			(xy 118.383957 -20.035796) (xy 118.353184 -20.082309) (xy 118.315967 -20.123846) (xy 118.273099 -20.159521)
			(xy 118.225493 -20.188575) (xy 118.174164 -20.210387) (xy 118.120207 -20.224493) (xy 118.06477 -20.230593)
			(xy 118.009036 -20.228556) (xy 117.954193 -20.218426) (xy 117.901409 -20.200419) (xy 117.851809 -20.174918)
			(xy 117.806451 -20.142467) (xy 117.766302 -20.103758) (xy 117.732216 -20.059615) (xy 117.70492 -20.01098)
			(xy 117.684997 -19.958889) (xy 117.672871 -19.904452) (xy 117.6688 -19.84883) (xy 115.98656 -19.84883)
			(xy 115.98656 -21.04009) (xy 116.190268 -21.243798) (xy 118.691914 -21.243798) (xy 119.658638 -22.210522)
			(xy 119.658638 -25.39492) (xy 122.571254 -25.39492) (xy 122.575325 -25.339298) (xy 122.587451 -25.284861)
			(xy 122.607374 -25.23277) (xy 122.63467 -25.184135) (xy 122.668756 -25.139992) (xy 122.708905 -25.101283)
			(xy 122.754263 -25.068832) (xy 122.803863 -25.043331) (xy 122.856647 -25.025324) (xy 122.91149 -25.015194)
			(xy 122.967224 -25.013157) (xy 123.022661 -25.019257) (xy 123.076618 -25.033363) (xy 123.127947 -25.055175)
			(xy 123.175553 -25.084229) (xy 123.218421 -25.119904) (xy 123.255638 -25.161441) (xy 123.286411 -25.207954)
			(xy 123.310083 -25.258451) (xy 123.326151 -25.311858) (xy 123.334271 -25.367034) (xy 123.33478 -25.39492)
			(xy 123.334271 -25.422806) (xy 123.33303 -25.431242) (xy 123.681234 -25.431242) (xy 123.685305 -25.37562)
			(xy 123.697431 -25.321183) (xy 123.717354 -25.269092) (xy 123.74465 -25.220457) (xy 123.778736 -25.176314)
			(xy 123.818885 -25.137605) (xy 123.864243 -25.105154) (xy 123.913843 -25.079653) (xy 123.966627 -25.061646)
			(xy 124.02147 -25.051516) (xy 124.077204 -25.049479) (xy 124.132641 -25.055579) (xy 124.186598 -25.069685)
			(xy 124.237927 -25.091497) (xy 124.285533 -25.120551) (xy 124.328401 -25.156226) (xy 124.365618 -25.197763)
			(xy 124.396391 -25.244276) (xy 124.402712 -25.25776) (xy 124.828552 -25.25776) (xy 124.832623 -25.202138)
			(xy 124.844749 -25.147701) (xy 124.864672 -25.09561) (xy 124.891968 -25.046975) (xy 124.926054 -25.002832)
			(xy 124.966203 -24.964123) (xy 125.011561 -24.931672) (xy 125.061161 -24.906171) (xy 125.113945 -24.888164)
			(xy 125.168788 -24.878034) (xy 125.224522 -24.875997) (xy 125.279959 -24.882097) (xy 125.333916 -24.896203)
			(xy 125.385245 -24.918015) (xy 125.432851 -24.947069) (xy 125.475719 -24.982744) (xy 125.512936 -25.024281)
			(xy 125.543709 -25.070794) (xy 125.567381 -25.121291) (xy 125.583449 -25.174698) (xy 125.591569 -25.229874)
			(xy 125.592078 -25.25776) (xy 125.591569 -25.285646) (xy 125.583449 -25.340822) (xy 125.567381 -25.394229)
			(xy 125.543709 -25.444726) (xy 125.512936 -25.491239) (xy 125.475719 -25.532776) (xy 125.432851 -25.568451)
			(xy 125.385245 -25.597505) (xy 125.333916 -25.619317) (xy 125.279959 -25.633423) (xy 125.224522 -25.639523)
			(xy 125.168788 -25.637486) (xy 125.113945 -25.627356) (xy 125.061161 -25.609349) (xy 125.011561 -25.583848)
			(xy 124.966203 -25.551397) (xy 124.926054 -25.512688) (xy 124.891968 -25.468545) (xy 124.864672 -25.41991)
			(xy 124.844749 -25.367819) (xy 124.832623 -25.313382) (xy 124.828552 -25.25776) (xy 124.402712 -25.25776)
			(xy 124.420063 -25.294773) (xy 124.436131 -25.34818) (xy 124.444251 -25.403356) (xy 124.44476 -25.431242)
			(xy 124.444251 -25.459128) (xy 124.436131 -25.514304) (xy 124.420063 -25.567711) (xy 124.396391 -25.618208)
			(xy 124.365618 -25.664721) (xy 124.328401 -25.706258) (xy 124.285533 -25.741933) (xy 124.237927 -25.770987)
			(xy 124.186598 -25.792799) (xy 124.132641 -25.806905) (xy 124.077204 -25.813005) (xy 124.02147 -25.810968)
			(xy 123.966627 -25.800838) (xy 123.913843 -25.782831) (xy 123.864243 -25.75733) (xy 123.818885 -25.724879)
			(xy 123.778736 -25.68617) (xy 123.74465 -25.642027) (xy 123.717354 -25.593392) (xy 123.697431 -25.541301)
			(xy 123.685305 -25.486864) (xy 123.681234 -25.431242) (xy 123.33303 -25.431242) (xy 123.326151 -25.477982)
			(xy 123.310083 -25.531389) (xy 123.286411 -25.581886) (xy 123.255638 -25.628399) (xy 123.218421 -25.669936)
			(xy 123.175553 -25.705611) (xy 123.127947 -25.734665) (xy 123.076618 -25.756477) (xy 123.022661 -25.770583)
			(xy 122.967224 -25.776683) (xy 122.91149 -25.774646) (xy 122.856647 -25.764516) (xy 122.803863 -25.746509)
			(xy 122.754263 -25.721008) (xy 122.708905 -25.688557) (xy 122.668756 -25.649848) (xy 122.63467 -25.605705)
			(xy 122.607374 -25.55707) (xy 122.587451 -25.504979) (xy 122.575325 -25.450542) (xy 122.571254 -25.39492)
			(xy 119.658638 -25.39492) (xy 119.658638 -27.588464) (xy 119.944384 -27.87421) (xy 123.606034 -27.87421)
			(xy 123.606034 -27.814274) (xy 123.613857 -27.754852) (xy 123.62937 -27.696959) (xy 123.652306 -27.641586)
			(xy 123.682273 -27.58968) (xy 123.71876 -27.54213) (xy 123.76114 -27.49975) (xy 123.80869 -27.463263)
			(xy 123.860596 -27.433296) (xy 123.915969 -27.41036) (xy 123.973862 -27.394847) (xy 124.033284 -27.387024)
			(xy 124.09322 -27.387024) (xy 124.152642 -27.394847) (xy 124.210535 -27.41036) (xy 124.265908 -27.433296)
			(xy 124.317814 -27.463263) (xy 124.365364 -27.49975) (xy 124.407744 -27.54213) (xy 124.444231 -27.58968)
			(xy 124.469336 -27.633164) (xy 125.108952 -27.633164) (xy 125.108952 -27.573228) (xy 125.116775 -27.513806)
			(xy 125.132288 -27.455913) (xy 125.155224 -27.40054) (xy 125.185191 -27.348634) (xy 125.221678 -27.301084)
			(xy 125.264058 -27.258704) (xy 125.311608 -27.222217) (xy 125.363514 -27.19225) (xy 125.418887 -27.169314)
			(xy 125.47678 -27.153801) (xy 125.536202 -27.145978) (xy 125.596138 -27.145978) (xy 125.65556 -27.153801)
			(xy 125.713453 -27.169314) (xy 125.768826 -27.19225) (xy 125.820732 -27.222217) (xy 125.868282 -27.258704)
			(xy 125.910662 -27.301084) (xy 125.947149 -27.348634) (xy 125.977116 -27.40054) (xy 126.000052 -27.455913)
			(xy 126.015565 -27.513806) (xy 126.023388 -27.573228) (xy 126.023878 -27.603196) (xy 126.023388 -27.633164)
			(xy 126.015565 -27.692586) (xy 126.000052 -27.750479) (xy 125.992148 -27.769562) (xy 126.621522 -27.769562)
			(xy 126.621522 -27.709626) (xy 126.629345 -27.650204) (xy 126.644858 -27.592311) (xy 126.667794 -27.536938)
			(xy 126.697761 -27.485032) (xy 126.734248 -27.437482) (xy 126.776628 -27.395102) (xy 126.824178 -27.358615)
			(xy 126.876084 -27.328648) (xy 126.931457 -27.305712) (xy 126.98935 -27.290199) (xy 127.048772 -27.282376)
			(xy 127.108708 -27.282376) (xy 127.16813 -27.290199) (xy 127.226023 -27.305712) (xy 127.281396 -27.328648)
			(xy 127.333302 -27.358615) (xy 127.380852 -27.395102) (xy 127.423232 -27.437482) (xy 127.459719 -27.485032)
			(xy 127.489686 -27.536938) (xy 127.512622 -27.592311) (xy 127.520915 -27.623258) (xy 129.813794 -27.623258)
			(xy 129.813794 -27.563322) (xy 129.821617 -27.5039) (xy 129.83713 -27.446007) (xy 129.860066 -27.390634)
			(xy 129.890033 -27.338728) (xy 129.92652 -27.291178) (xy 129.9689 -27.248798) (xy 130.01645 -27.212311)
			(xy 130.068356 -27.182344) (xy 130.123729 -27.159408) (xy 130.181622 -27.143895) (xy 130.241044 -27.136072)
			(xy 130.30098 -27.136072) (xy 130.360402 -27.143895) (xy 130.418295 -27.159408) (xy 130.473668 -27.182344)
			(xy 130.525574 -27.212311) (xy 130.573124 -27.248798) (xy 130.615504 -27.291178) (xy 130.651991 -27.338728)
			(xy 130.681958 -27.390634) (xy 130.704894 -27.446007) (xy 130.720407 -27.5039) (xy 130.72823 -27.563322)
			(xy 130.72872 -27.59329) (xy 130.728612 -27.59989) (xy 131.527532 -27.59989) (xy 131.527532 -27.539954)
			(xy 131.535355 -27.480532) (xy 131.550868 -27.422639) (xy 131.573804 -27.367266) (xy 131.603771 -27.31536)
			(xy 131.640258 -27.26781) (xy 131.682638 -27.22543) (xy 131.730188 -27.188943) (xy 131.782094 -27.158976)
			(xy 131.837467 -27.13604) (xy 131.89536 -27.120527) (xy 131.954782 -27.112704) (xy 132.014718 -27.112704)
			(xy 132.07414 -27.120527) (xy 132.132033 -27.13604) (xy 132.187406 -27.158976) (xy 132.239312 -27.188943)
			(xy 132.286862 -27.22543) (xy 132.329242 -27.26781) (xy 132.365729 -27.31536) (xy 132.395696 -27.367266)
			(xy 132.418632 -27.422639) (xy 132.434145 -27.480532) (xy 132.441968 -27.539954) (xy 132.442458 -27.569922)
			(xy 132.441968 -27.59989) (xy 132.434145 -27.659312) (xy 132.418632 -27.717205) (xy 132.395696 -27.772578)
			(xy 132.365729 -27.824484) (xy 132.329242 -27.872034) (xy 132.286862 -27.914414) (xy 132.239312 -27.950901)
			(xy 132.187406 -27.980868) (xy 132.132033 -28.003804) (xy 132.07414 -28.019317) (xy 132.014718 -28.02714)
			(xy 131.954782 -28.02714) (xy 131.89536 -28.019317) (xy 131.837467 -28.003804) (xy 131.782094 -27.980868)
			(xy 131.730188 -27.950901) (xy 131.682638 -27.914414) (xy 131.640258 -27.872034) (xy 131.603771 -27.824484)
			(xy 131.573804 -27.772578) (xy 131.550868 -27.717205) (xy 131.535355 -27.659312) (xy 131.527532 -27.59989)
			(xy 130.728612 -27.59989) (xy 130.72823 -27.623258) (xy 130.720407 -27.68268) (xy 130.704894 -27.740573)
			(xy 130.681958 -27.795946) (xy 130.651991 -27.847852) (xy 130.615504 -27.895402) (xy 130.573124 -27.937782)
			(xy 130.525574 -27.974269) (xy 130.473668 -28.004236) (xy 130.418295 -28.027172) (xy 130.360402 -28.042685)
			(xy 130.30098 -28.050508) (xy 130.241044 -28.050508) (xy 130.181622 -28.042685) (xy 130.123729 -28.027172)
			(xy 130.068356 -28.004236) (xy 130.01645 -27.974269) (xy 129.9689 -27.937782) (xy 129.92652 -27.895402)
			(xy 129.890033 -27.847852) (xy 129.860066 -27.795946) (xy 129.83713 -27.740573) (xy 129.821617 -27.68268)
			(xy 129.813794 -27.623258) (xy 127.520915 -27.623258) (xy 127.528135 -27.650204) (xy 127.535958 -27.709626)
			(xy 127.536448 -27.739594) (xy 127.535958 -27.769562) (xy 127.528135 -27.828984) (xy 127.512622 -27.886877)
			(xy 127.489686 -27.94225) (xy 127.459719 -27.994156) (xy 127.423232 -28.041706) (xy 127.380852 -28.084086)
			(xy 127.333302 -28.120573) (xy 127.281396 -28.15054) (xy 127.226023 -28.173476) (xy 127.16813 -28.188989)
			(xy 127.108708 -28.196812) (xy 127.048772 -28.196812) (xy 126.98935 -28.188989) (xy 126.931457 -28.173476)
			(xy 126.876084 -28.15054) (xy 126.824178 -28.120573) (xy 126.776628 -28.084086) (xy 126.734248 -28.041706)
			(xy 126.697761 -27.994156) (xy 126.667794 -27.94225) (xy 126.644858 -27.886877) (xy 126.629345 -27.828984)
			(xy 126.621522 -27.769562) (xy 125.992148 -27.769562) (xy 125.977116 -27.805852) (xy 125.947149 -27.857758)
			(xy 125.910662 -27.905308) (xy 125.868282 -27.947688) (xy 125.820732 -27.984175) (xy 125.768826 -28.014142)
			(xy 125.713453 -28.037078) (xy 125.65556 -28.052591) (xy 125.596138 -28.060414) (xy 125.536202 -28.060414)
			(xy 125.47678 -28.052591) (xy 125.418887 -28.037078) (xy 125.363514 -28.014142) (xy 125.311608 -27.984175)
			(xy 125.264058 -27.947688) (xy 125.221678 -27.905308) (xy 125.185191 -27.857758) (xy 125.155224 -27.805852)
			(xy 125.132288 -27.750479) (xy 125.116775 -27.692586) (xy 125.108952 -27.633164) (xy 124.469336 -27.633164)
			(xy 124.474198 -27.641586) (xy 124.497134 -27.696959) (xy 124.512647 -27.754852) (xy 124.52047 -27.814274)
			(xy 124.52096 -27.844242) (xy 124.52047 -27.87421) (xy 124.512647 -27.933632) (xy 124.497134 -27.991525)
			(xy 124.474198 -28.046898) (xy 124.444231 -28.098804) (xy 124.407744 -28.146354) (xy 124.365364 -28.188734)
			(xy 124.317814 -28.225221) (xy 124.265908 -28.255188) (xy 124.210535 -28.278124) (xy 124.152642 -28.293637)
			(xy 124.09322 -28.30146) (xy 124.033284 -28.30146) (xy 123.973862 -28.293637) (xy 123.915969 -28.278124)
			(xy 123.860596 -28.255188) (xy 123.80869 -28.225221) (xy 123.76114 -28.188734) (xy 123.71876 -28.146354)
			(xy 123.682273 -28.098804) (xy 123.652306 -28.046898) (xy 123.62937 -27.991525) (xy 123.613857 -27.933632)
			(xy 123.606034 -27.87421) (xy 119.944384 -27.87421) (xy 120.754136 -28.683962) (xy 122.567682 -28.683962)
			(xy 122.567682 -28.624026) (xy 122.575505 -28.564604) (xy 122.591018 -28.506711) (xy 122.613954 -28.451338)
			(xy 122.643921 -28.399432) (xy 122.680408 -28.351882) (xy 122.722788 -28.309502) (xy 122.770338 -28.273015)
			(xy 122.822244 -28.243048) (xy 122.877617 -28.220112) (xy 122.93551 -28.204599) (xy 122.994932 -28.196776)
			(xy 123.054868 -28.196776) (xy 123.11429 -28.204599) (xy 123.172183 -28.220112) (xy 123.227556 -28.243048)
			(xy 123.279462 -28.273015) (xy 123.327012 -28.309502) (xy 123.369392 -28.351882) (xy 123.405879 -28.399432)
			(xy 123.414413 -28.414214) (xy 127.749282 -28.414214) (xy 127.749282 -28.354278) (xy 127.757105 -28.294856)
			(xy 127.772618 -28.236963) (xy 127.795554 -28.18159) (xy 127.825521 -28.129684) (xy 127.862008 -28.082134)
			(xy 127.904388 -28.039754) (xy 127.951938 -28.003267) (xy 128.003844 -27.9733) (xy 128.059217 -27.950364)
			(xy 128.11711 -27.934851) (xy 128.176532 -27.927028) (xy 128.236468 -27.927028) (xy 128.29589 -27.934851)
			(xy 128.353783 -27.950364) (xy 128.409156 -27.9733) (xy 128.461062 -28.003267) (xy 128.508612 -28.039754)
			(xy 128.550992 -28.082134) (xy 128.587479 -28.129684) (xy 128.617446 -28.18159) (xy 128.640382 -28.236963)
			(xy 128.655895 -28.294856) (xy 128.663718 -28.354278) (xy 128.664208 -28.384246) (xy 128.663718 -28.414214)
			(xy 128.655895 -28.473636) (xy 128.640382 -28.531529) (xy 128.617446 -28.586902) (xy 128.587479 -28.638808)
			(xy 128.550992 -28.686358) (xy 128.52113 -28.71622) (xy 129.004296 -28.71622) (xy 129.004296 -28.656284)
			(xy 129.012119 -28.596862) (xy 129.027632 -28.538969) (xy 129.050568 -28.483596) (xy 129.080535 -28.43169)
			(xy 129.117022 -28.38414) (xy 129.159402 -28.34176) (xy 129.206952 -28.305273) (xy 129.258858 -28.275306)
			(xy 129.314231 -28.25237) (xy 129.372124 -28.236857) (xy 129.431546 -28.229034) (xy 129.491482 -28.229034)
			(xy 129.550904 -28.236857) (xy 129.608797 -28.25237) (xy 129.66417 -28.275306) (xy 129.716076 -28.305273)
			(xy 129.763626 -28.34176) (xy 129.806006 -28.38414) (xy 129.842493 -28.43169) (xy 129.87246 -28.483596)
			(xy 129.895396 -28.538969) (xy 129.910909 -28.596862) (xy 129.918732 -28.656284) (xy 129.919222 -28.686252)
			(xy 129.918732 -28.71622) (xy 129.912613 -28.762702) (xy 130.643866 -28.762702) (xy 130.643866 -28.702766)
			(xy 130.651689 -28.643344) (xy 130.667202 -28.585451) (xy 130.690138 -28.530078) (xy 130.720105 -28.478172)
			(xy 130.756592 -28.430622) (xy 130.798972 -28.388242) (xy 130.846522 -28.351755) (xy 130.898428 -28.321788)
			(xy 130.953801 -28.298852) (xy 131.011694 -28.283339) (xy 131.071116 -28.275516) (xy 131.131052 -28.275516)
			(xy 131.190474 -28.283339) (xy 131.248367 -28.298852) (xy 131.30374 -28.321788) (xy 131.355646 -28.351755)
			(xy 131.403196 -28.388242) (xy 131.445576 -28.430622) (xy 131.482063 -28.478172) (xy 131.51203 -28.530078)
			(xy 131.534966 -28.585451) (xy 131.550479 -28.643344) (xy 131.558302 -28.702766) (xy 131.558792 -28.732734)
			(xy 131.558302 -28.762702) (xy 131.550479 -28.822124) (xy 131.534966 -28.880017) (xy 131.51203 -28.93539)
			(xy 131.482063 -28.987296) (xy 131.445576 -29.034846) (xy 131.403196 -29.077226) (xy 131.355646 -29.113713)
			(xy 131.30374 -29.14368) (xy 131.248367 -29.166616) (xy 131.190474 -29.182129) (xy 131.131052 -29.189952)
			(xy 131.071116 -29.189952) (xy 131.011694 -29.182129) (xy 130.953801 -29.166616) (xy 130.898428 -29.14368)
			(xy 130.846522 -29.113713) (xy 130.798972 -29.077226) (xy 130.756592 -29.034846) (xy 130.720105 -28.987296)
			(xy 130.690138 -28.93539) (xy 130.667202 -28.880017) (xy 130.651689 -28.822124) (xy 130.643866 -28.762702)
			(xy 129.912613 -28.762702) (xy 129.910909 -28.775642) (xy 129.895396 -28.833535) (xy 129.87246 -28.888908)
			(xy 129.842493 -28.940814) (xy 129.806006 -28.988364) (xy 129.763626 -29.030744) (xy 129.716076 -29.067231)
			(xy 129.66417 -29.097198) (xy 129.608797 -29.120134) (xy 129.550904 -29.135647) (xy 129.491482 -29.14347)
			(xy 129.431546 -29.14347) (xy 129.372124 -29.135647) (xy 129.314231 -29.120134) (xy 129.258858 -29.097198)
			(xy 129.206952 -29.067231) (xy 129.159402 -29.030744) (xy 129.117022 -28.988364) (xy 129.080535 -28.940814)
			(xy 129.050568 -28.888908) (xy 129.027632 -28.833535) (xy 129.012119 -28.775642) (xy 129.004296 -28.71622)
			(xy 128.52113 -28.71622) (xy 128.508612 -28.728738) (xy 128.461062 -28.765225) (xy 128.409156 -28.795192)
			(xy 128.353783 -28.818128) (xy 128.29589 -28.833641) (xy 128.236468 -28.841464) (xy 128.176532 -28.841464)
			(xy 128.11711 -28.833641) (xy 128.059217 -28.818128) (xy 128.003844 -28.795192) (xy 127.951938 -28.765225)
			(xy 127.904388 -28.728738) (xy 127.862008 -28.686358) (xy 127.825521 -28.638808) (xy 127.795554 -28.586902)
			(xy 127.772618 -28.531529) (xy 127.757105 -28.473636) (xy 127.749282 -28.414214) (xy 123.414413 -28.414214)
			(xy 123.435846 -28.451338) (xy 123.458782 -28.506711) (xy 123.474295 -28.564604) (xy 123.482118 -28.624026)
			(xy 123.482608 -28.653994) (xy 123.482118 -28.683962) (xy 123.474295 -28.743384) (xy 123.458782 -28.801277)
			(xy 123.435846 -28.85665) (xy 123.405879 -28.908556) (xy 123.369392 -28.956106) (xy 123.327012 -28.998486)
			(xy 123.279462 -29.034973) (xy 123.227556 -29.06494) (xy 123.172183 -29.087876) (xy 123.11429 -29.103389)
			(xy 123.054868 -29.111212) (xy 122.994932 -29.111212) (xy 122.93551 -29.103389) (xy 122.877617 -29.087876)
			(xy 122.822244 -29.06494) (xy 122.770338 -29.034973) (xy 122.722788 -28.998486) (xy 122.680408 -28.956106)
			(xy 122.643921 -28.908556) (xy 122.613954 -28.85665) (xy 122.591018 -28.801277) (xy 122.575505 -28.743384)
			(xy 122.567682 -28.683962) (xy 120.754136 -28.683962) (xy 122.1105 -30.040326) (xy 123.645168 -30.040326)
		)
		(stroke
			(width 0)
			(type solid)
		)
		(fill yes)
		(layer "B.Cu")
		(net "P3V3_STB_NODE1")
	)
	(gr_poly
		(pts
			(xy 67.088766 -68.609464) (xy 67.104261 -68.625427) (xy 67.139777 -68.652212) (xy 67.179409 -68.672414)
			(xy 67.22195 -68.685417) (xy 67.266104 -68.690826) (xy 67.310526 -68.688476) (xy 67.353862 -68.678438)
			(xy 67.374516 -68.67017) (xy 67.39376 -68.661577) (xy 67.433731 -68.648214) (xy 67.454272 -68.6435)
			(xy 67.48148 -68.638096) (xy 67.536816 -68.634264) (xy 67.564508 -68.63588) (xy 67.592194 -68.637912)
			(xy 67.644518 -68.618608) (xy 68.512182 -67.75069) (xy 68.864988 -67.75069) (xy 68.884613 -67.750348)
			(xy 68.923402 -67.744353) (xy 68.960805 -67.732458) (xy 68.978526 -67.72402) (xy 69.027802 -67.654678)
			(xy 69.022468 -67.600576) (xy 69.021706 -67.59575) (xy 69.016891 -67.559954) (xy 69.01728 -67.48773)
			(xy 69.022468 -67.451986) (xy 69.025588 -67.429643) (xy 69.024823 -67.384541) (xy 69.016114 -67.340281)
			(xy 68.999735 -67.298251) (xy 68.976199 -67.259769) (xy 68.946245 -67.226041) (xy 68.910812 -67.198126)
			(xy 68.89115 -67.187064) (xy 68.867431 -67.174675) (xy 68.823408 -67.144254) (xy 68.784066 -67.107981)
			(xy 68.750178 -67.066567) (xy 68.722408 -67.020824) (xy 68.701301 -66.971651) (xy 68.687271 -66.920011)
			(xy 68.680593 -66.866918) (xy 68.681399 -66.813412) (xy 68.689671 -66.760544) (xy 68.705248 -66.70935)
			(xy 68.727825 -66.660834) (xy 68.742052 -66.63817) (xy 68.7526 -66.622297) (xy 68.776395 -66.592524)
			(xy 68.78955 -66.578734) (xy 68.805057 -66.560995) (xy 68.829875 -66.52095) (xy 68.846885 -66.477016)
			(xy 68.855505 -66.430699) (xy 68.855438 -66.383587) (xy 68.846688 -66.337295) (xy 68.829554 -66.293409)
			(xy 68.81749 -66.273172) (xy 68.801125 -66.245919) (xy 68.775257 -66.187851) (xy 68.75767 -66.126763)
			(xy 68.748704 -66.063829) (xy 68.748531 -66.00026) (xy 68.757155 -65.937278) (xy 68.774408 -65.876095)
			(xy 68.79996 -65.817887) (xy 68.81622 -65.790572) (xy 68.827189 -65.771966) (xy 68.843321 -65.731903)
			(xy 68.852448 -65.68969) (xy 68.854307 -65.646542) (xy 68.848844 -65.6037) (xy 68.836217 -65.562398)
			(xy 68.816789 -65.523826) (xy 68.791119 -65.489094) (xy 68.775834 -65.473834) (xy 68.756159 -65.454267)
			(xy 68.722106 -65.410456) (xy 68.694757 -65.362175) (xy 68.67469 -65.310442) (xy 68.662328 -65.256348)
			(xy 68.657932 -65.201034) (xy 68.661594 -65.145666) (xy 68.673238 -65.091413) (xy 68.692616 -65.039418)
			(xy 68.719322 -64.990779) (xy 68.752791 -64.946521) (xy 68.792318 -64.907577) (xy 68.837069 -64.87477)
			(xy 68.8861 -64.84879) (xy 68.938377 -64.830186) (xy 68.992797 -64.819351) (xy 69.048213 -64.816512)
			(xy 69.103456 -64.82173) (xy 69.15736 -64.834895) (xy 69.208789 -64.855728) (xy 69.256658 -64.883791)
			(xy 69.299958 -64.918492) (xy 69.300759 -64.919352) (xy 71.234298 -64.919352) (xy 71.238369 -64.86373)
			(xy 71.250495 -64.809293) (xy 71.270418 -64.757202) (xy 71.297714 -64.708567) (xy 71.3318 -64.664424)
			(xy 71.371949 -64.625715) (xy 71.417307 -64.593264) (xy 71.466907 -64.567763) (xy 71.519691 -64.549756)
			(xy 71.574534 -64.539626) (xy 71.630268 -64.537589) (xy 71.685705 -64.543689) (xy 71.739662 -64.557795)
			(xy 71.790991 -64.579607) (xy 71.838597 -64.608661) (xy 71.881465 -64.644336) (xy 71.918682 -64.685873)
			(xy 71.949455 -64.732386) (xy 71.973127 -64.782883) (xy 71.989195 -64.83629) (xy 71.997315 -64.891466)
			(xy 71.997824 -64.919352) (xy 71.997315 -64.947238) (xy 71.989195 -65.002414) (xy 71.973127 -65.055821)
			(xy 71.949455 -65.106318) (xy 71.918682 -65.152831) (xy 71.881465 -65.194368) (xy 71.838597 -65.230043)
			(xy 71.790991 -65.259097) (xy 71.739662 -65.280909) (xy 71.685705 -65.295015) (xy 71.630268 -65.301115)
			(xy 71.574534 -65.299078) (xy 71.519691 -65.288948) (xy 71.466907 -65.270941) (xy 71.417307 -65.24544)
			(xy 71.371949 -65.212989) (xy 71.3318 -65.17428) (xy 71.297714 -65.130137) (xy 71.270418 -65.081502)
			(xy 71.250495 -65.029411) (xy 71.238369 -64.974974) (xy 71.234298 -64.919352) (xy 69.300759 -64.919352)
			(xy 69.337774 -64.959099) (xy 69.36931 -65.004755) (xy 69.3939 -65.054497) (xy 69.411027 -65.107277)
			(xy 69.420327 -65.161981) (xy 69.421606 -65.217454) (xy 69.414836 -65.272528) (xy 69.40016 -65.326041)
			(xy 69.389498 -65.35166) (xy 69.381266 -65.371611) (xy 69.370893 -65.413501) (xy 69.367748 -65.456541)
			(xy 69.371921 -65.499494) (xy 69.383292 -65.541124) (xy 69.401534 -65.580234) (xy 69.426122 -65.615699)
			(xy 69.45635 -65.6465) (xy 69.473572 -65.659508) (xy 69.498454 -65.678096) (xy 69.543443 -65.720915)
			(xy 69.563234 -65.744852) (xy 69.582105 -65.769237) (xy 69.61382 -65.822115) (xy 69.638143 -65.878774)
			(xy 69.654636 -65.938187) (xy 69.662998 -65.999277) (xy 69.663078 -66.060936) (xy 69.6595 -66.091562)
			(xy 69.655067 -66.121269) (xy 69.639416 -66.179259) (xy 69.616309 -66.234701) (xy 69.586144 -66.286641)
			(xy 69.549441 -66.334187) (xy 69.50683 -66.376519) (xy 69.483224 -66.395092) (xy 69.465741 -66.410103)
			(xy 69.435993 -66.445289) (xy 69.413074 -66.485261) (xy 69.397734 -66.528709) (xy 69.390476 -66.574209)
			(xy 69.391538 -66.620273) (xy 69.400884 -66.665392) (xy 69.409056 -66.686938) (xy 69.417958 -66.707152)
			(xy 69.431583 -66.749166) (xy 69.436234 -66.770758) (xy 69.438439 -66.782222) (xy 69.441615 -66.805352)
			(xy 69.442584 -66.816986) (xy 69.442584 -66.817748) (xy 69.442838 -66.821812) (xy 69.44375 -66.839414)
			(xy 69.442735 -66.87465) (xy 69.440806 -66.89217) (xy 69.437504 -66.91884) (xy 69.452998 -66.969894)
			(xy 69.539866 -67.070732) (xy 69.579744 -67.08013) (xy 69.600064 -67.085464) (xy 69.633338 -67.096386)
			(xy 69.638164 -67.098164) (xy 69.660262 -67.107816) (xy 69.766942 -67.107816) (xy 69.845936 -67.059048)
			(xy 69.861938 -67.031108) (xy 69.8627 -67.029838) (xy 69.867526 -67.022218) (xy 69.883654 -66.998412)
			(xy 69.92191 -66.955484) (xy 69.966173 -66.918781) (xy 70.015442 -66.889134) (xy 70.068601 -66.867215)
			(xy 70.124447 -66.853518) (xy 70.181715 -66.848355) (xy 70.23911 -66.851843) (xy 70.295332 -66.863901)
			(xy 70.349109 -66.884258) (xy 70.399223 -66.912452) (xy 70.44454 -66.947846) (xy 70.46468 -66.96837)
			(xy 70.48722 -66.973237) (xy 70.533265 -66.975671) (xy 70.57899 -66.969743) (xy 70.622892 -66.955648)
			(xy 70.663523 -66.933851) (xy 70.68185 -66.919856) (xy 70.772528 -66.919856) (xy 70.797166 -66.908934)
			(xy 70.82388 -66.897724) (xy 70.879801 -66.882597) (xy 70.937365 -66.876091) (xy 70.96633 -66.876676)
			(xy 70.988001 -66.877097) (xy 71.030973 -66.871445) (xy 71.072364 -66.858588) (xy 71.110975 -66.838898)
			(xy 71.145688 -66.812946) (xy 71.175498 -66.781484) (xy 71.19954 -66.745422) (xy 71.217119 -66.705805)
			(xy 71.22287 -66.684906) (xy 71.230236 -66.655696) (xy 71.233303 -66.645269) (xy 71.240292 -66.624687)
			(xy 71.244206 -66.614548) (xy 71.257632 -66.582297) (xy 71.292835 -66.521959) (xy 71.31431 -66.494406)
			(xy 71.34225 -66.459862) (xy 71.342758 -66.369946) (xy 71.314564 -66.334894) (xy 71.308468 -66.32702)
			(xy 71.295607 -66.309538) (xy 71.264943 -66.27883) (xy 71.229506 -66.253779) (xy 71.190327 -66.235116)
			(xy 71.148546 -66.223383) (xy 71.105379 -66.218921) (xy 71.062082 -66.22186) (xy 71.019914 -66.232115)
			(xy 70.999858 -66.240406) (xy 70.971328 -66.252205) (xy 70.911887 -66.268894) (xy 70.850743 -66.277443)
			(xy 70.789004 -66.277696) (xy 70.727791 -66.269648) (xy 70.668216 -66.253447) (xy 70.611359 -66.229385)
			(xy 70.558251 -66.1979) (xy 70.509857 -66.159563) (xy 70.467055 -66.115069) (xy 70.430621 -66.065226)
			(xy 70.401217 -66.010939) (xy 70.379376 -65.953192) (xy 70.365494 -65.893034) (xy 70.359824 -65.831556)
			(xy 70.362469 -65.769873) (xy 70.37338 -65.709106) (xy 70.382384 -65.679574) (xy 70.392049 -65.651241)
			(xy 70.417721 -65.597159) (xy 70.450223 -65.546886) (xy 70.489002 -65.501278) (xy 70.533394 -65.461114)
			(xy 70.582643 -65.42708) (xy 70.635909 -65.399755) (xy 70.692282 -65.379608) (xy 70.7508 -65.36698)
			(xy 70.810465 -65.362088) (xy 70.870258 -65.365016) (xy 70.92916 -65.375712) (xy 70.986165 -65.393996)
			(xy 71.0403 -65.419554) (xy 71.090641 -65.45195) (xy 71.136331 -65.490633) (xy 71.176588 -65.534941)
			(xy 71.210725 -65.584118) (xy 71.224902 -65.610486) (xy 71.237198 -65.631161) (xy 71.268275 -65.66787)
			(xy 71.305707 -65.698072) (xy 71.348155 -65.720688) (xy 71.394102 -65.73491) (xy 71.441904 -65.740227)
			(xy 71.489852 -65.736452) (xy 71.513192 -65.730628) (xy 71.539899 -65.723814) (xy 71.594599 -65.717052)
			(xy 71.649704 -65.718231) (xy 71.704064 -65.727327) (xy 71.756551 -65.74415) (xy 71.80607 -65.768351)
			(xy 71.851592 -65.799425) (xy 71.892169 -65.836727) (xy 71.926956 -65.879479) (xy 71.955229 -65.926791)
			(xy 71.9764 -65.97768) (xy 71.990028 -66.031085) (xy 71.99583 -66.085895) (xy 71.993684 -66.14097)
			(xy 71.983636 -66.195163) (xy 71.965895 -66.247347) (xy 71.953882 -66.272156) (xy 71.947532 -66.284602)
			(xy 71.931784 -66.345054) (xy 71.973948 -66.43878) (xy 71.990966 -66.455544) (xy 72.016874 -66.48323)
			(xy 72.032114 -66.502026) (xy 72.038972 -66.510916) (xy 72.054212 -66.52914) (xy 72.09024 -66.560098)
			(xy 72.131392 -66.583824) (xy 72.176235 -66.59949) (xy 72.223209 -66.606552) (xy 72.270676 -66.604764)
			(xy 72.316985 -66.594187) (xy 72.360523 -66.57519) (xy 72.399773 -66.548435) (xy 72.416924 -66.531998)
			(xy 72.608186 -66.340736) (xy 72.623649 -66.324596) (xy 72.649225 -66.287944) (xy 72.668 -66.247385)
			(xy 72.679395 -66.204169) (xy 72.683059 -66.159626) (xy 72.678879 -66.115128) (xy 72.666985 -66.072046)
			(xy 72.647742 -66.031707) (xy 72.621743 -65.995354) (xy 72.589789 -65.964105) (xy 72.57161 -65.9511)
			(xy 72.544892 -65.934171) (xy 72.496906 -65.892972) (xy 72.456352 -65.844439) (xy 72.439784 -65.817496)
			(xy 72.426874 -65.794585) (xy 72.406776 -65.745989) (xy 72.393541 -65.695093) (xy 72.387419 -65.642862)
			(xy 72.388526 -65.590285) (xy 72.392286 -65.564258) (xy 72.396951 -65.538036) (xy 72.412596 -65.487127)
			(xy 72.435164 -65.438886) (xy 72.464217 -65.394249) (xy 72.499193 -65.354084) (xy 72.539411 -65.31917)
			(xy 72.584091 -65.290183) (xy 72.632366 -65.267688) (xy 72.683299 -65.252121) (xy 72.709532 -65.24752)
			(xy 72.726804 -65.245234) (xy 72.7498 -65.242155) (xy 72.794209 -65.228739) (xy 72.835446 -65.207486)
			(xy 72.87214 -65.179101) (xy 72.903073 -65.144527) (xy 72.927217 -65.104914) (xy 72.94377 -65.061576)
			(xy 72.952182 -65.015954) (xy 72.95261 -64.992758) (xy 72.95261 -64.054228) (xy 72.952119 -64.03757)
			(xy 72.943503 -64.005389) (xy 72.92685 -63.976534) (xy 72.903296 -63.952973) (xy 72.874447 -63.936312)
			(xy 72.842268 -63.927686) (xy 72.82561 -63.927228) (xy 72.553576 -63.927228) (xy 72.319388 -64.161416)
			(xy 72.299776 -64.18034) (xy 72.256148 -64.213) (xy 72.208315 -64.239119) (xy 72.157253 -64.258164)
			(xy 72.104 -64.269748) (xy 72.04964 -64.273636) (xy 71.99528 -64.269748) (xy 71.942027 -64.258164)
			(xy 71.890965 -64.239119) (xy 71.843132 -64.213) (xy 71.799504 -64.18034) (xy 71.760968 -64.141804)
			(xy 71.728308 -64.098176) (xy 71.702189 -64.050343) (xy 71.683144 -63.999281) (xy 71.67156 -63.946028)
			(xy 71.667672 -63.891668) (xy 71.67156 -63.837308) (xy 71.683144 -63.784055) (xy 71.702189 -63.732993)
			(xy 71.728308 -63.68516) (xy 71.760968 -63.641532) (xy 71.779892 -63.62192) (xy 72.2376 -63.164212)
			(xy 72.245982 -63.164212) (xy 72.402446 -63.007748) (xy 72.607932 -63.007748) (xy 72.617875 -63.007575)
			(xy 72.637524 -63.004514) (xy 72.647048 -63.001652) (xy 73.071736 -63.001652) (xy 73.1266 -62.946788)
			(xy 73.1266 -62.479428) (xy 72.987408 -62.340236) (xy 72.612758 -62.340236) (xy 72.586543 -62.338803)
			(xy 72.534847 -62.329643) (xy 72.484892 -62.313495) (xy 72.437616 -62.290661) (xy 72.393911 -62.261571)
			(xy 72.354599 -62.226773) (xy 72.337168 -62.20714) (xy 72.320239 -62.191149) (xy 72.281713 -62.165001)
			(xy 72.23907 -62.146302) (xy 72.193737 -62.135675) (xy 72.147227 -62.133476) (xy 72.101094 -62.139778)
			(xy 72.056877 -62.154371) (xy 72.016055 -62.176767) (xy 71.979991 -62.206219) (xy 71.96455 -62.22365)
			(xy 71.945114 -62.245791) (xy 71.900608 -62.28439) (xy 71.850689 -62.315675) (xy 71.823834 -62.32779)
			(xy 71.797926 -62.337696) (xy 71.789544 -62.34049) (xy 71.774516 -62.345144) (xy 71.74387 -62.352264)
			(xy 71.72833 -62.354714) (xy 71.68134 -62.361572) (xy 71.619872 -62.432946) (xy 71.619872 -62.910212)
			(xy 71.619425 -62.940089) (xy 71.612052 -62.999386) (xy 71.59742 -63.057321) (xy 71.575753 -63.113008)
			(xy 71.547382 -63.165597) (xy 71.51274 -63.214285) (xy 71.492872 -63.236602) (xy 71.492872 -63.29172)
			(xy 71.435722 -63.29172) (xy 71.403972 -63.312802) (xy 71.377492 -63.329755) (xy 71.321023 -63.35741)
			(xy 71.261444 -63.377504) (xy 71.199761 -63.389698) (xy 71.137018 -63.393786) (xy 71.074275 -63.389698)
			(xy 71.012592 -63.377504) (xy 70.953013 -63.35741) (xy 70.896544 -63.329755) (xy 70.870064 -63.312802)
			(xy 70.838314 -63.29172) (xy 70.781164 -63.29172) (xy 70.781164 -63.236602) (xy 70.761298 -63.214282)
			(xy 70.726651 -63.165599) (xy 70.698277 -63.113011) (xy 70.676611 -63.057323) (xy 70.661984 -62.999387)
			(xy 70.65462 -62.940089) (xy 70.654164 -62.910212) (xy 70.654164 -62.682882) (xy 70.360286 -62.389004)
			(xy 70.338284 -62.366271) (xy 70.299771 -62.316079) (xy 70.268138 -62.26129) (xy 70.243927 -62.20284)
			(xy 70.227553 -62.141731) (xy 70.219295 -62.079007) (xy 70.219295 -62.015741) (xy 70.227553 -61.953017)
			(xy 70.243927 -61.891908) (xy 70.268138 -61.833458) (xy 70.299771 -61.778669) (xy 70.338284 -61.728477)
			(xy 70.383019 -61.683742) (xy 70.433211 -61.645229) (xy 70.488 -61.613596) (xy 70.54645 -61.589385)
			(xy 70.607559 -61.573011) (xy 70.670283 -61.564753) (xy 70.733549 -61.564753) (xy 70.796273 -61.573011)
			(xy 70.857382 -61.589385) (xy 70.915832 -61.613596) (xy 70.970621 -61.645229) (xy 71.020813 -61.683742)
			(xy 71.043546 -61.705744) (xy 71.044562 -61.707014) (xy 71.060371 -61.722208) (xy 71.096207 -61.747468)
			(xy 71.135848 -61.766199) (xy 71.178117 -61.777846) (xy 71.221757 -61.782061) (xy 71.265473 -61.778719)
			(xy 71.307966 -61.76792) (xy 71.347974 -61.749985) (xy 71.384307 -61.725446) (xy 71.400416 -61.71057)
			(xy 71.40702 -61.703966) (xy 71.419466 -61.692282) (xy 71.438256 -61.67608) (xy 71.47928 -61.648175)
			(xy 71.501254 -61.636656) (xy 71.526121 -61.624651) (xy 71.578488 -61.607134) (xy 71.632832 -61.597347)
			(xy 71.68802 -61.595496) (xy 71.742898 -61.60162) (xy 71.79632 -61.615589) (xy 71.847171 -61.637112)
			(xy 71.894389 -61.665741) (xy 71.936987 -61.700876) (xy 71.955914 -61.720984) (xy 71.97209 -61.737651)
			(xy 72.009344 -61.765378) (xy 72.051018 -61.785872) (xy 72.095723 -61.798447) (xy 72.141969 -61.802686)
			(xy 72.188215 -61.798447) (xy 72.23292 -61.785872) (xy 72.274594 -61.765378) (xy 72.311848 -61.737651)
			(xy 72.328024 -61.720984) (xy 72.346189 -61.698949) (xy 72.387951 -61.660001) (xy 72.435046 -61.627706)
			(xy 72.486425 -61.602782) (xy 72.540942 -61.585786) (xy 72.597381 -61.577096) (xy 72.654486 -61.576906)
			(xy 72.710982 -61.585221) (xy 72.765611 -61.601855) (xy 72.817154 -61.626437) (xy 72.841104 -61.64199)
			(xy 72.873362 -61.663834) (xy 73.479914 -61.663834) (xy 73.509378 -61.646816) (xy 73.533001 -61.633784)
			(xy 73.5831 -61.61377) (xy 73.6092 -61.606938) (xy 73.64189 -61.599706) (xy 73.708702 -61.595494)
			(xy 73.742042 -61.598556) (xy 73.773079 -61.6027) (xy 73.833309 -61.619809) (xy 73.889929 -61.646539)
			(xy 73.916032 -61.663834) (xy 73.941432 -61.682884) (xy 73.941686 -61.683138) (xy 73.954048 -61.692642)
			(xy 73.982262 -61.705902) (xy 74.012849 -61.711921) (xy 74.043983 -61.710341) (xy 74.073803 -61.701256)
			(xy 74.10053 -61.685209) (xy 74.111866 -61.674502) (xy 74.930254 -60.856114) (xy 74.930254 -44.240196)
			(xy 74.401172 -43.711114) (xy 69.153786 -43.397678) (xy 58.88228 -40.545004) (xy 55.098442 -40.545004)
			(xy 53.59908 -42.044366) (xy 53.59908 -43.757088) (xy 53.61178 -43.769788) (xy 53.61178 -54.13629)
			(xy 52.696618 -55.051452) (xy 52.696618 -59.460892) (xy 52.697112 -59.477547) (xy 52.705732 -59.509721)
			(xy 52.722387 -59.538567) (xy 52.745941 -59.56212) (xy 52.774788 -59.578772) (xy 52.806963 -59.58739)
			(xy 52.823618 -59.587892) (xy 53.398166 -59.587892) (xy 53.47081 -59.521852) (xy 53.475382 -59.473084)
			(xy 53.47589 -59.469274) (xy 53.47843 -59.454796) (xy 53.480569 -59.444128) (xy 53.485904 -59.423033)
			(xy 53.489098 -59.412632) (xy 53.497589 -59.387181) (xy 53.520708 -59.338766) (xy 53.550372 -59.294061)
			(xy 53.567838 -59.273694) (xy 53.581475 -59.256414) (xy 53.603203 -59.218133) (xy 53.61801 -59.176681)
			(xy 53.625455 -59.133298) (xy 53.625314 -59.089282) (xy 53.617593 -59.045947) (xy 53.602521 -59.004591)
			(xy 53.580549 -58.96645) (xy 53.552335 -58.932664) (xy 53.535834 -58.918094) (xy 53.51284 -58.897991)
			(xy 53.471857 -58.852707) (xy 53.43726 -58.802376) (xy 53.409661 -58.747892) (xy 53.389553 -58.690221)
			(xy 53.377292 -58.630389) (xy 53.373095 -58.569457) (xy 53.377037 -58.508509) (xy 53.389048 -58.448626)
			(xy 53.408916 -58.390872) (xy 53.436286 -58.336272) (xy 53.470673 -58.285797) (xy 53.511467 -58.240342)
			(xy 53.557942 -58.200715) (xy 53.609274 -58.16762) (xy 53.66455 -58.141644) (xy 53.72279 -58.123249)
			(xy 53.782958 -58.112761) (xy 53.813456 -58.111136) (xy 53.842806 -58.110448) (xy 53.901282 -58.115653)
			(xy 53.958614 -58.12829) (xy 54.013859 -58.148153) (xy 54.066112 -58.174915) (xy 54.114515 -58.208138)
			(xy 54.158274 -58.247275) (xy 54.196671 -58.291686) (xy 54.229075 -58.340641) (xy 54.254954 -58.393337)
			(xy 54.273885 -58.448908) (xy 54.285557 -58.506444) (xy 54.289777 -58.565) (xy 54.287888 -58.598558)
			(xy 54.695072 -58.598558) (xy 54.695072 -58.538622) (xy 54.702895 -58.4792) (xy 54.718408 -58.421307)
			(xy 54.741344 -58.365934) (xy 54.771311 -58.314028) (xy 54.807798 -58.266478) (xy 54.850178 -58.224098)
			(xy 54.897728 -58.187611) (xy 54.949634 -58.157644) (xy 55.005007 -58.134708) (xy 55.0629 -58.119195)
			(xy 55.122322 -58.111372) (xy 55.182258 -58.111372) (xy 55.24168 -58.119195) (xy 55.299573 -58.134708)
			(xy 55.354946 -58.157644) (xy 55.406852 -58.187611) (xy 55.454402 -58.224098) (xy 55.496782 -58.266478)
			(xy 55.533269 -58.314028) (xy 55.563236 -58.365934) (xy 55.586172 -58.421307) (xy 55.601685 -58.4792)
			(xy 55.609508 -58.538622) (xy 55.609998 -58.56859) (xy 55.609508 -58.598558) (xy 55.601685 -58.65798)
			(xy 55.586172 -58.715873) (xy 55.563236 -58.771246) (xy 55.533269 -58.823152) (xy 55.496782 -58.870702)
			(xy 55.454402 -58.913082) (xy 55.406852 -58.949569) (xy 55.354946 -58.979536) (xy 55.299573 -59.002472)
			(xy 55.24168 -59.017985) (xy 55.182258 -59.025808) (xy 55.122322 -59.025808) (xy 55.0629 -59.017985)
			(xy 55.005007 -59.002472) (xy 54.949634 -58.979536) (xy 54.897728 -58.949569) (xy 54.850178 -58.913082)
			(xy 54.807798 -58.870702) (xy 54.771311 -58.823152) (xy 54.741344 -58.771246) (xy 54.718408 -58.715873)
			(xy 54.702895 -58.65798) (xy 54.695072 -58.598558) (xy 54.287888 -58.598558) (xy 54.286477 -58.623615)
			(xy 54.275711 -58.681327) (xy 54.257655 -58.737189) (xy 54.24551 -58.763916) (xy 54.232148 -58.791098)
			(xy 54.199297 -58.841985) (xy 54.160001 -58.888076) (xy 54.137814 -58.908696) (xy 54.122535 -58.924185)
			(xy 54.096979 -58.959392) (xy 54.077794 -58.998438) (xy 54.065542 -59.040182) (xy 54.060581 -59.083403)
			(xy 54.063056 -59.126837) (xy 54.072894 -59.169214) (xy 54.089808 -59.209296) (xy 54.113303 -59.24591)
			(xy 54.127654 -59.262264) (xy 54.141878 -59.277758) (xy 54.154473 -59.292722) (xy 54.176865 -59.324792)
			(xy 54.186582 -59.341766) (xy 54.197896 -59.362881) (xy 54.215721 -59.407347) (xy 54.227829 -59.453697)
			(xy 54.231286 -59.477402) (xy 54.237636 -59.5249) (xy 54.309264 -59.587892) (xy 56.595772 -59.587892)
			(xy 56.775604 -59.767724) (xy 56.780684 -59.772804) (xy 56.801766 -59.793886) (xy 56.887872 -59.879738)
			(xy 56.887872 -60.469272) (xy 56.888373 -60.49191) (xy 56.896404 -60.536468) (xy 56.9122 -60.5789)
			(xy 56.93526 -60.617863) (xy 56.964856 -60.652127) (xy 57.000052 -60.680608) (xy 57.039737 -60.702405)
			(xy 57.082653 -60.716829) (xy 57.127447 -60.723425) (xy 57.1727 -60.721984) (xy 57.216983 -60.712551)
			(xy 57.238138 -60.704476) (xy 57.260683 -60.693837) (xy 57.307901 -60.677846) (xy 57.356801 -60.668143)
			(xy 57.381648 -60.666122) (xy 57.403356 -60.663143) (xy 57.445366 -60.650709) (xy 57.484622 -60.631253)
			(xy 57.519959 -60.605353) (xy 57.55033 -60.573775) (xy 57.574835 -60.537457) (xy 57.592748 -60.497474)
			(xy 57.603538 -60.455011) (xy 57.605676 -60.433204) (xy 57.605676 -60.009786) (xy 57.603442 -59.987343)
			(xy 57.592068 -59.943705) (xy 57.573174 -59.902757) (xy 57.547354 -59.865784) (xy 57.515418 -59.833945)
			(xy 57.478365 -59.808238) (xy 57.43736 -59.78947) (xy 57.393686 -59.77823) (xy 57.371234 -59.776106)
			(xy 57.341619 -59.773341) (xy 57.28341 -59.761117) (xy 57.227274 -59.741456) (xy 57.174158 -59.71469)
			(xy 57.124955 -59.681269) (xy 57.080496 -59.641758) (xy 57.041529 -59.596821) (xy 57.00871 -59.547215)
			(xy 56.982593 -59.493777) (xy 56.963617 -59.437405) (xy 56.952102 -59.379051) (xy 56.948243 -59.319698)
			(xy 56.952103 -59.260344) (xy 56.963618 -59.20199) (xy 56.982595 -59.145619) (xy 57.008713 -59.092181)
			(xy 57.041532 -59.042575) (xy 57.080499 -58.997639) (xy 57.124959 -58.958128) (xy 57.174162 -58.924708)
			(xy 57.227279 -58.897942) (xy 57.283415 -58.878282) (xy 57.341624 -58.866058) (xy 57.371234 -58.86323)
			(xy 57.393675 -58.861051) (xy 57.43733 -58.849791) (xy 57.478318 -58.831016) (xy 57.515356 -58.805312)
			(xy 57.547287 -58.773485) (xy 57.573109 -58.736529) (xy 57.592016 -58.695602) (xy 57.603416 -58.651984)
			(xy 57.605676 -58.62955) (xy 57.605676 -56.575452) (xy 57.520332 -56.490108) (xy 57.263284 -56.490108)
			(xy 57.263284 -55.220362) (xy 57.26303 -55.220362) (xy 57.26303 -54.711346) (xy 58.775346 -54.711346)
			(xy 58.775346 -55.474362) (xy 58.775092 -55.474362) (xy 58.775092 -56.490108) (xy 58.673238 -56.490108)
			(xy 58.655888 -56.492305) (xy 58.62328 -56.504907) (xy 58.595296 -56.52586) (xy 58.587267 -56.536332)
			(xy 64.69175 -56.536332) (xy 64.69175 -56.476396) (xy 64.699573 -56.416974) (xy 64.715086 -56.359081)
			(xy 64.738022 -56.303708) (xy 64.767989 -56.251802) (xy 64.804476 -56.204252) (xy 64.846856 -56.161872)
			(xy 64.894406 -56.125385) (xy 64.946312 -56.095418) (xy 65.001685 -56.072482) (xy 65.059578 -56.056969)
			(xy 65.119 -56.049146) (xy 65.178936 -56.049146) (xy 65.238358 -56.056969) (xy 65.296251 -56.072482)
			(xy 65.351624 -56.095418) (xy 65.40353 -56.125385) (xy 65.45108 -56.161872) (xy 65.49346 -56.204252)
			(xy 65.529947 -56.251802) (xy 65.559914 -56.303708) (xy 65.58285 -56.359081) (xy 65.598363 -56.416974)
			(xy 65.606186 -56.476396) (xy 65.606676 -56.506364) (xy 65.606186 -56.536332) (xy 65.598363 -56.595754)
			(xy 65.58285 -56.653647) (xy 65.559914 -56.70902) (xy 65.529947 -56.760926) (xy 65.49346 -56.808476)
			(xy 65.45108 -56.850856) (xy 65.40353 -56.887343) (xy 65.351624 -56.91731) (xy 65.296251 -56.940246)
			(xy 65.238358 -56.955759) (xy 65.178936 -56.963582) (xy 65.119 -56.963582) (xy 65.059578 -56.955759)
			(xy 65.001685 -56.940246) (xy 64.946312 -56.91731) (xy 64.894406 -56.887343) (xy 64.846856 -56.850856)
			(xy 64.804476 -56.808476) (xy 64.767989 -56.760926) (xy 64.738022 -56.70902) (xy 64.715086 -56.653647)
			(xy 64.699573 -56.595754) (xy 64.69175 -56.536332) (xy 58.587267 -56.536332) (xy 58.574024 -56.553603)
			(xy 58.561049 -56.586066) (xy 58.558684 -56.603392) (xy 58.558684 -58.587524) (xy 64.114329 -58.587524)
			(xy 64.115579 -58.528809) (xy 64.124327 -58.470737) (xy 64.14043 -58.41426) (xy 64.163623 -58.360306)
			(xy 64.193525 -58.309761) (xy 64.229645 -58.263455) (xy 64.271391 -58.222148) (xy 64.318076 -58.186519)
			(xy 64.368934 -58.157153) (xy 64.395858 -58.145426) (xy 64.415789 -58.136599) (xy 64.452534 -58.113155)
			(xy 64.484742 -58.083788) (xy 64.511469 -58.049357) (xy 64.531934 -58.010873) (xy 64.545535 -57.969463)
			(xy 64.551875 -57.92634) (xy 64.550767 -57.882767) (xy 64.542245 -57.840022) (xy 64.526557 -57.799356)
			(xy 64.515746 -57.780428) (xy 64.502049 -57.756548) (xy 64.480801 -57.705765) (xy 64.467074 -57.652455)
			(xy 64.461151 -57.597726) (xy 64.463157 -57.542714) (xy 64.473049 -57.488561) (xy 64.490622 -57.436392)
			(xy 64.51551 -57.387291) (xy 64.547198 -57.342278) (xy 64.585027 -57.302286) (xy 64.628211 -57.268147)
			(xy 64.675854 -57.240569) (xy 64.726966 -57.220126) (xy 64.780486 -57.207242) (xy 64.835302 -57.202184)
			(xy 64.890275 -57.205057) (xy 64.944265 -57.215803) (xy 64.99615 -57.234197) (xy 65.044852 -57.259858)
			(xy 65.08936 -57.292252) (xy 65.12875 -57.330708) (xy 65.162203 -57.374425) (xy 65.189025 -57.422498)
			(xy 65.208659 -57.473926) (xy 65.220697 -57.527642) (xy 65.224888 -57.582531) (xy 65.221147 -57.637453)
			(xy 65.209551 -57.691266) (xy 65.19034 -57.742854) (xy 65.163914 -57.791145) (xy 65.130821 -57.835136)
			(xy 65.091749 -57.873914) (xy 65.047508 -57.906673) (xy 65.023492 -57.920128) (xy 65.004479 -57.930836)
			(xy 64.970126 -57.957735) (xy 64.940872 -57.990107) (xy 64.917579 -58.027001) (xy 64.900931 -58.067332)
			(xy 64.891418 -58.109914) (xy 64.889319 -58.153495) (xy 64.894696 -58.196794) (xy 64.907391 -58.238538)
			(xy 64.927031 -58.2775) (xy 64.939672 -58.295286) (xy 64.956786 -58.319042) (xy 64.985373 -58.370141)
			(xy 65.007211 -58.424468) (xy 65.021945 -58.481136) (xy 65.029334 -58.53922) (xy 65.029257 -58.597772)
			(xy 65.021717 -58.655837) (xy 65.006835 -58.712466) (xy 64.984856 -58.766736) (xy 64.956136 -58.817761)
			(xy 64.921146 -58.864708) (xy 64.880457 -58.906811) (xy 64.857884 -58.92546) (xy 64.839761 -58.940593)
			(xy 64.808957 -58.97637) (xy 64.785283 -59.017217) (xy 64.769552 -59.06173) (xy 64.762304 -59.108381)
			(xy 64.763789 -59.155569) (xy 64.773954 -59.201672) (xy 64.792451 -59.245109) (xy 64.818645 -59.284387)
			(xy 64.83477 -59.301634) (xy 64.853485 -59.32143) (xy 64.885639 -59.365406) (xy 64.91121 -59.413509)
			(xy 64.929678 -59.464759) (xy 64.940668 -59.518116) (xy 64.943956 -59.572494) (xy 64.939475 -59.626786)
			(xy 64.927316 -59.679889) (xy 64.907727 -59.730722) (xy 64.881106 -59.778252) (xy 64.847994 -59.821511)
			(xy 64.809065 -59.859619) (xy 64.765111 -59.891803) (xy 64.717025 -59.917406) (xy 64.665787 -59.935909)
			(xy 64.612437 -59.946935) (xy 64.558062 -59.950259) (xy 64.503767 -59.945814) (xy 64.450656 -59.933691)
			(xy 64.39981 -59.914136) (xy 64.352262 -59.887546) (xy 64.308981 -59.854463) (xy 64.270846 -59.81556)
			(xy 64.238633 -59.771627) (xy 64.212998 -59.723559) (xy 64.194461 -59.672333) (xy 64.183399 -59.618991)
			(xy 64.180039 -59.564618) (xy 64.184447 -59.51032) (xy 64.196535 -59.457201) (xy 64.216056 -59.406341)
			(xy 64.242613 -59.358776) (xy 64.275667 -59.315473) (xy 64.294766 -59.296046) (xy 64.31121 -59.27911)
			(xy 64.338213 -59.240398) (xy 64.357601 -59.197366) (xy 64.368709 -59.151493) (xy 64.371154 -59.104358)
			(xy 64.364852 -59.057582) (xy 64.35002 -59.012774) (xy 64.327168 -58.971477) (xy 64.297082 -58.93511)
			(xy 64.279272 -58.919618) (xy 64.256949 -58.900537) (xy 64.217 -58.857491) (xy 64.182883 -58.80969)
			(xy 64.155159 -58.757919) (xy 64.134283 -58.703026) (xy 64.120598 -58.645916) (xy 64.114329 -58.587524)
			(xy 58.558684 -58.587524) (xy 58.558684 -58.851546) (xy 58.560912 -58.874301) (xy 58.572494 -58.918528)
			(xy 58.59179 -58.959975) (xy 58.618179 -58.997308) (xy 58.650813 -59.029327) (xy 58.688641 -59.055002)
			(xy 58.730447 -59.073506) (xy 58.774886 -59.084245) (xy 58.820529 -59.086873) (xy 58.865907 -59.081305)
			(xy 58.90956 -59.067721) (xy 58.930032 -59.05754) (xy 58.956157 -59.042138) (xy 59.011619 -59.017605)
			(xy 59.069836 -59.000613) (xy 59.129787 -58.99146) (xy 59.190422 -58.990306) (xy 59.250678 -58.997172)
			(xy 59.309499 -59.011937) (xy 59.365855 -59.034343) (xy 59.418756 -59.063997) (xy 59.467277 -59.100379)
			(xy 59.510567 -59.142851) (xy 59.547868 -59.19067) (xy 59.578525 -59.242996) (xy 59.602001 -59.298914)
			(xy 59.617885 -59.357443) (xy 59.625899 -59.417557) (xy 59.625901 -59.478203) (xy 59.617893 -59.538318)
			(xy 59.602014 -59.596848) (xy 59.578543 -59.652768) (xy 59.54789 -59.705098) (xy 59.510594 -59.752919)
			(xy 59.467308 -59.795396) (xy 59.41879 -59.831782) (xy 59.36589 -59.86144) (xy 59.309537 -59.883851)
			(xy 59.250717 -59.898621) (xy 59.190462 -59.905492) (xy 59.129827 -59.904344) (xy 59.069875 -59.895196)
			(xy 59.011656 -59.878209) (xy 58.956192 -59.85368) (xy 58.930032 -59.838336) (xy 58.909531 -59.828231)
			(xy 58.865885 -59.814684) (xy 58.820522 -59.809143) (xy 58.774898 -59.811786) (xy 58.730478 -59.822527)
			(xy 58.688687 -59.841022) (xy 58.650867 -59.866677) (xy 58.618232 -59.898668) (xy 58.591829 -59.93597)
			(xy 58.572506 -59.977384) (xy 58.560882 -60.021582) (xy 58.558684 -60.04433) (xy 58.558684 -60.330334)
			(xy 58.560836 -60.352207) (xy 58.567439 -60.378098) (xy 61.127368 -60.378098) (xy 61.127368 -60.31813)
			(xy 61.135196 -60.258674) (xy 61.150717 -60.200749) (xy 61.173666 -60.145345) (xy 61.20365 -60.093411)
			(xy 61.240156 -60.045835) (xy 61.282561 -60.00343) (xy 61.330137 -59.966924) (xy 61.382071 -59.93694)
			(xy 61.437475 -59.913991) (xy 61.4954 -59.89847) (xy 61.554856 -59.890642) (xy 61.614824 -59.890642)
			(xy 61.67428 -59.89847) (xy 61.732205 -59.913991) (xy 61.787609 -59.93694) (xy 61.839543 -59.966924)
			(xy 61.887119 -60.00343) (xy 61.929524 -60.045835) (xy 61.96603 -60.093411) (xy 61.996014 -60.145345)
			(xy 62.010559 -60.18046) (xy 65.137355 -60.18046) (xy 65.141111 -60.12513) (xy 65.152837 -60.070927)
			(xy 65.172287 -60.018992) (xy 65.199051 -59.970421) (xy 65.232565 -59.926236) (xy 65.272123 -59.887368)
			(xy 65.316891 -59.854637) (xy 65.365926 -59.828732) (xy 65.418195 -59.810199) (xy 65.472596 -59.799428)
			(xy 65.527983 -59.796647) (xy 65.58319 -59.801914) (xy 65.637052 -59.815117) (xy 65.688436 -59.83598)
			(xy 65.736257 -59.864061) (xy 65.77951 -59.89877) (xy 65.817282 -59.939376) (xy 65.848777 -59.985021)
			(xy 65.873332 -60.034746) (xy 65.890429 -60.087502) (xy 65.899709 -60.142177) (xy 65.900976 -60.19762)
			(xy 65.894202 -60.252662) (xy 65.887346 -60.279534) (xy 65.881913 -60.301067) (xy 65.877772 -60.34528)
			(xy 65.881384 -60.389539) (xy 65.89264 -60.432495) (xy 65.911195 -60.472839) (xy 65.936484 -60.50934)
			(xy 65.967737 -60.540887) (xy 66.004 -60.566517) (xy 66.044169 -60.585448) (xy 66.087018 -60.597105)
			(xy 66.109088 -60.599574) (xy 66.138954 -60.602733) (xy 66.197536 -60.615965) (xy 66.253885 -60.636744)
			(xy 66.307033 -60.664713) (xy 66.356067 -60.699392) (xy 66.400145 -60.740186) (xy 66.43851 -60.786393)
			(xy 66.470502 -60.837221) (xy 66.495573 -60.891796) (xy 66.513292 -60.949181) (xy 66.523354 -61.00839)
			(xy 66.525587 -61.068407) (xy 66.519952 -61.1282) (xy 66.506546 -61.186743) (xy 66.4856 -61.24303)
			(xy 66.457473 -61.296095) (xy 66.422648 -61.345025) (xy 66.381723 -61.388981) (xy 66.335401 -61.427208)
			(xy 66.284479 -61.45905) (xy 66.229829 -61.483958) (xy 66.172392 -61.501506) (xy 66.113153 -61.511392)
			(xy 66.05313 -61.513446) (xy 65.993354 -61.507633) (xy 65.934851 -61.494053) (xy 65.878626 -61.47294)
			(xy 65.825646 -61.444655) (xy 65.776819 -61.409684) (xy 65.732985 -61.368629) (xy 65.694896 -61.322194)
			(xy 65.663207 -61.271176) (xy 65.638461 -61.216453) (xy 65.621084 -61.158964) (xy 65.611374 -61.099696)
			(xy 65.609499 -61.039667) (xy 65.615489 -60.979908) (xy 65.629243 -60.921446) (xy 65.639442 -60.893198)
			(xy 65.646886 -60.872274) (xy 65.655186 -60.828648) (xy 65.655772 -60.784244) (xy 65.648627 -60.740414)
			(xy 65.633968 -60.698495) (xy 65.612243 -60.659764) (xy 65.584112 -60.625402) (xy 65.550435 -60.596455)
			(xy 65.512236 -60.573807) (xy 65.47068 -60.558147) (xy 65.448942 -60.5536) (xy 65.421786 -60.547969)
			(xy 65.36934 -60.529945) (xy 65.320055 -60.504519) (xy 65.27497 -60.472225) (xy 65.235036 -60.433745)
			(xy 65.201093 -60.389888) (xy 65.173858 -60.34158) (xy 65.153903 -60.289837) (xy 65.141649 -60.235751)
			(xy 65.137355 -60.18046) (xy 62.010559 -60.18046) (xy 62.018963 -60.200749) (xy 62.034484 -60.258674)
			(xy 62.042312 -60.31813) (xy 62.042802 -60.348114) (xy 62.042312 -60.378098) (xy 62.034484 -60.437554)
			(xy 62.018963 -60.495479) (xy 61.996014 -60.550883) (xy 61.96603 -60.602817) (xy 61.929524 -60.650393)
			(xy 61.887119 -60.692798) (xy 61.839543 -60.729304) (xy 61.787609 -60.759288) (xy 61.732205 -60.782237)
			(xy 61.67428 -60.797758) (xy 61.614824 -60.805586) (xy 61.554856 -60.805586) (xy 61.4954 -60.797758)
			(xy 61.437475 -60.782237) (xy 61.382071 -60.759288) (xy 61.330137 -60.729304) (xy 61.282561 -60.692798)
			(xy 61.240156 -60.650393) (xy 61.20365 -60.602817) (xy 61.173666 -60.550883) (xy 61.150717 -60.495479)
			(xy 61.135196 -60.437554) (xy 61.127368 -60.378098) (xy 58.567439 -60.378098) (xy 58.571697 -60.394792)
			(xy 58.589718 -60.434875) (xy 58.614363 -60.471263) (xy 58.644897 -60.502872) (xy 58.680411 -60.52876)
			(xy 58.719848 -60.548156) (xy 58.762032 -60.560483) (xy 58.805707 -60.565373) (xy 58.82767 -60.564522)
			(xy 58.858058 -60.56325) (xy 58.918711 -60.567783) (xy 58.978229 -60.580309) (xy 59.035564 -60.600607)
			(xy 59.089706 -60.628319) (xy 59.139701 -60.662956) (xy 59.184669 -60.70391) (xy 59.223818 -60.750457)
			(xy 59.256457 -60.80178) (xy 59.282013 -60.856972) (xy 59.300034 -60.915063) (xy 59.310203 -60.975028)
			(xy 59.312342 -61.035813) (xy 59.306707 -61.093346) (xy 64.164954 -61.093346) (xy 64.164954 -61.03341)
			(xy 64.172777 -60.973988) (xy 64.18829 -60.916095) (xy 64.211226 -60.860722) (xy 64.241193 -60.808816)
			(xy 64.27768 -60.761266) (xy 64.32006 -60.718886) (xy 64.36761 -60.682399) (xy 64.419516 -60.652432)
			(xy 64.474889 -60.629496) (xy 64.532782 -60.613983) (xy 64.592204 -60.60616) (xy 64.65214 -60.60616)
			(xy 64.711562 -60.613983) (xy 64.769455 -60.629496) (xy 64.824828 -60.652432) (xy 64.876734 -60.682399)
			(xy 64.924284 -60.718886) (xy 64.966664 -60.761266) (xy 65.003151 -60.808816) (xy 65.033118 -60.860722)
			(xy 65.056054 -60.916095) (xy 65.071567 -60.973988) (xy 65.07939 -61.03341) (xy 65.07988 -61.063378)
			(xy 65.07939 -61.093346) (xy 65.071567 -61.152768) (xy 65.056054 -61.210661) (xy 65.033118 -61.266034)
			(xy 65.003151 -61.31794) (xy 64.966664 -61.36549) (xy 64.924284 -61.40787) (xy 64.876734 -61.444357)
			(xy 64.824828 -61.474324) (xy 64.769455 -61.49726) (xy 64.711562 -61.512773) (xy 64.65214 -61.520596)
			(xy 64.592204 -61.520596) (xy 64.532782 -61.512773) (xy 64.474889 -61.49726) (xy 64.419516 -61.474324)
			(xy 64.36761 -61.444357) (xy 64.32006 -61.40787) (xy 64.27768 -61.36549) (xy 64.241193 -61.31794)
			(xy 64.211226 -61.266034) (xy 64.18829 -61.210661) (xy 64.172777 -61.152768) (xy 64.164954 -61.093346)
			(xy 59.306707 -61.093346) (xy 59.306413 -61.096345) (xy 59.292519 -61.155558) (xy 59.270906 -61.212411)
			(xy 59.241955 -61.2659) (xy 59.206175 -61.315084) (xy 59.185556 -61.337444) (xy 59.170834 -61.353541)
			(xy 59.146571 -61.389789) (xy 59.128854 -61.429648) (xy 59.118205 -61.471947) (xy 59.114935 -61.515443)
			(xy 59.119142 -61.558858) (xy 59.1307 -61.600918) (xy 59.149272 -61.640386) (xy 59.161426 -61.6585)
			(xy 59.169763 -61.670059) (xy 59.184892 -61.694214) (xy 59.191652 -61.70676) (xy 59.204525 -61.732251)
			(xy 59.223392 -61.786148) (xy 59.234016 -61.842254) (xy 59.236161 -61.899317) (xy 59.229779 -61.956063)
			(xy 59.215012 -62.011224) (xy 59.212652 -62.016636) (xy 59.667122 -62.016636) (xy 59.667122 -61.9567)
			(xy 59.674945 -61.897278) (xy 59.690458 -61.839385) (xy 59.713394 -61.784012) (xy 59.743361 -61.732106)
			(xy 59.779848 -61.684556) (xy 59.822228 -61.642176) (xy 59.869778 -61.605689) (xy 59.921684 -61.575722)
			(xy 59.977057 -61.552786) (xy 60.03495 -61.537273) (xy 60.094372 -61.52945) (xy 60.12434 -61.52896)
			(xy 60.154308 -61.52945) (xy 60.21373 -61.537273) (xy 60.271623 -61.552786) (xy 60.326996 -61.575722)
			(xy 60.378902 -61.605689) (xy 60.426452 -61.642176) (xy 60.468832 -61.684556) (xy 60.505319 -61.732106)
			(xy 60.535286 -61.784012) (xy 60.558222 -61.839385) (xy 60.573735 -61.897278) (xy 60.581558 -61.9567)
			(xy 60.581558 -62.016636) (xy 60.573735 -62.076058) (xy 60.558222 -62.133951) (xy 60.535286 -62.189324)
			(xy 60.505319 -62.24123) (xy 60.468832 -62.28878) (xy 60.426452 -62.33116) (xy 60.378902 -62.367647)
			(xy 60.326996 -62.397614) (xy 60.271623 -62.42055) (xy 60.21373 -62.436063) (xy 60.154308 -62.443886)
			(xy 60.094372 -62.443886) (xy 60.03495 -62.436063) (xy 59.977057 -62.42055) (xy 59.921684 -62.397614)
			(xy 59.869778 -62.367647) (xy 59.822228 -62.33116) (xy 59.779848 -62.28878) (xy 59.743361 -62.24123)
			(xy 59.713394 -62.189324) (xy 59.690458 -62.133951) (xy 59.674945 -62.076058) (xy 59.667122 -62.016636)
			(xy 59.212652 -62.016636) (xy 59.192189 -62.063569) (xy 59.177428 -62.088014) (xy 59.162233 -62.111293)
			(xy 59.126169 -62.153599) (xy 59.084344 -62.190219) (xy 59.037645 -62.220377) (xy 58.987062 -62.243436)
			(xy 58.933667 -62.258904) (xy 58.878592 -62.266456) (xy 58.823003 -62.26593) (xy 58.768081 -62.257338)
			(xy 58.714988 -62.240862) (xy 58.66485 -62.216851) (xy 58.61873 -62.185814) (xy 58.5978 -62.167516)
			(xy 58.576634 -62.14756) (xy 58.540007 -62.102368) (xy 58.510675 -62.052135) (xy 58.499502 -62.025276)
			(xy 58.48985 -62.000638) (xy 58.418984 -61.929772) (xy 58.135012 -61.929772) (xy 57.622948 -61.417708)
			(xy 57.554368 -61.40069) (xy 57.520586 -61.411104) (xy 57.506108 -61.415168) (xy 57.479184 -61.421518)
			(xy 57.445673 -61.427231) (xy 57.377707 -61.428119) (xy 57.344056 -61.423296) (xy 57.307734 -61.415422)
			(xy 57.298072 -61.412747) (xy 57.279012 -61.40652) (xy 57.269634 -61.402976) (xy 57.238138 -61.38926)
			(xy 57.216995 -61.381139) (xy 57.172706 -61.371678) (xy 57.127442 -61.370218) (xy 57.082636 -61.376804)
			(xy 57.039706 -61.391227) (xy 57.000013 -61.413031) (xy 56.964813 -61.441525) (xy 56.93522 -61.475807)
			(xy 56.912173 -61.514792) (xy 56.8964 -61.557244) (xy 56.888402 -61.60182) (xy 56.887872 -61.624464)
			(xy 56.887872 -61.96076) (xy 56.971946 -62.045088) (xy 56.971946 -62.361572) (xy 56.972437 -62.378227)
			(xy 56.981055 -62.410403) (xy 56.997709 -62.43925) (xy 57.021264 -62.462802) (xy 57.050114 -62.479452)
			(xy 57.082291 -62.488065) (xy 57.098946 -62.488572) (xy 58.326528 -62.488572) (xy 58.642504 -62.804294)
			(xy 58.88228 -63.04407) (xy 58.88228 -63.09868) (xy 58.89879 -63.12789) (xy 58.912986 -63.153827)
			(xy 58.935319 -63.208575) (xy 58.950416 -63.265743) (xy 58.958025 -63.324379) (xy 58.958019 -63.383507)
			(xy 58.950399 -63.442142) (xy 58.935292 -63.499308) (xy 58.912948 -63.554051) (xy 58.89879 -63.58001)
			(xy 58.88228 -63.60922) (xy 58.88228 -64.255396) (xy 59.203336 -64.576706) (xy 59.203336 -65.61201)
			(xy 59.217814 -65.639696) (xy 59.224672 -65.653412) (xy 59.239912 -65.686432) (xy 59.33059 -65.745614)
			(xy 59.743594 -65.745614) (xy 59.755024 -65.73393) (xy 59.755024 -64.986154) (xy 59.906154 -64.835024)
			(xy 60.025026 -64.716406) (xy 60.038234 -64.703198) (xy 60.053531 -64.686184) (xy 60.078357 -64.647757)
			(xy 60.095903 -64.605507) (xy 60.105603 -64.560799) (xy 60.107143 -64.515076) (xy 60.104274 -64.492378)
			(xy 60.080381 -64.471626) (xy 60.039151 -64.423619) (xy 60.022232 -64.396874) (xy 60.009972 -64.375807)
			(xy 59.990303 -64.331209) (xy 59.976459 -64.284474) (xy 59.972194 -64.260476) (xy 59.9682 -64.232442)
			(xy 59.967556 -64.17582) (xy 59.975289 -64.119726) (xy 59.99123 -64.065391) (xy 60.015028 -64.014009)
			(xy 60.04616 -63.96671) (xy 60.06465 -63.945262) (xy 60.075269 -63.93256) (xy 60.090211 -63.90303)
			(xy 60.097066 -63.870653) (xy 60.095375 -63.837602) (xy 60.085251 -63.806093) (xy 60.067375 -63.778242)
			(xy 60.055506 -63.7667) (xy 60.032174 -63.744673) (xy 59.991286 -63.695222) (xy 59.957705 -63.640545)
			(xy 59.932089 -63.581715) (xy 59.91494 -63.519884) (xy 59.906594 -63.456263) (xy 59.907214 -63.392101)
			(xy 59.911488 -63.3603) (xy 59.917047 -63.327481) (xy 59.936411 -63.263797) (xy 59.964797 -63.203591)
			(xy 60.001605 -63.148132) (xy 60.04606 -63.09859) (xy 60.071254 -63.076836) (xy 60.093908 -63.05857)
			(xy 60.142994 -63.027308) (xy 60.195644 -63.002517) (xy 60.251011 -62.984597) (xy 60.308203 -62.973836)
			(xy 60.366297 -62.970408) (xy 60.395358 -62.971934) (xy 60.418016 -62.97219) (xy 60.462849 -62.965639)
			(xy 60.505808 -62.951239) (xy 60.545532 -62.929447) (xy 60.580759 -62.900953) (xy 60.610372 -62.866661)
			(xy 60.633433 -62.82766) (xy 60.649209 -62.785187) (xy 60.6572 -62.740589) (xy 60.65774 -62.717934)
			(xy 60.65774 -62.545468) (xy 60.78474 -62.418468) (xy 60.85078 -62.418468) (xy 60.867435 -62.417976)
			(xy 60.899611 -62.409357) (xy 60.928458 -62.392703) (xy 60.95201 -62.369148) (xy 60.968662 -62.340299)
			(xy 60.977277 -62.308123) (xy 60.97778 -62.291468) (xy 60.97778 -62.28461) (xy 61.001148 -62.28461)
			(xy 61.017793 -62.284061) (xy 61.049945 -62.275435) (xy 61.078771 -62.258784) (xy 61.102307 -62.235241)
			(xy 61.11895 -62.20641) (xy 61.127566 -62.174255) (xy 61.128148 -62.15761) (xy 61.128148 -61.144404)
			(xy 62.640464 -61.144404) (xy 62.640464 -62.496192) (xy 62.68974 -62.545468) (xy 62.68974 -63.87719)
			(xy 62.690234 -63.893844) (xy 62.698854 -63.926016) (xy 62.715509 -63.95486) (xy 62.739063 -63.978409)
			(xy 62.767912 -63.995058) (xy 62.800086 -64.00367) (xy 62.81674 -64.00419) (xy 63.23838 -64.00419)
			(xy 63.255036 -64.003698) (xy 63.287214 -63.99508) (xy 63.316064 -63.978426) (xy 63.33962 -63.954872)
			(xy 63.356276 -63.926023) (xy 63.364896 -63.893846) (xy 63.36538 -63.87719) (xy 63.36538 -63.10122)
			(xy 63.356744 -63.10122) (xy 63.356744 -62.742318) (xy 63.35649 -62.738762) (xy 63.356032 -62.729115)
			(xy 63.356035 -62.709801) (xy 63.35649 -62.700154) (xy 63.356744 -62.696598) (xy 63.356744 -62.338712)
			(xy 64.068452 -62.338712) (xy 64.068452 -62.457587) (xy 65.110022 -62.457587) (xy 65.114341 -62.392767)
			(xy 65.127218 -62.329092) (xy 65.148425 -62.267687) (xy 65.177589 -62.209638) (xy 65.19545 -62.182502)
			(xy 65.217548 -62.14999) (xy 65.217548 -62.101476) (xy 65.264792 -62.101476) (xy 65.287498 -62.080867)
			(xy 65.337131 -62.044855) (xy 65.390881 -62.01534) (xy 65.447905 -61.992788) (xy 65.507303 -61.977554)
			(xy 65.568142 -61.969876) (xy 65.598802 -61.969396) (xy 66.255392 -61.969396) (xy 66.272024 -61.968797)
			(xy 66.304139 -61.960126) (xy 66.332923 -61.943451) (xy 66.345054 -61.932058) (xy 67.085464 -61.191648)
			(xy 68.370196 -61.191648) (xy 68.386198 -61.207904) (xy 68.398326 -61.219318) (xy 68.427138 -61.235998)
			(xy 68.459285 -61.244656) (xy 68.492577 -61.2447) (xy 68.524747 -61.236129) (xy 68.553604 -61.219526)
			(xy 68.565776 -61.208158) (xy 68.58508 -61.189108) (xy 68.594732 -61.163962) (xy 68.605076 -61.138686)
			(xy 68.631932 -61.091131) (xy 68.665291 -61.047889) (xy 68.704472 -61.009842) (xy 68.748675 -60.977767)
			(xy 68.796998 -60.952318) (xy 68.82257 -60.942728) (xy 68.836497 -60.9373) (xy 68.861552 -60.921016)
			(xy 68.882138 -60.899357) (xy 68.897128 -60.873507) (xy 68.905701 -60.844881) (xy 68.907389 -60.815047)
			(xy 68.902098 -60.785638) (xy 68.896484 -60.771786) (xy 68.884038 -60.739528) (xy 68.878669 -60.725133)
			(xy 68.862173 -60.699228) (xy 68.839964 -60.678015) (xy 68.813328 -60.662726) (xy 68.783811 -60.654245)
			(xy 68.753122 -60.653065) (xy 68.737988 -60.655708) (xy 68.708314 -60.661281) (xy 68.648086 -60.66552)
			(xy 68.587824 -60.661803) (xy 68.528573 -60.650196) (xy 68.471363 -60.630899) (xy 68.417186 -60.604248)
			(xy 68.366984 -60.570705) (xy 68.321628 -60.530853) (xy 68.281904 -60.485384) (xy 68.248504 -60.435087)
			(xy 68.222007 -60.380835) (xy 68.202873 -60.32357) (xy 68.191434 -60.264287) (xy 68.187888 -60.204014)
			(xy 68.192298 -60.143798) (xy 68.204586 -60.084685) (xy 68.22454 -60.027701) (xy 68.251812 -59.973834)
			(xy 68.28593 -59.924021) (xy 68.326301 -59.879126) (xy 68.372225 -59.839929) (xy 68.422903 -59.80711)
			(xy 68.477456 -59.781239) (xy 68.534937 -59.762764) (xy 68.594348 -59.752008) (xy 68.654658 -59.749156)
			(xy 68.714819 -59.754258) (xy 68.773787 -59.767226) (xy 68.830538 -59.787834) (xy 68.884087 -59.815725)
			(xy 68.933504 -59.850413) (xy 68.977931 -59.891298) (xy 69.016598 -59.93767) (xy 69.048832 -59.988722)
			(xy 69.074074 -60.043569) (xy 69.091885 -60.101259) (xy 69.097398 -60.130944) (xy 69.100403 -60.145985)
			(xy 69.112616 -60.174111) (xy 69.131186 -60.198512) (xy 69.155041 -60.217778) (xy 69.182804 -60.230797)
			(xy 69.212871 -60.236815) (xy 69.228208 -60.236608) (xy 69.256305 -60.235776) (xy 69.312225 -60.241508)
			(xy 69.366699 -60.255381) (xy 69.418549 -60.277094) (xy 69.466653 -60.306178) (xy 69.50997 -60.342003)
			(xy 69.547564 -60.383795) (xy 69.578621 -60.43065) (xy 69.580887 -60.435486) (xy 70.449676 -60.435486)
			(xy 70.449676 -60.37555) (xy 70.457499 -60.316128) (xy 70.473012 -60.258235) (xy 70.495948 -60.202862)
			(xy 70.525915 -60.150956) (xy 70.562402 -60.103406) (xy 70.604782 -60.061026) (xy 70.652332 -60.024539)
			(xy 70.704238 -59.994572) (xy 70.759611 -59.971636) (xy 70.817504 -59.956123) (xy 70.876926 -59.9483)
			(xy 70.936862 -59.9483) (xy 70.996284 -59.956123) (xy 71.054177 -59.971636) (xy 71.10955 -59.994572)
			(xy 71.161456 -60.024539) (xy 71.209006 -60.061026) (xy 71.251386 -60.103406) (xy 71.287873 -60.150956)
			(xy 71.31784 -60.202862) (xy 71.340776 -60.258235) (xy 71.356289 -60.316128) (xy 71.364112 -60.37555)
			(xy 71.364602 -60.405518) (xy 71.364112 -60.435486) (xy 71.356289 -60.494908) (xy 71.340776 -60.552801)
			(xy 71.31784 -60.608174) (xy 71.287873 -60.66008) (xy 71.251386 -60.70763) (xy 71.209006 -60.75001)
			(xy 71.161456 -60.786497) (xy 71.10955 -60.816464) (xy 71.054177 -60.8394) (xy 70.996284 -60.854913)
			(xy 70.936862 -60.862736) (xy 70.876926 -60.862736) (xy 70.817504 -60.854913) (xy 70.759611 -60.8394)
			(xy 70.704238 -60.816464) (xy 70.652332 -60.786497) (xy 70.604782 -60.75001) (xy 70.562402 -60.70763)
			(xy 70.525915 -60.66008) (xy 70.495948 -60.608174) (xy 70.473012 -60.552801) (xy 70.457499 -60.494908)
			(xy 70.449676 -60.435486) (xy 69.580887 -60.435486) (xy 69.602469 -60.481553) (xy 69.618592 -60.535404)
			(xy 69.626641 -60.591037) (xy 69.626443 -60.64725) (xy 69.618002 -60.702825) (xy 69.601499 -60.756561)
			(xy 69.577293 -60.807295) (xy 69.545907 -60.853929) (xy 69.508019 -60.895455) (xy 69.46445 -60.930974)
			(xy 69.440552 -60.945776) (xy 69.421311 -60.957884) (xy 69.387036 -60.987738) (xy 69.358616 -61.023211)
			(xy 69.336958 -61.063174) (xy 69.322753 -61.106351) (xy 69.316453 -61.151367) (xy 69.31826 -61.196785)
			(xy 69.322696 -61.21908) (xy 69.328723 -61.248874) (xy 69.332374 -61.309548) (xy 69.326362 -61.370034)
			(xy 69.310837 -61.428801) (xy 69.286194 -61.484365) (xy 69.270118 -61.510164) (xy 69.25827 -61.529331)
			(xy 69.240732 -61.570831) (xy 69.230784 -61.614773) (xy 69.228736 -61.65978) (xy 69.234654 -61.704444)
			(xy 69.248353 -61.747365) (xy 69.269402 -61.787199) (xy 69.297143 -61.8227) (xy 69.330707 -61.852755)
			(xy 69.34962 -61.865002) (xy 69.372683 -61.879693) (xy 69.414661 -61.914738) (xy 69.451206 -61.955417)
			(xy 69.481567 -62.000898) (xy 69.505123 -62.050248) (xy 69.521391 -62.102456) (xy 69.530038 -62.156452)
			(xy 69.530886 -62.211129) (xy 69.523919 -62.265367) (xy 69.509278 -62.318054) (xy 69.487264 -62.368111)
			(xy 69.458328 -62.414512) (xy 69.423063 -62.456305) (xy 69.382191 -62.492635) (xy 69.336551 -62.522756)
			(xy 69.287078 -62.546052) (xy 69.234785 -62.562045) (xy 69.180745 -62.570408) (xy 69.126064 -62.570968)
			(xy 69.071863 -62.563715) (xy 69.019254 -62.548797) (xy 68.969314 -62.52652) (xy 68.923066 -62.49734)
			(xy 68.881459 -62.461855) (xy 68.845345 -62.420794) (xy 68.815464 -62.374996) (xy 68.80352 -62.350396)
			(xy 68.796676 -62.336572) (xy 68.777359 -62.312529) (xy 68.752828 -62.293836) (xy 68.724522 -62.281591)
			(xy 68.694102 -62.276512) (xy 68.663353 -62.278897) (xy 68.64858 -62.28334) (xy 68.621878 -62.291745)
			(xy 68.567143 -62.303501) (xy 68.511472 -62.3094) (xy 68.48348 -62.309756) (xy 68.431918 -62.309756)
			(xy 68.416313 -62.310133) (xy 68.386028 -62.317668) (xy 68.358483 -62.332341) (xy 68.335332 -62.353269)
			(xy 68.317964 -62.379199) (xy 68.307421 -62.408573) (xy 68.305426 -62.424056) (xy 68.305426 -62.42431)
			(xy 68.303394 -62.441582) (xy 68.304431 -62.464419) (xy 68.313553 -62.509207) (xy 68.330535 -62.551643)
			(xy 68.35483 -62.59036) (xy 68.385655 -62.624109) (xy 68.422017 -62.651803) (xy 68.462745 -62.672551)
			(xy 68.484496 -62.67958) (xy 68.511375 -62.688149) (xy 68.562426 -62.712161) (xy 68.609385 -62.743428)
			(xy 68.651229 -62.781268) (xy 68.687045 -62.824856) (xy 68.716054 -62.873243) (xy 68.737622 -62.925373)
			(xy 68.75128 -62.980111) (xy 68.75673 -63.036264) (xy 68.753853 -63.092606) (xy 68.742711 -63.147911)
			(xy 68.723549 -63.200973) (xy 68.696782 -63.250635) (xy 68.662996 -63.295816) (xy 68.622926 -63.335529)
			(xy 68.577445 -63.36891) (xy 68.527545 -63.39523) (xy 68.474314 -63.413917) (xy 68.418911 -63.424563)
			(xy 68.362545 -63.426936) (xy 68.306444 -63.420984) (xy 68.27901 -63.414402) (xy 68.255679 -63.408951)
			(xy 68.207874 -63.405856) (xy 68.160336 -63.411769) (xy 68.114746 -63.426481) (xy 68.072718 -63.449471)
			(xy 68.035739 -63.479925) (xy 68.005118 -63.516766) (xy 67.981938 -63.55869) (xy 67.973956 -63.58128)
			(xy 67.964919 -63.607386) (xy 67.94031 -63.656848) (xy 67.908824 -63.702243) (xy 67.871119 -63.742621)
			(xy 67.827985 -63.777139) (xy 67.780323 -63.805073) (xy 67.729129 -63.825841) (xy 67.675476 -63.839007)
			(xy 67.620484 -63.844297) (xy 67.565305 -63.841599) (xy 67.511092 -63.830971) (xy 67.458979 -63.812633)
			(xy 67.410055 -63.786971) (xy 67.365345 -63.75452) (xy 67.325784 -63.715959) (xy 67.292198 -63.672095)
			(xy 67.26529 -63.623846) (xy 67.245623 -63.57222) (xy 67.233609 -63.518296) (xy 67.229498 -63.463204)
			(xy 67.233377 -63.408095) (xy 67.245164 -63.354122) (xy 67.264613 -63.302413) (xy 67.291318 -63.254051)
			(xy 67.324719 -63.210046) (xy 67.364117 -63.171319) (xy 67.40869 -63.13868) (xy 67.457505 -63.112812)
			(xy 67.509541 -63.094255) (xy 67.563709 -63.083399) (xy 67.618876 -63.080469) (xy 67.67389 -63.085527)
			(xy 67.727598 -63.098467) (xy 67.778878 -63.119019) (xy 67.803014 -63.132462) (xy 67.817322 -63.140173)
			(xy 67.848646 -63.148809) (xy 67.881136 -63.149273) (xy 67.912694 -63.141533) (xy 67.92722 -63.13424)
			(xy 67.956684 -63.118238) (xy 67.99199 -63.06185) (xy 67.993514 -63.028576) (xy 67.994125 -63.017794)
			(xy 67.996414 -62.996319) (xy 67.998086 -62.98565) (xy 68.000156 -62.96965) (xy 67.997174 -62.93754)
			(xy 67.986239 -62.907201) (xy 67.968049 -62.880572) (xy 67.943765 -62.859352) (xy 67.914937 -62.844896)
			(xy 67.883406 -62.838128) (xy 67.867276 -62.83833) (xy 67.837217 -62.839115) (xy 67.77732 -62.833828)
			(xy 67.718624 -62.820769) (xy 67.662136 -62.800162) (xy 67.60882 -62.772358) (xy 67.559589 -62.737833)
			(xy 67.515285 -62.697179) (xy 67.476666 -62.65109) (xy 67.460114 -62.625986) (xy 67.445243 -62.609921)
			(xy 67.41103 -62.582617) (xy 67.372641 -62.561585) (xy 67.331214 -62.547448) (xy 67.287977 -62.540624)
			(xy 67.24421 -62.541317) (xy 67.222624 -62.54496) (xy 67.020694 -62.74689) (xy 67.000244 -62.776702)
			(xy 66.952459 -62.830954) (xy 66.897712 -62.878171) (xy 66.837029 -62.917467) (xy 66.80454 -62.933326)
			(xy 66.785998 -62.941962) (xy 66.781934 -62.945772) (xy 66.776346 -62.945772) (xy 66.755772 -62.952884)
			(xy 66.722047 -62.964088) (xy 66.652431 -62.978366) (xy 66.581528 -62.983154) (xy 66.510625 -62.978366)
			(xy 66.441009 -62.964088) (xy 66.407284 -62.952884) (xy 66.38671 -62.945772) (xy 65.598802 -62.945772)
			(xy 65.568142 -62.945299) (xy 65.507304 -62.937613) (xy 65.447906 -62.922375) (xy 65.390883 -62.899824)
			(xy 65.337129 -62.870314) (xy 65.287491 -62.834309) (xy 65.264792 -62.813692) (xy 65.217548 -62.813692)
			(xy 65.217548 -62.765178) (xy 65.19545 -62.732666) (xy 65.177576 -62.70554) (xy 65.148415 -62.647488)
			(xy 65.127211 -62.586082) (xy 65.114337 -62.522407) (xy 65.110022 -62.457587) (xy 64.068452 -62.457587)
			(xy 64.068452 -62.572392) (xy 64.077596 -62.581282) (xy 64.077596 -62.931548) (xy 64.078092 -62.954588)
			(xy 64.08639 -62.999914) (xy 64.102723 -63.043001) (xy 64.126557 -63.082438) (xy 64.15711 -63.116932)
			(xy 64.19338 -63.145352) (xy 64.23418 -63.166768) (xy 64.278173 -63.180478) (xy 64.323916 -63.186032)
			(xy 64.369911 -63.183248) (xy 64.414651 -63.172218) (xy 64.456669 -63.153304) (xy 64.494588 -63.127123)
			(xy 64.511174 -63.111126) (xy 64.767968 -63.36792) (xy 64.779906 -63.375286) (xy 64.787526 -63.380366)
			(xy 64.820038 -63.402464) (xy 64.877696 -63.402464) (xy 64.877696 -63.457836) (xy 64.885771 -63.466644)
			(xy 64.901145 -63.48494) (xy 64.90843 -63.494412) (xy 64.913764 -63.501778) (xy 64.92494 -63.518034)
			(xy 64.92875 -63.523876) (xy 64.93637 -63.536322) (xy 65.004696 -63.604648) (xy 65.004696 -64.2112)
			(xy 68.010784 -64.2112) (xy 68.014855 -64.155578) (xy 68.026981 -64.101141) (xy 68.046904 -64.04905)
			(xy 68.0742 -64.000415) (xy 68.108286 -63.956272) (xy 68.148435 -63.917563) (xy 68.193793 -63.885112)
			(xy 68.243393 -63.859611) (xy 68.296177 -63.841604) (xy 68.35102 -63.831474) (xy 68.406754 -63.829437)
			(xy 68.462191 -63.835537) (xy 68.516148 -63.849643) (xy 68.567477 -63.871455) (xy 68.615083 -63.900509)
			(xy 68.657951 -63.936184) (xy 68.695168 -63.977721) (xy 68.725941 -64.024234) (xy 68.749613 -64.074731)
			(xy 68.765681 -64.128138) (xy 68.77297 -64.177668) (xy 69.876398 -64.177668) (xy 69.876398 -64.117732)
			(xy 69.884221 -64.05831) (xy 69.899734 -64.000417) (xy 69.92267 -63.945044) (xy 69.952637 -63.893138)
			(xy 69.989124 -63.845588) (xy 70.031504 -63.803208) (xy 70.079054 -63.766721) (xy 70.13096 -63.736754)
			(xy 70.186333 -63.713818) (xy 70.244226 -63.698305) (xy 70.303648 -63.690482) (xy 70.363584 -63.690482)
			(xy 70.423006 -63.698305) (xy 70.480899 -63.713818) (xy 70.536272 -63.736754) (xy 70.588178 -63.766721)
			(xy 70.635728 -63.803208) (xy 70.678108 -63.845588) (xy 70.714595 -63.893138) (xy 70.744562 -63.945044)
			(xy 70.767498 -64.000417) (xy 70.783011 -64.05831) (xy 70.790834 -64.117732) (xy 70.791324 -64.1477)
			(xy 70.790834 -64.177668) (xy 70.783011 -64.23709) (xy 70.767498 -64.294983) (xy 70.744562 -64.350356)
			(xy 70.714595 -64.402262) (xy 70.678108 -64.449812) (xy 70.635728 -64.492192) (xy 70.588178 -64.528679)
			(xy 70.536272 -64.558646) (xy 70.480899 -64.581582) (xy 70.423006 -64.597095) (xy 70.363584 -64.604918)
			(xy 70.303648 -64.604918) (xy 70.244226 -64.597095) (xy 70.186333 -64.581582) (xy 70.13096 -64.558646)
			(xy 70.079054 -64.528679) (xy 70.031504 -64.492192) (xy 69.989124 -64.449812) (xy 69.952637 -64.402262)
			(xy 69.92267 -64.350356) (xy 69.899734 -64.294983) (xy 69.884221 -64.23709) (xy 69.876398 -64.177668)
			(xy 68.77297 -64.177668) (xy 68.773801 -64.183314) (xy 68.77431 -64.2112) (xy 68.773801 -64.239086)
			(xy 68.765681 -64.294262) (xy 68.749613 -64.347669) (xy 68.725941 -64.398166) (xy 68.695168 -64.444679)
			(xy 68.657951 -64.486216) (xy 68.615083 -64.521891) (xy 68.567477 -64.550945) (xy 68.516148 -64.572757)
			(xy 68.462191 -64.586863) (xy 68.406754 -64.592963) (xy 68.35102 -64.590926) (xy 68.296177 -64.580796)
			(xy 68.243393 -64.562789) (xy 68.193793 -64.537288) (xy 68.148435 -64.504837) (xy 68.108286 -64.466128)
			(xy 68.0742 -64.421985) (xy 68.046904 -64.37335) (xy 68.026981 -64.321259) (xy 68.014855 -64.266822)
			(xy 68.010784 -64.2112) (xy 65.004696 -64.2112) (xy 65.004696 -64.59982) (xy 65.014856 -64.60998)
			(xy 65.014856 -64.667638) (xy 65.017499 -64.692088) (xy 65.030959 -64.739382) (xy 65.053227 -64.783222)
			(xy 65.083479 -64.821987) (xy 65.120595 -64.854241) (xy 65.141602 -64.867028) (xy 65.1685 -64.865881)
			(xy 65.222159 -64.87025) (xy 65.274671 -64.882119) (xy 65.324993 -64.901251) (xy 65.372127 -64.927268)
			(xy 65.415135 -64.959651) (xy 65.453164 -64.997758) (xy 65.485459 -65.040833) (xy 65.511378 -65.08802)
			(xy 65.530407 -65.138381) (xy 65.542168 -65.190917) (xy 65.546427 -65.244585) (xy 65.5431 -65.298319)
			(xy 65.532252 -65.351052) (xy 65.523618 -65.376552) (xy 65.518521 -65.392168) (xy 65.515617 -65.424877)
			(xy 65.521165 -65.457242) (xy 65.534796 -65.487117) (xy 65.555606 -65.512519) (xy 65.568576 -65.522602)
			(xy 65.590836 -65.53928) (xy 65.630792 -65.577975) (xy 65.664794 -65.621992) (xy 65.692143 -65.670426)
			(xy 65.712274 -65.722277) (xy 65.724772 -65.776476) (xy 65.729379 -65.831906) (xy 65.726001 -65.887425)
			(xy 65.714708 -65.941887) (xy 65.695732 -65.994172) (xy 65.669464 -66.043199) (xy 65.636445 -66.08796)
			(xy 65.597357 -66.127531) (xy 65.575434 -66.144648) (xy 65.570066 -66.163957) (xy 65.564784 -66.203684)
			(xy 65.565815 -66.243746) (xy 65.569084 -66.26352) (xy 65.596008 -66.327274) (xy 65.69329 -66.366898)
			(xy 65.782444 -66.329814) (xy 65.798954 -66.314574) (xy 65.824608 -66.292984) (xy 65.847037 -66.276343)
			(xy 65.895793 -66.249106) (xy 65.947999 -66.22927) (xy 66.00254 -66.217259) (xy 66.05825 -66.21333)
			(xy 66.113937 -66.217565) (xy 66.168411 -66.229876) (xy 66.220507 -66.249999) (xy 66.269113 -66.277502)
			(xy 66.29146 -66.294254) (xy 66.300913 -66.301751) (xy 66.318961 -66.317764) (xy 66.327528 -66.326258)
			(xy 66.372994 -66.34353) (xy 66.489326 -66.34353) (xy 66.505974 -66.342984) (xy 66.538133 -66.334362)
			(xy 66.566967 -66.317713) (xy 66.59051 -66.29417) (xy 66.607161 -66.265337) (xy 66.615783 -66.233177)
			(xy 66.616326 -66.21653) (xy 66.616326 -66.187574) (xy 66.591688 -66.135758) (xy 66.569336 -66.117724)
			(xy 66.547702 -66.099545) (xy 66.509517 -66.057894) (xy 66.477895 -66.011065) (xy 66.453527 -65.960083)
			(xy 66.436947 -65.906064) (xy 66.428517 -65.85019) (xy 66.428423 -65.793684) (xy 66.436665 -65.737783)
			(xy 66.453064 -65.683709) (xy 66.477262 -65.632646) (xy 66.508727 -65.585711) (xy 66.546772 -65.543932)
			(xy 66.56832 -65.52565) (xy 66.604134 -65.49644) (xy 66.62166 -65.405254) (xy 66.5988 -65.364614)
			(xy 66.592658 -65.353463) (xy 66.581476 -65.330589) (xy 66.576448 -65.318894) (xy 66.565344 -65.291159)
			(xy 66.549606 -65.233527) (xy 66.541495 -65.174338) (xy 66.541146 -65.114597) (xy 66.548568 -65.055317)
			(xy 66.55562 -65.026286) (xy 66.56406 -64.995991) (xy 66.588114 -64.937884) (xy 66.619897 -64.883617)
			(xy 66.658811 -64.834213) (xy 66.704122 -64.790602) (xy 66.754977 -64.753606) (xy 66.810419 -64.72392)
			(xy 66.869403 -64.702104) (xy 66.930818 -64.68857) (xy 66.993508 -64.683572) (xy 67.056292 -64.687203)
			(xy 67.087242 -64.692784) (xy 67.114651 -64.698611) (xy 67.167898 -64.716068) (xy 67.218613 -64.739899)
			(xy 67.266038 -64.769746) (xy 67.309462 -64.805164) (xy 67.348234 -64.845621) (xy 67.365372 -64.86779)
			(xy 67.378473 -64.884578) (xy 67.409308 -64.913944) (xy 67.444605 -64.937762) (xy 67.483377 -64.955365)
			(xy 67.52454 -64.966263) (xy 67.566943 -64.970149) (xy 67.609401 -64.966915) (xy 67.650727 -64.956652)
			(xy 67.670426 -64.948562) (xy 67.696319 -64.937793) (xy 67.750441 -64.923113) (xy 67.806128 -64.916516)
			(xy 67.862182 -64.918143) (xy 67.917393 -64.92796) (xy 67.970572 -64.945756) (xy 68.020572 -64.971145)
			(xy 68.066316 -65.003583) (xy 68.106817 -65.042368) (xy 68.141204 -65.086665) (xy 68.168733 -65.13552)
			(xy 68.188813 -65.187879) (xy 68.20101 -65.242614) (xy 68.205061 -65.298544) (xy 68.20088 -65.354465)
			(xy 68.188555 -65.409172) (xy 68.168354 -65.461484) (xy 68.140711 -65.510274) (xy 68.106222 -65.554492)
			(xy 68.06563 -65.593182) (xy 68.019811 -65.625513) (xy 67.969752 -65.650786) (xy 67.916532 -65.668458)
			(xy 67.861298 -65.678147) (xy 67.805241 -65.679644) (xy 67.749568 -65.672917) (xy 67.695481 -65.658111)
			(xy 67.644144 -65.635546) (xy 67.596665 -65.605707) (xy 67.554066 -65.569237) (xy 67.517266 -65.526924)
			(xy 67.50177 -65.503552) (xy 67.492799 -65.490469) (xy 67.469619 -65.468828) (xy 67.441819 -65.453571)
			(xy 67.411115 -65.445639) (xy 67.379404 -65.445524) (xy 67.348643 -65.453232) (xy 67.320733 -65.468288)
			(xy 67.30873 -65.47866) (xy 67.294781 -65.491262) (xy 67.265151 -65.514403) (xy 67.249548 -65.524888)
			(xy 67.224148 -65.541398) (xy 67.164204 -65.644776) (xy 67.173602 -65.70726) (xy 67.177666 -65.721992)
			(xy 67.179698 -65.729612) (xy 67.186028 -65.757404) (xy 67.191337 -65.814153) (xy 67.188153 -65.87106)
			(xy 67.176545 -65.926863) (xy 67.156772 -65.98032) (xy 67.129274 -66.030245) (xy 67.112388 -66.053208)
			(xy 67.100581 -66.071413) (xy 67.082693 -66.110941) (xy 67.07178 -66.152933) (xy 67.068161 -66.196169)
			(xy 67.07194 -66.239392) (xy 67.083007 -66.281344) (xy 67.101041 -66.320805) (xy 67.125518 -66.356629)
			(xy 67.140328 -66.372486) (xy 67.152812 -66.385305) (xy 67.175583 -66.41291) (xy 67.185794 -66.427604)
			(xy 67.199814 -66.449018) (xy 67.222625 -66.494837) (xy 67.239122 -66.543289) (xy 67.244468 -66.56832)
			(xy 67.249634 -66.597479) (xy 67.251954 -66.656648) (xy 67.245112 -66.715466) (xy 67.229272 -66.772523)
			(xy 67.217544 -66.799714) (xy 67.207136 -66.82172) (xy 67.181532 -66.863124) (xy 67.16649 -66.882264)
			(xy 67.157032 -66.894629) (xy 67.143857 -66.922825) (xy 67.137906 -66.953373) (xy 67.139532 -66.984452)
			(xy 67.148639 -67.014212) (xy 67.164684 -67.040879) (xy 67.17538 -67.05219) (xy 67.563238 -67.440048)
			(xy 67.568572 -67.444366) (xy 67.591336 -67.463513) (xy 67.631213 -67.507646) (xy 67.663759 -67.557432)
			(xy 67.688185 -67.611666) (xy 67.696588 -67.6402) (xy 67.703646 -67.667977) (xy 67.710318 -67.724899)
			(xy 67.708402 -67.782178) (xy 67.697942 -67.838527) (xy 67.679173 -67.892677) (xy 67.652516 -67.943412)
			(xy 67.618572 -67.98959) (xy 67.578104 -68.030172) (xy 67.555364 -68.047616) (xy 67.53371 -68.063055)
			(xy 67.486976 -68.088432) (xy 67.437173 -68.107081) (xy 67.385264 -68.11864) (xy 67.332253 -68.122886)
			(xy 67.305682 -68.121784) (xy 67.288499 -68.121282) (xy 67.254881 -68.128386) (xy 67.224381 -68.144212)
			(xy 67.199217 -68.167611) (xy 67.181219 -68.196881) (xy 67.175888 -68.213224) (xy 67.172553 -68.224479)
			(xy 67.164675 -68.246593) (xy 67.16014 -68.25742) (xy 67.15633 -68.266056) (xy 67.143213 -68.293268)
			(xy 67.109703 -68.343528) (xy 67.068713 -68.387899) (xy 67.045332 -68.407026) (xy 67.039095 -68.426764)
			(xy 67.032382 -68.467609) (xy 67.032383 -68.509002) (xy 67.039097 -68.549847) (xy 67.045332 -68.569586)
			(xy 67.056861 -68.5788) (xy 67.078606 -68.598759)
		)
		(stroke
			(width 0)
			(type solid)
		)
		(fill yes)
		(layer "B.Cu")
		(net "PV_VDDR_NODE1")
	)
	(gr_poly
		(pts
			(xy 25.15108 -71.766176) (xy 25.15108 -64.662304) (xy 25.113996 -64.601598) (xy 25.082246 -64.585088)
			(xy 25.026568 -64.555915) (xy 24.918582 -64.491555) (xy 24.814836 -64.420562) (xy 24.715736 -64.343215)
			(xy 24.621671 -64.259819) (xy 24.53301 -64.170698) (xy 24.4501 -64.076204) (xy 24.373267 -63.976706)
			(xy 24.302811 -63.872594) (xy 24.239009 -63.764277) (xy 24.182111 -63.652179) (xy 24.132341 -63.53674)
			(xy 24.089892 -63.418413) (xy 24.054932 -63.297661) (xy 24.027598 -63.174958) (xy 24.007997 -63.050784)
			(xy 23.996205 -62.925628) (xy 23.99227 -62.799978) (xy 23.996205 -62.674329) (xy 24.007997 -62.549172)
			(xy 24.027599 -62.424999) (xy 24.054933 -62.302295) (xy 24.089893 -62.181543) (xy 24.132342 -62.063216)
			(xy 24.182113 -61.947777) (xy 24.239011 -61.83568) (xy 24.302813 -61.727363) (xy 24.373269 -61.623252)
			(xy 24.450103 -61.523754) (xy 24.533013 -61.429259) (xy 24.621674 -61.340139) (xy 24.715739 -61.256742)
			(xy 24.814839 -61.179396) (xy 24.918585 -61.108403) (xy 25.026572 -61.044043) (xy 25.082246 -61.014864)
			(xy 25.113996 -60.998354) (xy 25.15108 -60.937648) (xy 25.15108 -60.107576) (xy 25.037796 -59.983624)
			(xy 24.996648 -59.975496) (xy 24.969641 -59.969716) (xy 24.917535 -59.951411) (xy 24.868611 -59.925786)
			(xy 24.823893 -59.893376) (xy 24.784314 -59.854857) (xy 24.750701 -59.811036) (xy 24.723757 -59.762826)
			(xy 24.704043 -59.711236) (xy 24.691973 -59.657343) (xy 24.687799 -59.602273) (xy 24.691607 -59.547176)
			(xy 24.696928 -59.520074) (xy 24.701308 -59.497511) (xy 24.702802 -59.451577) (xy 24.696015 -59.406123)
			(xy 24.681168 -59.362629) (xy 24.658744 -59.322513) (xy 24.629475 -59.28708) (xy 24.594313 -59.257487)
			(xy 24.554405 -59.234695) (xy 24.511049 -59.219449) (xy 24.46566 -59.212244) (xy 24.442674 -59.212226)
			(xy 24.41654 -59.212898) (xy 24.364496 -59.207946) (xy 24.313616 -59.195932) (xy 24.264855 -59.17708)
			(xy 24.219125 -59.151744) (xy 24.177285 -59.1204) (xy 24.140119 -59.083634) (xy 24.123904 -59.063128)
			(xy 24.107406 -59.040793) (xy 24.080362 -58.992298) (xy 24.060635 -58.940395) (xy 24.048641 -58.88618)
			(xy 24.044635 -58.830799) (xy 24.048699 -58.775423) (xy 24.06075 -58.721221) (xy 24.080532 -58.669338)
			(xy 24.107627 -58.620872) (xy 24.124158 -58.598562) (xy 24.141451 -58.57687) (xy 24.181263 -58.538238)
			(xy 24.226251 -58.505779) (xy 24.275465 -58.480177) (xy 24.327867 -58.461973) (xy 24.382354 -58.45155)
			(xy 24.437776 -58.449128) (xy 24.492964 -58.454758) (xy 24.546756 -58.468322) (xy 24.598015 -58.489533)
			(xy 24.645662 -58.517944) (xy 24.688693 -58.552956) (xy 24.726199 -58.59383) (xy 24.757389 -58.639706)
			(xy 24.781607 -58.689615) (xy 24.798342 -58.742506) (xy 24.80724 -58.797262) (xy 24.808114 -58.85273)
			(xy 24.800946 -58.90774) (xy 24.785886 -58.961132) (xy 24.763253 -59.011779) (xy 24.733523 -59.058615)
			(xy 24.715724 -59.079892) (xy 24.705496 -59.092553) (xy 24.691221 -59.121794) (xy 24.684805 -59.153694)
			(xy 24.686666 -59.186179) (xy 24.696681 -59.217138) (xy 24.7142 -59.244558) (xy 24.738084 -59.266655)
			(xy 24.76678 -59.281995) (xy 24.798423 -59.289578) (xy 24.830955 -59.288912) (xy 24.862261 -59.280041)
			(xy 24.876506 -59.27217) (xy 24.90467 -59.256359) (xy 24.965074 -59.233505) (xy 24.996648 -59.226704)
			(xy 25.037796 -59.218576) (xy 25.15108 -59.094624) (xy 25.15108 -57.232042) (xy 25.150581 -57.208983)
			(xy 25.142267 -57.163622) (xy 25.125904 -57.120505) (xy 25.10203 -57.081049) (xy 25.071427 -57.046548)
			(xy 25.035102 -57.018136) (xy 24.994246 -56.996745) (xy 24.950201 -56.983077) (xy 24.904412 -56.977581)
			(xy 24.858384 -56.980438) (xy 24.813626 -56.991553) (xy 24.792432 -57.000648) (xy 24.767449 -57.011394)
			(xy 24.715206 -57.026498) (xy 24.661348 -57.03403) (xy 24.606966 -57.033839) (xy 24.553161 -57.025927)
			(xy 24.501026 -57.010455) (xy 24.451616 -56.987736) (xy 24.405933 -56.958232) (xy 24.364902 -56.922539)
			(xy 24.329355 -56.881382) (xy 24.300013 -56.835594) (xy 24.27747 -56.786104) (xy 24.262183 -56.733914)
			(xy 24.254462 -56.680082) (xy 24.254464 -56.6257) (xy 24.262187 -56.571868) (xy 24.277477 -56.519679)
			(xy 24.300022 -56.47019) (xy 24.329366 -56.424403) (xy 24.364915 -56.383248) (xy 24.405947 -56.347557)
			(xy 24.451632 -56.318055) (xy 24.501043 -56.295339) (xy 24.553179 -56.279869) (xy 24.606984 -56.27196)
			(xy 24.661366 -56.271771) (xy 24.715224 -56.279306) (xy 24.767466 -56.294412) (xy 24.792432 -56.305196)
			(xy 24.813648 -56.314237) (xy 24.858403 -56.325345) (xy 24.904428 -56.328197) (xy 24.950212 -56.322701)
			(xy 24.994254 -56.309037) (xy 25.035109 -56.287653) (xy 25.071437 -56.259251) (xy 25.102046 -56.224762)
			(xy 25.125932 -56.185317) (xy 25.142311 -56.142212) (xy 25.150647 -56.096858) (xy 25.15108 -56.073802)
			(xy 25.15108 -42.179494) (xy 22.796246 -39.82466) (xy 20.663154 -39.82466) (xy 20.640804 -39.825134)
			(xy 20.596795 -39.832961) (xy 20.554833 -39.848365) (xy 20.516213 -39.870873) (xy 20.482125 -39.899789)
			(xy 20.453621 -39.934221) (xy 20.431579 -39.973109) (xy 20.41668 -40.015253) (xy 20.409383 -40.059354)
			(xy 20.409154 -40.081708) (xy 20.409837 -40.109583) (xy 20.404085 -40.165044) (xy 20.390323 -40.219077)
			(xy 20.368844 -40.270531) (xy 20.340106 -40.318313) (xy 20.304719 -40.361403) (xy 20.263439 -40.398884)
			(xy 20.217143 -40.429959) (xy 20.166818 -40.453966) (xy 20.113535 -40.470393) (xy 20.058428 -40.478891)
			(xy 20.002672 -40.479279) (xy 19.947452 -40.471548) (xy 19.893946 -40.455863) (xy 19.843292 -40.432559)
			(xy 19.796568 -40.402131) (xy 19.754771 -40.365227) (xy 19.718789 -40.322633) (xy 19.689388 -40.275256)
			(xy 19.677888 -40.249856) (xy 19.666973 -40.228652) (xy 19.638486 -40.190412) (xy 19.603369 -40.158152)
			(xy 19.562855 -40.133005) (xy 19.518362 -40.115851) (xy 19.471452 -40.107292) (xy 19.423769 -40.107629)
			(xy 19.400266 -40.11168) (xy 19.371965 -40.116789) (xy 19.314592 -40.120736) (xy 19.257176 -40.117464)
			(xy 19.228816 -40.112696) (xy 19.200864 -40.107113) (xy 19.146517 -40.089919) (xy 19.094727 -40.066109)
			(xy 19.046294 -40.036052) (xy 19.001969 -40.000213) (xy 18.962437 -39.959146) (xy 18.928313 -39.913488)
			(xy 18.913856 -39.888922) (xy 18.896838 -39.859204) (xy 18.837656 -39.82466) (xy 11.58875 -39.82466)
			(xy 11.324082 -40.089328) (xy 10.424017 -40.989504) (xy 14.766542 -40.989504) (xy 14.770613 -40.933882)
			(xy 14.782739 -40.879445) (xy 14.802662 -40.827354) (xy 14.829958 -40.778719) (xy 14.864044 -40.734576)
			(xy 14.904193 -40.695867) (xy 14.949551 -40.663416) (xy 14.999151 -40.637915) (xy 15.051935 -40.619908)
			(xy 15.106778 -40.609778) (xy 15.162512 -40.607741) (xy 15.217949 -40.613841) (xy 15.271906 -40.627947)
			(xy 15.323235 -40.649759) (xy 15.370841 -40.678813) (xy 15.413709 -40.714488) (xy 15.450926 -40.756025)
			(xy 15.481699 -40.802538) (xy 15.505371 -40.853035) (xy 15.521439 -40.906442) (xy 15.529559 -40.961618)
			(xy 15.530068 -40.989504) (xy 15.529559 -41.01739) (xy 15.521439 -41.072566) (xy 15.505371 -41.125973)
			(xy 15.481699 -41.17647) (xy 15.450926 -41.222983) (xy 15.413709 -41.26452) (xy 15.370841 -41.300195)
			(xy 15.323235 -41.329249) (xy 15.271906 -41.351061) (xy 15.217949 -41.365167) (xy 15.162512 -41.371267)
			(xy 15.106778 -41.36923) (xy 15.051935 -41.3591) (xy 14.999151 -41.341093) (xy 14.949551 -41.315592)
			(xy 14.904193 -41.283141) (xy 14.864044 -41.244432) (xy 14.829958 -41.200289) (xy 14.802662 -41.151654)
			(xy 14.782739 -41.099563) (xy 14.770613 -41.045126) (xy 14.766542 -40.989504) (xy 10.424017 -40.989504)
			(xy 9.271 -42.142664) (xy 9.271 -42.857987) (xy 9.994378 -42.857987) (xy 9.994378 -42.762365) (xy 10.002274 -42.667069)
			(xy 10.018013 -42.572751) (xy 10.041487 -42.480054) (xy 10.072536 -42.389613) (xy 10.110947 -42.302045)
			(xy 10.156458 -42.217947) (xy 10.208758 -42.137895) (xy 10.267491 -42.062436) (xy 10.332254 -41.992084)
			(xy 10.402606 -41.927321) (xy 10.478065 -41.868588) (xy 10.558117 -41.816288) (xy 10.642215 -41.770777)
			(xy 10.729783 -41.732366) (xy 10.820224 -41.701317) (xy 10.912921 -41.677843) (xy 11.007239 -41.662104)
			(xy 11.102535 -41.654208) (xy 11.198157 -41.654208) (xy 11.293453 -41.662104) (xy 11.387771 -41.677843)
			(xy 11.480468 -41.701317) (xy 11.570909 -41.732366) (xy 11.658477 -41.770777) (xy 11.703593 -41.795192)
			(xy 17.781522 -41.795192) (xy 17.785593 -41.73957) (xy 17.797719 -41.685133) (xy 17.817642 -41.633042)
			(xy 17.844938 -41.584407) (xy 17.879024 -41.540264) (xy 17.919173 -41.501555) (xy 17.964531 -41.469104)
			(xy 18.014131 -41.443603) (xy 18.066915 -41.425596) (xy 18.121758 -41.415466) (xy 18.177492 -41.413429)
			(xy 18.232929 -41.419529) (xy 18.286886 -41.433635) (xy 18.338215 -41.455447) (xy 18.385821 -41.484501)
			(xy 18.428689 -41.520176) (xy 18.465906 -41.561713) (xy 18.496679 -41.608226) (xy 18.520351 -41.658723)
			(xy 18.536419 -41.71213) (xy 18.544539 -41.767306) (xy 18.545048 -41.795192) (xy 18.544539 -41.823078)
			(xy 18.536419 -41.878254) (xy 18.520351 -41.931661) (xy 18.496679 -41.982158) (xy 18.465906 -42.028671)
			(xy 18.428689 -42.070208) (xy 18.385821 -42.105883) (xy 18.338215 -42.134937) (xy 18.286886 -42.156749)
			(xy 18.232929 -42.170855) (xy 18.177492 -42.176955) (xy 18.121758 -42.174918) (xy 18.066915 -42.164788)
			(xy 18.014131 -42.146781) (xy 17.964531 -42.12128) (xy 17.919173 -42.088829) (xy 17.879024 -42.05012)
			(xy 17.844938 -42.005977) (xy 17.817642 -41.957342) (xy 17.797719 -41.905251) (xy 17.785593 -41.850814)
			(xy 17.781522 -41.795192) (xy 11.703593 -41.795192) (xy 11.742575 -41.816288) (xy 11.822627 -41.868588)
			(xy 11.898086 -41.927321) (xy 11.968438 -41.992084) (xy 12.033201 -42.062436) (xy 12.091934 -42.137895)
			(xy 12.144234 -42.217947) (xy 12.189745 -42.302045) (xy 12.228156 -42.389613) (xy 12.259205 -42.480054)
			(xy 12.282679 -42.572751) (xy 12.286313 -42.59453) (xy 17.082006 -42.59453) (xy 17.086077 -42.538908)
			(xy 17.098203 -42.484471) (xy 17.118126 -42.43238) (xy 17.145422 -42.383745) (xy 17.179508 -42.339602)
			(xy 17.219657 -42.300893) (xy 17.265015 -42.268442) (xy 17.314615 -42.242941) (xy 17.367399 -42.224934)
			(xy 17.422242 -42.214804) (xy 17.477976 -42.212767) (xy 17.533413 -42.218867) (xy 17.58737 -42.232973)
			(xy 17.638699 -42.254785) (xy 17.686305 -42.283839) (xy 17.729173 -42.319514) (xy 17.76639 -42.361051)
			(xy 17.797163 -42.407564) (xy 17.820835 -42.458061) (xy 17.836903 -42.511468) (xy 17.845023 -42.566644)
			(xy 17.845532 -42.59453) (xy 17.845023 -42.622416) (xy 17.836903 -42.677592) (xy 17.820835 -42.730999)
			(xy 17.797163 -42.781496) (xy 17.76639 -42.828009) (xy 17.729173 -42.869546) (xy 17.686305 -42.905221)
			(xy 17.638699 -42.934275) (xy 17.58737 -42.956087) (xy 17.533413 -42.970193) (xy 17.477976 -42.976293)
			(xy 17.422242 -42.974256) (xy 17.367399 -42.964126) (xy 17.314615 -42.946119) (xy 17.265015 -42.920618)
			(xy 17.219657 -42.888167) (xy 17.179508 -42.849458) (xy 17.145422 -42.805315) (xy 17.118126 -42.75668)
			(xy 17.098203 -42.704589) (xy 17.086077 -42.650152) (xy 17.082006 -42.59453) (xy 12.286313 -42.59453)
			(xy 12.298418 -42.667069) (xy 12.306314 -42.762365) (xy 12.306808 -42.810176) (xy 12.306314 -42.857987)
			(xy 12.298418 -42.953283) (xy 12.282679 -43.047601) (xy 12.259205 -43.140298) (xy 12.23302 -43.216572)
			(xy 13.815042 -43.216572) (xy 13.815042 -43.156636) (xy 13.822865 -43.097214) (xy 13.838378 -43.039321)
			(xy 13.861314 -42.983948) (xy 13.891281 -42.932042) (xy 13.927768 -42.884492) (xy 13.970148 -42.842112)
			(xy 14.017698 -42.805625) (xy 14.069604 -42.775658) (xy 14.124977 -42.752722) (xy 14.18287 -42.737209)
			(xy 14.242292 -42.729386) (xy 14.302228 -42.729386) (xy 14.36165 -42.737209) (xy 14.419543 -42.752722)
			(xy 14.474916 -42.775658) (xy 14.526822 -42.805625) (xy 14.574372 -42.842112) (xy 14.616752 -42.884492)
			(xy 14.653239 -42.932042) (xy 14.683206 -42.983948) (xy 14.706142 -43.039321) (xy 14.721655 -43.097214)
			(xy 14.729478 -43.156636) (xy 14.729968 -43.186604) (xy 14.729478 -43.216572) (xy 14.721655 -43.275994)
			(xy 14.706142 -43.333887) (xy 14.683206 -43.38926) (xy 14.653239 -43.441166) (xy 14.616752 -43.488716)
			(xy 14.574372 -43.531096) (xy 14.526822 -43.567583) (xy 14.474916 -43.59755) (xy 14.419543 -43.620486)
			(xy 14.36165 -43.635999) (xy 14.302228 -43.643822) (xy 14.242292 -43.643822) (xy 14.18287 -43.635999)
			(xy 14.124977 -43.620486) (xy 14.069604 -43.59755) (xy 14.017698 -43.567583) (xy 13.970148 -43.531096)
			(xy 13.927768 -43.488716) (xy 13.891281 -43.441166) (xy 13.861314 -43.38926) (xy 13.838378 -43.333887)
			(xy 13.822865 -43.275994) (xy 13.815042 -43.216572) (xy 12.23302 -43.216572) (xy 12.228156 -43.230739)
			(xy 12.189745 -43.318307) (xy 12.144234 -43.402405) (xy 12.091934 -43.482457) (xy 12.033201 -43.557916)
			(xy 11.968438 -43.628268) (xy 11.898086 -43.693031) (xy 11.822627 -43.751764) (xy 11.742575 -43.804064)
			(xy 11.673084 -43.84167) (xy 20.199602 -43.84167) (xy 20.203673 -43.786048) (xy 20.215799 -43.731611)
			(xy 20.235722 -43.67952) (xy 20.263018 -43.630885) (xy 20.297104 -43.586742) (xy 20.337253 -43.548033)
			(xy 20.382611 -43.515582) (xy 20.432211 -43.490081) (xy 20.484995 -43.472074) (xy 20.539838 -43.461944)
			(xy 20.595572 -43.459907) (xy 20.651009 -43.466007) (xy 20.704966 -43.480113) (xy 20.756295 -43.501925)
			(xy 20.803901 -43.530979) (xy 20.846769 -43.566654) (xy 20.883986 -43.608191) (xy 20.914759 -43.654704)
			(xy 20.938431 -43.705201) (xy 20.954499 -43.758608) (xy 20.962619 -43.813784) (xy 20.963128 -43.84167)
			(xy 20.962619 -43.869556) (xy 20.954499 -43.924732) (xy 20.938431 -43.978139) (xy 20.914759 -44.028636)
			(xy 20.883986 -44.075149) (xy 20.846769 -44.116686) (xy 20.803901 -44.152361) (xy 20.756295 -44.181415)
			(xy 20.704966 -44.203227) (xy 20.651009 -44.217333) (xy 20.595572 -44.223433) (xy 20.539838 -44.221396)
			(xy 20.484995 -44.211266) (xy 20.432211 -44.193259) (xy 20.382611 -44.167758) (xy 20.337253 -44.135307)
			(xy 20.297104 -44.096598) (xy 20.263018 -44.052455) (xy 20.235722 -44.00382) (xy 20.215799 -43.951729)
			(xy 20.203673 -43.897292) (xy 20.199602 -43.84167) (xy 11.673084 -43.84167) (xy 11.658477 -43.849575)
			(xy 11.570909 -43.887986) (xy 11.480468 -43.919035) (xy 11.387771 -43.942509) (xy 11.293453 -43.958248)
			(xy 11.198157 -43.966144) (xy 11.102535 -43.966144) (xy 11.007239 -43.958248) (xy 10.912921 -43.942509)
			(xy 10.820224 -43.919035) (xy 10.729783 -43.887986) (xy 10.642215 -43.849575) (xy 10.558117 -43.804064)
			(xy 10.478065 -43.751764) (xy 10.402606 -43.693031) (xy 10.332254 -43.628268) (xy 10.267491 -43.557916)
			(xy 10.208758 -43.482457) (xy 10.156458 -43.402405) (xy 10.110947 -43.318307) (xy 10.072536 -43.230739)
			(xy 10.041487 -43.140298) (xy 10.018013 -43.047601) (xy 10.002274 -42.953283) (xy 9.994378 -42.857987)
			(xy 9.271 -42.857987) (xy 9.271 -45.243242) (xy 9.271478 -45.259345) (xy 9.279555 -45.290522) (xy 9.295184 -45.318681)
			(xy 9.317369 -45.342029) (xy 9.344694 -45.359075) (xy 9.3599 -45.3644) (xy 9.39582 -45.376236) (xy 9.465094 -45.406592)
			(xy 9.530685 -45.444249) (xy 9.591828 -45.488767) (xy 9.647807 -45.539626) (xy 9.697968 -45.596232)
			(xy 9.741725 -45.657922) (xy 9.778566 -45.723975) (xy 9.80806 -45.793619) (xy 9.829864 -45.866041)
			(xy 9.843721 -45.940393) (xy 9.847072 -45.978064) (xy 9.850882 -46.027594) (xy 9.92378 -46.095412)
			(xy 10.211816 -46.095412) (xy 10.228233 -46.094885) (xy 10.259973 -46.086482) (xy 10.288521 -46.07026)
			(xy 10.311986 -46.047293) (xy 10.328817 -46.019101) (xy 10.337901 -45.987548) (xy 10.338636 -45.954722)
			(xy 10.330975 -45.922794) (xy 10.315423 -45.893877) (xy 10.293009 -45.869882) (xy 10.27938 -45.860716)
			(xy 10.248033 -45.840532) (xy 10.189398 -45.794476) (xy 10.135997 -45.742441) (xy 10.088438 -45.685019)
			(xy 10.047261 -45.622861) (xy 10.012932 -45.556673) (xy 9.985843 -45.487208) (xy 9.966301 -45.415255)
			(xy 9.954528 -45.34163) (xy 9.950657 -45.26717) (xy 9.954733 -45.192722) (xy 9.966709 -45.11913)
			(xy 9.98645 -45.04723) (xy 10.01373 -44.97784) (xy 10.048241 -44.911748) (xy 10.08959 -44.849703)
			(xy 10.137308 -44.792412) (xy 10.190851 -44.740525) (xy 10.249613 -44.694631) (xy 10.312926 -44.655252)
			(xy 10.38007 -44.622835) (xy 10.450283 -44.597747) (xy 10.522767 -44.580275) (xy 10.596699 -44.570617)
			(xy 10.671239 -44.568882) (xy 10.74554 -44.57509) (xy 10.818759 -44.58917) (xy 10.890063 -44.610964)
			(xy 10.933684 -44.629574) (xy 16.990042 -44.629574) (xy 16.990042 -44.569638) (xy 16.997865 -44.510216)
			(xy 17.013378 -44.452323) (xy 17.036314 -44.39695) (xy 17.066281 -44.345044) (xy 17.102768 -44.297494)
			(xy 17.145148 -44.255114) (xy 17.192698 -44.218627) (xy 17.244604 -44.18866) (xy 17.299977 -44.165724)
			(xy 17.35787 -44.150211) (xy 17.417292 -44.142388) (xy 17.477228 -44.142388) (xy 17.53665 -44.150211)
			(xy 17.594543 -44.165724) (xy 17.649916 -44.18866) (xy 17.701822 -44.218627) (xy 17.749372 -44.255114)
			(xy 17.791752 -44.297494) (xy 17.828239 -44.345044) (xy 17.858206 -44.39695) (xy 17.881142 -44.452323)
			(xy 17.896655 -44.510216) (xy 17.904478 -44.569638) (xy 17.904968 -44.599606) (xy 17.904478 -44.629574)
			(xy 17.896655 -44.688996) (xy 17.881142 -44.746889) (xy 17.858206 -44.802262) (xy 17.828239 -44.854168)
			(xy 17.791752 -44.901718) (xy 17.749372 -44.944098) (xy 17.701822 -44.980585) (xy 17.649916 -45.010552)
			(xy 17.594543 -45.033488) (xy 17.53665 -45.049001) (xy 17.477228 -45.056824) (xy 17.417292 -45.056824)
			(xy 17.35787 -45.049001) (xy 17.299977 -45.033488) (xy 17.244604 -45.010552) (xy 17.192698 -44.980585)
			(xy 17.145148 -44.944098) (xy 17.102768 -44.901718) (xy 17.066281 -44.854168) (xy 17.036314 -44.802262)
			(xy 17.013378 -44.746889) (xy 16.997865 -44.688996) (xy 16.990042 -44.629574) (xy 10.933684 -44.629574)
			(xy 10.958643 -44.640222) (xy 11.023719 -44.676613) (xy 11.084553 -44.719723) (xy 11.140453 -44.769062)
			(xy 11.190784 -44.824071) (xy 11.234975 -44.884124) (xy 11.272523 -44.94854) (xy 11.303003 -45.016585)
			(xy 11.326068 -45.087488) (xy 11.341455 -45.160443) (xy 11.345841 -45.203618) (xy 22.700994 -45.203618)
			(xy 22.705065 -45.147996) (xy 22.717191 -45.093559) (xy 22.737114 -45.041468) (xy 22.76441 -44.992833)
			(xy 22.798496 -44.94869) (xy 22.838645 -44.909981) (xy 22.884003 -44.87753) (xy 22.933603 -44.852029)
			(xy 22.986387 -44.834022) (xy 23.04123 -44.823892) (xy 23.096964 -44.821855) (xy 23.152401 -44.827955)
			(xy 23.206358 -44.842061) (xy 23.257687 -44.863873) (xy 23.305293 -44.892927) (xy 23.348161 -44.928602)
			(xy 23.385378 -44.970139) (xy 23.416151 -45.016652) (xy 23.439823 -45.067149) (xy 23.455891 -45.120556)
			(xy 23.464011 -45.175732) (xy 23.46452 -45.203618) (xy 23.464011 -45.231504) (xy 23.455891 -45.28668)
			(xy 23.439823 -45.340087) (xy 23.416151 -45.390584) (xy 23.385378 -45.437097) (xy 23.348161 -45.478634)
			(xy 23.305293 -45.514309) (xy 23.257687 -45.543363) (xy 23.206358 -45.565175) (xy 23.152401 -45.579281)
			(xy 23.096964 -45.585381) (xy 23.04123 -45.583344) (xy 22.986387 -45.573214) (xy 22.933603 -45.555207)
			(xy 22.884003 -45.529706) (xy 22.838645 -45.497255) (xy 22.798496 -45.458546) (xy 22.76441 -45.414403)
			(xy 22.737114 -45.365768) (xy 22.717191 -45.313677) (xy 22.705065 -45.25924) (xy 22.700994 -45.203618)
			(xy 11.345841 -45.203618) (xy 11.348991 -45.234622) (xy 11.348589 -45.309181) (xy 11.340254 -45.383274)
			(xy 11.32408 -45.456059) (xy 11.300253 -45.526709) (xy 11.269041 -45.594422) (xy 11.2308 -45.658429)
			(xy 11.208766 -45.688504) (xy 11.195475 -45.706967) (xy 11.17499 -45.747581) (xy 11.162064 -45.791193)
			(xy 11.15711 -45.83641) (xy 11.160287 -45.881787) (xy 11.171493 -45.925872) (xy 11.173748 -45.930816)
			(xy 14.08606 -45.930816) (xy 14.08606 -45.87088) (xy 14.093883 -45.811458) (xy 14.109396 -45.753565)
			(xy 14.132332 -45.698192) (xy 14.162299 -45.646286) (xy 14.198786 -45.598736) (xy 14.241166 -45.556356)
			(xy 14.288716 -45.519869) (xy 14.340622 -45.489902) (xy 14.395995 -45.466966) (xy 14.453888 -45.451453)
			(xy 14.51331 -45.44363) (xy 14.573246 -45.44363) (xy 14.632668 -45.451453) (xy 14.690561 -45.466966)
			(xy 14.745934 -45.489902) (xy 14.79784 -45.519869) (xy 14.84539 -45.556356) (xy 14.88777 -45.598736)
			(xy 14.924257 -45.646286) (xy 14.954224 -45.698192) (xy 14.97716 -45.753565) (xy 14.992673 -45.811458)
			(xy 15.000496 -45.87088) (xy 15.000986 -45.900848) (xy 15.000496 -45.930816) (xy 14.999426 -45.938944)
			(xy 16.777444 -45.938944) (xy 16.777444 -45.879008) (xy 16.785267 -45.819586) (xy 16.80078 -45.761693)
			(xy 16.823716 -45.70632) (xy 16.853683 -45.654414) (xy 16.89017 -45.606864) (xy 16.93255 -45.564484)
			(xy 16.9801 -45.527997) (xy 17.032006 -45.49803) (xy 17.087379 -45.475094) (xy 17.145272 -45.459581)
			(xy 17.204694 -45.451758) (xy 17.26463 -45.451758) (xy 17.324052 -45.459581) (xy 17.381945 -45.475094)
			(xy 17.437318 -45.49803) (xy 17.489224 -45.527997) (xy 17.536774 -45.564484) (xy 17.579154 -45.606864)
			(xy 17.615641 -45.654414) (xy 17.645608 -45.70632) (xy 17.668544 -45.761693) (xy 17.684057 -45.819586)
			(xy 17.69188 -45.879008) (xy 17.69237 -45.908976) (xy 17.69188 -45.938944) (xy 17.684057 -45.998366)
			(xy 17.668544 -46.056259) (xy 17.645608 -46.111632) (xy 17.615641 -46.163538) (xy 17.579154 -46.211088)
			(xy 17.536774 -46.253468) (xy 17.489224 -46.289955) (xy 17.437318 -46.319922) (xy 17.381945 -46.342858)
			(xy 17.324052 -46.358371) (xy 17.26463 -46.366194) (xy 17.204694 -46.366194) (xy 17.145272 -46.358371)
			(xy 17.087379 -46.342858) (xy 17.032006 -46.319922) (xy 16.9801 -46.289955) (xy 16.93255 -46.253468)
			(xy 16.89017 -46.211088) (xy 16.853683 -46.163538) (xy 16.823716 -46.111632) (xy 16.80078 -46.056259)
			(xy 16.785267 -45.998366) (xy 16.777444 -45.938944) (xy 14.999426 -45.938944) (xy 14.992673 -45.990238)
			(xy 14.97716 -46.048131) (xy 14.954224 -46.103504) (xy 14.924257 -46.15541) (xy 14.88777 -46.20296)
			(xy 14.84539 -46.24534) (xy 14.79784 -46.281827) (xy 14.745934 -46.311794) (xy 14.690561 -46.33473)
			(xy 14.632668 -46.350243) (xy 14.573246 -46.358066) (xy 14.51331 -46.358066) (xy 14.453888 -46.350243)
			(xy 14.395995 -46.33473) (xy 14.340622 -46.311794) (xy 14.288716 -46.281827) (xy 14.241166 -46.24534)
			(xy 14.198786 -46.20296) (xy 14.162299 -46.15541) (xy 14.132332 -46.103504) (xy 14.109396 -46.048131)
			(xy 14.093883 -45.990238) (xy 14.08606 -45.930816) (xy 11.173748 -45.930816) (xy 11.190369 -45.967258)
			(xy 11.216313 -46.004621) (xy 11.248496 -46.036768) (xy 11.285888 -46.062671) (xy 11.327295 -46.081501)
			(xy 11.349228 -46.087538) (xy 11.349228 -47.500794) (xy 11.327322 -47.506887) (xy 11.285959 -47.525753)
			(xy 11.248609 -47.551673) (xy 11.216462 -47.583821) (xy 11.190545 -47.621173) (xy 11.171681 -47.662538)
			(xy 11.160473 -47.706598) (xy 11.157278 -47.751949) (xy 11.162198 -47.797145) (xy 11.175075 -47.840746)
			(xy 11.195499 -47.881363) (xy 11.208766 -47.899828) (xy 11.232241 -47.931973) (xy 11.272554 -48.000611)
			(xy 11.304811 -48.073384) (xy 11.328595 -48.149349) (xy 11.343597 -48.227523) (xy 11.34801 -48.28565)
			(xy 16.451562 -48.28565) (xy 16.451562 -48.225714) (xy 16.459385 -48.166292) (xy 16.474898 -48.108399)
			(xy 16.497834 -48.053026) (xy 16.527801 -48.00112) (xy 16.564288 -47.95357) (xy 16.606668 -47.91119)
			(xy 16.654218 -47.874703) (xy 16.706124 -47.844736) (xy 16.761497 -47.8218) (xy 16.81939 -47.806287)
			(xy 16.878812 -47.798464) (xy 16.938748 -47.798464) (xy 16.99817 -47.806287) (xy 17.056063 -47.8218)
			(xy 17.111436 -47.844736) (xy 17.163342 -47.874703) (xy 17.210892 -47.91119) (xy 17.253272 -47.95357)
			(xy 17.282979 -47.992284) (xy 18.727926 -47.992284) (xy 18.731997 -47.936662) (xy 18.744123 -47.882225)
			(xy 18.764046 -47.830134) (xy 18.791342 -47.781499) (xy 18.825428 -47.737356) (xy 18.865577 -47.698647)
			(xy 18.910935 -47.666196) (xy 18.960535 -47.640695) (xy 19.013319 -47.622688) (xy 19.068162 -47.612558)
			(xy 19.123896 -47.610521) (xy 19.179333 -47.616621) (xy 19.23329 -47.630727) (xy 19.284619 -47.652539)
			(xy 19.332225 -47.681593) (xy 19.375093 -47.717268) (xy 19.41231 -47.758805) (xy 19.443083 -47.805318)
			(xy 19.466755 -47.855815) (xy 19.482823 -47.909222) (xy 19.490943 -47.964398) (xy 19.491452 -47.992284)
			(xy 19.490943 -48.02017) (xy 19.482823 -48.075346) (xy 19.466755 -48.128753) (xy 19.443083 -48.17925)
			(xy 19.41231 -48.225763) (xy 19.375093 -48.2673) (xy 19.332225 -48.302975) (xy 19.284619 -48.332029)
			(xy 19.23329 -48.353841) (xy 19.179333 -48.367947) (xy 19.123896 -48.374047) (xy 19.068162 -48.37201)
			(xy 19.013319 -48.36188) (xy 18.960535 -48.343873) (xy 18.910935 -48.318372) (xy 18.865577 -48.285921)
			(xy 18.825428 -48.247212) (xy 18.791342 -48.203069) (xy 18.764046 -48.154434) (xy 18.744123 -48.102343)
			(xy 18.731997 -48.047906) (xy 18.727926 -47.992284) (xy 17.282979 -47.992284) (xy 17.289759 -48.00112)
			(xy 17.319726 -48.053026) (xy 17.342662 -48.108399) (xy 17.358175 -48.166292) (xy 17.365998 -48.225714)
			(xy 17.366488 -48.255682) (xy 17.365998 -48.28565) (xy 17.358175 -48.345072) (xy 17.342662 -48.402965)
			(xy 17.319726 -48.458338) (xy 17.289759 -48.510244) (xy 17.253272 -48.557794) (xy 17.210892 -48.600174)
			(xy 17.163342 -48.636661) (xy 17.111436 -48.666628) (xy 17.056063 -48.689564) (xy 16.99817 -48.705077)
			(xy 16.938748 -48.7129) (xy 16.878812 -48.7129) (xy 16.81939 -48.705077) (xy 16.761497 -48.689564)
			(xy 16.706124 -48.666628) (xy 16.654218 -48.636661) (xy 16.606668 -48.600174) (xy 16.564288 -48.557794)
			(xy 16.527801 -48.510244) (xy 16.497834 -48.458338) (xy 16.474898 -48.402965) (xy 16.459385 -48.345072)
			(xy 16.451562 -48.28565) (xy 11.34801 -48.28565) (xy 11.349623 -48.306896) (xy 11.346596 -48.386439)
			(xy 11.3411 -48.425862) (xy 11.334668 -48.464436) (xy 11.314321 -48.539948) (xy 11.28567 -48.612717)
			(xy 11.249076 -48.681833) (xy 11.216104 -48.73015) (xy 20.378402 -48.73015) (xy 20.378402 -48.670214)
			(xy 20.386225 -48.610792) (xy 20.401738 -48.552899) (xy 20.424674 -48.497526) (xy 20.454641 -48.44562)
			(xy 20.491128 -48.39807) (xy 20.533508 -48.35569) (xy 20.581058 -48.319203) (xy 20.632964 -48.289236)
			(xy 20.688337 -48.2663) (xy 20.74623 -48.250787) (xy 20.805652 -48.242964) (xy 20.865588 -48.242964)
			(xy 20.92501 -48.250787) (xy 20.982903 -48.2663) (xy 21.038276 -48.289236) (xy 21.090182 -48.319203)
			(xy 21.137732 -48.35569) (xy 21.180112 -48.39807) (xy 21.216599 -48.44562) (xy 21.246566 -48.497526)
			(xy 21.269502 -48.552899) (xy 21.285015 -48.610792) (xy 21.292838 -48.670214) (xy 21.293328 -48.700182)
			(xy 21.292838 -48.73015) (xy 21.285015 -48.789572) (xy 21.269502 -48.847465) (xy 21.246566 -48.902838)
			(xy 21.216599 -48.954744) (xy 21.180112 -49.002294) (xy 21.137732 -49.044674) (xy 21.090182 -49.081161)
			(xy 21.038276 -49.111128) (xy 20.982903 -49.134064) (xy 20.92501 -49.149577) (xy 20.865588 -49.1574)
			(xy 20.805652 -49.1574) (xy 20.74623 -49.149577) (xy 20.688337 -49.134064) (xy 20.632964 -49.111128)
			(xy 20.581058 -49.081161) (xy 20.533508 -49.044674) (xy 20.491128 -49.002294) (xy 20.454641 -48.954744)
			(xy 20.424674 -48.902838) (xy 20.401738 -48.847465) (xy 20.386225 -48.789572) (xy 20.378402 -48.73015)
			(xy 11.216104 -48.73015) (xy 11.204994 -48.746431) (xy 11.153976 -48.805704) (xy 11.09666 -48.858912)
			(xy 11.06551 -48.882554) (xy 11.047532 -48.897151) (xy 11.016698 -48.931695) (xy 10.992633 -48.971254)
			(xy 10.976133 -49.014519) (xy 10.967745 -49.060057) (xy 10.967747 -49.106361) (xy 10.976138 -49.151898)
			(xy 10.99264 -49.195161) (xy 11.016708 -49.234719) (xy 11.047545 -49.269261) (xy 11.06551 -49.283874)
			(xy 11.096126 -49.307137) (xy 11.152594 -49.359328) (xy 11.202995 -49.417402) (xy 11.246717 -49.480656)
			(xy 11.283234 -49.548326) (xy 11.312104 -49.619595) (xy 11.332978 -49.693601) (xy 11.345604 -49.769452)
			(xy 11.34983 -49.84623) (xy 11.345604 -49.923008) (xy 11.332978 -49.998859) (xy 11.312104 -50.072865)
			(xy 11.306369 -50.087022) (xy 17.126202 -50.087022) (xy 17.130273 -50.0314) (xy 17.142399 -49.976963)
			(xy 17.162322 -49.924872) (xy 17.189618 -49.876237) (xy 17.223704 -49.832094) (xy 17.263853 -49.793385)
			(xy 17.309211 -49.760934) (xy 17.358811 -49.735433) (xy 17.411595 -49.717426) (xy 17.466438 -49.707296)
			(xy 17.522172 -49.705259) (xy 17.577609 -49.711359) (xy 17.631566 -49.725465) (xy 17.682895 -49.747277)
			(xy 17.730501 -49.776331) (xy 17.773369 -49.812006) (xy 17.810586 -49.853543) (xy 17.841359 -49.900056)
			(xy 17.865031 -49.950553) (xy 17.881099 -50.00396) (xy 17.889219 -50.059136) (xy 17.889728 -50.087022)
			(xy 17.889219 -50.114908) (xy 17.881099 -50.170084) (xy 17.865031 -50.223491) (xy 17.841359 -50.273988)
			(xy 17.810586 -50.320501) (xy 17.773369 -50.362038) (xy 17.730501 -50.397713) (xy 17.682895 -50.426767)
			(xy 17.631566 -50.448579) (xy 17.577609 -50.462685) (xy 17.522172 -50.468785) (xy 17.466438 -50.466748)
			(xy 17.411595 -50.456618) (xy 17.358811 -50.438611) (xy 17.309211 -50.41311) (xy 17.263853 -50.380659)
			(xy 17.223704 -50.34195) (xy 17.189618 -50.297807) (xy 17.162322 -50.249172) (xy 17.142399 -50.197081)
			(xy 17.130273 -50.142644) (xy 17.126202 -50.087022) (xy 11.306369 -50.087022) (xy 11.283234 -50.144134)
			(xy 11.246717 -50.211804) (xy 11.202995 -50.275058) (xy 11.152594 -50.333132) (xy 11.096126 -50.385323)
			(xy 11.06551 -50.408586) (xy 11.047531 -50.423183) (xy 11.016695 -50.457729) (xy 10.992628 -50.497289)
			(xy 10.976126 -50.540555) (xy 10.967736 -50.586095) (xy 10.967736 -50.632401) (xy 10.976125 -50.67794)
			(xy 10.980538 -50.68951) (xy 13.832584 -50.68951) (xy 13.836655 -50.633888) (xy 13.848781 -50.579451)
			(xy 13.868704 -50.52736) (xy 13.896 -50.478725) (xy 13.930086 -50.434582) (xy 13.970235 -50.395873)
			(xy 14.015593 -50.363422) (xy 14.065193 -50.337921) (xy 14.117977 -50.319914) (xy 14.17282 -50.309784)
			(xy 14.228554 -50.307747) (xy 14.283991 -50.313847) (xy 14.337948 -50.327953) (xy 14.389277 -50.349765)
			(xy 14.436883 -50.378819) (xy 14.479751 -50.414494) (xy 14.516968 -50.456031) (xy 14.547741 -50.502544)
			(xy 14.571413 -50.553041) (xy 14.587481 -50.606448) (xy 14.595601 -50.661624) (xy 14.59611 -50.68951)
			(xy 14.595601 -50.717396) (xy 14.587481 -50.772572) (xy 14.571413 -50.825979) (xy 14.547741 -50.876476)
			(xy 14.516968 -50.922989) (xy 14.479751 -50.964526) (xy 14.436883 -51.000201) (xy 14.389277 -51.029255)
			(xy 14.337948 -51.051067) (xy 14.283991 -51.065173) (xy 14.228554 -51.071273) (xy 14.17282 -51.069236)
			(xy 14.117977 -51.059106) (xy 14.065193 -51.041099) (xy 14.015593 -51.015598) (xy 13.970235 -50.983147)
			(xy 13.930086 -50.944438) (xy 13.896 -50.900295) (xy 13.868704 -50.85166) (xy 13.848781 -50.799569)
			(xy 13.836655 -50.745132) (xy 13.832584 -50.68951) (xy 10.980538 -50.68951) (xy 10.992626 -50.721207)
			(xy 11.016692 -50.760767) (xy 11.047528 -50.795313) (xy 11.06551 -50.809906) (xy 11.096118 -50.83316)
			(xy 11.152575 -50.885333) (xy 11.202967 -50.943385) (xy 11.246684 -51.006616) (xy 11.2832 -51.074263)
			(xy 11.286208 -51.081686) (xy 18.759168 -51.081686) (xy 18.763239 -51.026064) (xy 18.775365 -50.971627)
			(xy 18.795288 -50.919536) (xy 18.822584 -50.870901) (xy 18.85667 -50.826758) (xy 18.896819 -50.788049)
			(xy 18.942177 -50.755598) (xy 18.991777 -50.730097) (xy 19.044561 -50.71209) (xy 19.099404 -50.70196)
			(xy 19.155138 -50.699923) (xy 19.210575 -50.706023) (xy 19.264532 -50.720129) (xy 19.315861 -50.741941)
			(xy 19.363467 -50.770995) (xy 19.406335 -50.80667) (xy 19.443552 -50.848207) (xy 19.474325 -50.89472)
			(xy 19.497997 -50.945217) (xy 19.514065 -50.998624) (xy 19.522185 -51.0538) (xy 19.522694 -51.081686)
			(xy 19.522185 -51.109572) (xy 19.514065 -51.164748) (xy 19.497997 -51.218155) (xy 19.474325 -51.268652)
			(xy 19.443552 -51.315165) (xy 19.406335 -51.356702) (xy 19.363467 -51.392377) (xy 19.315861 -51.421431)
			(xy 19.264532 -51.443243) (xy 19.210575 -51.457349) (xy 19.155138 -51.463449) (xy 19.099404 -51.461412)
			(xy 19.044561 -51.451282) (xy 18.991777 -51.433275) (xy 18.942177 -51.407774) (xy 18.896819 -51.375323)
			(xy 18.85667 -51.336614) (xy 18.822584 -51.292471) (xy 18.795288 -51.243836) (xy 18.775365 -51.191745)
			(xy 18.763239 -51.137308) (xy 18.759168 -51.081686) (xy 11.286208 -51.081686) (xy 11.312072 -51.145507)
			(xy 11.332954 -51.219489) (xy 11.345591 -51.295316) (xy 11.349832 -51.372071) (xy 11.345626 -51.448829)
			(xy 11.333023 -51.524661) (xy 11.312175 -51.598653) (xy 11.283335 -51.66991) (xy 11.24685 -51.737573)
			(xy 11.203161 -51.800824) (xy 11.152796 -51.858899) (xy 11.109654 -51.898804) (xy 14.286228 -51.898804)
			(xy 14.290299 -51.843182) (xy 14.302425 -51.788745) (xy 14.322348 -51.736654) (xy 14.349644 -51.688019)
			(xy 14.38373 -51.643876) (xy 14.423879 -51.605167) (xy 14.469237 -51.572716) (xy 14.518837 -51.547215)
			(xy 14.571621 -51.529208) (xy 14.626464 -51.519078) (xy 14.682198 -51.517041) (xy 14.737635 -51.523141)
			(xy 14.791592 -51.537247) (xy 14.842921 -51.559059) (xy 14.890527 -51.588113) (xy 14.933395 -51.623788)
			(xy 14.970612 -51.665325) (xy 15.001385 -51.711838) (xy 15.025057 -51.762335) (xy 15.041125 -51.815742)
			(xy 15.049245 -51.870918) (xy 15.049754 -51.898804) (xy 15.049245 -51.92669) (xy 15.041125 -51.981866)
			(xy 15.025057 -52.035273) (xy 15.001385 -52.08577) (xy 14.970612 -52.132283) (xy 14.933395 -52.17382)
			(xy 14.890527 -52.209495) (xy 14.842921 -52.238549) (xy 14.791592 -52.260361) (xy 14.737635 -52.274467)
			(xy 14.682198 -52.280567) (xy 14.626464 -52.27853) (xy 14.571621 -52.2684) (xy 14.518837 -52.250393)
			(xy 14.469237 -52.224892) (xy 14.423879 -52.192441) (xy 14.38373 -52.153732) (xy 14.349644 -52.109589)
			(xy 14.322348 -52.060954) (xy 14.302425 -52.008863) (xy 14.290299 -51.954426) (xy 14.286228 -51.898804)
			(xy 11.109654 -51.898804) (xy 11.096363 -51.911098) (xy 11.065764 -51.934364) (xy 11.047753 -51.948957)
			(xy 11.016857 -51.983509) (xy 10.992741 -52.023092) (xy 10.976205 -52.066393) (xy 10.967797 -52.111975)
			(xy 10.967797 -52.158326) (xy 10.976205 -52.203908) (xy 10.992741 -52.247209) (xy 11.016858 -52.286792)
			(xy 11.021962 -52.2925) (xy 18.305762 -52.2925) (xy 18.305762 -52.232564) (xy 18.313585 -52.173142)
			(xy 18.329098 -52.115249) (xy 18.352034 -52.059876) (xy 18.382001 -52.00797) (xy 18.418488 -51.96042)
			(xy 18.460868 -51.91804) (xy 18.508418 -51.881553) (xy 18.560324 -51.851586) (xy 18.615697 -51.82865)
			(xy 18.67359 -51.813137) (xy 18.733012 -51.805314) (xy 18.792948 -51.805314) (xy 18.85237 -51.813137)
			(xy 18.910263 -51.82865) (xy 18.965636 -51.851586) (xy 19.017542 -51.881553) (xy 19.065092 -51.91804)
			(xy 19.107472 -51.96042) (xy 19.143959 -52.00797) (xy 19.173926 -52.059876) (xy 19.196862 -52.115249)
			(xy 19.212375 -52.173142) (xy 19.220198 -52.232564) (xy 19.220688 -52.262532) (xy 19.220298 -52.286408)
			(xy 21.604222 -52.286408) (xy 21.608293 -52.230786) (xy 21.620419 -52.176349) (xy 21.640342 -52.124258)
			(xy 21.667638 -52.075623) (xy 21.701724 -52.03148) (xy 21.741873 -51.992771) (xy 21.787231 -51.96032)
			(xy 21.836831 -51.934819) (xy 21.889615 -51.916812) (xy 21.944458 -51.906682) (xy 22.000192 -51.904645)
			(xy 22.055629 -51.910745) (xy 22.109586 -51.924851) (xy 22.160915 -51.946663) (xy 22.208521 -51.975717)
			(xy 22.251389 -52.011392) (xy 22.288606 -52.052929) (xy 22.319379 -52.099442) (xy 22.343051 -52.149939)
			(xy 22.359119 -52.203346) (xy 22.367239 -52.258522) (xy 22.367748 -52.286408) (xy 22.367239 -52.314294)
			(xy 22.359119 -52.36947) (xy 22.343051 -52.422877) (xy 22.319379 -52.473374) (xy 22.288606 -52.519887)
			(xy 22.251389 -52.561424) (xy 22.208521 -52.597099) (xy 22.160915 -52.626153) (xy 22.109586 -52.647965)
			(xy 22.055629 -52.662071) (xy 22.000192 -52.668171) (xy 21.944458 -52.666134) (xy 21.889615 -52.656004)
			(xy 21.836831 -52.637997) (xy 21.787231 -52.612496) (xy 21.741873 -52.580045) (xy 21.701724 -52.541336)
			(xy 21.667638 -52.497193) (xy 21.640342 -52.448558) (xy 21.620419 -52.396467) (xy 21.608293 -52.34203)
			(xy 21.604222 -52.286408) (xy 19.220298 -52.286408) (xy 19.220198 -52.2925) (xy 19.212375 -52.351922)
			(xy 19.196862 -52.409815) (xy 19.173926 -52.465188) (xy 19.143959 -52.517094) (xy 19.107472 -52.564644)
			(xy 19.065092 -52.607024) (xy 19.017542 -52.643511) (xy 18.965636 -52.673478) (xy 18.910263 -52.696414)
			(xy 18.85237 -52.711927) (xy 18.792948 -52.71975) (xy 18.733012 -52.71975) (xy 18.67359 -52.711927)
			(xy 18.615697 -52.696414) (xy 18.560324 -52.673478) (xy 18.508418 -52.643511) (xy 18.460868 -52.607024)
			(xy 18.418488 -52.564644) (xy 18.382001 -52.517094) (xy 18.352034 -52.465188) (xy 18.329098 -52.409815)
			(xy 18.313585 -52.351922) (xy 18.305762 -52.2925) (xy 11.021962 -52.2925) (xy 11.047754 -52.321343)
			(xy 11.065764 -52.335938) (xy 11.096357 -52.359209) (xy 11.15278 -52.411412) (xy 11.203136 -52.46949)
			(xy 11.246816 -52.532742) (xy 11.283293 -52.600404) (xy 11.312127 -52.671659) (xy 11.33297 -52.745648)
			(xy 11.345571 -52.821477) (xy 11.349776 -52.89823) (xy 11.345536 -52.974981) (xy 11.332901 -53.050804)
			(xy 11.312024 -53.124783) (xy 11.283157 -53.196025) (xy 11.246649 -53.263671) (xy 11.20294 -53.326902)
			(xy 11.152557 -53.384957) (xy 11.09611 -53.437135) (xy 11.06551 -53.460396) (xy 11.047531 -53.474993)
			(xy 11.016695 -53.509539) (xy 10.992628 -53.549099) (xy 10.976126 -53.592365) (xy 10.967736 -53.637905)
			(xy 10.967736 -53.684211) (xy 10.976125 -53.72975) (xy 10.992626 -53.773017) (xy 11.016692 -53.812577)
			(xy 11.047528 -53.847123) (xy 11.06551 -53.861716) (xy 11.096125 -53.884979) (xy 11.152594 -53.93717)
			(xy 11.202994 -53.995244) (xy 11.246716 -54.058498) (xy 11.283233 -54.126168) (xy 11.312102 -54.197436)
			(xy 11.332976 -54.271443) (xy 11.345602 -54.347293) (xy 11.349828 -54.424071) (xy 11.345602 -54.500849)
			(xy 11.332976 -54.576699) (xy 11.312102 -54.650706) (xy 11.283232 -54.721975) (xy 11.246715 -54.789644)
			(xy 11.206734 -54.847486) (xy 17.025602 -54.847486) (xy 17.025602 -54.78755) (xy 17.033425 -54.728128)
			(xy 17.048938 -54.670235) (xy 17.071874 -54.614862) (xy 17.101841 -54.562956) (xy 17.138328 -54.515406)
			(xy 17.180708 -54.473026) (xy 17.228258 -54.436539) (xy 17.280164 -54.406572) (xy 17.335537 -54.383636)
			(xy 17.39343 -54.368123) (xy 17.452852 -54.3603) (xy 17.512788 -54.3603) (xy 17.57221 -54.368123)
			(xy 17.630103 -54.383636) (xy 17.685476 -54.406572) (xy 17.737382 -54.436539) (xy 17.784932 -54.473026)
			(xy 17.827312 -54.515406) (xy 17.830122 -54.519068) (xy 19.478242 -54.519068) (xy 19.482313 -54.463446)
			(xy 19.494439 -54.409009) (xy 19.514362 -54.356918) (xy 19.541658 -54.308283) (xy 19.575744 -54.26414)
			(xy 19.615893 -54.225431) (xy 19.661251 -54.19298) (xy 19.710851 -54.167479) (xy 19.763635 -54.149472)
			(xy 19.818478 -54.139342) (xy 19.874212 -54.137305) (xy 19.929649 -54.143405) (xy 19.983606 -54.157511)
			(xy 20.034935 -54.179323) (xy 20.082541 -54.208377) (xy 20.125409 -54.244052) (xy 20.162626 -54.285589)
			(xy 20.193399 -54.332102) (xy 20.217071 -54.382599) (xy 20.233139 -54.436006) (xy 20.241259 -54.491182)
			(xy 20.241768 -54.519068) (xy 20.241259 -54.546954) (xy 20.233139 -54.60213) (xy 20.217071 -54.655537)
			(xy 20.193399 -54.706034) (xy 20.162626 -54.752547) (xy 20.125409 -54.794084) (xy 20.082541 -54.829759)
			(xy 20.034935 -54.858813) (xy 19.983606 -54.880625) (xy 19.929649 -54.894731) (xy 19.874212 -54.900831)
			(xy 19.818478 -54.898794) (xy 19.763635 -54.888664) (xy 19.710851 -54.870657) (xy 19.661251 -54.845156)
			(xy 19.615893 -54.812705) (xy 19.575744 -54.773996) (xy 19.541658 -54.729853) (xy 19.514362 -54.681218)
			(xy 19.494439 -54.629127) (xy 19.482313 -54.57469) (xy 19.478242 -54.519068) (xy 17.830122 -54.519068)
			(xy 17.863799 -54.562956) (xy 17.893766 -54.614862) (xy 17.916702 -54.670235) (xy 17.932215 -54.728128)
			(xy 17.940038 -54.78755) (xy 17.940528 -54.817518) (xy 17.940038 -54.847486) (xy 17.932215 -54.906908)
			(xy 17.916702 -54.964801) (xy 17.893766 -55.020174) (xy 17.863799 -55.07208) (xy 17.827312 -55.11963)
			(xy 17.784932 -55.16201) (xy 17.737382 -55.198497) (xy 17.685476 -55.228464) (xy 17.630103 -55.2514)
			(xy 17.57221 -55.266913) (xy 17.512788 -55.274736) (xy 17.452852 -55.274736) (xy 17.39343 -55.266913)
			(xy 17.335537 -55.2514) (xy 17.280164 -55.228464) (xy 17.228258 -55.198497) (xy 17.180708 -55.16201)
			(xy 17.138328 -55.11963) (xy 17.101841 -55.07208) (xy 17.071874 -55.020174) (xy 17.048938 -54.964801)
			(xy 17.033425 -54.906908) (xy 17.025602 -54.847486) (xy 11.206734 -54.847486) (xy 11.202993 -54.852898)
			(xy 11.152593 -54.910971) (xy 11.096124 -54.963163) (xy 11.06551 -54.986428) (xy 11.04753 -55.001025)
			(xy 11.016691 -55.03557) (xy 10.992621 -55.075131) (xy 10.976118 -55.118398) (xy 10.967726 -55.163939)
			(xy 10.967725 -55.210246) (xy 10.976114 -55.255788) (xy 10.992615 -55.299056) (xy 11.016682 -55.338618)
			(xy 11.047519 -55.373165) (xy 11.06551 -55.387748) (xy 11.095211 -55.410279) (xy 11.15013 -55.460698)
			(xy 11.193432 -55.509922) (xy 13.939264 -55.509922) (xy 13.943335 -55.4543) (xy 13.955461 -55.399863)
			(xy 13.975384 -55.347772) (xy 14.00268 -55.299137) (xy 14.036766 -55.254994) (xy 14.076915 -55.216285)
			(xy 14.122273 -55.183834) (xy 14.171873 -55.158333) (xy 14.224657 -55.140326) (xy 14.2795 -55.130196)
			(xy 14.335234 -55.128159) (xy 14.390671 -55.134259) (xy 14.444628 -55.148365) (xy 14.495957 -55.170177)
			(xy 14.543563 -55.199231) (xy 14.586431 -55.234906) (xy 14.623648 -55.276443) (xy 14.654421 -55.322956)
			(xy 14.678093 -55.373453) (xy 14.694161 -55.42686) (xy 14.702281 -55.482036) (xy 14.702651 -55.502302)
			(xy 18.810222 -55.502302) (xy 18.814293 -55.44668) (xy 18.826419 -55.392243) (xy 18.846342 -55.340152)
			(xy 18.873638 -55.291517) (xy 18.907724 -55.247374) (xy 18.947873 -55.208665) (xy 18.993231 -55.176214)
			(xy 19.042831 -55.150713) (xy 19.095615 -55.132706) (xy 19.150458 -55.122576) (xy 19.206192 -55.120539)
			(xy 19.261629 -55.126639) (xy 19.315586 -55.140745) (xy 19.366915 -55.162557) (xy 19.414521 -55.191611)
			(xy 19.457389 -55.227286) (xy 19.494606 -55.268823) (xy 19.525379 -55.315336) (xy 19.549051 -55.365833)
			(xy 19.565119 -55.41924) (xy 19.573239 -55.474416) (xy 19.573748 -55.502302) (xy 19.573239 -55.530188)
			(xy 19.565119 -55.585364) (xy 19.557555 -55.610506) (xy 21.430486 -55.610506) (xy 21.434557 -55.554884)
			(xy 21.446683 -55.500447) (xy 21.466606 -55.448356) (xy 21.493902 -55.399721) (xy 21.527988 -55.355578)
			(xy 21.568137 -55.316869) (xy 21.613495 -55.284418) (xy 21.663095 -55.258917) (xy 21.715879 -55.24091)
			(xy 21.770722 -55.23078) (xy 21.826456 -55.228743) (xy 21.881893 -55.234843) (xy 21.93585 -55.248949)
			(xy 21.987179 -55.270761) (xy 22.034785 -55.299815) (xy 22.077653 -55.33549) (xy 22.11487 -55.377027)
			(xy 22.145643 -55.42354) (xy 22.169315 -55.474037) (xy 22.185383 -55.527444) (xy 22.193503 -55.58262)
			(xy 22.194012 -55.610506) (xy 22.193503 -55.638392) (xy 22.185383 -55.693568) (xy 22.169315 -55.746975)
			(xy 22.145643 -55.797472) (xy 22.11487 -55.843985) (xy 22.077653 -55.885522) (xy 22.034785 -55.921197)
			(xy 21.987179 -55.950251) (xy 21.93585 -55.972063) (xy 21.881893 -55.986169) (xy 21.826456 -55.992269)
			(xy 21.770722 -55.990232) (xy 21.715879 -55.980102) (xy 21.663095 -55.962095) (xy 21.613495 -55.936594)
			(xy 21.568137 -55.904143) (xy 21.527988 -55.865434) (xy 21.493902 -55.821291) (xy 21.466606 -55.772656)
			(xy 21.446683 -55.720565) (xy 21.434557 -55.666128) (xy 21.430486 -55.610506) (xy 19.557555 -55.610506)
			(xy 19.549051 -55.638771) (xy 19.525379 -55.689268) (xy 19.494606 -55.735781) (xy 19.457389 -55.777318)
			(xy 19.414521 -55.812993) (xy 19.366915 -55.842047) (xy 19.315586 -55.863859) (xy 19.261629 -55.877965)
			(xy 19.206192 -55.884065) (xy 19.150458 -55.882028) (xy 19.095615 -55.871898) (xy 19.042831 -55.853891)
			(xy 18.993231 -55.82839) (xy 18.947873 -55.795939) (xy 18.907724 -55.75723) (xy 18.873638 -55.713087)
			(xy 18.846342 -55.664452) (xy 18.826419 -55.612361) (xy 18.814293 -55.557924) (xy 18.810222 -55.502302)
			(xy 14.702651 -55.502302) (xy 14.70279 -55.509922) (xy 14.702281 -55.537808) (xy 14.694161 -55.592984)
			(xy 14.678093 -55.646391) (xy 14.654421 -55.696888) (xy 14.623648 -55.743401) (xy 14.586431 -55.784938)
			(xy 14.543563 -55.820613) (xy 14.495957 -55.849667) (xy 14.444628 -55.871479) (xy 14.390671 -55.885585)
			(xy 14.335234 -55.891685) (xy 14.2795 -55.889648) (xy 14.224657 -55.879518) (xy 14.171873 -55.861511)
			(xy 14.122273 -55.83601) (xy 14.076915 -55.803559) (xy 14.036766 -55.76485) (xy 14.00268 -55.720707)
			(xy 13.975384 -55.672072) (xy 13.955461 -55.619981) (xy 13.943335 -55.565544) (xy 13.939264 -55.509922)
			(xy 11.193432 -55.509922) (xy 11.199372 -55.516675) (xy 11.242377 -55.577574) (xy 11.278657 -55.642704)
			(xy 11.307801 -55.711325) (xy 11.329477 -55.782657) (xy 11.343439 -55.855891) (xy 11.349528 -55.930195)
			(xy 11.347676 -56.004726) (xy 11.337903 -56.078635) (xy 11.320321 -56.151086) (xy 11.295128 -56.221253)
			(xy 11.262612 -56.288342) (xy 11.223141 -56.351589) (xy 11.177163 -56.410277) (xy 11.125202 -56.463739)
			(xy 11.067846 -56.511367) (xy 11.005748 -56.552622) (xy 10.939612 -56.587035) (xy 10.870189 -56.614214)
			(xy 10.798269 -56.633851) (xy 10.724667 -56.645723) (xy 10.65022 -56.649696) (xy 10.575773 -56.645723)
			(xy 10.502171 -56.633851) (xy 10.430251 -56.614214) (xy 10.360828 -56.587035) (xy 10.294692 -56.552622)
			(xy 10.232594 -56.511367) (xy 10.175238 -56.463739) (xy 10.123277 -56.410277) (xy 10.077299 -56.351589)
			(xy 10.037828 -56.288342) (xy 10.005312 -56.221253) (xy 9.980119 -56.151086) (xy 9.962537 -56.078635)
			(xy 9.952764 -56.004726) (xy 9.950912 -55.930195) (xy 9.957001 -55.855891) (xy 9.970963 -55.782657)
			(xy 9.992639 -55.711325) (xy 10.021783 -55.642704) (xy 10.058063 -55.577574) (xy 10.101068 -55.516675)
			(xy 10.15031 -55.460698) (xy 10.205229 -55.410279) (xy 10.23493 -55.387748) (xy 10.252906 -55.37315)
			(xy 10.283735 -55.338604) (xy 10.307797 -55.299044) (xy 10.324294 -55.25578) (xy 10.332681 -55.210244)
			(xy 10.332679 -55.163941) (xy 10.32429 -55.118405) (xy 10.307791 -55.075143) (xy 10.283727 -55.035585)
			(xy 10.252895 -55.00104) (xy 10.23493 -54.986428) (xy 10.204314 -54.963165) (xy 10.147845 -54.910974)
			(xy 10.097445 -54.8529) (xy 10.053722 -54.789646) (xy 10.017205 -54.721976) (xy 9.988335 -54.650707)
			(xy 9.967461 -54.5767) (xy 9.954835 -54.500849) (xy 9.950609 -54.424071) (xy 9.954834 -54.347293)
			(xy 9.967461 -54.271442) (xy 9.988334 -54.197435) (xy 10.017204 -54.126166) (xy 10.053721 -54.058496)
			(xy 10.097443 -53.995242) (xy 10.147844 -53.937168) (xy 10.204313 -53.884976) (xy 10.23493 -53.861716)
			(xy 10.252908 -53.847119) (xy 10.283743 -53.812574) (xy 10.307809 -53.773014) (xy 10.324309 -53.729749)
			(xy 10.332698 -53.68421) (xy 10.332698 -53.637905) (xy 10.324308 -53.592367) (xy 10.307807 -53.549102)
			(xy 10.28374 -53.509542) (xy 10.252905 -53.474998) (xy 10.23493 -53.460396) (xy 10.204322 -53.437142)
			(xy 10.147864 -53.384969) (xy 10.097473 -53.326917) (xy 10.053755 -53.263685) (xy 10.017239 -53.196039)
			(xy 9.988366 -53.124795) (xy 9.967485 -53.050812) (xy 9.954848 -52.974986) (xy 9.950606 -52.89823)
			(xy 9.954812 -52.821472) (xy 9.967415 -52.74564) (xy 9.988263 -52.671648) (xy 10.017103 -52.60039)
			(xy 10.053588 -52.532727) (xy 10.097277 -52.469476) (xy 10.147642 -52.411401) (xy 10.204075 -52.359202)
			(xy 10.234676 -52.335938) (xy 10.252656 -52.321325) (xy 10.283492 -52.286751) (xy 10.307557 -52.247165)
			(xy 10.324057 -52.203876) (xy 10.332446 -52.158314) (xy 10.332446 -52.111987) (xy 10.324057 -52.066426)
			(xy 10.307558 -52.023136) (xy 10.283492 -51.98355) (xy 10.252657 -51.948976) (xy 10.234676 -51.934364)
			(xy 10.204083 -51.911093) (xy 10.14766 -51.85889) (xy 10.097304 -51.800812) (xy 10.053624 -51.73756)
			(xy 10.017146 -51.669898) (xy 9.988312 -51.598642) (xy 9.967468 -51.524653) (xy 9.954868 -51.448825)
			(xy 9.950662 -51.372071) (xy 9.954903 -51.29532) (xy 9.967538 -51.219497) (xy 9.988414 -51.145517)
			(xy 10.017281 -51.074275) (xy 10.053789 -51.00663) (xy 10.097498 -50.943398) (xy 10.147881 -50.885342)
			(xy 10.204328 -50.833165) (xy 10.23493 -50.809906) (xy 10.252908 -50.795309) (xy 10.283743 -50.760764)
			(xy 10.307809 -50.721204) (xy 10.324309 -50.677939) (xy 10.332698 -50.6324) (xy 10.332698 -50.586095)
			(xy 10.324308 -50.540557) (xy 10.307807 -50.497292) (xy 10.28374 -50.457732) (xy 10.252905 -50.423188)
			(xy 10.23493 -50.408586) (xy 10.204314 -50.385323) (xy 10.147846 -50.333132) (xy 10.097445 -50.275058)
			(xy 10.053723 -50.211804) (xy 10.017206 -50.144134) (xy 9.988336 -50.072865) (xy 9.967462 -49.998859)
			(xy 9.954836 -49.923008) (xy 9.95061 -49.84623) (xy 9.954836 -49.769452) (xy 9.967462 -49.693601)
			(xy 9.988336 -49.619595) (xy 10.017206 -49.548326) (xy 10.053723 -49.480656) (xy 10.097445 -49.417402)
			(xy 10.147846 -49.359328) (xy 10.204314 -49.307137) (xy 10.23493 -49.283874) (xy 10.252908 -49.269275)
			(xy 10.283742 -49.234729) (xy 10.307808 -49.195167) (xy 10.32431 -49.151901) (xy 10.3327 -49.106362)
			(xy 10.332701 -49.060056) (xy 10.324314 -49.014515) (xy 10.307816 -48.971248) (xy 10.283753 -48.931685)
			(xy 10.252921 -48.897136) (xy 10.23493 -48.882554) (xy 10.20622 -48.860776) (xy 10.15298 -48.812207)
			(xy 10.105018 -48.758419) (xy 10.062844 -48.699982) (xy 10.026904 -48.637518) (xy 9.997581 -48.571687)
			(xy 9.975185 -48.50319) (xy 9.959954 -48.432752) (xy 9.95205 -48.361121) (xy 9.951556 -48.289057)
			(xy 9.954514 -48.253142) (xy 9.958702 -48.214976) (xy 9.97437 -48.13981) (xy 9.998183 -48.066813)
			(xy 10.029855 -47.996867) (xy 10.069002 -47.930814) (xy 10.091674 -47.899828) (xy 10.104196 -47.882489)
			(xy 10.123857 -47.844511) (xy 10.136877 -47.803775) (xy 10.142886 -47.761433) (xy 10.141714 -47.718683)
			(xy 10.133395 -47.676734) (xy 10.118164 -47.636772) (xy 10.096451 -47.599927) (xy 10.068871 -47.567243)
			(xy 10.052812 -47.553118) (xy 10.040862 -47.543644) (xy 10.013546 -47.530108) (xy 9.983798 -47.523444)
			(xy 9.953317 -47.524032) (xy 9.923848 -47.531839) (xy 9.897074 -47.546419) (xy 9.874527 -47.566938)
			(xy 9.857496 -47.592222) (xy 9.846953 -47.620827) (xy 9.844786 -47.635922) (xy 9.842381 -47.655507)
			(xy 9.835644 -47.694392) (xy 9.831324 -47.713646) (xy 9.822992 -47.748062) (xy 9.800271 -47.815133)
			(xy 9.770881 -47.87956) (xy 9.735124 -47.940684) (xy 9.693366 -47.997877) (xy 9.646036 -48.050551)
			(xy 9.593619 -48.098167) (xy 9.565386 -48.119538) (xy 9.547408 -48.134136) (xy 9.516574 -48.168682)
			(xy 9.492508 -48.208242) (xy 9.476008 -48.251507) (xy 9.467619 -48.297046) (xy 9.467619 -48.343351)
			(xy 9.476007 -48.38889) (xy 9.492507 -48.432156) (xy 9.516572 -48.471716) (xy 9.547406 -48.506262)
			(xy 9.565386 -48.520858) (xy 9.596001 -48.54412) (xy 9.65247 -48.596312) (xy 9.70287 -48.654385)
			(xy 9.746593 -48.717639) (xy 9.783109 -48.785309) (xy 9.811979 -48.856578) (xy 9.832853 -48.930584)
			(xy 9.845478 -49.006435) (xy 9.849704 -49.083212) (xy 9.845478 -49.15999) (xy 9.832851 -49.23584)
			(xy 9.811977 -49.309847) (xy 9.783107 -49.381115) (xy 9.74659 -49.448785) (xy 9.702867 -49.512038)
			(xy 9.652467 -49.570111) (xy 9.595998 -49.622303) (xy 9.565386 -49.64557) (xy 9.547408 -49.660167)
			(xy 9.516573 -49.694713) (xy 9.492507 -49.734273) (xy 9.476006 -49.777538) (xy 9.467617 -49.823077)
			(xy 9.467617 -49.869383) (xy 9.476006 -49.914922) (xy 9.492507 -49.958187) (xy 9.516573 -49.997747)
			(xy 9.547408 -50.032293) (xy 9.565386 -50.04689) (xy 9.59523 -50.069539) (xy 9.650395 -50.12024)
			(xy 9.699822 -50.176549) (xy 9.742943 -50.237821) (xy 9.779265 -50.303353) (xy 9.80837 -50.372394)
			(xy 9.829925 -50.444152) (xy 9.843682 -50.517802) (xy 9.849484 -50.592502) (xy 9.847264 -50.667394)
			(xy 9.837048 -50.741619) (xy 9.818952 -50.814326) (xy 9.793185 -50.884681) (xy 9.760042 -50.951876)
			(xy 9.719903 -51.015142) (xy 9.673228 -51.073752) (xy 9.620553 -51.127035) (xy 9.562482 -51.174379)
			(xy 9.53135 -51.195224) (xy 9.520174 -51.20259) (xy 9.16305 -51.559714) (xy 8.775192 -51.559714)
			(xy 8.553958 -51.780948) (xy 8.553958 -52.533296) (xy 8.756142 -52.73548) (xy 9.271 -52.73548) (xy 9.271 -52.914804)
			(xy 9.320276 -52.98186) (xy 9.3599 -52.994306) (xy 9.396513 -53.006365) (xy 9.467054 -53.037456)
			(xy 9.533745 -53.076121) (xy 9.595777 -53.121891) (xy 9.652395 -53.174208) (xy 9.702912 -53.232438)
			(xy 9.746715 -53.295873) (xy 9.783271 -53.363743) (xy 9.812136 -53.435224) (xy 9.832961 -53.509447)
			(xy 9.845491 -53.585511) (xy 9.848088 -53.623972) (xy 9.849598 -53.662314) (xy 9.845244 -53.738928)
			(xy 9.83253 -53.814604) (xy 9.811607 -53.888434) (xy 9.782728 -53.95953) (xy 9.74624 -54.027037)
			(xy 9.702581 -54.090144) (xy 9.652276 -54.148092) (xy 9.59593 -54.200185) (xy 9.565386 -54.223412)
			(xy 9.547408 -54.238009) (xy 9.516573 -54.272555) (xy 9.492507 -54.312115) (xy 9.476007 -54.35538)
			(xy 9.467618 -54.400919) (xy 9.467618 -54.447224) (xy 9.476008 -54.492762) (xy 9.492508 -54.536028)
			(xy 9.516575 -54.575587) (xy 9.54741 -54.610132) (xy 9.565386 -54.624732) (xy 9.593761 -54.646242)
			(xy 9.646441 -54.694153) (xy 9.693978 -54.747169) (xy 9.735882 -54.804743) (xy 9.771717 -54.866277)
			(xy 9.801113 -54.931134) (xy 9.823765 -54.998643) (xy 9.839439 -55.068104) (xy 9.847973 -55.138799)
			(xy 9.849104 -55.174388) (xy 9.849257 -55.214522) (xy 9.841483 -55.294406) (xy 9.824611 -55.372875)
			(xy 9.798865 -55.448895) (xy 9.764582 -55.521466) (xy 9.722214 -55.589634) (xy 9.69772 -55.621428)
			(xy 9.673738 -55.65089) (xy 9.620382 -55.704968) (xy 9.561475 -55.752941) (xy 9.497715 -55.794245)
			(xy 9.429851 -55.828391) (xy 9.394444 -55.842154) (xy 9.35863 -55.855362) (xy 9.271 -55.974996) (xy 9.271 -56.881776)
			(xy 14.079726 -56.881776) (xy 14.083797 -56.826154) (xy 14.095923 -56.771717) (xy 14.115846 -56.719626)
			(xy 14.143142 -56.670991) (xy 14.177228 -56.626848) (xy 14.217377 -56.588139) (xy 14.262735 -56.555688)
			(xy 14.312335 -56.530187) (xy 14.365119 -56.51218) (xy 14.419962 -56.50205) (xy 14.475696 -56.500013)
			(xy 14.531133 -56.506113) (xy 14.58509 -56.520219) (xy 14.636419 -56.542031) (xy 14.684025 -56.571085)
			(xy 14.726893 -56.60676) (xy 14.76411 -56.648297) (xy 14.794883 -56.69481) (xy 14.818555 -56.745307)
			(xy 14.834623 -56.798714) (xy 14.842743 -56.85389) (xy 14.843252 -56.881776) (xy 14.842743 -56.909662)
			(xy 14.834623 -56.964838) (xy 14.818555 -57.018245) (xy 14.794883 -57.068742) (xy 14.76411 -57.115255)
			(xy 14.726893 -57.156792) (xy 14.689883 -57.187592) (xy 17.944082 -57.187592) (xy 17.948153 -57.13197)
			(xy 17.960279 -57.077533) (xy 17.980202 -57.025442) (xy 18.007498 -56.976807) (xy 18.041584 -56.932664)
			(xy 18.081733 -56.893955) (xy 18.127091 -56.861504) (xy 18.176691 -56.836003) (xy 18.229475 -56.817996)
			(xy 18.284318 -56.807866) (xy 18.340052 -56.805829) (xy 18.395489 -56.811929) (xy 18.449446 -56.826035)
			(xy 18.500775 -56.847847) (xy 18.548381 -56.876901) (xy 18.591249 -56.912576) (xy 18.628466 -56.954113)
			(xy 18.659239 -57.000626) (xy 18.682911 -57.051123) (xy 18.698979 -57.10453) (xy 18.707099 -57.159706)
			(xy 18.707608 -57.187592) (xy 18.707099 -57.215478) (xy 18.698979 -57.270654) (xy 18.682911 -57.324061)
			(xy 18.659239 -57.374558) (xy 18.628466 -57.421071) (xy 18.591249 -57.462608) (xy 18.548381 -57.498283)
			(xy 18.500775 -57.527337) (xy 18.449446 -57.549149) (xy 18.395489 -57.563255) (xy 18.340052 -57.569355)
			(xy 18.284318 -57.567318) (xy 18.229475 -57.557188) (xy 18.176691 -57.539181) (xy 18.127091 -57.51368)
			(xy 18.081733 -57.481229) (xy 18.041584 -57.44252) (xy 18.007498 -57.398377) (xy 17.980202 -57.349742)
			(xy 17.960279 -57.297651) (xy 17.948153 -57.243214) (xy 17.944082 -57.187592) (xy 14.689883 -57.187592)
			(xy 14.684025 -57.192467) (xy 14.636419 -57.221521) (xy 14.58509 -57.243333) (xy 14.531133 -57.257439)
			(xy 14.475696 -57.263539) (xy 14.419962 -57.261502) (xy 14.365119 -57.251372) (xy 14.312335 -57.233365)
			(xy 14.262735 -57.207864) (xy 14.217377 -57.175413) (xy 14.177228 -57.136704) (xy 14.143142 -57.092561)
			(xy 14.115846 -57.043926) (xy 14.095923 -56.991835) (xy 14.083797 -56.937398) (xy 14.079726 -56.881776)
			(xy 9.271 -56.881776) (xy 9.271 -58.837889) (xy 9.994378 -58.837889) (xy 9.994378 -58.742267) (xy 10.002274 -58.646971)
			(xy 10.018013 -58.552653) (xy 10.041487 -58.459956) (xy 10.072536 -58.369515) (xy 10.110947 -58.281947)
			(xy 10.156458 -58.197849) (xy 10.208758 -58.117797) (xy 10.267491 -58.042338) (xy 10.332254 -57.971986)
			(xy 10.402606 -57.907223) (xy 10.478065 -57.84849) (xy 10.558117 -57.79619) (xy 10.642215 -57.750679)
			(xy 10.729783 -57.712268) (xy 10.820224 -57.681219) (xy 10.912921 -57.657745) (xy 11.007239 -57.642006)
			(xy 11.102535 -57.63411) (xy 11.198157 -57.63411) (xy 11.293453 -57.642006) (xy 11.387771 -57.657745)
			(xy 11.480468 -57.681219) (xy 11.570909 -57.712268) (xy 11.658477 -57.750679) (xy 11.742575 -57.79619)
			(xy 11.822627 -57.84849) (xy 11.898086 -57.907223) (xy 11.968438 -57.971986) (xy 12.033201 -58.042338)
			(xy 12.066782 -58.085482) (xy 15.802862 -58.085482) (xy 15.806933 -58.02986) (xy 15.819059 -57.975423)
			(xy 15.838982 -57.923332) (xy 15.866278 -57.874697) (xy 15.900364 -57.830554) (xy 15.940513 -57.791845)
			(xy 15.985871 -57.759394) (xy 16.035471 -57.733893) (xy 16.088255 -57.715886) (xy 16.143098 -57.705756)
			(xy 16.198832 -57.703719) (xy 16.254269 -57.709819) (xy 16.308226 -57.723925) (xy 16.359555 -57.745737)
			(xy 16.407161 -57.774791) (xy 16.450029 -57.810466) (xy 16.487246 -57.852003) (xy 16.518019 -57.898516)
			(xy 16.541691 -57.949013) (xy 16.557759 -58.00242) (xy 16.565879 -58.057596) (xy 16.566388 -58.085482)
			(xy 16.565879 -58.113368) (xy 16.557759 -58.168544) (xy 16.541691 -58.221951) (xy 16.518019 -58.272448)
			(xy 16.487246 -58.318961) (xy 16.450029 -58.360498) (xy 16.407161 -58.396173) (xy 16.363779 -58.422649)
			(xy 19.586611 -58.422649) (xy 19.587227 -58.368134) (xy 19.595598 -58.314263) (xy 19.611554 -58.262131)
			(xy 19.634768 -58.212802) (xy 19.664768 -58.16728) (xy 19.700943 -58.126493) (xy 19.742557 -58.091271)
			(xy 19.78876 -58.062332) (xy 19.838613 -58.040266) (xy 19.8911 -58.025521) (xy 19.945151 -58.018399)
			(xy 19.999666 -58.019044) (xy 20.053533 -58.027443) (xy 20.105656 -58.043426) (xy 20.154973 -58.066666)
			(xy 20.200479 -58.09669) (xy 20.241247 -58.132887) (xy 20.276447 -58.174519) (xy 20.305362 -58.220738)
			(xy 20.327402 -58.270603) (xy 20.342119 -58.323097) (xy 20.349213 -58.377152) (xy 20.348539 -58.431666)
			(xy 20.340111 -58.485529) (xy 20.324101 -58.537644) (xy 20.312888 -58.562494) (xy 20.303335 -58.583842)
			(xy 20.291396 -58.629056) (xy 20.287938 -58.675692) (xy 20.293078 -58.722173) (xy 20.306642 -58.766927)
			(xy 20.328172 -58.80844) (xy 20.356939 -58.845309) (xy 20.374102 -58.861198) (xy 20.394154 -58.879666)
			(xy 20.429388 -58.921259) (xy 20.458343 -58.967444) (xy 20.480427 -59.017281) (xy 20.495192 -59.069754)
			(xy 20.502336 -59.123795) (xy 20.501713 -59.178303) (xy 20.493338 -59.232166) (xy 20.477379 -59.284289)
			(xy 20.454162 -59.333608) (xy 20.424161 -59.379121) (xy 20.387986 -59.419898) (xy 20.346374 -59.45511)
			(xy 20.300173 -59.48404) (xy 20.250324 -59.506097) (xy 20.197843 -59.520833) (xy 20.143798 -59.527948)
			(xy 20.089291 -59.527296) (xy 20.035432 -59.518891) (xy 19.983318 -59.502904) (xy 19.934011 -59.479661)
			(xy 19.888515 -59.449635) (xy 19.847757 -59.413438) (xy 19.812568 -59.371807) (xy 19.783663 -59.32559)
			(xy 19.761633 -59.275729) (xy 19.746925 -59.22324) (xy 19.73984 -59.169192) (xy 19.740521 -59.114685)
			(xy 19.748955 -59.06083) (xy 19.76497 -59.008725) (xy 19.776186 -58.98388) (xy 19.785772 -58.962546)
			(xy 19.797709 -58.917327) (xy 19.801164 -58.870687) (xy 19.796019 -58.824202) (xy 19.782449 -58.779446)
			(xy 19.760913 -58.737932) (xy 19.732138 -58.701064) (xy 19.714972 -58.685176) (xy 19.694833 -58.6668)
			(xy 19.65959 -58.625206) (xy 19.630627 -58.579017) (xy 19.608534 -58.529176) (xy 19.593762 -58.476697)
			(xy 19.586611 -58.422649) (xy 16.363779 -58.422649) (xy 16.359555 -58.425227) (xy 16.308226 -58.447039)
			(xy 16.254269 -58.461145) (xy 16.198832 -58.467245) (xy 16.143098 -58.465208) (xy 16.088255 -58.455078)
			(xy 16.035471 -58.437071) (xy 15.985871 -58.41157) (xy 15.940513 -58.379119) (xy 15.900364 -58.34041)
			(xy 15.866278 -58.296267) (xy 15.838982 -58.247632) (xy 15.819059 -58.195541) (xy 15.806933 -58.141104)
			(xy 15.802862 -58.085482) (xy 12.066782 -58.085482) (xy 12.091934 -58.117797) (xy 12.144234 -58.197849)
			(xy 12.189745 -58.281947) (xy 12.228156 -58.369515) (xy 12.259205 -58.459956) (xy 12.282679 -58.552653)
			(xy 12.298418 -58.646971) (xy 12.306314 -58.742267) (xy 12.306808 -58.790078) (xy 12.306314 -58.837889)
			(xy 12.298418 -58.933185) (xy 12.282679 -59.027503) (xy 12.259205 -59.1202) (xy 12.228156 -59.210641)
			(xy 12.189745 -59.298209) (xy 12.144234 -59.382307) (xy 12.091934 -59.462359) (xy 12.033201 -59.537818)
			(xy 11.968438 -59.60817) (xy 11.898086 -59.672933) (xy 11.822627 -59.731666) (xy 11.742575 -59.783966)
			(xy 11.658477 -59.829477) (xy 11.570909 -59.867888) (xy 11.480468 -59.898937) (xy 11.387771 -59.922411)
			(xy 11.293453 -59.93815) (xy 11.198157 -59.946046) (xy 11.102535 -59.946046) (xy 11.007239 -59.93815)
			(xy 10.912921 -59.922411) (xy 10.820224 -59.898937) (xy 10.729783 -59.867888) (xy 10.642215 -59.829477)
			(xy 10.558117 -59.783966) (xy 10.478065 -59.731666) (xy 10.402606 -59.672933) (xy 10.332254 -59.60817)
			(xy 10.267491 -59.537818) (xy 10.208758 -59.462359) (xy 10.156458 -59.382307) (xy 10.110947 -59.298209)
			(xy 10.072536 -59.210641) (xy 10.041487 -59.1202) (xy 10.018013 -59.027503) (xy 10.002274 -58.933185)
			(xy 9.994378 -58.837889) (xy 9.271 -58.837889) (xy 9.271 -60.743588) (xy 15.727154 -60.743588) (xy 15.727154 -60.683652)
			(xy 15.734977 -60.62423) (xy 15.75049 -60.566337) (xy 15.773426 -60.510964) (xy 15.803393 -60.459058)
			(xy 15.83988 -60.411508) (xy 15.88226 -60.369128) (xy 15.92981 -60.332641) (xy 15.981716 -60.302674)
			(xy 16.037089 -60.279738) (xy 16.094982 -60.264225) (xy 16.154404 -60.256402) (xy 16.21434 -60.256402)
			(xy 16.273762 -60.264225) (xy 16.331655 -60.279738) (xy 16.387028 -60.302674) (xy 16.438934 -60.332641)
			(xy 16.486484 -60.369128) (xy 16.528864 -60.411508) (xy 16.565351 -60.459058) (xy 16.595318 -60.510964)
			(xy 16.618254 -60.566337) (xy 16.633767 -60.62423) (xy 16.64159 -60.683652) (xy 16.64208 -60.71362)
			(xy 16.64159 -60.743588) (xy 16.633767 -60.80301) (xy 16.618254 -60.860903) (xy 16.595318 -60.916276)
			(xy 16.565351 -60.968182) (xy 16.528864 -61.015732) (xy 16.486484 -61.058112) (xy 16.438934 -61.094599)
			(xy 16.387028 -61.124566) (xy 16.331655 -61.147502) (xy 16.273762 -61.163015) (xy 16.21434 -61.170838)
			(xy 16.154404 -61.170838) (xy 16.094982 -61.163015) (xy 16.037089 -61.147502) (xy 15.981716 -61.124566)
			(xy 15.92981 -61.094599) (xy 15.88226 -61.058112) (xy 15.83988 -61.015732) (xy 15.803393 -60.968182)
			(xy 15.773426 -60.916276) (xy 15.75049 -60.860903) (xy 15.734977 -60.80301) (xy 15.727154 -60.743588)
			(xy 9.271 -60.743588) (xy 9.271 -64.501776) (xy 9.714992 -64.501776) (xy 9.714992 -62.088776) (xy 9.715492 -62.053129)
			(xy 9.723474 -61.982283) (xy 9.739338 -61.912777) (xy 9.762885 -61.845483) (xy 9.793819 -61.78125)
			(xy 9.83175 -61.720883) (xy 9.876201 -61.665143) (xy 9.926613 -61.614731) (xy 9.982353 -61.57028)
			(xy 10.04272 -61.532349) (xy 10.106953 -61.501415) (xy 10.174247 -61.477868) (xy 10.243753 -61.462004)
			(xy 10.314599 -61.454022) (xy 10.385893 -61.454022) (xy 10.456739 -61.462004) (xy 10.526245 -61.477868)
			(xy 10.593539 -61.501415) (xy 10.657772 -61.532349) (xy 10.718139 -61.57028) (xy 10.773879 -61.614731)
			(xy 10.824291 -61.665143) (xy 10.868742 -61.720883) (xy 10.906673 -61.78125) (xy 10.937607 -61.845483)
			(xy 10.961154 -61.912777) (xy 10.977018 -61.982283) (xy 10.977483 -61.986414) (xy 22.071328 -61.986414)
			(xy 22.075399 -61.930792) (xy 22.087525 -61.876355) (xy 22.107448 -61.824264) (xy 22.134744 -61.775629)
			(xy 22.16883 -61.731486) (xy 22.208979 -61.692777) (xy 22.254337 -61.660326) (xy 22.303937 -61.634825)
			(xy 22.356721 -61.616818) (xy 22.411564 -61.606688) (xy 22.467298 -61.604651) (xy 22.522735 -61.610751)
			(xy 22.576692 -61.624857) (xy 22.628021 -61.646669) (xy 22.675627 -61.675723) (xy 22.718495 -61.711398)
			(xy 22.755712 -61.752935) (xy 22.786485 -61.799448) (xy 22.810157 -61.849945) (xy 22.826225 -61.903352)
			(xy 22.834345 -61.958528) (xy 22.834854 -61.986414) (xy 22.834345 -62.0143) (xy 22.826225 -62.069476)
			(xy 22.810157 -62.122883) (xy 22.786485 -62.17338) (xy 22.755712 -62.219893) (xy 22.718495 -62.26143)
			(xy 22.675627 -62.297105) (xy 22.628021 -62.326159) (xy 22.576692 -62.347971) (xy 22.522735 -62.362077)
			(xy 22.467298 -62.368177) (xy 22.411564 -62.36614) (xy 22.356721 -62.35601) (xy 22.303937 -62.338003)
			(xy 22.254337 -62.312502) (xy 22.208979 -62.280051) (xy 22.16883 -62.241342) (xy 22.134744 -62.197199)
			(xy 22.107448 -62.148564) (xy 22.087525 -62.096473) (xy 22.075399 -62.042036) (xy 22.071328 -61.986414)
			(xy 10.977483 -61.986414) (xy 10.985 -62.053129) (xy 10.9855 -62.088776) (xy 10.9855 -63.311786)
			(xy 21.583648 -63.311786) (xy 21.587719 -63.256164) (xy 21.599845 -63.201727) (xy 21.619768 -63.149636)
			(xy 21.647064 -63.101001) (xy 21.68115 -63.056858) (xy 21.721299 -63.018149) (xy 21.766657 -62.985698)
			(xy 21.816257 -62.960197) (xy 21.869041 -62.94219) (xy 21.923884 -62.93206) (xy 21.979618 -62.930023)
			(xy 22.035055 -62.936123) (xy 22.089012 -62.950229) (xy 22.140341 -62.972041) (xy 22.187947 -63.001095)
			(xy 22.230815 -63.03677) (xy 22.268032 -63.078307) (xy 22.298805 -63.12482) (xy 22.322477 -63.175317)
			(xy 22.338545 -63.228724) (xy 22.346665 -63.2839) (xy 22.347174 -63.311786) (xy 22.346665 -63.339672)
			(xy 22.338545 -63.394848) (xy 22.322477 -63.448255) (xy 22.298805 -63.498752) (xy 22.268032 -63.545265)
			(xy 22.230815 -63.586802) (xy 22.187947 -63.622477) (xy 22.140341 -63.651531) (xy 22.089012 -63.673343)
			(xy 22.035055 -63.687449) (xy 21.979618 -63.693549) (xy 21.923884 -63.691512) (xy 21.869041 -63.681382)
			(xy 21.816257 -63.663375) (xy 21.766657 -63.637874) (xy 21.721299 -63.605423) (xy 21.68115 -63.566714)
			(xy 21.647064 -63.522571) (xy 21.619768 -63.473936) (xy 21.599845 -63.421845) (xy 21.587719 -63.367408)
			(xy 21.583648 -63.311786) (xy 10.9855 -63.311786) (xy 10.9855 -64.501776) (xy 10.985 -64.537423)
			(xy 10.977018 -64.608269) (xy 10.961154 -64.677775) (xy 10.937607 -64.745069) (xy 10.906673 -64.809302)
			(xy 10.868742 -64.869669) (xy 10.824291 -64.925409) (xy 10.773879 -64.975821) (xy 10.718139 -65.020272)
			(xy 10.657772 -65.058203) (xy 10.593539 -65.089137) (xy 10.526245 -65.112684) (xy 10.456739 -65.128548)
			(xy 10.385893 -65.13653) (xy 10.314599 -65.13653) (xy 10.243753 -65.128548) (xy 10.174247 -65.112684)
			(xy 10.106953 -65.089137) (xy 10.04272 -65.058203) (xy 9.982353 -65.020272) (xy 9.926613 -64.975821)
			(xy 9.876201 -64.925409) (xy 9.83175 -64.869669) (xy 9.793819 -64.809302) (xy 9.762885 -64.745069)
			(xy 9.739338 -64.677775) (xy 9.723474 -64.608269) (xy 9.715492 -64.537423) (xy 9.714992 -64.501776)
			(xy 9.271 -64.501776) (xy 9.271 -65.290446) (xy 13.34973 -65.290446) (xy 13.353801 -65.234824) (xy 13.365927 -65.180387)
			(xy 13.38585 -65.128296) (xy 13.413146 -65.079661) (xy 13.447232 -65.035518) (xy 13.487381 -64.996809)
			(xy 13.532739 -64.964358) (xy 13.582339 -64.938857) (xy 13.635123 -64.92085) (xy 13.689966 -64.91072)
			(xy 13.7457 -64.908683) (xy 13.801137 -64.914783) (xy 13.855094 -64.928889) (xy 13.906423 -64.950701)
			(xy 13.954029 -64.979755) (xy 13.996897 -65.01543) (xy 14.034114 -65.056967) (xy 14.064887 -65.10348)
			(xy 14.088559 -65.153977) (xy 14.104627 -65.207384) (xy 14.112747 -65.26256) (xy 14.113256 -65.290446)
			(xy 14.112747 -65.318332) (xy 14.104627 -65.373508) (xy 14.088559 -65.426915) (xy 14.064887 -65.477412)
			(xy 14.034114 -65.523925) (xy 13.996897 -65.565462) (xy 13.954029 -65.601137) (xy 13.906423 -65.630191)
			(xy 13.855094 -65.652003) (xy 13.801137 -65.666109) (xy 13.7457 -65.672209) (xy 13.689966 -65.670172)
			(xy 13.635123 -65.660042) (xy 13.582339 -65.642035) (xy 13.532739 -65.616534) (xy 13.487381 -65.584083)
			(xy 13.447232 -65.545374) (xy 13.413146 -65.501231) (xy 13.38585 -65.452596) (xy 13.365927 -65.400505)
			(xy 13.353801 -65.346068) (xy 13.34973 -65.290446) (xy 9.271 -65.290446) (xy 9.271 -66.26424) (xy 19.160781 -66.26424)
			(xy 19.162431 -66.20395) (xy 19.171983 -66.144398) (xy 19.189275 -66.086617) (xy 19.214004 -66.031607)
			(xy 19.245744 -65.980321) (xy 19.283944 -65.933647) (xy 19.327943 -65.892395) (xy 19.376979 -65.857278)
			(xy 19.430201 -65.828905) (xy 19.486689 -65.807767) (xy 19.545463 -65.794231) (xy 19.605507 -65.788531)
			(xy 19.665778 -65.790766) (xy 19.725234 -65.800897) (xy 19.782845 -65.818748) (xy 19.837613 -65.844011)
			(xy 19.888588 -65.876247) (xy 19.934888 -65.914899) (xy 19.975712 -65.959296) (xy 20.010351 -66.00867)
			(xy 20.038205 -66.062166) (xy 20.058794 -66.118856) (xy 20.065746 -66.148204) (xy 20.069507 -66.162909)
			(xy 20.082938 -66.190117) (xy 20.102419 -66.21338) (xy 20.126846 -66.231379) (xy 20.154836 -66.243094)
			(xy 20.184802 -66.247861) (xy 20.215045 -66.24541) (xy 20.243852 -66.235879) (xy 20.26959 -66.21981)
			(xy 20.2908 -66.198112) (xy 20.298918 -66.185288) (xy 20.30597 -66.173707) (xy 20.321477 -66.151459)
			(xy 20.329906 -66.140838) (xy 20.344391 -66.121924) (xy 20.366749 -66.079862) (xy 20.380881 -66.034371)
			(xy 20.386293 -65.987045) (xy 20.382797 -65.939538) (xy 20.370514 -65.893514) (xy 20.349874 -65.850582)
			(xy 20.3216 -65.812246) (xy 20.304506 -65.795652) (xy 20.282644 -65.774689) (xy 20.244069 -65.727994)
			(xy 20.211989 -65.676619) (xy 20.186966 -65.621461) (xy 20.169436 -65.563485) (xy 20.159707 -65.503704)
			(xy 20.157947 -65.443161) (xy 20.164188 -65.382915) (xy 20.178321 -65.324019) (xy 20.200099 -65.267501)
			(xy 20.22914 -65.214349) (xy 20.264939 -65.165493) (xy 20.306869 -65.121784) (xy 20.354197 -65.083989)
			(xy 20.406097 -65.052765) (xy 20.461662 -65.02866) (xy 20.519921 -65.012094) (xy 20.579856 -65.003357)
			(xy 20.640419 -65.002602) (xy 20.700553 -65.009841) (xy 20.759207 -65.024948) (xy 20.815356 -65.04766)
			(xy 20.868019 -65.077579) (xy 20.916275 -65.114183) (xy 20.959282 -65.156832) (xy 20.996288 -65.20478)
			(xy 21.026647 -65.257191) (xy 21.049827 -65.313148) (xy 21.065425 -65.371673) (xy 21.073167 -65.431745)
			(xy 21.072918 -65.492312) (xy 21.064682 -65.552318) (xy 21.048604 -65.610714) (xy 21.024965 -65.666478)
			(xy 20.994177 -65.718638) (xy 20.956778 -65.76628) (xy 20.935442 -65.787778) (xy 20.918783 -65.804811)
			(xy 20.891481 -65.843848) (xy 20.871935 -65.88729) (xy 20.86083 -65.933614) (xy 20.858555 -65.981197)
			(xy 20.865191 -66.028369) (xy 20.880504 -66.073478) (xy 20.903958 -66.114941) (xy 20.918932 -66.133472)
			(xy 20.936402 -66.155144) (xy 20.965739 -66.202444) (xy 20.98789 -66.253506) (xy 21.002386 -66.307244)
			(xy 21.008919 -66.362518) (xy 21.00735 -66.418155) (xy 20.997714 -66.472974) (xy 20.980213 -66.52581)
			(xy 20.95522 -66.575543) (xy 20.923265 -66.621115) (xy 20.885027 -66.66156) (xy 20.841318 -66.696019)
			(xy 20.793065 -66.723761) (xy 20.741293 -66.744196) (xy 20.687101 -66.756891) (xy 20.631639 -66.761577)
			(xy 20.576085 -66.758152) (xy 20.521619 -66.746692) (xy 20.469396 -66.727438) (xy 20.420525 -66.7008)
			(xy 20.376044 -66.667342) (xy 20.336898 -66.627776) (xy 20.32 -66.605658) (xy 20.306747 -66.588455)
			(xy 20.275432 -66.558373) (xy 20.239457 -66.534055) (xy 20.19987 -66.51621) (xy 20.157826 -66.505357)
			(xy 20.114548 -66.501813) (xy 20.071298 -66.505681) (xy 20.029335 -66.516848) (xy 19.989884 -66.534989)
			(xy 19.954092 -66.559576) (xy 19.938238 -66.574416) (xy 19.91628 -66.595093) (xy 19.867935 -66.631155)
			(xy 19.815274 -66.660556) (xy 19.759207 -66.682786) (xy 19.700707 -66.697461) (xy 19.640785 -66.704326)
			(xy 19.580482 -66.703262) (xy 19.52084 -66.694288) (xy 19.462894 -66.677559) (xy 19.407646 -66.653364)
			(xy 19.356054 -66.622124) (xy 19.309012 -66.584379) (xy 19.267334 -66.540782) (xy 19.231743 -66.49209)
			(xy 19.202855 -66.439145) (xy 19.18117 -66.382866) (xy 19.167064 -66.324225) (xy 19.160781 -66.26424)
			(xy 9.271 -66.26424) (xy 9.271 -67.965066) (xy 19.822158 -67.965066) (xy 19.826229 -67.909444) (xy 19.838355 -67.855007)
			(xy 19.858278 -67.802916) (xy 19.885574 -67.754281) (xy 19.91966 -67.710138) (xy 19.959809 -67.671429)
			(xy 20.005167 -67.638978) (xy 20.054767 -67.613477) (xy 20.107551 -67.59547) (xy 20.162394 -67.58534)
			(xy 20.218128 -67.583303) (xy 20.273565 -67.589403) (xy 20.327522 -67.603509) (xy 20.378851 -67.625321)
			(xy 20.426457 -67.654375) (xy 20.469325 -67.69005) (xy 20.506542 -67.731587) (xy 20.537315 -67.7781)
			(xy 20.560987 -67.828597) (xy 20.577055 -67.882004) (xy 20.585175 -67.93718) (xy 20.585684 -67.965066)
			(xy 20.585175 -67.992952) (xy 20.577055 -68.048128) (xy 20.560987 -68.101535) (xy 20.537315 -68.152032)
			(xy 20.506542 -68.198545) (xy 20.469325 -68.240082) (xy 20.426457 -68.275757) (xy 20.378851 -68.304811)
			(xy 20.327522 -68.326623) (xy 20.273565 -68.340729) (xy 20.218128 -68.346829) (xy 20.162394 -68.344792)
			(xy 20.107551 -68.334662) (xy 20.054767 -68.316655) (xy 20.005167 -68.291154) (xy 19.959809 -68.258703)
			(xy 19.91966 -68.219994) (xy 19.885574 -68.175851) (xy 19.858278 -68.127216) (xy 19.838355 -68.075125)
			(xy 19.826229 -68.020688) (xy 19.822158 -67.965066) (xy 9.271 -67.965066) (xy 9.271 -69.42328) (xy 11.942826 -72.095106)
			(xy 24.82215 -72.095106)
		)
		(stroke
			(width 0)
			(type solid)
		)
		(fill yes)
		(layer "B.Cu")
		(net "P5V_CRT")
	)
	(gr_poly
		(pts
			(xy 177.772568 -140.377164) (xy 177.789078 -140.3604) (xy 177.808702 -140.341298) (xy 177.852441 -140.308345)
			(xy 177.900442 -140.281985) (xy 177.95172 -140.262759) (xy 178.00522 -140.251063) (xy 178.059842 -140.247138)
			(xy 178.114464 -140.251063) (xy 178.167964 -140.262759) (xy 178.219242 -140.281985) (xy 178.267243 -140.308345)
			(xy 178.310982 -140.341298) (xy 178.330606 -140.3604) (xy 178.347116 -140.377164) (xy 178.440588 -140.419328)
			(xy 181.2036 -140.419328) (xy 190.690754 -130.932174) (xy 190.690754 -121.615962) (xy 189.4078 -120.333008)
			(xy 182.9054 -120.333008) (xy 182.88 -120.344692) (xy 182.854805 -120.355812) (xy 182.802014 -120.371499)
			(xy 182.747516 -120.379424) (xy 182.692444 -120.379424) (xy 182.637946 -120.371499) (xy 182.585155 -120.355812)
			(xy 182.55996 -120.344692) (xy 182.53456 -120.333008) (xy 181.089808 -120.333008) (xy 181.068026 -120.333464)
			(xy 181.025103 -120.340903) (xy 180.984076 -120.35555) (xy 180.946145 -120.376974) (xy 180.91242 -120.404549)
			(xy 180.883888 -120.437468) (xy 180.861383 -120.474769) (xy 180.845565 -120.515359) (xy 180.836896 -120.558051)
			(xy 180.83563 -120.601596) (xy 180.841803 -120.64472) (xy 180.855235 -120.68616) (xy 180.865018 -120.705626)
			(xy 180.878507 -120.729853) (xy 180.899108 -120.781332) (xy 180.912037 -120.835252) (xy 180.917021 -120.890477)
			(xy 180.913956 -120.94584) (xy 180.902905 -121.000177) (xy 180.893974 -121.026428) (xy 180.884471 -121.05142)
			(xy 180.859469 -121.098684) (xy 180.82812 -121.141999) (xy 180.791034 -121.180516) (xy 180.770276 -121.19737)
			(xy 180.753135 -121.211366) (xy 180.723511 -121.244235) (xy 180.700033 -121.281742) (xy 180.683412 -121.322751)
			(xy 180.674152 -121.36602) (xy 180.672533 -121.410239) (xy 180.678604 -121.45407) (xy 180.69218 -121.496185)
			(xy 180.708224 -121.52655) (xy 182.458342 -121.52655) (xy 182.458342 -121.466614) (xy 182.466165 -121.407192)
			(xy 182.481678 -121.349299) (xy 182.504614 -121.293926) (xy 182.534581 -121.24202) (xy 182.571068 -121.19447)
			(xy 182.613448 -121.15209) (xy 182.660998 -121.115603) (xy 182.712904 -121.085636) (xy 182.768277 -121.0627)
			(xy 182.82617 -121.047187) (xy 182.885592 -121.039364) (xy 182.945528 -121.039364) (xy 183.00495 -121.047187)
			(xy 183.062843 -121.0627) (xy 183.118216 -121.085636) (xy 183.121691 -121.087642) (xy 185.378342 -121.087642)
			(xy 185.382413 -121.03202) (xy 185.394539 -120.977583) (xy 185.414462 -120.925492) (xy 185.441758 -120.876857)
			(xy 185.475844 -120.832714) (xy 185.515993 -120.794005) (xy 185.561351 -120.761554) (xy 185.610951 -120.736053)
			(xy 185.663735 -120.718046) (xy 185.718578 -120.707916) (xy 185.774312 -120.705879) (xy 185.829749 -120.711979)
			(xy 185.883706 -120.726085) (xy 185.935035 -120.747897) (xy 185.982641 -120.776951) (xy 186.025509 -120.812626)
			(xy 186.062726 -120.854163) (xy 186.093499 -120.900676) (xy 186.117171 -120.951173) (xy 186.133239 -121.00458)
			(xy 186.141359 -121.059756) (xy 186.141868 -121.087642) (xy 186.141359 -121.115528) (xy 186.133239 -121.170704)
			(xy 186.117171 -121.224111) (xy 186.093499 -121.274608) (xy 186.062726 -121.321121) (xy 186.025509 -121.362658)
			(xy 185.982641 -121.398333) (xy 185.935035 -121.427387) (xy 185.883706 -121.449199) (xy 185.829749 -121.463305)
			(xy 185.774312 -121.469405) (xy 185.718578 -121.467368) (xy 185.663735 -121.457238) (xy 185.610951 -121.439231)
			(xy 185.561351 -121.41373) (xy 185.515993 -121.381279) (xy 185.475844 -121.34257) (xy 185.441758 -121.298427)
			(xy 185.414462 -121.249792) (xy 185.394539 -121.197701) (xy 185.382413 -121.143264) (xy 185.378342 -121.087642)
			(xy 183.121691 -121.087642) (xy 183.170122 -121.115603) (xy 183.217672 -121.15209) (xy 183.260052 -121.19447)
			(xy 183.296539 -121.24202) (xy 183.326506 -121.293926) (xy 183.349442 -121.349299) (xy 183.364955 -121.407192)
			(xy 183.372778 -121.466614) (xy 183.373268 -121.496582) (xy 183.372778 -121.52655) (xy 183.364955 -121.585972)
			(xy 183.349442 -121.643865) (xy 183.326506 -121.699238) (xy 183.296539 -121.751144) (xy 183.260052 -121.798694)
			(xy 183.217672 -121.841074) (xy 183.170122 -121.877561) (xy 183.118216 -121.907528) (xy 183.062843 -121.930464)
			(xy 183.00495 -121.945977) (xy 182.945528 -121.9538) (xy 182.885592 -121.9538) (xy 182.82617 -121.945977)
			(xy 182.768277 -121.930464) (xy 182.712904 -121.907528) (xy 182.660998 -121.877561) (xy 182.613448 -121.841074)
			(xy 182.571068 -121.798694) (xy 182.534581 -121.751144) (xy 182.504614 -121.699238) (xy 182.481678 -121.643865)
			(xy 182.466165 -121.585972) (xy 182.458342 -121.52655) (xy 180.708224 -121.52655) (xy 180.712852 -121.535308)
			(xy 180.739993 -121.570256) (xy 180.756052 -121.585482) (xy 180.77619 -121.603802) (xy 180.811462 -121.64527)
			(xy 180.840326 -121.691428) (xy 180.862168 -121.741294) (xy 180.876523 -121.793808) (xy 180.883086 -121.847851)
			(xy 180.881717 -121.902273) (xy 180.872445 -121.955918) (xy 180.855467 -122.007643) (xy 180.831145 -122.056347)
			(xy 180.799996 -122.100996) (xy 180.762684 -122.140637) (xy 180.720001 -122.174429) (xy 180.672856 -122.201652)
			(xy 180.644907 -122.212739) (xy 181.311358 -122.212739) (xy 181.314185 -122.157969) (xy 181.324826 -122.104168)
			(xy 181.343061 -122.052446) (xy 181.368514 -122.003868) (xy 181.400661 -121.959434) (xy 181.438839 -121.920062)
			(xy 181.482261 -121.886562) (xy 181.530033 -121.859625) (xy 181.581169 -121.839806) (xy 181.634616 -121.827513)
			(xy 181.689273 -121.823) (xy 181.744013 -121.82636) (xy 181.797707 -121.837524) (xy 181.84925 -121.85626)
			(xy 181.897579 -121.882184) (xy 181.941698 -121.914761) (xy 181.980697 -121.95332) (xy 182.013773 -121.997066)
			(xy 182.040245 -122.045097) (xy 182.059566 -122.096423) (xy 182.071339 -122.149988) (xy 182.073506 -122.174)
			(xy 189.717678 -122.174) (xy 189.721751 -122.118341) (xy 189.733886 -122.063868) (xy 189.753822 -122.011742)
			(xy 189.781136 -121.963074) (xy 189.815244 -121.918902) (xy 189.855421 -121.880167) (xy 189.900809 -121.847695)
			(xy 189.950441 -121.822177) (xy 190.003261 -121.804158) (xy 190.05814 -121.794021) (xy 190.113911 -121.791983)
			(xy 190.169385 -121.798086) (xy 190.223378 -121.812202) (xy 190.274741 -121.834029) (xy 190.322379 -121.863102)
			(xy 190.365275 -121.898801) (xy 190.402517 -121.940365) (xy 190.433311 -121.986909) (xy 190.456999 -122.03744)
			(xy 190.473077 -122.090882) (xy 190.481203 -122.146096) (xy 190.481712 -122.174) (xy 190.481203 -122.201904)
			(xy 190.473077 -122.257118) (xy 190.456999 -122.31056) (xy 190.433311 -122.361091) (xy 190.402517 -122.407635)
			(xy 190.365275 -122.449199) (xy 190.322379 -122.484898) (xy 190.274741 -122.513971) (xy 190.223378 -122.535798)
			(xy 190.169385 -122.549914) (xy 190.113911 -122.556017) (xy 190.05814 -122.553979) (xy 190.003261 -122.543842)
			(xy 189.950441 -122.525823) (xy 189.900809 -122.500305) (xy 189.855421 -122.467833) (xy 189.815244 -122.429098)
			(xy 189.781136 -122.384926) (xy 189.753822 -122.336258) (xy 189.733886 -122.284132) (xy 189.721751 -122.229659)
			(xy 189.717678 -122.174) (xy 182.073506 -122.174) (xy 182.073804 -122.177302) (xy 182.075885 -122.199373)
			(xy 182.086675 -122.242366) (xy 182.104766 -122.282832) (xy 182.129609 -122.319542) (xy 182.160449 -122.351381)
			(xy 182.196349 -122.377381) (xy 182.236218 -122.396753) (xy 182.278846 -122.408908) (xy 182.322936 -122.413476)
			(xy 182.36715 -122.410319) (xy 182.388764 -122.405394) (xy 182.414473 -122.399448) (xy 182.466938 -122.393799)
			(xy 182.51968 -122.395434) (xy 182.571693 -122.404322) (xy 182.621985 -122.420294) (xy 182.669597 -122.443044)
			(xy 182.713619 -122.472138) (xy 182.753211 -122.507021) (xy 182.787618 -122.547028) (xy 182.802276 -122.56897)
			(xy 182.815715 -122.588207) (xy 182.848522 -122.621755) (xy 182.88693 -122.64871) (xy 182.929635 -122.668155)
			(xy 182.975183 -122.67943) (xy 183.022027 -122.682151) (xy 183.068574 -122.676225) (xy 183.091074 -122.669554)
			(xy 183.117268 -122.661644) (xy 183.171221 -122.652531) (xy 183.225923 -122.651221) (xy 183.28025 -122.657738)
			(xy 183.33309 -122.67195) (xy 183.383356 -122.693566) (xy 183.430019 -122.722141) (xy 183.472121 -122.757089)
			(xy 183.508798 -122.797694) (xy 183.539298 -122.843122) (xy 183.562995 -122.892442) (xy 183.579403 -122.944641)
			(xy 183.588185 -122.998649) (xy 183.589161 -123.053357) (xy 183.582311 -123.107644) (xy 183.567776 -123.160395)
			(xy 183.545853 -123.210529) (xy 183.516993 -123.257016) (xy 183.481787 -123.298903) (xy 183.440959 -123.335331)
			(xy 183.395345 -123.365553) (xy 183.345881 -123.388947) (xy 183.293583 -123.405035) (xy 183.239522 -123.413487)
			(xy 183.184809 -123.414128) (xy 183.130565 -123.406946) (xy 183.077904 -123.392088) (xy 183.027905 -123.369859)
			(xy 182.981596 -123.340715) (xy 182.939924 -123.305254) (xy 182.903747 -123.264203) (xy 182.888382 -123.241562)
			(xy 182.875144 -123.22225) (xy 182.842788 -123.188416) (xy 182.804782 -123.161081) (xy 182.762412 -123.141169)
			(xy 182.717112 -123.129354) (xy 182.670414 -123.126036) (xy 182.623898 -123.131327) (xy 182.601362 -123.137676)
			(xy 182.575871 -123.145577) (xy 182.523365 -123.155116) (xy 182.470042 -123.157245) (xy 182.416943 -123.151922)
			(xy 182.365103 -123.139252) (xy 182.315535 -123.119482) (xy 182.269206 -123.092997) (xy 182.227019 -123.060315)
			(xy 182.189799 -123.022072) (xy 182.158271 -122.979016) (xy 182.13305 -122.931986) (xy 182.114629 -122.881901)
			(xy 182.103368 -122.829738) (xy 182.100982 -122.803158) (xy 182.098951 -122.781082) (xy 182.088153 -122.738087)
			(xy 182.070055 -122.69762) (xy 182.045206 -122.660909) (xy 182.01436 -122.629071) (xy 181.978455 -122.603072)
			(xy 181.938581 -122.583702) (xy 181.895949 -122.571548) (xy 181.851855 -122.566982) (xy 181.807638 -122.57014)
			(xy 181.786022 -122.575066) (xy 181.759309 -122.581275) (xy 181.70475 -122.586849) (xy 181.649955 -122.584554)
			(xy 181.596054 -122.574436) (xy 181.544157 -122.556705) (xy 181.495333 -122.531725) (xy 181.45059 -122.500011)
			(xy 181.410848 -122.462218) (xy 181.376928 -122.419123) (xy 181.349528 -122.371616) (xy 181.329213 -122.320674)
			(xy 181.316402 -122.267349) (xy 181.311358 -122.212739) (xy 180.644907 -122.212739) (xy 180.622252 -122.221726)
			(xy 180.569267 -122.234225) (xy 180.542184 -122.236992) (xy 180.514249 -122.238901) (xy 180.458371 -122.235322)
			(xy 180.403658 -122.223424) (xy 180.35134 -122.203475) (xy 180.302596 -122.175923) (xy 180.258522 -122.141389)
			(xy 180.22011 -122.100651) (xy 180.188225 -122.054625) (xy 180.163584 -122.004346) (xy 180.146742 -121.950947)
			(xy 180.138078 -121.895629) (xy 180.137787 -121.839638) (xy 180.145876 -121.784234) (xy 180.162162 -121.730662)
			(xy 180.186279 -121.680131) (xy 180.217684 -121.633775) (xy 180.25567 -121.59264) (xy 180.277262 -121.574814)
			(xy 180.294335 -121.560541) (xy 180.323679 -121.52709) (xy 180.346745 -121.489037) (xy 180.362827 -121.447548)
			(xy 180.371435 -121.403891) (xy 180.372303 -121.359402) (xy 180.365406 -121.315442) (xy 180.350955 -121.273357)
			(xy 180.329392 -121.234433) (xy 180.301376 -121.199863) (xy 180.284882 -121.184924) (xy 180.274489 -121.175779)
			(xy 180.254908 -121.156204) (xy 180.245766 -121.145808) (xy 180.229012 -121.125652) (xy 180.200609 -121.081603)
			(xy 180.178502 -121.03408) (xy 180.163108 -120.983979) (xy 180.154718 -120.932242) (xy 180.153488 -120.879844)
			(xy 180.159442 -120.82777) (xy 180.172468 -120.777002) (xy 180.192321 -120.728494) (xy 180.205126 -120.705626)
			(xy 180.214904 -120.686148) (xy 180.228383 -120.644704) (xy 180.234593 -120.601568) (xy 180.233353 -120.558005)
			(xy 180.2247 -120.515292) (xy 180.208886 -120.474681) (xy 180.186376 -120.437364) (xy 180.157829 -120.404435)
			(xy 180.124083 -120.376858) (xy 180.086126 -120.355443) (xy 180.045073 -120.340817) (xy 180.002127 -120.33341)
			(xy 179.980336 -120.333008) (xy 179.932584 -120.333008) (xy 179.9213 -120.31423) (xy 179.893333 -120.280514)
			(xy 179.860001 -120.252092) (xy 179.822289 -120.229804) (xy 179.781315 -120.214312) (xy 179.738291 -120.206073)
			(xy 179.694492 -120.205332) (xy 179.651215 -120.21211) (xy 179.630324 -120.218708) (xy 179.604392 -120.226999)
			(xy 179.550845 -120.236833) (xy 179.496438 -120.23877) (xy 179.442328 -120.232769) (xy 179.389667 -120.218959)
			(xy 179.339576 -120.197632) (xy 179.293121 -120.169243) (xy 179.251293 -120.134397) (xy 179.21498 -120.093834)
			(xy 179.184956 -120.048419) (xy 179.161861 -119.999119) (xy 179.146185 -119.946983) (xy 179.138263 -119.89312)
			(xy 179.138263 -119.838678) (xy 179.146185 -119.784816) (xy 179.161861 -119.73268) (xy 179.184957 -119.683379)
			(xy 179.214981 -119.637965) (xy 179.251294 -119.597403) (xy 179.293122 -119.562556) (xy 179.339577 -119.534167)
			(xy 179.389668 -119.512841) (xy 179.442329 -119.49903) (xy 179.496439 -119.49303) (xy 179.550847 -119.494967)
			(xy 179.604393 -119.504801) (xy 179.630324 -119.513096) (xy 179.651243 -119.519721) (xy 179.694592 -119.526501)
			(xy 179.738461 -119.525735) (xy 179.781546 -119.517446) (xy 179.822568 -119.501879) (xy 179.860307 -119.479499)
			(xy 179.89364 -119.450969) (xy 179.921578 -119.417138) (xy 179.943291 -119.379011) (xy 179.958132 -119.337721)
			(xy 179.96566 -119.294496) (xy 179.966112 -119.272558) (xy 179.966112 -116.924328) (xy 179.458112 -116.416328)
			(xy 179.45354 -116.416328) (xy 179.056792 -116.01958) (xy 179.040327 -116.003836) (xy 179.002891 -115.977887)
			(xy 178.961428 -115.959026) (xy 178.917268 -115.947859) (xy 178.871824 -115.944742) (xy 178.826553 -115.949775)
			(xy 178.782903 -115.962798) (xy 178.742274 -115.983393) (xy 178.723798 -115.99672) (xy 178.701385 -116.013075)
			(xy 178.652773 -116.039821) (xy 178.600801 -116.059243) (xy 178.546563 -116.070933) (xy 178.491204 -116.074643)
			(xy 178.435891 -116.070297) (xy 178.381791 -116.057984) (xy 178.330045 -116.037965) (xy 178.281744 -116.010663)
			(xy 178.237907 -115.976652) (xy 178.199459 -115.936651) (xy 178.16721 -115.891502) (xy 178.14184 -115.842159)
			(xy 178.123885 -115.789661) (xy 178.113723 -115.735116) (xy 178.112166 -115.707414) (xy 178.110134 -115.65636)
			(xy 178.036474 -115.585494) (xy 176.376076 -115.585494) (xy 176.359434 -115.586018) (xy 176.327299 -115.594689)
			(xy 176.298502 -115.611383) (xy 176.286414 -115.622832) (xy 175.67021 -116.239036) (xy 175.586644 -116.239036)
			(xy 175.409098 -116.416328) (xy 173.158912 -116.416328) (xy 172.930312 -116.644928) (xy 172.930312 -117.330474)
			(xy 172.930787 -117.352904) (xy 172.938658 -117.397068) (xy 172.954162 -117.439163) (xy 172.976816 -117.477882)
			(xy 173.005917 -117.512023) (xy 173.04056 -117.540523) (xy 173.079668 -117.562498) (xy 173.122028 -117.577265)
			(xy 173.166322 -117.584366) (xy 173.211175 -117.583579) (xy 173.255193 -117.574928) (xy 173.297008 -117.558684)
			(xy 173.316392 -117.54739) (xy 173.339911 -117.533637) (xy 173.390064 -117.512357) (xy 173.442781 -117.498603)
			(xy 173.496938 -117.49267) (xy 173.551382 -117.494684) (xy 173.604952 -117.504602) (xy 173.656509 -117.522211)
			(xy 173.704953 -117.547139) (xy 173.749253 -117.578852) (xy 173.788464 -117.616676) (xy 173.821751 -117.659805)
			(xy 173.848406 -117.707321) (xy 173.867861 -117.75821) (xy 173.8797 -117.811389) (xy 173.883672 -117.865725)
			(xy 173.879693 -117.920061) (xy 173.867846 -117.973238) (xy 173.848385 -118.024125) (xy 173.821724 -118.071636)
			(xy 173.78843 -118.114761) (xy 173.749214 -118.15258) (xy 173.70491 -118.184287) (xy 173.656463 -118.209208)
			(xy 173.604904 -118.226811) (xy 173.551332 -118.236721) (xy 173.496888 -118.238728) (xy 173.442732 -118.232788)
			(xy 173.390017 -118.219027) (xy 173.339867 -118.19774) (xy 173.316392 -118.183914) (xy 173.296987 -118.172659)
			(xy 173.255174 -118.156422) (xy 173.21116 -118.147778) (xy 173.166312 -118.146993) (xy 173.122022 -118.154093)
			(xy 173.079667 -118.168856) (xy 173.04056 -118.190826) (xy 173.005917 -118.219318) (xy 172.976813 -118.25345)
			(xy 172.954152 -118.29216) (xy 172.938638 -118.334246) (xy 172.930753 -118.378403) (xy 172.930312 -118.40083)
			(xy 172.930312 -118.889891) (xy 174.138046 -118.889891) (xy 174.138564 -118.83455) (xy 174.147261 -118.779895)
			(xy 174.163946 -118.727128) (xy 174.188253 -118.677409) (xy 174.219646 -118.631831) (xy 174.257435 -118.591399)
			(xy 174.278798 -118.573804) (xy 174.296059 -118.559393) (xy 174.325792 -118.52567) (xy 174.349127 -118.487241)
			(xy 174.365334 -118.445305) (xy 174.373907 -118.401172) (xy 174.374581 -118.356218) (xy 174.367332 -118.311848)
			(xy 174.352388 -118.269445) (xy 174.330215 -118.230335) (xy 174.301505 -118.195737) (xy 174.28464 -118.180866)
			(xy 174.263823 -118.162723) (xy 174.227241 -118.121355) (xy 174.197005 -118.075146) (xy 174.173747 -118.025061)
			(xy 174.157951 -117.972147) (xy 174.149947 -117.917508) (xy 174.149904 -117.862286) (xy 174.157822 -117.807634)
			(xy 174.173536 -117.754695) (xy 174.196717 -117.704574) (xy 174.226881 -117.658318) (xy 174.263398 -117.616894)
			(xy 174.305505 -117.581166) (xy 174.352322 -117.551881) (xy 174.402872 -117.529651) (xy 174.456099 -117.514941)
			(xy 174.51089 -117.508056) (xy 174.566101 -117.509143) (xy 174.620579 -117.518177) (xy 174.673186 -117.534969)
			(xy 174.722823 -117.55917) (xy 174.768452 -117.590274) (xy 174.809122 -117.62763) (xy 174.82693 -117.648736)
			(xy 174.841891 -117.666281) (xy 174.876941 -117.696227) (xy 174.916818 -117.719361) (xy 174.960213 -117.734924)
			(xy 175.005704 -117.742405) (xy 175.051797 -117.741559) (xy 175.096982 -117.732415) (xy 175.139778 -117.715271)
			(xy 175.178779 -117.69069) (xy 175.212708 -117.659478) (xy 175.22698 -117.64137) (xy 175.243955 -117.619586)
			(xy 175.283145 -117.580675) (xy 175.327533 -117.547819) (xy 175.376194 -117.521703) (xy 175.401986 -117.51183)
			(xy 175.428656 -117.502432) (xy 176.342294 -116.588794) (xy 176.34458 -116.539518) (xy 176.346545 -116.509366)
			(xy 176.357285 -116.449907) (xy 176.375756 -116.392378) (xy 176.401637 -116.33778) (xy 176.434477 -116.287063)
			(xy 176.473705 -116.241108) (xy 176.51864 -116.200715) (xy 176.568499 -116.166586) (xy 176.622416 -116.139314)
			(xy 176.679453 -116.119375) (xy 176.738617 -116.107115) (xy 176.79888 -116.102747) (xy 176.859194 -116.106346)
			(xy 176.91851 -116.117852) (xy 176.975796 -116.137062) (xy 177.030056 -116.163644) (xy 177.080346 -116.197135)
			(xy 177.125792 -116.236952) (xy 177.165603 -116.282404) (xy 177.199087 -116.332698) (xy 177.225662 -116.386962)
			(xy 177.244864 -116.444251) (xy 177.256361 -116.503568) (xy 177.259953 -116.563883) (xy 177.255576 -116.624145)
			(xy 177.243308 -116.683308) (xy 177.223361 -116.740342) (xy 177.196082 -116.794255) (xy 177.161946 -116.844109)
			(xy 177.121547 -116.889039) (xy 177.075587 -116.928261) (xy 177.024865 -116.961094) (xy 176.970263 -116.986967)
			(xy 176.912732 -117.00543) (xy 176.853271 -117.016162) (xy 176.823116 -117.018054) (xy 176.77384 -117.02034)
			(xy 176.402696 -117.391484) (xy 177.492261 -117.391484) (xy 177.499498 -117.332162) (xy 177.514393 -117.274286)
			(xy 177.536693 -117.218841) (xy 177.566019 -117.166769) (xy 177.601872 -117.118956) (xy 177.643642 -117.076215)
			(xy 177.690618 -117.039274) (xy 177.742002 -117.008759) (xy 177.796921 -116.985191) (xy 177.854439 -116.96897)
			(xy 177.913579 -116.960372) (xy 177.973335 -116.959543) (xy 178.032691 -116.966498) (xy 178.090637 -116.981117)
			(xy 178.146188 -117.003153) (xy 178.198399 -117.03223) (xy 178.246382 -117.067854) (xy 178.289322 -117.10942)
			(xy 178.326487 -117.15622) (xy 178.357246 -117.207458) (xy 178.381075 -117.262263) (xy 178.389788 -117.29085)
			(xy 178.398932 -117.3226) (xy 178.573176 -117.496844) (xy 178.606196 -117.50548) (xy 178.632082 -117.512868)
			(xy 178.681571 -117.534048) (xy 178.727498 -117.562129) (xy 178.768906 -117.596526) (xy 178.804933 -117.636523)
			(xy 178.834831 -117.681288) (xy 178.857975 -117.729889) (xy 178.873886 -117.781315) (xy 178.882231 -117.834495)
			(xy 178.882838 -117.888323) (xy 178.875692 -117.941677) (xy 178.860944 -117.993448) (xy 178.838899 -118.042558)
			(xy 178.810018 -118.087985) (xy 178.7749 -118.128784) (xy 178.734277 -118.164105) (xy 178.688995 -118.193212)
			(xy 178.639995 -118.215502) (xy 178.588298 -118.230508) (xy 178.53498 -118.23792) (xy 178.48115 -118.237582)
			(xy 178.427929 -118.229502) (xy 178.376425 -118.213848) (xy 178.327709 -118.190946) (xy 178.282795 -118.161272)
			(xy 178.242619 -118.125445) (xy 178.208016 -118.084209) (xy 178.179706 -118.038423) (xy 178.15828 -117.98904)
			(xy 178.150774 -117.963188) (xy 178.146266 -117.948621) (xy 178.131525 -117.921946) (xy 178.110865 -117.89954)
			(xy 178.08547 -117.882688) (xy 178.056797 -117.872357) (xy 178.02649 -117.869138) (xy 178.011328 -117.870732)
			(xy 177.981665 -117.874352) (xy 177.921903 -117.874612) (xy 177.862616 -117.867092) (xy 177.804812 -117.851921)
			(xy 177.749474 -117.829357) (xy 177.697542 -117.799783) (xy 177.649901 -117.763703) (xy 177.60736 -117.72173)
			(xy 177.570643 -117.674578) (xy 177.540374 -117.623048) (xy 177.517068 -117.568018) (xy 177.501121 -117.510423)
			(xy 177.492805 -117.451243) (xy 177.492261 -117.391484) (xy 176.402696 -117.391484) (xy 175.915574 -117.878606)
			(xy 175.909986 -117.921278) (xy 175.9058 -117.948705) (xy 175.890558 -118.002051) (xy 175.867751 -118.052627)
			(xy 175.837859 -118.099367) (xy 175.801513 -118.141284) (xy 175.759478 -118.177495) (xy 175.712643 -118.207236)
			(xy 175.661994 -118.22988) (xy 175.608599 -118.244949) (xy 175.553584 -118.252126) (xy 175.49811 -118.25126)
			(xy 175.443347 -118.242367) (xy 175.390449 -118.225637) (xy 175.340532 -118.201422) (xy 175.294648 -118.170232)
			(xy 175.253766 -118.132726) (xy 175.23587 -118.111524) (xy 175.220913 -118.093975) (xy 175.185864 -118.064021)
			(xy 175.145988 -118.040881) (xy 175.102591 -118.025315) (xy 175.057098 -118.017831) (xy 175.011001 -118.018677)
			(xy 174.965814 -118.027824) (xy 174.923017 -118.044973) (xy 174.884016 -118.06956) (xy 174.85009 -118.100779)
			(xy 174.83582 -118.11889) (xy 174.820204 -118.138939) (xy 174.784526 -118.175128) (xy 174.7647 -118.191026)
			(xy 174.747259 -118.205235) (xy 174.717106 -118.238608) (xy 174.693301 -118.27677) (xy 174.676589 -118.318528)
			(xy 174.667492 -118.362577) (xy 174.666296 -118.407539) (xy 174.673036 -118.452009) (xy 174.687503 -118.494597)
			(xy 174.709244 -118.533971) (xy 174.737579 -118.568901) (xy 174.754286 -118.583964) (xy 174.774866 -118.602469)
			(xy 174.810891 -118.644481) (xy 174.840306 -118.69136) (xy 174.862464 -118.742073) (xy 174.876877 -118.795506)
			(xy 174.883228 -118.850483) (xy 174.881378 -118.905794) (xy 174.871368 -118.960224) (xy 174.853416 -119.012575)
			(xy 174.82792 -119.061694) (xy 174.795438 -119.106502) (xy 174.756686 -119.146013) (xy 174.712517 -119.179358)
			(xy 174.663901 -119.205803) (xy 174.611909 -119.224766) (xy 174.557684 -119.235831) (xy 174.502418 -119.238753)
			(xy 174.447329 -119.23347) (xy 174.393626 -119.220096) (xy 174.342493 -119.198926) (xy 174.295052 -119.170426)
			(xy 174.25235 -119.135223) (xy 174.215323 -119.09409) (xy 174.184788 -119.047934) (xy 174.161415 -118.997769)
			(xy 174.14572 -118.944699) (xy 174.138046 -118.889891) (xy 172.930312 -118.889891) (xy 172.930312 -119.286528)
			(xy 172.343826 -119.873014) (xy 173.137586 -119.873014) (xy 173.141562 -119.818688) (xy 173.153405 -119.765519)
			(xy 173.172864 -119.714642) (xy 173.199524 -119.66714) (xy 173.232815 -119.624026) (xy 173.272029 -119.586219)
			(xy 173.316331 -119.554524) (xy 173.364774 -119.529618) (xy 173.416328 -119.51203) (xy 173.469894 -119.502136)
			(xy 173.524329 -119.500146) (xy 173.578474 -119.506104) (xy 173.631174 -119.519882) (xy 173.681307 -119.541186)
			(xy 173.727803 -119.569562) (xy 173.769673 -119.604406) (xy 173.806022 -119.644975) (xy 173.836078 -119.690404)
			(xy 173.859199 -119.739725) (xy 173.874892 -119.791887) (xy 173.882823 -119.845778) (xy 173.88332 -119.873014)
			(xy 173.882823 -119.90025) (xy 173.874892 -119.954141) (xy 173.859199 -120.006303) (xy 173.836078 -120.055624)
			(xy 173.806022 -120.101053) (xy 173.769673 -120.141622) (xy 173.727803 -120.176466) (xy 173.681307 -120.204842)
			(xy 173.631174 -120.226146) (xy 173.578474 -120.239924) (xy 173.524329 -120.245882) (xy 173.469894 -120.243892)
			(xy 173.416328 -120.233998) (xy 173.364774 -120.21641) (xy 173.316331 -120.191504) (xy 173.272029 -120.159809)
			(xy 173.232815 -120.122002) (xy 173.199524 -120.078888) (xy 173.172864 -120.031386) (xy 173.153405 -119.980509)
			(xy 173.141562 -119.92734) (xy 173.137586 -119.873014) (xy 172.343826 -119.873014) (xy 172.092112 -120.124728)
			(xy 172.092112 -121.853275) (xy 173.128595 -121.853275) (xy 173.134492 -121.79766) (xy 173.148445 -121.743502)
			(xy 173.170156 -121.691961) (xy 173.199158 -121.644142) (xy 173.234831 -121.601069) (xy 173.27641 -121.563666)
			(xy 173.323004 -121.532734) (xy 173.373614 -121.508935) (xy 173.427157 -121.49278) (xy 173.482485 -121.484615)
			(xy 173.538411 -121.484615) (xy 173.593739 -121.49278) (xy 173.647282 -121.508935) (xy 173.697892 -121.532734)
			(xy 173.744486 -121.563666) (xy 173.786065 -121.601069) (xy 173.821738 -121.644142) (xy 173.85074 -121.691961)
			(xy 173.872451 -121.743502) (xy 173.886404 -121.79766) (xy 173.892001 -121.850444) (xy 175.065482 -121.850444)
			(xy 175.071696 -121.789996) (xy 175.086083 -121.730958) (xy 175.108375 -121.674429) (xy 175.138158 -121.621461)
			(xy 175.174875 -121.573043) (xy 175.195992 -121.551192) (xy 175.386492 -121.360438) (xy 175.396812 -121.349602)
			(xy 175.412442 -121.32409) (xy 175.421706 -121.295641) (xy 175.424096 -121.265818) (xy 175.419481 -121.236256)
			(xy 175.414178 -121.222262) (xy 175.381666 -121.143776) (xy 175.366172 -121.143776) (xy 175.366172 -120.285256)
			(xy 175.365749 -120.269408) (xy 175.357976 -120.238682) (xy 175.342849 -120.210832) (xy 175.321306 -120.187585)
			(xy 175.30826 -120.178576) (xy 175.285336 -120.163227) (xy 175.243948 -120.126749) (xy 175.208389 -120.084568)
			(xy 175.179438 -120.037605) (xy 175.157728 -119.986887) (xy 175.143733 -119.933523) (xy 175.137758 -119.878678)
			(xy 175.139935 -119.823552) (xy 175.150216 -119.769349) (xy 175.168376 -119.717254) (xy 175.194019 -119.668406)
			(xy 175.226583 -119.623873) (xy 175.265357 -119.584627) (xy 175.309494 -119.551527) (xy 175.358028 -119.525297)
			(xy 175.4099 -119.506508) (xy 175.463974 -119.495573) (xy 175.51907 -119.49273) (xy 175.573983 -119.498041)
			(xy 175.627513 -119.511391) (xy 175.653192 -119.521478) (xy 175.674371 -119.529664) (xy 175.718728 -119.539339)
			(xy 175.764097 -119.540984) (xy 175.809037 -119.534546) (xy 175.85212 -119.52023) (xy 175.891976 -119.498491)
			(xy 175.927338 -119.47002) (xy 175.957082 -119.435722) (xy 175.980263 -119.396687) (xy 175.996144 -119.354156)
			(xy 176.00422 -119.309481) (xy 176.004728 -119.286782) (xy 176.004728 -118.881652) (xy 176.811178 -118.881652)
			(xy 177.16881 -118.52402) (xy 177.191543 -118.502018) (xy 177.241735 -118.463505) (xy 177.296524 -118.431872)
			(xy 177.354974 -118.407661) (xy 177.416083 -118.391287) (xy 177.478807 -118.383029) (xy 177.542073 -118.383029)
			(xy 177.604797 -118.391287) (xy 177.665906 -118.407661) (xy 177.724356 -118.431872) (xy 177.779145 -118.463505)
			(xy 177.829337 -118.502018) (xy 177.874072 -118.546753) (xy 177.912585 -118.596945) (xy 177.944218 -118.651734)
			(xy 177.968429 -118.710184) (xy 177.984803 -118.771293) (xy 177.993061 -118.834017) (xy 177.993061 -118.897283)
			(xy 177.984803 -118.960007) (xy 177.968429 -119.021116) (xy 177.944218 -119.079566) (xy 177.912585 -119.134355)
			(xy 177.874072 -119.184547) (xy 177.85207 -119.20728) (xy 177.794666 -119.264684) (xy 177.779778 -119.280191)
			(xy 177.754953 -119.315282) (xy 177.736387 -119.354051) (xy 177.724611 -119.395392) (xy 177.71996 -119.438124)
			(xy 177.722566 -119.48103) (xy 177.732356 -119.522886) (xy 177.74905 -119.562497) (xy 177.772172 -119.598733)
			(xy 177.786284 -119.61495) (xy 177.803439 -119.634446) (xy 177.832659 -119.677378) (xy 177.85564 -119.72395)
			(xy 177.871936 -119.773259) (xy 177.881235 -119.824352) (xy 177.883354 -119.876242) (xy 177.878254 -119.927923)
			(xy 177.866033 -119.978397) (xy 177.846927 -120.026688) (xy 177.821307 -120.07186) (xy 177.805842 -120.092724)
			(xy 177.794666 -120.107456) (xy 177.798222 -120.20296) (xy 177.85334 -120.20296) (xy 177.85334 -120.8659)
			(xy 179.13732 -120.8659) (xy 179.141296 -120.811574) (xy 179.153139 -120.758405) (xy 179.172598 -120.707528)
			(xy 179.199258 -120.660026) (xy 179.232549 -120.616912) (xy 179.271763 -120.579105) (xy 179.316065 -120.54741)
			(xy 179.364508 -120.522504) (xy 179.416062 -120.504916) (xy 179.469628 -120.495022) (xy 179.524063 -120.493032)
			(xy 179.578208 -120.49899) (xy 179.630908 -120.512768) (xy 179.681041 -120.534072) (xy 179.727537 -120.562448)
			(xy 179.769407 -120.597292) (xy 179.805756 -120.637861) (xy 179.835812 -120.68329) (xy 179.858933 -120.732611)
			(xy 179.874626 -120.784773) (xy 179.882557 -120.838664) (xy 179.883054 -120.8659) (xy 179.882557 -120.893136)
			(xy 179.874626 -120.947027) (xy 179.858933 -120.999189) (xy 179.835812 -121.04851) (xy 179.805756 -121.093939)
			(xy 179.769407 -121.134508) (xy 179.727537 -121.169352) (xy 179.681041 -121.197728) (xy 179.630908 -121.219032)
			(xy 179.578208 -121.23281) (xy 179.524063 -121.238768) (xy 179.469628 -121.236778) (xy 179.416062 -121.226884)
			(xy 179.364508 -121.209296) (xy 179.316065 -121.18439) (xy 179.271763 -121.152695) (xy 179.232549 -121.114888)
			(xy 179.199258 -121.071774) (xy 179.172598 -121.024272) (xy 179.153139 -120.973395) (xy 179.141296 -120.920226)
			(xy 179.13732 -120.8659) (xy 177.85334 -120.8659) (xy 177.85334 -121.346976) (xy 177.730404 -121.346976)
			(xy 177.67554 -121.40184) (xy 177.824892 -121.551192) (xy 177.846708 -121.573679) (xy 177.884384 -121.623739)
			(xy 177.914658 -121.678593) (xy 177.936929 -121.737154) (xy 177.950757 -121.798262) (xy 177.955868 -121.860707)
			(xy 177.955575 -121.865644) (xy 179.13732 -121.865644) (xy 179.141296 -121.811318) (xy 179.153139 -121.758149)
			(xy 179.172598 -121.707272) (xy 179.199258 -121.65977) (xy 179.232549 -121.616656) (xy 179.271763 -121.578849)
			(xy 179.316065 -121.547154) (xy 179.364508 -121.522248) (xy 179.416062 -121.50466) (xy 179.469628 -121.494766)
			(xy 179.524063 -121.492776) (xy 179.578208 -121.498734) (xy 179.630908 -121.512512) (xy 179.681041 -121.533816)
			(xy 179.727537 -121.562192) (xy 179.769407 -121.597036) (xy 179.805756 -121.637605) (xy 179.835812 -121.683034)
			(xy 179.858933 -121.732355) (xy 179.874626 -121.784517) (xy 179.882557 -121.838408) (xy 179.883054 -121.865644)
			(xy 179.882557 -121.89288) (xy 179.874626 -121.946771) (xy 179.858933 -121.998933) (xy 179.835812 -122.048254)
			(xy 179.805756 -122.093683) (xy 179.769407 -122.134252) (xy 179.727537 -122.169096) (xy 179.681041 -122.197472)
			(xy 179.630908 -122.218776) (xy 179.578208 -122.232554) (xy 179.524063 -122.238512) (xy 179.469628 -122.236522)
			(xy 179.416062 -122.226628) (xy 179.364508 -122.20904) (xy 179.316065 -122.184134) (xy 179.271763 -122.152439)
			(xy 179.232549 -122.114632) (xy 179.199258 -122.071518) (xy 179.172598 -122.024016) (xy 179.153139 -121.973139)
			(xy 179.141296 -121.91997) (xy 179.13732 -121.865644) (xy 177.955575 -121.865644) (xy 177.952159 -121.92325)
			(xy 177.939706 -121.984654) (xy 177.918754 -122.0437) (xy 177.889718 -122.099219) (xy 177.871882 -122.124978)
			(xy 177.859178 -122.143411) (xy 177.839838 -122.183782) (xy 177.827865 -122.226916) (xy 177.82363 -122.27148)
			(xy 177.827263 -122.316097) (xy 177.838652 -122.359389) (xy 177.857445 -122.400018) (xy 177.883061 -122.436729)
			(xy 177.898552 -122.452892) (xy 178.034696 -122.589036) (xy 178.046361 -122.600009) (xy 178.073939 -122.616273)
			(xy 178.104699 -122.625154) (xy 178.136702 -122.62609) (xy 178.167928 -122.619024) (xy 178.19641 -122.6044)
			(xy 178.208686 -122.594116) (xy 178.20894 -122.593862) (xy 178.229446 -122.576295) (xy 178.274547 -122.546609)
			(xy 178.32346 -122.523743) (xy 178.375162 -122.508176) (xy 178.428569 -122.500235) (xy 178.482563 -122.500085)
			(xy 178.536013 -122.507729) (xy 178.587801 -122.523008) (xy 178.636841 -122.545602) (xy 178.682106 -122.575037)
			(xy 178.722649 -122.610697) (xy 178.757621 -122.651835) (xy 178.786289 -122.69759) (xy 178.808053 -122.747004)
			(xy 178.822457 -122.799041) (xy 178.8292 -122.852613) (xy 178.828944 -122.865642) (xy 179.13732 -122.865642)
			(xy 179.141296 -122.811316) (xy 179.153139 -122.758147) (xy 179.172598 -122.70727) (xy 179.199258 -122.659768)
			(xy 179.232549 -122.616654) (xy 179.271763 -122.578847) (xy 179.316065 -122.547152) (xy 179.364508 -122.522246)
			(xy 179.416062 -122.504658) (xy 179.469628 -122.494764) (xy 179.524063 -122.492774) (xy 179.578208 -122.498732)
			(xy 179.630908 -122.51251) (xy 179.681041 -122.533814) (xy 179.727537 -122.56219) (xy 179.769407 -122.597034)
			(xy 179.805756 -122.637603) (xy 179.835812 -122.683032) (xy 179.858933 -122.732353) (xy 179.874626 -122.784515)
			(xy 179.882557 -122.838406) (xy 179.883054 -122.865642) (xy 179.882557 -122.892878) (xy 179.874626 -122.946769)
			(xy 179.858933 -122.998931) (xy 179.835812 -123.048252) (xy 179.805756 -123.093681) (xy 179.769407 -123.13425)
			(xy 179.727537 -123.169094) (xy 179.681041 -123.19747) (xy 179.630908 -123.218774) (xy 179.578208 -123.232552)
			(xy 179.524063 -123.23851) (xy 179.469628 -123.23652) (xy 179.416062 -123.226626) (xy 179.364508 -123.209038)
			(xy 179.316065 -123.184132) (xy 179.271763 -123.152437) (xy 179.232549 -123.11463) (xy 179.199258 -123.071516)
			(xy 179.172598 -123.024014) (xy 179.153139 -122.973137) (xy 179.141296 -122.919968) (xy 179.13732 -122.865642)
			(xy 178.828944 -122.865642) (xy 178.82814 -122.906597) (xy 178.8193 -122.959862) (xy 178.802864 -123.011294)
			(xy 178.779177 -123.059815) (xy 178.748736 -123.10441) (xy 178.712176 -123.144144) (xy 178.670265 -123.178185)
			(xy 178.623879 -123.205821) (xy 178.57399 -123.226472) (xy 178.521643 -123.239707) (xy 178.467934 -123.245247)
			(xy 178.413987 -123.242978) (xy 178.360933 -123.232947) (xy 178.309882 -123.215363) (xy 178.261904 -123.190595)
			(xy 178.239674 -123.175268) (xy 178.221213 -123.162687) (xy 178.180903 -123.14344) (xy 178.137851 -123.131529)
			(xy 178.09338 -123.12732) (xy 178.048857 -123.130942) (xy 178.005652 -123.142284) (xy 177.965091 -123.160998)
			(xy 177.928422 -123.186508) (xy 177.912268 -123.201938) (xy 177.728626 -123.38558) (xy 177.71717 -123.397716)
			(xy 177.700462 -123.426594) (xy 177.691812 -123.458816) (xy 177.691811 -123.492179) (xy 177.70046 -123.524401)
			(xy 177.717167 -123.553279) (xy 177.728626 -123.565412) (xy 177.747761 -123.585094) (xy 177.780527 -123.629136)
			(xy 177.800249 -123.665895) (xy 183.954029 -123.665895) (xy 183.954887 -123.610498) (xy 183.96375 -123.555807)
			(xy 183.980431 -123.502975) (xy 184.00458 -123.45311) (xy 184.035687 -123.407264) (xy 184.0731 -123.366399)
			(xy 184.11603 -123.331377) (xy 184.163574 -123.302933) (xy 184.214734 -123.281665) (xy 184.268432 -123.268022)
			(xy 184.323538 -123.262291) (xy 184.378894 -123.264591) (xy 184.433335 -123.274874) (xy 184.485716 -123.292925)
			(xy 184.534935 -123.318362) (xy 184.579956 -123.350653) (xy 184.619833 -123.389116) (xy 184.637172 -123.410726)
			(xy 184.65152 -123.428457) (xy 184.685415 -123.458973) (xy 184.724212 -123.482951) (xy 184.766664 -123.49962)
			(xy 184.81141 -123.508447) (xy 184.857013 -123.509146) (xy 184.902008 -123.501697) (xy 184.944952 -123.486337)
			(xy 184.984466 -123.463561) (xy 185.019281 -123.434099) (xy 185.034174 -123.416822) (xy 185.052142 -123.395728)
			(xy 185.093192 -123.358509) (xy 185.139194 -123.32762) (xy 185.189181 -123.303711) (xy 185.242101 -123.287284)
			(xy 185.296841 -123.278686) (xy 185.352248 -123.278096) (xy 185.407158 -123.285527) (xy 185.460416 -123.300824)
			(xy 185.510901 -123.323664) (xy 185.55755 -123.353567) (xy 185.599383 -123.389903) (xy 185.63552 -123.431909)
			(xy 185.6652 -123.4787) (xy 185.6878 -123.529293) (xy 185.702842 -123.582623) (xy 185.710013 -123.637568)
			(xy 185.709159 -123.692972) (xy 185.7003 -123.74767) (xy 185.683621 -123.800511) (xy 185.659474 -123.850383)
			(xy 185.652742 -123.860306) (xy 188.283848 -123.860306) (xy 188.287919 -123.804684) (xy 188.300045 -123.750247)
			(xy 188.319968 -123.698156) (xy 188.347264 -123.649521) (xy 188.38135 -123.605378) (xy 188.421499 -123.566669)
			(xy 188.466857 -123.534218) (xy 188.516457 -123.508717) (xy 188.569241 -123.49071) (xy 188.624084 -123.48058)
			(xy 188.679818 -123.478543) (xy 188.735255 -123.484643) (xy 188.789212 -123.498749) (xy 188.840541 -123.520561)
			(xy 188.888147 -123.549615) (xy 188.931015 -123.58529) (xy 188.968232 -123.626827) (xy 188.999005 -123.67334)
			(xy 189.022677 -123.723837) (xy 189.038745 -123.777244) (xy 189.046865 -123.83242) (xy 189.047374 -123.860306)
			(xy 189.046865 -123.888192) (xy 189.038745 -123.943368) (xy 189.022677 -123.996775) (xy 188.999005 -124.047272)
			(xy 188.968232 -124.093785) (xy 188.931015 -124.135322) (xy 188.888147 -124.170997) (xy 188.840541 -124.200051)
			(xy 188.789212 -124.221863) (xy 188.735255 -124.235969) (xy 188.679818 -124.242069) (xy 188.624084 -124.240032)
			(xy 188.569241 -124.229902) (xy 188.516457 -124.211895) (xy 188.466857 -124.186394) (xy 188.421499 -124.153943)
			(xy 188.38135 -124.115234) (xy 188.347264 -124.071091) (xy 188.319968 -124.022456) (xy 188.300045 -123.970365)
			(xy 188.287919 -123.915928) (xy 188.283848 -123.860306) (xy 185.652742 -123.860306) (xy 185.628366 -123.896238)
			(xy 185.590953 -123.937111) (xy 185.54802 -123.972141) (xy 185.500471 -124.000593) (xy 185.449307 -124.021867)
			(xy 185.395604 -124.035515) (xy 185.34049 -124.041252) (xy 185.285127 -124.038955) (xy 185.230679 -124.028674)
			(xy 185.17829 -124.010625) (xy 185.129063 -123.985187) (xy 185.084034 -123.952896) (xy 185.04415 -123.91443)
			(xy 185.026808 -123.892818) (xy 185.012484 -123.875065) (xy 184.978587 -123.844544) (xy 184.939787 -123.820563)
			(xy 184.897331 -123.803891) (xy 184.85258 -123.795065) (xy 184.806973 -123.794368) (xy 184.761973 -123.801821)
			(xy 184.719026 -123.817187) (xy 184.679511 -123.83997) (xy 184.644697 -123.869441) (xy 184.629806 -123.886722)
			(xy 184.611795 -123.907776) (xy 184.570745 -123.944985) (xy 184.524745 -123.975864) (xy 184.474762 -123.999765)
			(xy 184.421847 -124.016183) (xy 184.367113 -124.024775) (xy 184.311712 -124.025358) (xy 184.25681 -124.017922)
			(xy 184.203561 -124.002621) (xy 184.153085 -123.979779) (xy 184.106444 -123.949875) (xy 184.06462 -123.913539)
			(xy 184.028492 -123.871535) (xy 183.99882 -123.824747) (xy 183.976229 -123.774158) (xy 183.961193 -123.720834)
			(xy 183.954029 -123.665895) (xy 177.800249 -123.665895) (xy 177.806479 -123.677507) (xy 177.825056 -123.729162)
			(xy 177.835855 -123.782983) (xy 177.838643 -123.837806) (xy 177.83336 -123.892445) (xy 177.820119 -123.945718)
			(xy 177.799208 -123.996473) (xy 177.771079 -124.043612) (xy 177.73634 -124.086115) (xy 177.695742 -124.123063)
			(xy 177.650164 -124.153657) (xy 177.600591 -124.177234) (xy 177.548097 -124.193286) (xy 177.493816 -124.201464)
			(xy 177.438922 -124.201592) (xy 177.384603 -124.193668) (xy 177.332035 -124.177861) (xy 177.306986 -124.16663)
			(xy 177.270664 -124.149358) (xy 177.19167 -124.163328) (xy 177.030656 -124.324529) (xy 185.753362 -124.324529)
			(xy 185.756164 -124.269495) (xy 185.766848 -124.215435) (xy 185.785193 -124.163472) (xy 185.810818 -124.114686)
			(xy 185.843189 -124.070091) (xy 185.881636 -124.030613) (xy 185.925358 -123.997072) (xy 185.973448 -123.970165)
			(xy 186.024907 -123.95045) (xy 186.078666 -123.938338) (xy 186.133607 -123.934081) (xy 186.188589 -123.937765)
			(xy 186.242471 -123.949316) (xy 186.294133 -123.968493) (xy 186.342501 -123.994897) (xy 186.386571 -124.02798)
			(xy 186.425427 -124.067056) (xy 186.458262 -124.111311) (xy 186.484394 -124.159827) (xy 186.503279 -124.211595)
			(xy 186.514527 -124.265541) (xy 186.517902 -124.320544) (xy 186.513335 -124.37546) (xy 186.500921 -124.429149)
			(xy 186.480918 -124.480496) (xy 186.46775 -124.504704) (xy 186.461407 -124.516731) (xy 186.454704 -124.543074)
			(xy 186.455177 -124.570252) (xy 186.462792 -124.596346) (xy 186.477011 -124.619512) (xy 186.49683 -124.638115)
			(xy 186.520849 -124.650841) (xy 186.547372 -124.656791) (xy 186.560968 -124.656596) (xy 186.590869 -124.655659)
			(xy 186.650482 -124.660704) (xy 186.70893 -124.673469) (xy 186.765218 -124.693737) (xy 186.818387 -124.721162)
			(xy 186.867532 -124.755278) (xy 186.911815 -124.795502) (xy 186.950484 -124.841152) (xy 186.982879 -124.891448)
			(xy 187.008447 -124.945534) (xy 187.026755 -125.002489) (xy 187.03749 -125.061344) (xy 187.04047 -125.121095)
			(xy 187.040155 -125.124984) (xy 188.899528 -125.124984) (xy 188.899528 -125.065016) (xy 188.907356 -125.00556)
			(xy 188.922877 -124.947635) (xy 188.945826 -124.892231) (xy 188.97581 -124.840297) (xy 189.012316 -124.792721)
			(xy 189.054721 -124.750316) (xy 189.102297 -124.71381) (xy 189.154231 -124.683826) (xy 189.209635 -124.660877)
			(xy 189.26756 -124.645356) (xy 189.327016 -124.637528) (xy 189.386984 -124.637528) (xy 189.44644 -124.645356)
			(xy 189.504365 -124.660877) (xy 189.559769 -124.683826) (xy 189.611703 -124.71381) (xy 189.659279 -124.750316)
			(xy 189.701684 -124.792721) (xy 189.73819 -124.840297) (xy 189.768174 -124.892231) (xy 189.791123 -124.947635)
			(xy 189.806644 -125.00556) (xy 189.814472 -125.065016) (xy 189.814962 -125.095) (xy 189.814472 -125.124984)
			(xy 189.806644 -125.18444) (xy 189.791123 -125.242365) (xy 189.768174 -125.297769) (xy 189.73819 -125.349703)
			(xy 189.701684 -125.397279) (xy 189.659279 -125.439684) (xy 189.611703 -125.47619) (xy 189.559769 -125.506174)
			(xy 189.504365 -125.529123) (xy 189.44644 -125.544644) (xy 189.386984 -125.552472) (xy 189.327016 -125.552472)
			(xy 189.26756 -125.544644) (xy 189.209635 -125.529123) (xy 189.154231 -125.506174) (xy 189.102297 -125.47619)
			(xy 189.054721 -125.439684) (xy 189.012316 -125.397279) (xy 188.97581 -125.349703) (xy 188.945826 -125.297769)
			(xy 188.922877 -125.242365) (xy 188.907356 -125.18444) (xy 188.899528 -125.124984) (xy 187.040155 -125.124984)
			(xy 187.035642 -125.180726) (xy 187.023091 -125.23922) (xy 187.003029 -125.295581) (xy 186.975798 -125.34885)
			(xy 186.941863 -125.398119) (xy 186.9018 -125.44255) (xy 186.856292 -125.481385) (xy 186.806115 -125.513963)
			(xy 186.752122 -125.539729) (xy 186.695234 -125.558245) (xy 186.636419 -125.569195) (xy 186.576679 -125.572392)
			(xy 186.517032 -125.567783) (xy 186.458492 -125.555445) (xy 186.402058 -125.53559) (xy 186.34869 -125.508554)
			(xy 186.299297 -125.474798) (xy 186.25472 -125.434898) (xy 186.215719 -125.389532) (xy 186.182958 -125.339474)
			(xy 186.156995 -125.285576) (xy 186.138271 -125.228756) (xy 186.127107 -125.169982) (xy 186.123691 -125.110254)
			(xy 186.128082 -125.05059) (xy 186.140206 -124.992005) (xy 186.159856 -124.935499) (xy 186.186696 -124.882032)
			(xy 186.203082 -124.857002) (xy 186.210367 -124.845509) (xy 186.219174 -124.819773) (xy 186.22089 -124.792626)
			(xy 186.215394 -124.765986) (xy 186.203074 -124.741734) (xy 186.184801 -124.721585) (xy 186.161866 -124.706961)
			(xy 186.135888 -124.698895) (xy 186.12231 -124.697998) (xy 186.094791 -124.69654) (xy 186.040566 -124.686725)
			(xy 185.988316 -124.669217) (xy 185.939125 -124.644378) (xy 185.894016 -124.612726) (xy 185.853926 -124.574919)
			(xy 185.819687 -124.53174) (xy 185.792012 -124.484088) (xy 185.771474 -124.432952) (xy 185.758501 -124.379395)
			(xy 185.753362 -124.324529) (xy 177.030656 -124.324529) (xy 176.972976 -124.382276) (xy 176.116996 -124.382276)
			(xy 175.871886 -124.137166) (xy 175.776128 -124.131324) (xy 175.738282 -124.160534) (xy 175.71606 -124.176976)
			(xy 175.667807 -124.20394) (xy 175.616102 -124.22348) (xy 175.562076 -124.235168) (xy 175.506917 -124.238747)
			(xy 175.451835 -124.234139) (xy 175.398037 -124.221445) (xy 175.346705 -124.200943) (xy 175.298964 -124.173083)
			(xy 175.255863 -124.138477) (xy 175.218346 -124.097883) (xy 175.187238 -124.052193) (xy 175.16322 -124.002409)
			(xy 175.146819 -123.949623) (xy 175.138396 -123.894994) (xy 175.138135 -123.839719) (xy 175.146042 -123.785013)
			(xy 175.161944 -123.732074) (xy 175.185491 -123.682066) (xy 175.216167 -123.636084) (xy 175.253298 -123.595138)
			(xy 175.296071 -123.560127) (xy 175.343547 -123.531817) (xy 175.394683 -123.510832) (xy 175.448358 -123.49763)
			(xy 175.503395 -123.492502) (xy 175.531018 -123.49353) (xy 175.553959 -123.494268) (xy 175.599489 -123.488493)
			(xy 175.643243 -123.474642) (xy 175.683802 -123.453164) (xy 175.719849 -123.424758) (xy 175.750214 -123.390345)
			(xy 175.773911 -123.351041) (xy 175.790171 -123.308123) (xy 175.798466 -123.262985) (xy 175.798988 -123.240038)
			(xy 175.798988 -123.173236) (xy 176.430432 -122.541792) (xy 176.860454 -122.541792) (xy 176.877088 -122.54123)
			(xy 176.909205 -122.532543) (xy 176.937988 -122.515853) (xy 176.950116 -122.504454) (xy 177.145442 -122.309128)
			(xy 177.156825 -122.29701) (xy 177.173408 -122.268205) (xy 177.181987 -122.236095) (xy 177.181981 -122.202857)
			(xy 177.173389 -122.17075) (xy 177.156795 -122.141952) (xy 177.145442 -122.129804) (xy 176.786032 -121.77014)
			(xy 176.786032 -121.473976) (xy 176.785478 -121.457329) (xy 176.776857 -121.425171) (xy 176.760209 -121.396339)
			(xy 176.736668 -121.372796) (xy 176.707836 -121.356146) (xy 176.675679 -121.347523) (xy 176.659032 -121.346976)
			(xy 176.608232 -121.346976) (xy 176.608232 -120.20296) (xy 177.163222 -120.20296) (xy 177.23993 -120.126252)
			(xy 177.21199 -120.088914) (xy 177.20004 -120.072417) (xy 177.17942 -120.037286) (xy 177.170842 -120.01881)
			(xy 177.162435 -120.003449) (xy 177.138627 -119.977781) (xy 177.10876 -119.959517) (xy 177.075062 -119.950023)
			(xy 177.057558 -119.949468) (xy 176.560988 -119.949468) (xy 176.544342 -119.950032) (xy 176.512184 -119.95865)
			(xy 176.483351 -119.975296) (xy 176.459808 -119.998836) (xy 176.443158 -120.027665) (xy 176.434535 -120.059822)
			(xy 176.433988 -120.076468) (xy 176.433988 -121.143776) (xy 176.419256 -121.143776) (xy 176.345088 -121.217944)
			(xy 176.345088 -121.660158) (xy 175.824896 -122.180096) (xy 175.803045 -122.201213) (xy 175.754627 -122.23793)
			(xy 175.701659 -122.267713) (xy 175.64513 -122.290005) (xy 175.586092 -122.304392) (xy 175.525644 -122.310606)
			(xy 175.464914 -122.308532) (xy 175.405031 -122.298207) (xy 175.347113 -122.279824) (xy 175.292236 -122.253726)
			(xy 175.241425 -122.220399) (xy 175.195625 -122.180463) (xy 175.155689 -122.134663) (xy 175.122362 -122.083852)
			(xy 175.096264 -122.028975) (xy 175.077881 -121.971057) (xy 175.067556 -121.911174) (xy 175.065482 -121.850444)
			(xy 173.892001 -121.850444) (xy 173.892301 -121.853275) (xy 173.890015 -121.909155) (xy 173.879596 -121.964103)
			(xy 173.861267 -122.016941) (xy 173.83542 -122.066536) (xy 173.80261 -122.111827) (xy 173.763539 -122.151843)
			(xy 173.741588 -122.169174) (xy 173.723353 -122.183614) (xy 173.692089 -122.218053) (xy 173.667611 -122.257603)
			(xy 173.650733 -122.300945) (xy 173.64202 -122.346634) (xy 173.641761 -122.393146) (xy 173.649966 -122.438929)
			(xy 173.66636 -122.482456) (xy 173.690398 -122.522276) (xy 173.721276 -122.55706) (xy 173.739302 -122.571764)
			(xy 173.760444 -122.588854) (xy 173.798023 -122.628134) (xy 173.829493 -122.672459) (xy 173.854186 -122.720888)
			(xy 173.871577 -122.772392) (xy 173.881296 -122.825877) (xy 173.882644 -122.865642) (xy 174.13733 -122.865642)
			(xy 174.141306 -122.811316) (xy 174.153149 -122.758147) (xy 174.172608 -122.70727) (xy 174.199268 -122.659768)
			(xy 174.232559 -122.616654) (xy 174.271773 -122.578847) (xy 174.316075 -122.547152) (xy 174.364518 -122.522246)
			(xy 174.416072 -122.504658) (xy 174.469638 -122.494764) (xy 174.524073 -122.492774) (xy 174.578218 -122.498732)
			(xy 174.630918 -122.51251) (xy 174.681051 -122.533814) (xy 174.727547 -122.56219) (xy 174.769417 -122.597034)
			(xy 174.805766 -122.637603) (xy 174.835822 -122.683032) (xy 174.858943 -122.732353) (xy 174.874636 -122.784515)
			(xy 174.882567 -122.838406) (xy 174.883064 -122.865642) (xy 174.882567 -122.892878) (xy 174.874636 -122.946769)
			(xy 174.858943 -122.998931) (xy 174.835822 -123.048252) (xy 174.805766 -123.093681) (xy 174.769417 -123.13425)
			(xy 174.727547 -123.169094) (xy 174.681051 -123.19747) (xy 174.630918 -123.218774) (xy 174.578218 -123.232552)
			(xy 174.524073 -123.23851) (xy 174.469638 -123.23652) (xy 174.416072 -123.226626) (xy 174.364518 -123.209038)
			(xy 174.316075 -123.184132) (xy 174.271773 -123.152437) (xy 174.232559 -123.11463) (xy 174.199268 -123.071516)
			(xy 174.172608 -123.024014) (xy 174.153149 -122.973137) (xy 174.141306 -122.919968) (xy 174.13733 -122.865642)
			(xy 173.882644 -122.865642) (xy 173.883138 -122.880207) (xy 173.877062 -122.934228) (xy 173.863198 -122.986791)
			(xy 173.841841 -123.036781) (xy 173.813444 -123.083135) (xy 173.77861 -123.12487) (xy 173.73808 -123.161097)
			(xy 173.692714 -123.191048) (xy 173.643476 -123.214086) (xy 173.591412 -123.229722) (xy 173.537629 -123.237624)
			(xy 173.483267 -123.237624) (xy 173.429484 -123.229722) (xy 173.37742 -123.214086) (xy 173.328182 -123.191048)
			(xy 173.282816 -123.161097) (xy 173.242286 -123.12487) (xy 173.207452 -123.083135) (xy 173.179055 -123.036781)
			(xy 173.157698 -122.986791) (xy 173.143834 -122.934228) (xy 173.137758 -122.880207) (xy 173.1396 -122.825877)
			(xy 173.149319 -122.772392) (xy 173.16671 -122.720888) (xy 173.191403 -122.672459) (xy 173.222873 -122.628134)
			(xy 173.260452 -122.588854) (xy 173.281594 -122.571764) (xy 173.299566 -122.557003) (xy 173.330435 -122.52223)
			(xy 173.354466 -122.482422) (xy 173.370856 -122.438908) (xy 173.379058 -122.393139) (xy 173.378799 -122.346642)
			(xy 173.370089 -122.300967) (xy 173.353216 -122.257638) (xy 173.328745 -122.2181) (xy 173.29749 -122.183672)
			(xy 173.279308 -122.169174) (xy 173.257357 -122.151843) (xy 173.218286 -122.111827) (xy 173.185476 -122.066536)
			(xy 173.159629 -122.016941) (xy 173.1413 -121.964103) (xy 173.130881 -121.909155) (xy 173.128595 -121.853275)
			(xy 172.092112 -121.853275) (xy 172.092112 -123.858528) (xy 172.099224 -123.86564) (xy 173.137332 -123.86564)
			(xy 173.141308 -123.811314) (xy 173.153151 -123.758145) (xy 173.17261 -123.707268) (xy 173.19927 -123.659766)
			(xy 173.232561 -123.616652) (xy 173.271775 -123.578845) (xy 173.316077 -123.54715) (xy 173.36452 -123.522244)
			(xy 173.416074 -123.504656) (xy 173.46964 -123.494762) (xy 173.524075 -123.492772) (xy 173.57822 -123.49873)
			(xy 173.63092 -123.512508) (xy 173.681053 -123.533812) (xy 173.727549 -123.562188) (xy 173.769419 -123.597032)
			(xy 173.805768 -123.637601) (xy 173.835824 -123.68303) (xy 173.858945 -123.732351) (xy 173.874638 -123.784513)
			(xy 173.882569 -123.838404) (xy 173.883066 -123.86564) (xy 174.13733 -123.86564) (xy 174.141306 -123.811314)
			(xy 174.153149 -123.758145) (xy 174.172608 -123.707268) (xy 174.199268 -123.659766) (xy 174.232559 -123.616652)
			(xy 174.271773 -123.578845) (xy 174.316075 -123.54715) (xy 174.364518 -123.522244) (xy 174.416072 -123.504656)
			(xy 174.469638 -123.494762) (xy 174.524073 -123.492772) (xy 174.578218 -123.49873) (xy 174.630918 -123.512508)
			(xy 174.681051 -123.533812) (xy 174.727547 -123.562188) (xy 174.769417 -123.597032) (xy 174.805766 -123.637601)
			(xy 174.835822 -123.68303) (xy 174.858943 -123.732351) (xy 174.874636 -123.784513) (xy 174.882567 -123.838404)
			(xy 174.883064 -123.86564) (xy 174.882567 -123.892876) (xy 174.874636 -123.946767) (xy 174.858943 -123.998929)
			(xy 174.835822 -124.04825) (xy 174.805766 -124.093679) (xy 174.769417 -124.134248) (xy 174.727547 -124.169092)
			(xy 174.681051 -124.197468) (xy 174.630918 -124.218772) (xy 174.578218 -124.23255) (xy 174.524073 -124.238508)
			(xy 174.469638 -124.236518) (xy 174.416072 -124.226624) (xy 174.364518 -124.209036) (xy 174.316075 -124.18413)
			(xy 174.271773 -124.152435) (xy 174.232559 -124.114628) (xy 174.199268 -124.071514) (xy 174.172608 -124.024012)
			(xy 174.153149 -123.973135) (xy 174.141306 -123.919966) (xy 174.13733 -123.86564) (xy 173.883066 -123.86564)
			(xy 173.882569 -123.892876) (xy 173.874638 -123.946767) (xy 173.858945 -123.998929) (xy 173.835824 -124.04825)
			(xy 173.805768 -124.093679) (xy 173.769419 -124.134248) (xy 173.727549 -124.169092) (xy 173.681053 -124.197468)
			(xy 173.63092 -124.218772) (xy 173.57822 -124.23255) (xy 173.524075 -124.238508) (xy 173.46964 -124.236518)
			(xy 173.416074 -124.226624) (xy 173.36452 -124.209036) (xy 173.316077 -124.18413) (xy 173.271775 -124.152435)
			(xy 173.232561 -124.114628) (xy 173.19927 -124.071514) (xy 173.17261 -124.024012) (xy 173.153151 -123.973135)
			(xy 173.141308 -123.919966) (xy 173.137332 -123.86564) (xy 172.099224 -123.86564) (xy 172.614336 -124.380752)
			(xy 172.649134 -124.389134) (xy 172.679563 -124.397002) (xy 172.738075 -124.419949) (xy 172.792897 -124.450686)
			(xy 172.842998 -124.488635) (xy 172.887435 -124.533082) (xy 172.925372 -124.583192) (xy 172.956097 -124.638021)
			(xy 172.97903 -124.696538) (xy 172.986954 -124.726954) (xy 172.995336 -124.761752) (xy 173.108112 -124.874528)
			(xy 182.536082 -124.874528) (xy 182.540153 -124.818906) (xy 182.552279 -124.764469) (xy 182.572202 -124.712378)
			(xy 182.599498 -124.663743) (xy 182.633584 -124.6196) (xy 182.673733 -124.580891) (xy 182.719091 -124.54844)
			(xy 182.768691 -124.522939) (xy 182.821475 -124.504932) (xy 182.876318 -124.494802) (xy 182.932052 -124.492765)
			(xy 182.987489 -124.498865) (xy 183.041446 -124.512971) (xy 183.092775 -124.534783) (xy 183.140381 -124.563837)
			(xy 183.183249 -124.599512) (xy 183.220466 -124.641049) (xy 183.251239 -124.687562) (xy 183.274911 -124.738059)
			(xy 183.290979 -124.791466) (xy 183.299099 -124.846642) (xy 183.299608 -124.874528) (xy 183.299099 -124.902414)
			(xy 183.290979 -124.95759) (xy 183.274911 -125.010997) (xy 183.251239 -125.061494) (xy 183.220466 -125.108007)
			(xy 183.183249 -125.149544) (xy 183.140381 -125.185219) (xy 183.092775 -125.214273) (xy 183.041446 -125.236085)
			(xy 182.987489 -125.250191) (xy 182.932052 -125.256291) (xy 182.876318 -125.254254) (xy 182.821475 -125.244124)
			(xy 182.768691 -125.226117) (xy 182.719091 -125.200616) (xy 182.673733 -125.168165) (xy 182.633584 -125.129456)
			(xy 182.599498 -125.085313) (xy 182.572202 -125.036678) (xy 182.552279 -124.984587) (xy 182.540153 -124.93015)
			(xy 182.536082 -124.874528) (xy 173.108112 -124.874528) (xy 174.276512 -126.042928) (xy 174.293646 -126.059312)
			(xy 174.332801 -126.086031) (xy 174.37623 -126.105028) (xy 174.422428 -126.115645) (xy 174.469793 -126.117513)
			(xy 174.516683 -126.110568) (xy 174.561474 -126.09505) (xy 174.602611 -126.071498) (xy 174.638668 -126.040728)
			(xy 174.653956 -126.022608) (xy 174.672908 -125.999837) (xy 174.715726 -125.958892) (xy 174.763469 -125.923815)
			(xy 174.81534 -125.895191) (xy 174.87047 -125.8735) (xy 174.927939 -125.859104) (xy 174.986785 -125.852245)
			(xy 175.046023 -125.853036) (xy 175.104665 -125.861464) (xy 175.161729 -125.877389) (xy 175.21626 -125.900544)
			(xy 175.267348 -125.930542) (xy 175.314138 -125.966882) (xy 175.355847 -126.008956) (xy 175.391779 -126.05606)
			(xy 175.421332 -126.107407) (xy 175.444012 -126.162138) (xy 175.45944 -126.219338) (xy 175.467358 -126.27805)
			(xy 175.467634 -126.337294) (xy 175.460262 -126.396078) (xy 175.445367 -126.453419) (xy 175.434752 -126.481078)
			(xy 175.44606 -126.510518) (xy 175.461396 -126.57169) (xy 175.468182 -126.634389) (xy 175.46629 -126.697426)
			(xy 175.455755 -126.759606) (xy 175.436777 -126.819748) (xy 175.409716 -126.876712) (xy 175.375085 -126.929418)
			(xy 175.354742 -126.953518) (xy 175.344639 -126.965855) (xy 175.330294 -126.994322) (xy 175.323447 -127.025456)
			(xy 175.324525 -127.057315) (xy 175.333461 -127.087914) (xy 175.349698 -127.115346) (xy 175.360584 -127.127)
			(xy 175.43526 -127.201676) (xy 175.844962 -127.201676) (xy 175.86833 -127.192024) (xy 175.893476 -127.182626)
			(xy 175.91362 -127.174844) (xy 175.951124 -127.153442) (xy 175.984465 -127.126003) (xy 176.012683 -127.093317)
			(xy 176.034963 -127.056329) (xy 176.050663 -127.016103) (xy 176.05933 -126.973801) (xy 176.060714 -126.930643)
			(xy 176.054776 -126.887872) (xy 176.04867 -126.867158) (xy 176.039868 -126.837796) (xy 176.029291 -126.777419)
			(xy 176.026865 -126.71617) (xy 176.032635 -126.655145) (xy 176.046497 -126.595436) (xy 176.068202 -126.53811)
			(xy 176.097364 -126.484194) (xy 176.13346 -126.434652) (xy 176.175844 -126.39037) (xy 176.223759 -126.35214)
			(xy 176.276346 -126.320646) (xy 176.332666 -126.296451) (xy 176.391711 -126.279989) (xy 176.452425 -126.271553)
			(xy 176.513722 -126.271295) (xy 176.574505 -126.279219) (xy 176.633686 -126.295183) (xy 176.690208 -126.318902)
			(xy 176.743059 -126.349952) (xy 176.791294 -126.387777) (xy 176.83405 -126.431701) (xy 176.870562 -126.480937)
			(xy 176.900177 -126.534605) (xy 176.922365 -126.591746) (xy 176.936729 -126.651336) (xy 176.943013 -126.71231)
			(xy 176.941979 -126.745488) (xy 178.553346 -126.745488) (xy 178.553346 -126.685552) (xy 178.561169 -126.62613)
			(xy 178.576682 -126.568237) (xy 178.599618 -126.512864) (xy 178.629585 -126.460958) (xy 178.666072 -126.413408)
			(xy 178.708452 -126.371028) (xy 178.756002 -126.334541) (xy 178.807908 -126.304574) (xy 178.863281 -126.281638)
			(xy 178.921174 -126.266125) (xy 178.980596 -126.258302) (xy 179.040532 -126.258302) (xy 179.099954 -126.266125)
			(xy 179.157847 -126.281638) (xy 179.21322 -126.304574) (xy 179.265126 -126.334541) (xy 179.312676 -126.371028)
			(xy 179.355056 -126.413408) (xy 179.391543 -126.460958) (xy 179.42151 -126.512864) (xy 179.433172 -126.541018)
			(xy 180.893194 -126.541018) (xy 180.893194 -126.481082) (xy 180.901017 -126.42166) (xy 180.91653 -126.363767)
			(xy 180.939466 -126.308394) (xy 180.969433 -126.256488) (xy 181.00592 -126.208938) (xy 181.0483 -126.166558)
			(xy 181.09585 -126.130071) (xy 181.147756 -126.100104) (xy 181.203129 -126.077168) (xy 181.261022 -126.061655)
			(xy 181.320444 -126.053832) (xy 181.38038 -126.053832) (xy 181.439802 -126.061655) (xy 181.497695 -126.077168)
			(xy 181.553068 -126.100104) (xy 181.604974 -126.130071) (xy 181.652524 -126.166558) (xy 181.673166 -126.1872)
			(xy 189.685928 -126.1872) (xy 189.690001 -126.131541) (xy 189.702136 -126.077068) (xy 189.722072 -126.024942)
			(xy 189.749386 -125.976274) (xy 189.783494 -125.932102) (xy 189.823671 -125.893367) (xy 189.869059 -125.860895)
			(xy 189.918691 -125.835377) (xy 189.971511 -125.817358) (xy 190.02639 -125.807221) (xy 190.082161 -125.805183)
			(xy 190.137635 -125.811286) (xy 190.191628 -125.825402) (xy 190.242991 -125.847229) (xy 190.290629 -125.876302)
			(xy 190.333525 -125.912001) (xy 190.370767 -125.953565) (xy 190.401561 -126.000109) (xy 190.425249 -126.05064)
			(xy 190.441327 -126.104082) (xy 190.449453 -126.159296) (xy 190.449962 -126.1872) (xy 190.449453 -126.215104)
			(xy 190.441327 -126.270318) (xy 190.425249 -126.32376) (xy 190.401561 -126.374291) (xy 190.370767 -126.420835)
			(xy 190.333525 -126.462399) (xy 190.290629 -126.498098) (xy 190.242991 -126.527171) (xy 190.191628 -126.548998)
			(xy 190.137635 -126.563114) (xy 190.082161 -126.569217) (xy 190.02639 -126.567179) (xy 189.971511 -126.557042)
			(xy 189.918691 -126.539023) (xy 189.869059 -126.513505) (xy 189.823671 -126.481033) (xy 189.783494 -126.442298)
			(xy 189.749386 -126.398126) (xy 189.722072 -126.349458) (xy 189.702136 -126.297332) (xy 189.690001 -126.242859)
			(xy 189.685928 -126.1872) (xy 181.673166 -126.1872) (xy 181.694904 -126.208938) (xy 181.731391 -126.256488)
			(xy 181.761358 -126.308394) (xy 181.784294 -126.363767) (xy 181.799807 -126.42166) (xy 181.80763 -126.481082)
			(xy 181.80812 -126.51105) (xy 181.80763 -126.541018) (xy 181.799807 -126.60044) (xy 181.784294 -126.658333)
			(xy 181.761358 -126.713706) (xy 181.731391 -126.765612) (xy 181.694904 -126.813162) (xy 181.652524 -126.855542)
			(xy 181.604974 -126.892029) (xy 181.553068 -126.921996) (xy 181.497695 -126.944932) (xy 181.439802 -126.960445)
			(xy 181.38038 -126.968268) (xy 181.320444 -126.968268) (xy 181.261022 -126.960445) (xy 181.203129 -126.944932)
			(xy 181.147756 -126.921996) (xy 181.09585 -126.892029) (xy 181.0483 -126.855542) (xy 181.00592 -126.813162)
			(xy 180.969433 -126.765612) (xy 180.939466 -126.713706) (xy 180.91653 -126.658333) (xy 180.901017 -126.60044)
			(xy 180.893194 -126.541018) (xy 179.433172 -126.541018) (xy 179.444446 -126.568237) (xy 179.459959 -126.62613)
			(xy 179.467782 -126.685552) (xy 179.468272 -126.71552) (xy 179.467782 -126.745488) (xy 179.459959 -126.80491)
			(xy 179.444446 -126.862803) (xy 179.42151 -126.918176) (xy 179.391543 -126.970082) (xy 179.355056 -127.017632)
			(xy 179.347288 -127.0254) (xy 184.428636 -127.0254) (xy 184.432709 -126.969741) (xy 184.444844 -126.915268)
			(xy 184.46478 -126.863142) (xy 184.492094 -126.814474) (xy 184.526202 -126.770302) (xy 184.566379 -126.731567)
			(xy 184.611767 -126.699095) (xy 184.661399 -126.673577) (xy 184.714219 -126.655558) (xy 184.769098 -126.645421)
			(xy 184.824869 -126.643383) (xy 184.880343 -126.649486) (xy 184.934336 -126.663602) (xy 184.985699 -126.685429)
			(xy 185.033337 -126.714502) (xy 185.076233 -126.750201) (xy 185.113475 -126.791765) (xy 185.144269 -126.838309)
			(xy 185.167957 -126.88884) (xy 185.184035 -126.942282) (xy 185.192161 -126.997496) (xy 185.19267 -127.0254)
			(xy 185.192161 -127.053304) (xy 185.184035 -127.108518) (xy 185.167957 -127.16196) (xy 185.144269 -127.212491)
			(xy 185.113475 -127.259035) (xy 185.076233 -127.300599) (xy 185.033337 -127.336298) (xy 184.985699 -127.365371)
			(xy 184.934336 -127.387198) (xy 184.880343 -127.401314) (xy 184.824869 -127.407417) (xy 184.769098 -127.405379)
			(xy 184.714219 -127.395242) (xy 184.661399 -127.377223) (xy 184.611767 -127.351705) (xy 184.566379 -127.319233)
			(xy 184.526202 -127.280498) (xy 184.492094 -127.236326) (xy 184.46478 -127.187658) (xy 184.444844 -127.135532)
			(xy 184.432709 -127.081059) (xy 184.428636 -127.0254) (xy 179.347288 -127.0254) (xy 179.312676 -127.060012)
			(xy 179.265126 -127.096499) (xy 179.21322 -127.126466) (xy 179.157847 -127.149402) (xy 179.099954 -127.164915)
			(xy 179.040532 -127.172738) (xy 178.980596 -127.172738) (xy 178.921174 -127.164915) (xy 178.863281 -127.149402)
			(xy 178.807908 -127.126466) (xy 178.756002 -127.096499) (xy 178.708452 -127.060012) (xy 178.666072 -127.017632)
			(xy 178.629585 -126.970082) (xy 178.599618 -126.918176) (xy 178.576682 -126.862803) (xy 178.561169 -126.80491)
			(xy 178.553346 -126.745488) (xy 176.941979 -126.745488) (xy 176.941104 -126.773578) (xy 176.931035 -126.834042)
			(xy 176.912988 -126.892622) (xy 176.887285 -126.94827) (xy 176.854386 -126.99999) (xy 176.814879 -127.046858)
			(xy 176.769471 -127.088034) (xy 176.718975 -127.122782) (xy 176.664293 -127.15048) (xy 176.606404 -127.170634)
			(xy 176.576482 -127.177292) (xy 176.555353 -127.182042) (xy 176.515001 -127.197759) (xy 176.477903 -127.220098)
			(xy 176.445135 -127.248409) (xy 176.417648 -127.281871) (xy 176.39624 -127.319514) (xy 176.381532 -127.360244)
			(xy 176.373951 -127.40288) (xy 176.373717 -127.446183) (xy 176.376838 -127.467614) (xy 176.381567 -127.495647)
			(xy 176.383468 -127.552463) (xy 176.376716 -127.608909) (xy 176.361467 -127.663674) (xy 176.338076 -127.715487)
			(xy 176.307084 -127.763144) (xy 176.269212 -127.80554) (xy 176.225339 -127.84169) (xy 176.176483 -127.870756)
			(xy 176.123778 -127.892062) (xy 176.068448 -127.905114) (xy 176.011778 -127.909608) (xy 175.983392 -127.90805)
			(xy 175.960578 -127.907537) (xy 175.915362 -127.913663) (xy 175.871966 -127.927763) (xy 175.831785 -127.949386)
			(xy 175.796111 -127.977835) (xy 175.76609 -128.012197) (xy 175.742687 -128.051367) (xy 175.740805 -128.056382)
			(xy 177.553348 -128.056382) (xy 177.553348 -127.996446) (xy 177.561171 -127.937024) (xy 177.576684 -127.879131)
			(xy 177.59962 -127.823758) (xy 177.629587 -127.771852) (xy 177.666074 -127.724302) (xy 177.708454 -127.681922)
			(xy 177.756004 -127.645435) (xy 177.80791 -127.615468) (xy 177.863283 -127.592532) (xy 177.921176 -127.577019)
			(xy 177.980598 -127.569196) (xy 178.040534 -127.569196) (xy 178.099956 -127.577019) (xy 178.157849 -127.592532)
			(xy 178.213222 -127.615468) (xy 178.265128 -127.645435) (xy 178.312678 -127.681922) (xy 178.328748 -127.697992)
			(xy 187.103002 -127.697992) (xy 187.107073 -127.64237) (xy 187.119199 -127.587933) (xy 187.139122 -127.535842)
			(xy 187.166418 -127.487207) (xy 187.200504 -127.443064) (xy 187.240653 -127.404355) (xy 187.286011 -127.371904)
			(xy 187.335611 -127.346403) (xy 187.388395 -127.328396) (xy 187.443238 -127.318266) (xy 187.498972 -127.316229)
			(xy 187.554409 -127.322329) (xy 187.608366 -127.336435) (xy 187.659695 -127.358247) (xy 187.707301 -127.387301)
			(xy 187.750169 -127.422976) (xy 187.787386 -127.464513) (xy 187.818159 -127.511026) (xy 187.841831 -127.561523)
			(xy 187.857899 -127.61493) (xy 187.866019 -127.670106) (xy 187.866528 -127.697992) (xy 187.866019 -127.725878)
			(xy 187.857899 -127.781054) (xy 187.841831 -127.834461) (xy 187.818159 -127.884958) (xy 187.787386 -127.931471)
			(xy 187.750169 -127.973008) (xy 187.707301 -128.008683) (xy 187.659695 -128.037737) (xy 187.608366 -128.059549)
			(xy 187.554409 -128.073655) (xy 187.498972 -128.079755) (xy 187.443238 -128.077718) (xy 187.388395 -128.067588)
			(xy 187.335611 -128.049581) (xy 187.286011 -128.02408) (xy 187.240653 -127.991629) (xy 187.200504 -127.95292)
			(xy 187.166418 -127.908777) (xy 187.139122 -127.860142) (xy 187.119199 -127.808051) (xy 187.107073 -127.753614)
			(xy 187.103002 -127.697992) (xy 178.328748 -127.697992) (xy 178.355058 -127.724302) (xy 178.391545 -127.771852)
			(xy 178.421512 -127.823758) (xy 178.444448 -127.879131) (xy 178.459961 -127.937024) (xy 178.467784 -127.996446)
			(xy 178.468274 -128.026414) (xy 178.467784 -128.056382) (xy 178.459961 -128.115804) (xy 178.444448 -128.173697)
			(xy 178.421512 -128.22907) (xy 178.391545 -128.280976) (xy 178.355058 -128.328526) (xy 178.312678 -128.370906)
			(xy 178.265128 -128.407393) (xy 178.213222 -128.43736) (xy 178.19232 -128.446018) (xy 179.354462 -128.446018)
			(xy 179.354462 -128.386082) (xy 179.362285 -128.32666) (xy 179.377798 -128.268767) (xy 179.400734 -128.213394)
			(xy 179.430701 -128.161488) (xy 179.467188 -128.113938) (xy 179.509568 -128.071558) (xy 179.557118 -128.035071)
			(xy 179.609024 -128.005104) (xy 179.664397 -127.982168) (xy 179.72229 -127.966655) (xy 179.781712 -127.958832)
			(xy 179.841648 -127.958832) (xy 179.90107 -127.966655) (xy 179.958963 -127.982168) (xy 180.014336 -128.005104)
			(xy 180.066242 -128.035071) (xy 180.113792 -128.071558) (xy 180.156172 -128.113938) (xy 180.192659 -128.161488)
			(xy 180.222626 -128.213394) (xy 180.245562 -128.268767) (xy 180.261075 -128.32666) (xy 180.268898 -128.386082)
			(xy 180.269388 -128.41605) (xy 180.268898 -128.446018) (xy 180.261075 -128.50544) (xy 180.245562 -128.563333)
			(xy 180.222626 -128.618706) (xy 180.192659 -128.670612) (xy 180.188218 -128.6764) (xy 187.069728 -128.6764)
			(xy 187.073801 -128.620741) (xy 187.085936 -128.566268) (xy 187.105872 -128.514142) (xy 187.133186 -128.465474)
			(xy 187.167294 -128.421302) (xy 187.207471 -128.382567) (xy 187.252859 -128.350095) (xy 187.302491 -128.324577)
			(xy 187.355311 -128.306558) (xy 187.41019 -128.296421) (xy 187.465961 -128.294383) (xy 187.521435 -128.300486)
			(xy 187.575428 -128.314602) (xy 187.626791 -128.336429) (xy 187.674429 -128.365502) (xy 187.717325 -128.401201)
			(xy 187.754567 -128.442765) (xy 187.785361 -128.489309) (xy 187.809049 -128.53984) (xy 187.825127 -128.593282)
			(xy 187.833253 -128.648496) (xy 187.833762 -128.6764) (xy 187.833253 -128.704304) (xy 187.825127 -128.759518)
			(xy 187.809049 -128.81296) (xy 187.785361 -128.863491) (xy 187.754567 -128.910035) (xy 187.717325 -128.951599)
			(xy 187.674429 -128.987298) (xy 187.626791 -129.016371) (xy 187.575428 -129.038198) (xy 187.521435 -129.052314)
			(xy 187.465961 -129.058417) (xy 187.41019 -129.056379) (xy 187.355311 -129.046242) (xy 187.302491 -129.028223)
			(xy 187.252859 -129.002705) (xy 187.207471 -128.970233) (xy 187.167294 -128.931498) (xy 187.133186 -128.887326)
			(xy 187.105872 -128.838658) (xy 187.085936 -128.786532) (xy 187.073801 -128.732059) (xy 187.069728 -128.6764)
			(xy 180.188218 -128.6764) (xy 180.156172 -128.718162) (xy 180.113792 -128.760542) (xy 180.066242 -128.797029)
			(xy 180.014336 -128.826996) (xy 179.958963 -128.849932) (xy 179.90107 -128.865445) (xy 179.841648 -128.873268)
			(xy 179.781712 -128.873268) (xy 179.72229 -128.865445) (xy 179.664397 -128.849932) (xy 179.609024 -128.826996)
			(xy 179.557118 -128.797029) (xy 179.509568 -128.760542) (xy 179.467188 -128.718162) (xy 179.430701 -128.670612)
			(xy 179.400734 -128.618706) (xy 179.377798 -128.563333) (xy 179.362285 -128.50544) (xy 179.354462 -128.446018)
			(xy 178.19232 -128.446018) (xy 178.157849 -128.460296) (xy 178.099956 -128.475809) (xy 178.040534 -128.483632)
			(xy 177.980598 -128.483632) (xy 177.921176 -128.475809) (xy 177.863283 -128.460296) (xy 177.80791 -128.43736)
			(xy 177.756004 -128.407393) (xy 177.708454 -128.370906) (xy 177.666074 -128.328526) (xy 177.629587 -128.280976)
			(xy 177.59962 -128.22907) (xy 177.576684 -128.173697) (xy 177.561171 -128.115804) (xy 177.553348 -128.056382)
			(xy 175.740805 -128.056382) (xy 175.726654 -128.094086) (xy 175.718506 -128.138982) (xy 175.717962 -128.161796)
			(xy 175.717962 -128.246632) (xy 175.718509 -128.263279) (xy 175.727131 -128.295439) (xy 175.743781 -128.324272)
			(xy 175.767324 -128.347815) (xy 175.796156 -128.364466) (xy 175.828315 -128.37309) (xy 175.844962 -128.373632)
			(xy 175.85182 -128.373632) (xy 175.858678 -128.37287) (xy 175.886745 -128.370313) (xy 175.943059 -128.372503)
			(xy 175.998438 -128.382953) (xy 176.051677 -128.401438) (xy 176.101617 -128.427553) (xy 176.147172 -128.460732)
			(xy 176.187349 -128.500252) (xy 176.221276 -128.545253) (xy 176.248212 -128.594755) (xy 176.267573 -128.647682)
			(xy 176.278937 -128.702881) (xy 176.282055 -128.759151) (xy 176.276862 -128.815268) (xy 176.263469 -128.87001)
			(xy 176.259867 -128.878834) (xy 176.553096 -128.878834) (xy 176.553096 -128.818898) (xy 176.560919 -128.759476)
			(xy 176.576432 -128.701583) (xy 176.599368 -128.64621) (xy 176.629335 -128.594304) (xy 176.665822 -128.546754)
			(xy 176.708202 -128.504374) (xy 176.755752 -128.467887) (xy 176.807658 -128.43792) (xy 176.863031 -128.414984)
			(xy 176.920924 -128.399471) (xy 176.980346 -128.391648) (xy 177.040282 -128.391648) (xy 177.099704 -128.399471)
			(xy 177.157597 -128.414984) (xy 177.21297 -128.43792) (xy 177.264876 -128.467887) (xy 177.312426 -128.504374)
			(xy 177.354806 -128.546754) (xy 177.391293 -128.594304) (xy 177.42126 -128.64621) (xy 177.444196 -128.701583)
			(xy 177.459709 -128.759476) (xy 177.467532 -128.818898) (xy 177.468022 -128.848866) (xy 177.467532 -128.878834)
			(xy 177.459709 -128.938256) (xy 177.444196 -128.996149) (xy 177.42126 -129.051522) (xy 177.391293 -129.103428)
			(xy 177.354806 -129.150978) (xy 177.312426 -129.193358) (xy 177.264876 -129.229845) (xy 177.21297 -129.259812)
			(xy 177.157597 -129.282748) (xy 177.099704 -129.298261) (xy 177.040282 -129.306084) (xy 176.980346 -129.306084)
			(xy 176.920924 -129.298261) (xy 176.863031 -129.282748) (xy 176.807658 -129.259812) (xy 176.755752 -129.229845)
			(xy 176.708202 -129.193358) (xy 176.665822 -129.150978) (xy 176.629335 -129.103428) (xy 176.599368 -129.051522)
			(xy 176.576432 -128.996149) (xy 176.560919 -128.938256) (xy 176.553096 -128.878834) (xy 176.259867 -128.878834)
			(xy 176.242168 -128.922186) (xy 176.213423 -128.97066) (xy 176.177859 -129.014378) (xy 176.13625 -129.052388)
			(xy 176.089501 -129.083863) (xy 176.038631 -129.108118) (xy 175.984746 -129.124625) (xy 175.929019 -129.133024)
			(xy 175.900842 -129.1336) (xy 175.877787 -129.134153) (xy 175.83245 -129.142572) (xy 175.789376 -129.159031)
			(xy 175.749978 -129.182992) (xy 175.71555 -129.213667) (xy 175.68722 -129.25005) (xy 175.665919 -129.290948)
			(xy 175.652346 -129.335017) (xy 175.646946 -129.380811) (xy 175.647858 -129.403856) (xy 175.649339 -129.434457)
			(xy 175.645089 -129.495574) (xy 175.632721 -129.555578) (xy 175.612458 -129.613395) (xy 175.584662 -129.667992)
			(xy 175.54983 -129.718392) (xy 175.508585 -129.763693) (xy 175.461664 -129.803087) (xy 175.409906 -129.835867)
			(xy 175.354238 -129.861449) (xy 175.295654 -129.879374) (xy 175.235202 -129.889323) (xy 175.173963 -129.891116)
			(xy 175.113032 -129.884723) (xy 175.053499 -129.870257) (xy 174.996429 -129.847977) (xy 174.942842 -129.818282)
			(xy 174.893696 -129.781702) (xy 174.84987 -129.738892) (xy 174.812148 -129.690617) (xy 174.796196 -129.66446)
			(xy 174.78356 -129.645523) (xy 174.752692 -129.612067) (xy 174.71636 -129.58464) (xy 174.675727 -129.56412)
			(xy 174.632089 -129.551162) (xy 174.586842 -129.546179) (xy 174.54143 -129.549331) (xy 174.497305 -129.560517)
			(xy 174.455876 -129.57938) (xy 174.418467 -129.605317) (xy 174.401988 -129.621026) (xy 173.549056 -130.473958)
			(xy 176.527458 -130.473958) (xy 176.531529 -130.418336) (xy 176.543655 -130.363899) (xy 176.563578 -130.311808)
			(xy 176.590874 -130.263173) (xy 176.62496 -130.21903) (xy 176.665109 -130.180321) (xy 176.710467 -130.14787)
			(xy 176.760067 -130.122369) (xy 176.812851 -130.104362) (xy 176.867694 -130.094232) (xy 176.923428 -130.092195)
			(xy 176.978865 -130.098295) (xy 177.032822 -130.112401) (xy 177.084151 -130.134213) (xy 177.131757 -130.163267)
			(xy 177.174625 -130.198942) (xy 177.211842 -130.240479) (xy 177.242615 -130.286992) (xy 177.266287 -130.337489)
			(xy 177.282355 -130.390896) (xy 177.290475 -130.446072) (xy 177.290984 -130.473958) (xy 177.290475 -130.501844)
			(xy 177.282355 -130.55702) (xy 177.266287 -130.610427) (xy 177.242615 -130.660924) (xy 177.211842 -130.707437)
			(xy 177.174625 -130.748974) (xy 177.131757 -130.784649) (xy 177.084151 -130.813703) (xy 177.032822 -130.835515)
			(xy 176.978865 -130.849621) (xy 176.923428 -130.855721) (xy 176.867694 -130.853684) (xy 176.812851 -130.843554)
			(xy 176.760067 -130.825547) (xy 176.710467 -130.800046) (xy 176.665109 -130.767595) (xy 176.62496 -130.728886)
			(xy 176.590874 -130.684743) (xy 176.563578 -130.636108) (xy 176.543655 -130.584017) (xy 176.531529 -130.52958)
			(xy 176.527458 -130.473958) (xy 173.549056 -130.473958) (xy 172.716698 -131.306316) (xy 177.600608 -131.306316)
			(xy 177.604679 -131.250694) (xy 177.616805 -131.196257) (xy 177.636728 -131.144166) (xy 177.664024 -131.095531)
			(xy 177.69811 -131.051388) (xy 177.738259 -131.012679) (xy 177.783617 -130.980228) (xy 177.833217 -130.954727)
			(xy 177.886001 -130.93672) (xy 177.940844 -130.92659) (xy 177.996578 -130.924553) (xy 178.052015 -130.930653)
			(xy 178.105972 -130.944759) (xy 178.157301 -130.966571) (xy 178.204907 -130.995625) (xy 178.247775 -131.0313)
			(xy 178.284992 -131.072837) (xy 178.315765 -131.11935) (xy 178.339437 -131.169847) (xy 178.355505 -131.223254)
			(xy 178.363625 -131.27843) (xy 178.364134 -131.306316) (xy 178.363629 -131.333998) (xy 181.412116 -131.333998)
			(xy 181.412116 -131.274062) (xy 181.419939 -131.21464) (xy 181.435452 -131.156747) (xy 181.458388 -131.101374)
			(xy 181.488355 -131.049468) (xy 181.524842 -131.001918) (xy 181.567222 -130.959538) (xy 181.614772 -130.923051)
			(xy 181.666678 -130.893084) (xy 181.722051 -130.870148) (xy 181.779944 -130.854635) (xy 181.839366 -130.846812)
			(xy 181.899302 -130.846812) (xy 181.958724 -130.854635) (xy 182.016617 -130.870148) (xy 182.07199 -130.893084)
			(xy 182.123896 -130.923051) (xy 182.171446 -130.959538) (xy 182.213826 -131.001918) (xy 182.214102 -131.002278)
			(xy 185.02325 -131.002278) (xy 185.027321 -130.946656) (xy 185.039447 -130.892219) (xy 185.05937 -130.840128)
			(xy 185.086666 -130.791493) (xy 185.120752 -130.74735) (xy 185.160901 -130.708641) (xy 185.206259 -130.67619)
			(xy 185.255859 -130.650689) (xy 185.308643 -130.632682) (xy 185.363486 -130.622552) (xy 185.41922 -130.620515)
			(xy 185.474657 -130.626615) (xy 185.528614 -130.640721) (xy 185.579943 -130.662533) (xy 185.627549 -130.691587)
			(xy 185.670417 -130.727262) (xy 185.707634 -130.768799) (xy 185.738407 -130.815312) (xy 185.762079 -130.865809)
			(xy 185.778147 -130.919216) (xy 185.786267 -130.974392) (xy 185.786776 -131.002278) (xy 185.786267 -131.030164)
			(xy 185.778147 -131.08534) (xy 185.762079 -131.138747) (xy 185.738407 -131.189244) (xy 185.707634 -131.235757)
			(xy 185.670417 -131.277294) (xy 185.627549 -131.312969) (xy 185.579943 -131.342023) (xy 185.528614 -131.363835)
			(xy 185.474657 -131.377941) (xy 185.41922 -131.384041) (xy 185.363486 -131.382004) (xy 185.308643 -131.371874)
			(xy 185.255859 -131.353867) (xy 185.206259 -131.328366) (xy 185.160901 -131.295915) (xy 185.120752 -131.257206)
			(xy 185.086666 -131.213063) (xy 185.05937 -131.164428) (xy 185.039447 -131.112337) (xy 185.027321 -131.0579)
			(xy 185.02325 -131.002278) (xy 182.214102 -131.002278) (xy 182.250313 -131.049468) (xy 182.28028 -131.101374)
			(xy 182.303216 -131.156747) (xy 182.318729 -131.21464) (xy 182.326552 -131.274062) (xy 182.327042 -131.30403)
			(xy 182.326552 -131.333998) (xy 182.318729 -131.39342) (xy 182.303216 -131.451313) (xy 182.28028 -131.506686)
			(xy 182.250313 -131.558592) (xy 182.213826 -131.606142) (xy 182.171446 -131.648522) (xy 182.123896 -131.685009)
			(xy 182.07199 -131.714976) (xy 182.016617 -131.737912) (xy 181.958724 -131.753425) (xy 181.899302 -131.761248)
			(xy 181.839366 -131.761248) (xy 181.779944 -131.753425) (xy 181.722051 -131.737912) (xy 181.666678 -131.714976)
			(xy 181.614772 -131.685009) (xy 181.567222 -131.648522) (xy 181.524842 -131.606142) (xy 181.488355 -131.558592)
			(xy 181.458388 -131.506686) (xy 181.435452 -131.451313) (xy 181.419939 -131.39342) (xy 181.412116 -131.333998)
			(xy 178.363629 -131.333998) (xy 178.363625 -131.334202) (xy 178.355505 -131.389378) (xy 178.339437 -131.442785)
			(xy 178.315765 -131.493282) (xy 178.284992 -131.539795) (xy 178.247775 -131.581332) (xy 178.204907 -131.617007)
			(xy 178.157301 -131.646061) (xy 178.105972 -131.667873) (xy 178.052015 -131.681979) (xy 177.996578 -131.688079)
			(xy 177.940844 -131.686042) (xy 177.886001 -131.675912) (xy 177.833217 -131.657905) (xy 177.783617 -131.632404)
			(xy 177.738259 -131.599953) (xy 177.69811 -131.561244) (xy 177.664024 -131.517101) (xy 177.636728 -131.468466)
			(xy 177.616805 -131.416375) (xy 177.604679 -131.361938) (xy 177.600608 -131.306316) (xy 172.716698 -131.306316)
			(xy 172.277278 -131.745736) (xy 175.172876 -131.745736) (xy 175.176947 -131.690114) (xy 175.189073 -131.635677)
			(xy 175.208996 -131.583586) (xy 175.236292 -131.534951) (xy 175.270378 -131.490808) (xy 175.310527 -131.452099)
			(xy 175.355885 -131.419648) (xy 175.405485 -131.394147) (xy 175.458269 -131.37614) (xy 175.513112 -131.36601)
			(xy 175.568846 -131.363973) (xy 175.624283 -131.370073) (xy 175.67824 -131.384179) (xy 175.729569 -131.405991)
			(xy 175.777175 -131.435045) (xy 175.820043 -131.47072) (xy 175.85726 -131.512257) (xy 175.888033 -131.55877)
			(xy 175.911705 -131.609267) (xy 175.927773 -131.662674) (xy 175.935893 -131.71785) (xy 175.936402 -131.745736)
			(xy 175.935893 -131.773622) (xy 175.927773 -131.828798) (xy 175.911705 -131.882205) (xy 175.888033 -131.932702)
			(xy 175.85726 -131.979215) (xy 175.820043 -132.020752) (xy 175.777175 -132.056427) (xy 175.729569 -132.085481)
			(xy 175.67824 -132.107293) (xy 175.624283 -132.121399) (xy 175.568846 -132.127499) (xy 175.513112 -132.125462)
			(xy 175.458269 -132.115332) (xy 175.405485 -132.097325) (xy 175.355885 -132.071824) (xy 175.310527 -132.039373)
			(xy 175.270378 -132.000664) (xy 175.236292 -131.956521) (xy 175.208996 -131.907886) (xy 175.189073 -131.855795)
			(xy 175.176947 -131.801358) (xy 175.172876 -131.745736) (xy 172.277278 -131.745736) (xy 171.8818 -132.141214)
			(xy 171.8818 -133.061202) (xy 171.889928 -133.082792) (xy 171.900941 -133.113771) (xy 171.914989 -133.177999)
			(xy 171.919706 -133.243576) (xy 171.914996 -133.309153) (xy 171.900955 -133.373383) (xy 171.889928 -133.404356)
			(xy 171.8818 -133.425946) (xy 171.8818 -133.541174) (xy 180.537522 -133.541174) (xy 180.54266 -133.48643)
			(xy 180.555604 -133.432991) (xy 180.576088 -133.381964) (xy 180.603685 -133.334406) (xy 180.637825 -133.291304)
			(xy 180.677799 -133.25355) (xy 180.72278 -133.221926) (xy 180.771836 -133.197089) (xy 180.823949 -133.179552)
			(xy 180.87804 -133.169679) (xy 180.932988 -133.167675) (xy 180.987655 -133.173581) (xy 181.040907 -133.187275)
			(xy 181.091642 -133.208473) (xy 181.138807 -133.236736) (xy 181.16042 -133.253734) (xy 181.177518 -133.267192)
			(xy 181.215431 -133.288541) (xy 181.256427 -133.30312) (xy 181.299307 -133.310503) (xy 181.342818 -133.310475)
			(xy 181.385689 -133.303037) (xy 181.426666 -133.288405) (xy 181.464552 -133.267007) (xy 181.49824 -133.239469)
			(xy 181.526745 -133.206595) (xy 181.538372 -133.188202) (xy 181.554611 -133.162227) (xy 181.59301 -133.114495)
			(xy 181.637433 -133.072312) (xy 181.687087 -133.036432) (xy 181.741083 -133.007498) (xy 181.798457 -132.986026)
			(xy 181.858183 -132.9724) (xy 181.919192 -132.966864) (xy 181.980395 -132.969516) (xy 182.040697 -132.98031)
			(xy 182.099019 -132.999052) (xy 182.154321 -133.025408) (xy 182.205611 -133.058905) (xy 182.251975 -133.098946)
			(xy 182.292582 -133.144814) (xy 182.326707 -133.195689) (xy 182.353739 -133.250662) (xy 182.373197 -133.30875)
			(xy 182.38473 -133.368915) (xy 182.388134 -133.430081) (xy 182.383348 -133.491153) (xy 182.370457 -133.551042)
			(xy 182.349691 -133.608675) (xy 182.321422 -133.663023) (xy 182.286156 -133.713114) (xy 182.244522 -133.758052)
			(xy 182.197265 -133.797034) (xy 182.14523 -133.829363) (xy 182.089347 -133.854461) (xy 182.030615 -133.871879)
			(xy 181.970084 -133.881307) (xy 181.908837 -133.882575) (xy 181.847969 -133.87566) (xy 181.788566 -133.860687)
			(xy 181.731693 -133.837923) (xy 181.678364 -133.807775) (xy 181.629535 -133.770782) (xy 181.60746 -133.749542)
			(xy 181.591748 -133.734501) (xy 181.556103 -133.709575) (xy 181.516738 -133.691078) (xy 181.474798 -133.679548)
			(xy 181.431509 -133.675322) (xy 181.388132 -133.678524) (xy 181.345932 -133.68906) (xy 181.30614 -133.706622)
			(xy 181.269917 -133.730699) (xy 181.238318 -133.760588) (xy 181.224936 -133.777736) (xy 181.208114 -133.799486)
			(xy 181.169215 -133.838348) (xy 181.12514 -133.871222) (xy 181.076802 -133.897427) (xy 181.025202 -133.916421)
			(xy 180.971409 -133.927809) (xy 180.916539 -133.931356) (xy 180.861728 -133.926987) (xy 180.808112 -133.914795)
			(xy 180.756802 -133.89503) (xy 180.708862 -133.868104) (xy 180.665284 -133.834573) (xy 180.626972 -133.795132)
			(xy 180.59472 -133.7506) (xy 180.569196 -133.701898) (xy 180.550929 -133.650036) (xy 180.540298 -133.596089)
			(xy 180.537522 -133.541174) (xy 171.8818 -133.541174) (xy 171.8818 -133.88848) (xy 172.004228 -134.013194)
			(xy 172.049186 -134.018274) (xy 172.079334 -134.022126) (xy 172.13832 -134.036778) (xy 172.194849 -134.059108)
			(xy 172.247924 -134.088723) (xy 172.296614 -134.125101) (xy 172.340061 -134.167603) (xy 172.377501 -134.21548)
			(xy 172.408276 -134.267892) (xy 172.431843 -134.323916) (xy 172.447789 -134.382565) (xy 172.455833 -134.442809)
			(xy 172.455833 -134.503588) (xy 172.44779 -134.563832) (xy 172.431844 -134.622482) (xy 172.408277 -134.678506)
			(xy 172.377503 -134.730917) (xy 172.340063 -134.778796) (xy 172.296616 -134.821298) (xy 172.247927 -134.857676)
			(xy 172.194851 -134.887291) (xy 172.138323 -134.909621) (xy 172.079337 -134.924273) (xy 172.049186 -134.928102)
			(xy 172.004228 -134.933182) (xy 171.8818 -135.057896) (xy 171.8818 -135.318496) (xy 178.958476 -135.318496)
			(xy 178.958476 -135.25856) (xy 178.966299 -135.199138) (xy 178.981812 -135.141245) (xy 179.004748 -135.085872)
			(xy 179.034715 -135.033966) (xy 179.071202 -134.986416) (xy 179.113582 -134.944036) (xy 179.161132 -134.907549)
			(xy 179.213038 -134.877582) (xy 179.268411 -134.854646) (xy 179.326304 -134.839133) (xy 179.385726 -134.83131)
			(xy 179.445662 -134.83131) (xy 179.505084 -134.839133) (xy 179.562977 -134.854646) (xy 179.61835 -134.877582)
			(xy 179.670256 -134.907549) (xy 179.717806 -134.944036) (xy 179.760186 -134.986416) (xy 179.796673 -135.033966)
			(xy 179.82664 -135.085872) (xy 179.849576 -135.141245) (xy 179.865089 -135.199138) (xy 179.872912 -135.25856)
			(xy 179.873061 -135.267696) (xy 182.362076 -135.267696) (xy 182.362076 -135.20776) (xy 182.369899 -135.148338)
			(xy 182.385412 -135.090445) (xy 182.408348 -135.035072) (xy 182.438315 -134.983166) (xy 182.474802 -134.935616)
			(xy 182.517182 -134.893236) (xy 182.564732 -134.856749) (xy 182.616638 -134.826782) (xy 182.672011 -134.803846)
			(xy 182.729904 -134.788333) (xy 182.789326 -134.78051) (xy 182.849262 -134.78051) (xy 182.908684 -134.788333)
			(xy 182.966577 -134.803846) (xy 183.02195 -134.826782) (xy 183.073856 -134.856749) (xy 183.121406 -134.893236)
			(xy 183.163786 -134.935616) (xy 183.200273 -134.983166) (xy 183.23024 -135.035072) (xy 183.253176 -135.090445)
			(xy 183.268689 -135.148338) (xy 183.276512 -135.20776) (xy 183.277002 -135.237728) (xy 183.276512 -135.267696)
			(xy 183.268689 -135.327118) (xy 183.253176 -135.385011) (xy 183.23024 -135.440384) (xy 183.200273 -135.49229)
			(xy 183.163786 -135.53984) (xy 183.121406 -135.58222) (xy 183.073856 -135.618707) (xy 183.02195 -135.648674)
			(xy 182.966577 -135.67161) (xy 182.908684 -135.687123) (xy 182.849262 -135.694946) (xy 182.789326 -135.694946)
			(xy 182.729904 -135.687123) (xy 182.672011 -135.67161) (xy 182.616638 -135.648674) (xy 182.564732 -135.618707)
			(xy 182.517182 -135.58222) (xy 182.474802 -135.53984) (xy 182.438315 -135.49229) (xy 182.408348 -135.440384)
			(xy 182.385412 -135.385011) (xy 182.369899 -135.327118) (xy 182.362076 -135.267696) (xy 179.873061 -135.267696)
			(xy 179.873402 -135.288528) (xy 179.872912 -135.318496) (xy 179.865089 -135.377918) (xy 179.849576 -135.435811)
			(xy 179.82664 -135.491184) (xy 179.796673 -135.54309) (xy 179.760186 -135.59064) (xy 179.717806 -135.63302)
			(xy 179.670256 -135.669507) (xy 179.61835 -135.699474) (xy 179.562977 -135.72241) (xy 179.505084 -135.737923)
			(xy 179.445662 -135.745746) (xy 179.385726 -135.745746) (xy 179.326304 -135.737923) (xy 179.268411 -135.72241)
			(xy 179.213038 -135.699474) (xy 179.161132 -135.669507) (xy 179.113582 -135.63302) (xy 179.071202 -135.59064)
			(xy 179.034715 -135.54309) (xy 179.004748 -135.491184) (xy 178.981812 -135.435811) (xy 178.966299 -135.377918)
			(xy 178.958476 -135.318496) (xy 171.8818 -135.318496) (xy 171.8818 -136.735058) (xy 171.882305 -136.758181)
			(xy 171.886507 -136.781032) (xy 177.715162 -136.781032) (xy 177.719233 -136.72541) (xy 177.731359 -136.670973)
			(xy 177.751282 -136.618882) (xy 177.778578 -136.570247) (xy 177.812664 -136.526104) (xy 177.852813 -136.487395)
			(xy 177.898171 -136.454944) (xy 177.947771 -136.429443) (xy 178.000555 -136.411436) (xy 178.055398 -136.401306)
			(xy 178.111132 -136.399269) (xy 178.166569 -136.405369) (xy 178.220526 -136.419475) (xy 178.271855 -136.441287)
			(xy 178.319461 -136.470341) (xy 178.362329 -136.506016) (xy 178.399546 -136.547553) (xy 178.430319 -136.594066)
			(xy 178.453991 -136.644563) (xy 178.470059 -136.69797) (xy 178.478179 -136.753146) (xy 178.478688 -136.781032)
			(xy 178.478179 -136.808918) (xy 178.470059 -136.864094) (xy 178.453991 -136.917501) (xy 178.447118 -136.932162)
			(xy 180.106572 -136.932162) (xy 180.110643 -136.87654) (xy 180.122769 -136.822103) (xy 180.142692 -136.770012)
			(xy 180.169988 -136.721377) (xy 180.204074 -136.677234) (xy 180.244223 -136.638525) (xy 180.289581 -136.606074)
			(xy 180.339181 -136.580573) (xy 180.391965 -136.562566) (xy 180.446808 -136.552436) (xy 180.502542 -136.550399)
			(xy 180.557979 -136.556499) (xy 180.611936 -136.570605) (xy 180.663265 -136.592417) (xy 180.710871 -136.621471)
			(xy 180.753739 -136.657146) (xy 180.790956 -136.698683) (xy 180.821729 -136.745196) (xy 180.845401 -136.795693)
			(xy 180.861469 -136.8491) (xy 180.869589 -136.904276) (xy 180.870098 -136.932162) (xy 180.869589 -136.960048)
			(xy 180.861469 -137.015224) (xy 180.845401 -137.068631) (xy 180.821729 -137.119128) (xy 180.790956 -137.165641)
			(xy 180.753739 -137.207178) (xy 180.710871 -137.242853) (xy 180.663265 -137.271907) (xy 180.611936 -137.293719)
			(xy 180.557979 -137.307825) (xy 180.502542 -137.313925) (xy 180.446808 -137.311888) (xy 180.391965 -137.301758)
			(xy 180.339181 -137.283751) (xy 180.289581 -137.25825) (xy 180.244223 -137.225799) (xy 180.204074 -137.18709)
			(xy 180.169988 -137.142947) (xy 180.142692 -137.094312) (xy 180.122769 -137.042221) (xy 180.110643 -136.987784)
			(xy 180.106572 -136.932162) (xy 178.447118 -136.932162) (xy 178.430319 -136.967998) (xy 178.399546 -137.014511)
			(xy 178.362329 -137.056048) (xy 178.319461 -137.091723) (xy 178.271855 -137.120777) (xy 178.220526 -137.142589)
			(xy 178.166569 -137.156695) (xy 178.111132 -137.162795) (xy 178.055398 -137.160758) (xy 178.000555 -137.150628)
			(xy 177.947771 -137.132621) (xy 177.898171 -137.10712) (xy 177.852813 -137.074669) (xy 177.812664 -137.03596)
			(xy 177.778578 -136.991817) (xy 177.751282 -136.943182) (xy 177.731359 -136.891091) (xy 177.719233 -136.836654)
			(xy 177.715162 -136.781032) (xy 171.886507 -136.781032) (xy 171.890668 -136.803663) (xy 171.907124 -136.846881)
			(xy 171.931132 -136.886406) (xy 171.961896 -136.920933) (xy 171.998402 -136.949322) (xy 172.039443 -136.970634)
			(xy 172.083664 -136.984166) (xy 172.129604 -136.989471) (xy 172.175745 -136.986373) (xy 172.198284 -136.981184)
			(xy 172.224678 -136.974964) (xy 172.278593 -136.969176) (xy 172.332785 -136.971082) (xy 172.38616 -136.980642)
			(xy 172.437644 -136.997664) (xy 172.486199 -137.021805) (xy 172.530846 -137.052578) (xy 172.570686 -137.089363)
			(xy 172.604916 -137.131419) (xy 172.632845 -137.177898) (xy 172.653911 -137.227863) (xy 172.66769 -137.280309)
			(xy 172.673903 -137.334176) (xy 172.672426 -137.388381) (xy 172.663288 -137.441831) (xy 172.646674 -137.493448)
			(xy 172.622918 -137.542192) (xy 172.592499 -137.587081) (xy 172.556029 -137.627211) (xy 172.514245 -137.661771)
			(xy 172.4914 -137.676382) (xy 172.472065 -137.688789) (xy 172.437826 -137.719412) (xy 172.409651 -137.755692)
			(xy 172.388457 -137.796447) (xy 172.374934 -137.840347) (xy 172.369525 -137.885963) (xy 172.372404 -137.931809)
			(xy 172.383479 -137.97639) (xy 172.402388 -138.018254) (xy 172.413634 -138.034518) (xy 173.982362 -138.034518)
			(xy 173.982362 -137.974582) (xy 173.990185 -137.91516) (xy 174.005698 -137.857267) (xy 174.028634 -137.801894)
			(xy 174.058601 -137.749988) (xy 174.095088 -137.702438) (xy 174.137468 -137.660058) (xy 174.185018 -137.623571)
			(xy 174.236924 -137.593604) (xy 174.292297 -137.570668) (xy 174.35019 -137.555155) (xy 174.409612 -137.547332)
			(xy 174.469548 -137.547332) (xy 174.52897 -137.555155) (xy 174.586863 -137.570668) (xy 174.642236 -137.593604)
			(xy 174.694142 -137.623571) (xy 174.741692 -137.660058) (xy 174.784072 -137.702438) (xy 174.820559 -137.749988)
			(xy 174.850526 -137.801894) (xy 174.873462 -137.857267) (xy 174.888975 -137.91516) (xy 174.896798 -137.974582)
			(xy 174.897288 -138.00455) (xy 174.896798 -138.034518) (xy 174.888975 -138.09394) (xy 174.873462 -138.151833)
			(xy 174.850526 -138.207206) (xy 174.820559 -138.259112) (xy 174.784072 -138.306662) (xy 174.741692 -138.349042)
			(xy 174.694142 -138.385529) (xy 174.642236 -138.415496) (xy 174.586863 -138.438432) (xy 174.52897 -138.453945)
			(xy 174.469548 -138.461768) (xy 174.409612 -138.461768) (xy 174.35019 -138.453945) (xy 174.292297 -138.438432)
			(xy 174.236924 -138.415496) (xy 174.185018 -138.385529) (xy 174.137468 -138.349042) (xy 174.095088 -138.306662)
			(xy 174.058601 -138.259112) (xy 174.028634 -138.207206) (xy 174.005698 -138.151833) (xy 173.990185 -138.09394)
			(xy 173.982362 -138.034518) (xy 172.413634 -138.034518) (xy 172.428514 -138.056036) (xy 172.44441 -138.072622)
			(xy 174.791116 -140.419328) (xy 177.679096 -140.419328)
		)
		(stroke
			(width 0)
			(type solid)
		)
		(fill yes)
		(layer "B.Cu")
		(net "P3V3_STB_NODE1")
	)
	(gr_poly
		(pts
			(xy 35.037014 -144.592548) (xy 36.252404 -144.592548) (xy 36.277296 -144.593818) (xy 39.607236 -144.593818)
			(xy 39.631094 -144.593245) (xy 39.677962 -144.584282) (xy 39.722336 -144.566735) (xy 39.762658 -144.541218)
			(xy 39.797513 -144.508629) (xy 39.825677 -144.47011) (xy 39.846163 -144.427013) (xy 39.85825 -144.380852)
			(xy 39.860474 -144.35709) (xy 39.862104 -144.337258) (xy 39.868971 -144.29806) (xy 39.87419 -144.278858)
			(xy 39.880006 -144.256508) (xy 39.88438 -144.210537) (xy 39.880381 -144.164532) (xy 39.86814 -144.120006)
			(xy 39.848061 -144.078422) (xy 39.820802 -144.041147) (xy 39.787261 -144.009407) (xy 39.74854 -143.984245)
			(xy 39.705912 -143.966488) (xy 39.660779 -143.956721) (xy 39.637716 -143.955516) (xy 39.608252 -143.955516)
			(xy 39.590726 -143.960596) (xy 39.562924 -143.968281) (xy 39.506076 -143.97805) (xy 39.448486 -143.981321)
			(xy 39.390896 -143.97805) (xy 39.334048 -143.968281) (xy 39.306246 -143.960596) (xy 39.28872 -143.955516)
			(xy 38.914832 -143.955516) (xy 38.914832 -142.989808) (xy 38.940232 -142.989808) (xy 38.940232 -142.755874)
			(xy 38.930072 -142.731998) (xy 38.918067 -142.702478) (xy 38.90067 -142.64117) (xy 38.891074 -142.578169)
			(xy 38.889428 -142.514462) (xy 38.895758 -142.45105) (xy 38.909966 -142.388925) (xy 38.931828 -142.329065)
			(xy 38.961 -142.272406) (xy 38.997027 -142.219838) (xy 39.039342 -142.172186) (xy 39.087281 -142.130198)
			(xy 39.140093 -142.094531) (xy 39.19695 -142.065745) (xy 39.256959 -142.044293) (xy 39.319178 -142.03051)
			(xy 39.382633 -142.024612) (xy 39.446327 -142.026693) (xy 39.509261 -142.036719) (xy 39.570448 -142.054533)
			(xy 39.628929 -142.079856) (xy 39.683786 -142.112291) (xy 39.734157 -142.151329) (xy 39.757096 -142.173452)
			(xy 39.95674 -142.373096) (xy 39.95674 -142.989808) (xy 39.98214 -142.989808) (xy 39.98214 -143.755618)
			(xy 39.983285 -143.777444) (xy 39.992122 -143.820244) (xy 40.008154 -143.860899) (xy 40.030909 -143.898211)
			(xy 40.059714 -143.931076) (xy 40.09372 -143.958526) (xy 40.131923 -143.97975) (xy 40.173195 -143.994122)
			(xy 40.216317 -144.001217) (xy 40.238172 -144.00149) (xy 40.265913 -144.001767) (xy 40.320865 -144.009364)
			(xy 40.374139 -144.024837) (xy 40.424611 -144.04786) (xy 40.471218 -144.077949) (xy 40.512977 -144.114469)
			(xy 40.549008 -144.15665) (xy 40.578552 -144.203604) (xy 40.600986 -144.25434) (xy 40.615838 -144.307791)
			(xy 40.622794 -144.362828) (xy 40.621709 -144.418293) (xy 40.617648 -144.445736) (xy 40.61587 -144.45615)
			(xy 40.61587 -144.466818) (xy 40.616415 -144.483466) (xy 40.625036 -144.515628) (xy 40.641684 -144.544463)
			(xy 40.665227 -144.568008) (xy 40.694061 -144.58466) (xy 40.726222 -144.593283) (xy 40.74287 -144.593818)
			(xy 40.840914 -144.593818) (xy 40.857562 -144.593273) (xy 40.889723 -144.584653) (xy 40.918558 -144.568005)
			(xy 40.942102 -144.544461) (xy 40.958752 -144.515627) (xy 40.967373 -144.483466) (xy 40.967914 -144.466818)
			(xy 40.967914 -144.461484) (xy 40.967406 -144.45615) (xy 40.965549 -144.427885) (xy 40.969202 -144.371361)
			(xy 40.981169 -144.315997) (xy 41.001188 -144.26301) (xy 41.028818 -144.213564) (xy 41.063454 -144.168745)
			(xy 41.104333 -144.129538) (xy 41.150559 -144.096804) (xy 41.201115 -144.071261) (xy 41.254892 -144.053472)
			(xy 41.310707 -144.043826) (xy 41.339008 -144.042638) (xy 41.365143 -144.042466) (xy 41.417066 -144.048414)
			(xy 41.467689 -144.061403) (xy 41.516062 -144.081191) (xy 41.561275 -144.107405) (xy 41.60248 -144.139554)
			(xy 41.638904 -144.177033) (xy 41.65473 -144.197832) (xy 41.668253 -144.214534) (xy 41.699926 -144.243572)
			(xy 41.736034 -144.266866) (xy 41.775548 -144.283751) (xy 41.81734 -144.293744) (xy 41.860218 -144.296562)
			(xy 41.902958 -144.292123) (xy 41.944341 -144.280554) (xy 41.983187 -144.262185) (xy 42.018388 -144.237541)
			(xy 42.033952 -144.222724) (xy 42.055003 -144.201561) (xy 42.101646 -144.164314) (xy 42.152735 -144.133444)
			(xy 42.207403 -144.109476) (xy 42.264722 -144.092817) (xy 42.32372 -144.083748) (xy 42.383396 -144.082424)
			(xy 42.442738 -144.088868) (xy 42.471848 -144.09547) (xy 42.501552 -144.103207) (xy 42.558721 -144.12556)
			(xy 42.612389 -144.155351) (xy 42.661596 -144.192047) (xy 42.705458 -144.234989) (xy 42.743188 -144.283407)
			(xy 42.774111 -144.336432) (xy 42.797671 -144.393113) (xy 42.813446 -144.452434) (xy 42.817796 -144.48282)
			(xy 42.820178 -144.497946) (xy 42.831167 -144.526517) (xy 42.848649 -144.551645) (xy 42.871617 -144.571881)
			(xy 42.898747 -144.586059) (xy 42.928475 -144.59336) (xy 42.94378 -144.593818) (xy 43.007026 -144.593818)
			(xy 43.073066 -144.54632) (xy 43.086274 -144.507712) (xy 43.095712 -144.481438) (xy 43.12118 -144.431759)
			(xy 43.153616 -144.386322) (xy 43.19233 -144.346099) (xy 43.236492 -144.311948) (xy 43.285161 -144.284598)
			(xy 43.337296 -144.264634) (xy 43.391784 -144.252483) (xy 43.447462 -144.248404) (xy 43.50314 -144.252483)
			(xy 43.557628 -144.264634) (xy 43.609763 -144.284598) (xy 43.658432 -144.311948) (xy 43.702594 -144.346099)
			(xy 43.741308 -144.386322) (xy 43.773744 -144.431759) (xy 43.799212 -144.481438) (xy 43.80865 -144.507712)
			(xy 43.821858 -144.54632) (xy 43.887898 -144.593818) (xy 44.08424 -144.593818) (xy 44.098823 -144.593412)
			(xy 44.127227 -144.586788) (xy 44.153389 -144.573894) (xy 44.175944 -144.555402) (xy 44.193717 -144.532276)
			(xy 44.200064 -144.519142) (xy 44.200064 -144.518888) (xy 44.211741 -144.49411) (xy 44.241143 -144.447896)
			(xy 44.276849 -144.406359) (xy 44.318128 -144.370354) (xy 44.364129 -144.34062) (xy 44.413909 -144.317768)
			(xy 44.466445 -144.302267) (xy 44.520657 -144.294436) (xy 44.575431 -144.294436) (xy 44.629643 -144.302267)
			(xy 44.682179 -144.317768) (xy 44.731959 -144.34062) (xy 44.77796 -144.370354) (xy 44.819239 -144.406359)
			(xy 44.854945 -144.447896) (xy 44.884347 -144.49411) (xy 44.896024 -144.518888) (xy 44.896024 -144.519142)
			(xy 44.902393 -144.532269) (xy 44.92013 -144.555428) (xy 44.942676 -144.573938) (xy 44.968845 -144.586826)
			(xy 44.997262 -144.593415) (xy 45.011848 -144.593818) (xy 45.147484 -144.593818) (xy 45.163158 -144.593358)
			(xy 45.19356 -144.585714) (xy 45.221178 -144.570885) (xy 45.244344 -144.549766) (xy 45.261658 -144.523634)
			(xy 45.272074 -144.494067) (xy 45.273976 -144.478502) (xy 45.277076 -144.450439) (xy 45.290489 -144.395597)
			(xy 45.311836 -144.343329) (xy 45.340652 -144.294778) (xy 45.376306 -144.251002) (xy 45.418022 -144.212957)
			(xy 45.464888 -144.181474) (xy 45.515881 -144.157241) (xy 45.569888 -144.140785) (xy 45.625731 -144.132466)
			(xy 45.682189 -144.132466) (xy 45.738032 -144.140785) (xy 45.792039 -144.157241) (xy 45.843032 -144.181474)
			(xy 45.889898 -144.212957) (xy 45.931614 -144.251002) (xy 45.967268 -144.294778) (xy 45.996084 -144.343329)
			(xy 46.017431 -144.395597) (xy 46.030844 -144.450439) (xy 46.033944 -144.478502) (xy 46.035849 -144.494065)
			(xy 46.046265 -144.523629) (xy 46.063579 -144.549759) (xy 46.086745 -144.570874) (xy 46.114363 -144.585699)
			(xy 46.144763 -144.593338) (xy 46.160436 -144.593818) (xy 46.382686 -144.593818) (xy 46.395386 -144.581118)
			(xy 49.60366 -144.581118) (xy 49.625825 -144.580657) (xy 49.669488 -144.573007) (xy 49.711162 -144.557896)
			(xy 49.749582 -144.535783) (xy 49.783581 -144.50734) (xy 49.798224 -144.490694) (xy 49.807608 -144.478868)
			(xy 49.821056 -144.45185) (xy 49.82777 -144.422425) (xy 49.827373 -144.392248) (xy 49.819887 -144.36301)
			(xy 49.81321 -144.34947) (xy 49.799473 -144.322372) (xy 49.77848 -144.265362) (xy 49.765213 -144.206075)
			(xy 49.759904 -144.145554) (xy 49.762647 -144.084863) (xy 49.773394 -144.025068) (xy 49.791956 -143.96722)
			(xy 49.818006 -143.912336) (xy 49.851088 -143.86138) (xy 49.890619 -143.815247) (xy 49.935905 -143.774748)
			(xy 49.986149 -143.740596) (xy 50.04047 -143.71339) (xy 50.097912 -143.693608) (xy 50.157467 -143.681598)
			(xy 50.218086 -143.677571) (xy 50.278705 -143.681598) (xy 50.33826 -143.693608) (xy 50.395702 -143.71339)
			(xy 50.450023 -143.740596) (xy 50.500267 -143.774748) (xy 50.545553 -143.815247) (xy 50.585084 -143.86138)
			(xy 50.618166 -143.912336) (xy 50.644216 -143.96722) (xy 50.662778 -144.025068) (xy 50.673525 -144.084863)
			(xy 50.676268 -144.145554) (xy 50.670959 -144.206075) (xy 50.657692 -144.265362) (xy 50.636699 -144.322372)
			(xy 50.622962 -144.34947) (xy 50.616291 -144.363006) (xy 50.608847 -144.392241) (xy 50.608472 -144.422407)
			(xy 50.615187 -144.451819) (xy 50.628617 -144.478833) (xy 50.637948 -144.490694) (xy 50.65259 -144.507341)
			(xy 50.686589 -144.535788) (xy 50.725008 -144.557905) (xy 50.766682 -144.57302) (xy 50.810347 -144.580675)
			(xy 50.832512 -144.581118) (xy 52.222908 -144.581118) (xy 52.239525 -144.580577) (xy 52.271629 -144.571984)
			(xy 52.30042 -144.555383) (xy 52.31257 -144.544034) (xy 52.998878 -143.857726) (xy 53.008276 -143.828516)
			(xy 53.018869 -143.79703) (xy 53.046503 -143.736617) (xy 53.081102 -143.679905) (xy 53.122177 -143.627692)
			(xy 53.16915 -143.580714) (xy 53.221359 -143.539633) (xy 53.278068 -143.505029) (xy 53.338479 -143.477389)
			(xy 53.369972 -143.46682) (xy 53.399182 -143.457422) (xy 55.619904 -141.236446) (xy 55.619904 -139.288012)
			(xy 55.633112 -139.275058) (xy 55.633112 -139.102338) (xy 56.720994 -138.014456) (xy 57.049924 -138.014456)
			(xy 57.050686 -138.015218) (xy 57.736486 -138.015218) (xy 58.199782 -137.551922) (xy 58.199782 -137.438892)
			(xy 58.191654 -137.417302) (xy 58.18253 -137.391461) (xy 58.171098 -137.337868) (xy 58.167635 -137.283178)
			(xy 58.172217 -137.22857) (xy 58.184744 -137.175222) (xy 58.204947 -137.124283) (xy 58.23239 -137.07685)
			(xy 58.249058 -137.055098) (xy 58.266377 -137.03418) (xy 58.306031 -136.997076) (xy 58.328052 -136.981184)
			(xy 58.336486 -136.958542) (xy 58.345618 -136.911102) (xy 58.345626 -136.862791) (xy 58.336512 -136.815348)
			(xy 58.328052 -136.792716) (xy 58.306466 -136.777183) (xy 58.267543 -136.740947) (xy 58.234178 -136.699536)
			(xy 58.207052 -136.653795) (xy 58.19648 -136.629394) (xy 58.186221 -136.603269) (xy 58.172783 -136.548777)
			(xy 58.167667 -136.492885) (xy 58.170988 -136.436859) (xy 58.182672 -136.381963) (xy 58.202455 -136.32944)
			(xy 58.229888 -136.280477) (xy 58.264353 -136.23618) (xy 58.305069 -136.197551) (xy 58.327798 -136.181084)
			(xy 58.336192 -136.158468) (xy 58.34527 -136.111096) (xy 58.345266 -136.062862) (xy 58.33618 -136.015491)
			(xy 58.327798 -135.99287) (xy 58.306827 -135.977723) (xy 58.268877 -135.942568) (xy 58.236157 -135.9025)
			(xy 58.209295 -135.858289) (xy 58.18881 -135.810788) (xy 58.175094 -135.760908) (xy 58.171334 -135.735314)
			(xy 58.168186 -135.707212) (xy 58.169411 -135.65068) (xy 58.179171 -135.594983) (xy 58.19724 -135.541402)
			(xy 58.223204 -135.49117) (xy 58.256466 -135.445441) (xy 58.29626 -135.405268) (xy 58.341671 -135.371575)
			(xy 58.366406 -135.35787) (xy 58.391628 -135.343886) (xy 58.445601 -135.32358) (xy 58.502191 -135.312484)
			(xy 58.530998 -135.311134) (xy 58.555169 -135.310847) (xy 58.603215 -135.316147) (xy 58.650064 -135.328049)
			(xy 58.694814 -135.346324) (xy 58.71591 -135.358124) (xy 58.730294 -135.366011) (xy 58.757763 -135.383948)
			(xy 58.770774 -135.393938) (xy 58.792303 -135.411439) (xy 58.830432 -135.451741) (xy 58.84672 -135.474202)
			(xy 58.869362 -135.482631) (xy 58.9168 -135.491753) (xy 58.965108 -135.491753) (xy 59.012546 -135.482631)
			(xy 59.035188 -135.474202) (xy 59.052682 -135.450092) (xy 59.094043 -135.40723) (xy 59.141681 -135.371473)
			(xy 59.167776 -135.357108) (xy 59.190481 -135.344595) (xy 59.238758 -135.325702) (xy 59.289307 -135.314196)
			(xy 59.341004 -135.310332) (xy 59.392701 -135.314196) (xy 59.44325 -135.325702) (xy 59.491527 -135.344595)
			(xy 59.514232 -135.357108) (xy 59.540334 -135.371465) (xy 59.587995 -135.407198) (xy 59.629346 -135.450075)
			(xy 59.64682 -135.474202) (xy 59.669462 -135.482631) (xy 59.7169 -135.491753) (xy 59.765208 -135.491753)
			(xy 59.812646 -135.482631) (xy 59.835288 -135.474202) (xy 59.851576 -135.451742) (xy 59.889708 -135.411442)
			(xy 59.911234 -135.393938) (xy 59.924238 -135.383937) (xy 59.951711 -135.366007) (xy 59.966098 -135.358124)
			(xy 59.987192 -135.346315) (xy 60.031934 -135.328013) (xy 60.078786 -135.316107) (xy 60.126838 -135.310829)
			(xy 60.15101 -135.311134) (xy 60.179815 -135.312506) (xy 60.2364 -135.323607) (xy 60.290378 -135.343894)
			(xy 60.315602 -135.35787) (xy 60.340325 -135.37158) (xy 60.38569 -135.40531) (xy 60.425445 -135.445501)
			(xy 60.458678 -135.491231) (xy 60.484629 -135.541453) (xy 60.502702 -135.595017) (xy 60.512484 -135.650695)
			(xy 60.513752 -135.707211) (xy 60.510674 -135.735314) (xy 60.506886 -135.760902) (xy 60.49316 -135.810775)
			(xy 60.472673 -135.858272) (xy 60.445818 -135.902481) (xy 60.413111 -135.942555) (xy 60.375179 -135.977724)
			(xy 60.35421 -135.99287) (xy 60.345775 -136.015479) (xy 60.336641 -136.062855) (xy 60.336636 -136.111103)
			(xy 60.345763 -136.15848) (xy 60.35421 -136.181084) (xy 60.376654 -136.197357) (xy 60.41692 -136.23546)
			(xy 60.45109 -136.279114) (xy 60.478407 -136.327353) (xy 60.48883 -136.353042) (xy 60.480194 -136.361678)
			(xy 60.486544 -136.421876) (xy 60.488787 -136.447999) (xy 60.486326 -136.50037) (xy 60.47602 -136.551777)
			(xy 60.458105 -136.60105) (xy 60.432988 -136.647071) (xy 60.401239 -136.688795) (xy 60.363579 -136.725272)
			(xy 60.342526 -136.7409) (xy 60.31738 -136.75868) (xy 60.289186 -136.81329) (xy 60.289186 -136.8425)
			(xy 60.289648 -136.858179) (xy 60.297295 -136.888591) (xy 60.312127 -136.91622) (xy 60.33325 -136.939398)
			(xy 60.346082 -136.948418) (xy 60.37707 -136.971278) (xy 60.50026 -136.971278) (xy 60.608464 -136.863074)
			(xy 61.054742 -136.863074) (xy 61.368686 -136.54913) (xy 61.90234 -136.54913) (xy 62.029086 -136.422384)
			(xy 62.029086 -134.872984) (xy 61.952886 -134.796784) (xy 61.55055 -134.796784) (xy 61.55055 -134.797038)
			(xy 60.82792 -134.797038) (xy 60.7695 -134.855458) (xy 60.291218 -134.855458) (xy 60.232036 -134.914132)
			(xy 60.197492 -134.948676) (xy 60.153296 -134.993126) (xy 56.843676 -134.993126) (xy 56.79948 -134.948676)
			(xy 56.706262 -134.855458) (xy 51.529996 -134.855458) (xy 49.710086 -133.035802) (xy 49.710086 -125.797818)
			(xy 49.202086 -125.289818) (xy 45.021754 -125.289818) (xy 43.853862 -124.121926) (xy 43.836763 -124.105561)
			(xy 43.797688 -124.078864) (xy 43.754345 -124.059864) (xy 43.708234 -124.049219) (xy 43.660949 -124.047296)
			(xy 43.614125 -124.054163) (xy 43.569383 -124.069582) (xy 43.52827 -124.09302) (xy 43.492208 -124.123665)
			(xy 43.476926 -124.141738) (xy 43.458427 -124.165557) (xy 43.41618 -124.208599) (xy 43.368647 -124.245721)
			(xy 43.316653 -124.276281) (xy 43.261095 -124.299749) (xy 43.202938 -124.315721) (xy 43.143187 -124.323918)
			(xy 43.082877 -124.324199) (xy 43.023052 -124.316559) (xy 42.964748 -124.301131) (xy 42.908975 -124.278181)
			(xy 42.856697 -124.248107) (xy 42.808821 -124.21143) (xy 42.766174 -124.168784) (xy 42.729496 -124.120908)
			(xy 42.699422 -124.068631) (xy 42.676471 -124.012858) (xy 42.661042 -123.954554) (xy 42.653402 -123.894729)
			(xy 42.653682 -123.834419) (xy 42.661878 -123.774668) (xy 42.677848 -123.716511) (xy 42.701316 -123.660953)
			(xy 42.731876 -123.608958) (xy 42.768997 -123.561425) (xy 42.812038 -123.519177) (xy 42.83583 -123.500642)
			(xy 42.853882 -123.485347) (xy 42.884501 -123.449281) (xy 42.907916 -123.408171) (xy 42.923319 -123.363438)
			(xy 42.930176 -123.316628) (xy 42.928252 -123.269357) (xy 42.917612 -123.223258) (xy 42.898625 -123.179926)
			(xy 42.871946 -123.140855) (xy 42.855642 -123.123706) (xy 42.257472 -122.525536) (xy 36.232084 -122.525536)
			(xy 34.84372 -123.9139) (xy 34.84372 -126.995936) (xy 34.09188 -127.747776) (xy 32.690054 -127.747776)
			(xy 32.59582 -127.84201) (xy 32.59582 -128.526286) (xy 32.431416 -128.69069) (xy 37.770317 -128.69069)
			(xy 37.777789 -128.629307) (xy 37.792625 -128.569276) (xy 37.814608 -128.511478) (xy 37.843414 -128.456761)
			(xy 37.878623 -128.405926) (xy 37.898832 -128.382522) (xy 37.898832 -128.365504) (xy 37.914072 -128.365504)
			(xy 37.918136 -128.361948) (xy 37.942175 -128.338558) (xy 37.995303 -128.297619) (xy 38.053337 -128.263993)
			(xy 38.115276 -128.238259) (xy 38.180053 -128.220861) (xy 38.24655 -128.212099) (xy 38.280086 -128.21158)
			(xy 39.22014 -128.21158) (xy 39.554658 -128.546098) (xy 39.576972 -128.569123) (xy 39.595952 -128.593592)
			(xy 41.63236 -128.593592) (xy 41.63236 -128.533656) (xy 41.640183 -128.474234) (xy 41.655696 -128.416341)
			(xy 41.678632 -128.360968) (xy 41.708599 -128.309062) (xy 41.745086 -128.261512) (xy 41.787466 -128.219132)
			(xy 41.835016 -128.182645) (xy 41.886922 -128.152678) (xy 41.942295 -128.129742) (xy 42.000188 -128.114229)
			(xy 42.05961 -128.106406) (xy 42.119546 -128.106406) (xy 42.178968 -128.114229) (xy 42.236861 -128.129742)
			(xy 42.292234 -128.152678) (xy 42.34414 -128.182645) (xy 42.39169 -128.219132) (xy 42.43407 -128.261512)
			(xy 42.470557 -128.309062) (xy 42.500524 -128.360968) (xy 42.52346 -128.416341) (xy 42.538973 -128.474234)
			(xy 42.546796 -128.533656) (xy 42.547286 -128.563624) (xy 42.546796 -128.593592) (xy 42.538973 -128.653014)
			(xy 42.52346 -128.710907) (xy 42.500524 -128.76628) (xy 42.470557 -128.818186) (xy 42.43407 -128.865736)
			(xy 42.39169 -128.908116) (xy 42.34414 -128.944603) (xy 42.292234 -128.97457) (xy 42.236861 -128.997506)
			(xy 42.178968 -129.013019) (xy 42.119546 -129.020842) (xy 42.05961 -129.020842) (xy 42.000188 -129.013019)
			(xy 41.942295 -128.997506) (xy 41.886922 -128.97457) (xy 41.835016 -128.944603) (xy 41.787466 -128.908116)
			(xy 41.745086 -128.865736) (xy 41.708599 -128.818186) (xy 41.678632 -128.76628) (xy 41.655696 -128.710907)
			(xy 41.640183 -128.653014) (xy 41.63236 -128.593592) (xy 39.595952 -128.593592) (xy 39.616271 -128.619788)
			(xy 39.648911 -128.674978) (xy 39.674376 -128.733824) (xy 39.692265 -128.795398) (xy 39.702295 -128.858728)
			(xy 39.704309 -128.922816) (xy 39.698275 -128.986651) (xy 39.684288 -129.049226) (xy 39.662568 -129.109555)
			(xy 39.633458 -129.166686) (xy 39.597418 -129.219718) (xy 39.555015 -129.267815) (xy 39.506918 -129.310218)
			(xy 39.453886 -129.346258) (xy 39.396755 -129.375368) (xy 39.336426 -129.397088) (xy 39.273851 -129.411075)
			(xy 39.210016 -129.417109) (xy 39.145928 -129.415095) (xy 39.082598 -129.405065) (xy 39.021024 -129.387176)
			(xy 38.962178 -129.361711) (xy 38.906988 -129.329071) (xy 38.856323 -129.289772) (xy 38.833298 -129.267458)
			(xy 38.797484 -129.231644) (xy 38.280086 -129.231644) (xy 38.246546 -129.231176) (xy 38.180039 -129.222429)
			(xy 38.115254 -129.205035) (xy 38.05331 -129.179294) (xy 37.995277 -129.145652) (xy 37.942158 -129.104688)
			(xy 37.918136 -129.081276) (xy 37.914072 -129.07772) (xy 37.898832 -129.07772) (xy 37.898832 -129.060702)
			(xy 37.878634 -129.037288) (xy 37.843424 -128.986455) (xy 37.814615 -128.931738) (xy 37.792631 -128.873941)
			(xy 37.777792 -128.813911) (xy 37.770318 -128.752527) (xy 37.770317 -128.69069) (xy 32.431416 -128.69069)
			(xy 32.216598 -128.905508) (xy 31.81858 -128.905508) (xy 31.814516 -128.901444) (xy 30.729936 -128.901444)
			(xy 30.56382 -129.06756) (xy 30.56382 -129.706112) (xy 43.25288 -129.706112) (xy 43.25288 -129.646176)
			(xy 43.260703 -129.586754) (xy 43.276216 -129.528861) (xy 43.299152 -129.473488) (xy 43.329119 -129.421582)
			(xy 43.365606 -129.374032) (xy 43.407986 -129.331652) (xy 43.455536 -129.295165) (xy 43.507442 -129.265198)
			(xy 43.562815 -129.242262) (xy 43.620708 -129.226749) (xy 43.68013 -129.218926) (xy 43.740066 -129.218926)
			(xy 43.799488 -129.226749) (xy 43.857381 -129.242262) (xy 43.912754 -129.265198) (xy 43.96466 -129.295165)
			(xy 44.01221 -129.331652) (xy 44.05459 -129.374032) (xy 44.091077 -129.421582) (xy 44.121044 -129.473488)
			(xy 44.14398 -129.528861) (xy 44.159493 -129.586754) (xy 44.167316 -129.646176) (xy 44.167806 -129.676144)
			(xy 44.167316 -129.706112) (xy 44.159493 -129.765534) (xy 44.14398 -129.823427) (xy 44.121044 -129.8788)
			(xy 44.091077 -129.930706) (xy 44.05459 -129.978256) (xy 44.01221 -130.020636) (xy 43.96466 -130.057123)
			(xy 43.912754 -130.08709) (xy 43.857381 -130.110026) (xy 43.799488 -130.125539) (xy 43.740066 -130.133362)
			(xy 43.68013 -130.133362) (xy 43.620708 -130.125539) (xy 43.562815 -130.110026) (xy 43.507442 -130.08709)
			(xy 43.455536 -130.057123) (xy 43.407986 -130.020636) (xy 43.365606 -129.978256) (xy 43.329119 -129.930706)
			(xy 43.299152 -129.8788) (xy 43.276216 -129.823427) (xy 43.260703 -129.765534) (xy 43.25288 -129.706112)
			(xy 30.56382 -129.706112) (xy 30.56382 -129.884932) (xy 30.564367 -129.901577) (xy 30.572991 -129.93373)
			(xy 30.589642 -129.962556) (xy 30.613186 -129.98609) (xy 30.642018 -130.002729) (xy 30.674175 -130.01134)
			(xy 30.69082 -130.011932) (xy 31.346394 -130.011932) (xy 32.34182 -131.007358) (xy 32.34182 -131.233517)
			(xy 35.016556 -131.233517) (xy 35.01949 -131.177679) (xy 35.030539 -131.122865) (xy 35.049467 -131.070251)
			(xy 35.075869 -131.020961) (xy 35.092132 -130.998214) (xy 35.10527 -130.979699) (xy 35.125419 -130.939021)
			(xy 35.13801 -130.895407) (xy 35.142642 -130.850249) (xy 35.139166 -130.804988) (xy 35.127694 -130.761066)
			(xy 35.108592 -130.719886) (xy 35.095942 -130.701034) (xy 35.080269 -130.677882) (xy 35.055134 -130.627944)
			(xy 35.037553 -130.574873) (xy 35.027903 -130.519805) (xy 35.026391 -130.463919) (xy 35.033048 -130.40841)
			(xy 35.047732 -130.354466) (xy 35.07013 -130.303241) (xy 35.099761 -130.255832) (xy 35.135992 -130.213254)
			(xy 35.178047 -130.176417) (xy 35.225026 -130.146109) (xy 35.275924 -130.12298) (xy 35.329652 -130.107525)
			(xy 35.38506 -130.100073) (xy 35.440963 -130.100784) (xy 35.496163 -130.109644) (xy 35.549481 -130.126463)
			(xy 35.599774 -130.15088) (xy 35.645966 -130.182373) (xy 35.68707 -130.220269) (xy 35.722205 -130.263756)
			(xy 35.75062 -130.311904) (xy 35.771706 -130.363682) (xy 35.785012 -130.417982) (xy 35.790254 -130.473643)
			(xy 35.787319 -130.529473) (xy 35.785504 -130.538474) (xy 38.874202 -130.538474) (xy 38.878178 -130.484148)
			(xy 38.890021 -130.430979) (xy 38.90948 -130.380102) (xy 38.93614 -130.3326) (xy 38.969431 -130.289486)
			(xy 39.008645 -130.251679) (xy 39.052947 -130.219984) (xy 39.10139 -130.195078) (xy 39.152944 -130.17749)
			(xy 39.20651 -130.167596) (xy 39.260945 -130.165606) (xy 39.31509 -130.171564) (xy 39.36779 -130.185342)
			(xy 39.417923 -130.206646) (xy 39.464419 -130.235022) (xy 39.506289 -130.269866) (xy 39.542638 -130.310435)
			(xy 39.572694 -130.355864) (xy 39.595815 -130.405185) (xy 39.611508 -130.457347) (xy 39.619439 -130.511238)
			(xy 39.619936 -130.538474) (xy 39.619439 -130.56571) (xy 39.611508 -130.619601) (xy 39.595815 -130.671763)
			(xy 39.572694 -130.721084) (xy 39.542638 -130.766513) (xy 39.506289 -130.807082) (xy 39.464419 -130.841926)
			(xy 39.417923 -130.870302) (xy 39.36779 -130.891606) (xy 39.31509 -130.905384) (xy 39.260945 -130.911342)
			(xy 39.20651 -130.909352) (xy 39.152944 -130.899458) (xy 39.10139 -130.88187) (xy 39.052947 -130.856964)
			(xy 39.008645 -130.825269) (xy 38.969431 -130.787462) (xy 38.93614 -130.744348) (xy 38.90948 -130.696846)
			(xy 38.890021 -130.645969) (xy 38.878178 -130.5928) (xy 38.874202 -130.538474) (xy 35.785504 -130.538474)
			(xy 35.776271 -130.584277) (xy 35.757345 -130.636883) (xy 35.730946 -130.686165) (xy 35.714686 -130.708908)
			(xy 35.701527 -130.727409) (xy 35.681379 -130.768091) (xy 35.668789 -130.811708) (xy 35.66416 -130.856868)
			(xy 35.667639 -130.902133) (xy 35.676643 -130.936592) (xy 39.978411 -130.936592) (xy 39.986104 -130.8771)
			(xy 40.001502 -130.819124) (xy 40.02434 -130.763654) (xy 40.054228 -130.711643) (xy 40.090652 -130.663981)
			(xy 40.132989 -130.621485) (xy 40.180514 -130.584882) (xy 40.232413 -130.5548) (xy 40.287796 -130.531754)
			(xy 40.345715 -130.516139) (xy 40.405177 -130.508222) (xy 40.465163 -130.50814) (xy 40.494966 -130.51155)
			(xy 40.518168 -130.514035) (xy 40.564759 -130.511555) (xy 40.610112 -130.500605) (xy 40.652702 -130.481555)
			(xy 40.691095 -130.455044) (xy 40.724 -130.421966) (xy 40.750308 -130.383434) (xy 40.769134 -130.340745)
			(xy 40.779845 -130.295334) (xy 40.78208 -130.248731) (xy 40.779446 -130.225546) (xy 40.775852 -130.195769)
			(xy 40.775592 -130.13579) (xy 40.783168 -130.076291) (xy 40.79845 -130.018291) (xy 40.821176 -129.962783)
			(xy 40.850957 -129.91072) (xy 40.887282 -129.862991) (xy 40.92953 -129.820416) (xy 40.976977 -129.783723)
			(xy 41.028809 -129.753541) (xy 41.084139 -129.730387) (xy 41.14202 -129.714657) (xy 41.201458 -129.706622)
			(xy 41.261438 -129.706419) (xy 41.32093 -129.71405) (xy 41.378915 -129.729386) (xy 41.434401 -129.752164)
			(xy 41.486437 -129.781994) (xy 41.534132 -129.818364) (xy 41.576668 -129.860651) (xy 41.613316 -129.908132)
			(xy 41.64345 -129.959993) (xy 41.666552 -130.015344) (xy 41.682227 -130.073239) (xy 41.690207 -130.132686)
			(xy 41.690355 -130.192665) (xy 41.682667 -130.25215) (xy 41.667277 -130.310121) (xy 41.644447 -130.365586)
			(xy 41.614569 -130.417594) (xy 41.578155 -130.465255) (xy 41.535827 -130.507751) (xy 41.488312 -130.544355)
			(xy 41.436424 -130.57444) (xy 41.38105 -130.597491) (xy 41.323141 -130.613112) (xy 41.263687 -130.621036)
			(xy 41.203707 -130.621128) (xy 41.173908 -130.617722) (xy 41.150714 -130.615128) (xy 41.104112 -130.617613)
			(xy 41.058749 -130.628571) (xy 41.01615 -130.647631) (xy 40.983704 -130.670042) (xy 42.262788 -130.670042)
			(xy 42.262788 -130.610106) (xy 42.270611 -130.550684) (xy 42.286124 -130.492791) (xy 42.30906 -130.437418)
			(xy 42.339027 -130.385512) (xy 42.375514 -130.337962) (xy 42.417894 -130.295582) (xy 42.465444 -130.259095)
			(xy 42.51735 -130.229128) (xy 42.572723 -130.206192) (xy 42.630616 -130.190679) (xy 42.690038 -130.182856)
			(xy 42.749974 -130.182856) (xy 42.809396 -130.190679) (xy 42.867289 -130.206192) (xy 42.922662 -130.229128)
			(xy 42.974568 -130.259095) (xy 43.022118 -130.295582) (xy 43.064498 -130.337962) (xy 43.100985 -130.385512)
			(xy 43.130952 -130.437418) (xy 43.153888 -130.492791) (xy 43.169401 -130.550684) (xy 43.177224 -130.610106)
			(xy 43.177714 -130.640074) (xy 43.177224 -130.670042) (xy 43.169401 -130.729464) (xy 43.153888 -130.787357)
			(xy 43.130952 -130.84273) (xy 43.100985 -130.894636) (xy 43.064498 -130.942186) (xy 43.022118 -130.984566)
			(xy 42.981166 -131.01599) (xy 43.54879 -131.01599) (xy 43.54879 -130.956054) (xy 43.556613 -130.896632)
			(xy 43.572126 -130.838739) (xy 43.595062 -130.783366) (xy 43.625029 -130.73146) (xy 43.661516 -130.68391)
			(xy 43.703896 -130.64153) (xy 43.751446 -130.605043) (xy 43.803352 -130.575076) (xy 43.858725 -130.55214)
			(xy 43.916618 -130.536627) (xy 43.97604 -130.528804) (xy 44.035976 -130.528804) (xy 44.095398 -130.536627)
			(xy 44.153291 -130.55214) (xy 44.208664 -130.575076) (xy 44.26057 -130.605043) (xy 44.30812 -130.64153)
			(xy 44.3505 -130.68391) (xy 44.386987 -130.73146) (xy 44.416954 -130.783366) (xy 44.43989 -130.838739)
			(xy 44.455403 -130.896632) (xy 44.463226 -130.956054) (xy 44.463716 -130.986022) (xy 44.463226 -131.01599)
			(xy 44.455403 -131.075412) (xy 44.43989 -131.133305) (xy 44.416954 -131.188678) (xy 44.386987 -131.240584)
			(xy 44.3505 -131.288134) (xy 44.30812 -131.330514) (xy 44.26057 -131.367001) (xy 44.208664 -131.396968)
			(xy 44.153291 -131.419904) (xy 44.095398 -131.435417) (xy 44.035976 -131.44324) (xy 43.97604 -131.44324)
			(xy 43.916618 -131.435417) (xy 43.858725 -131.419904) (xy 43.803352 -131.396968) (xy 43.751446 -131.367001)
			(xy 43.703896 -131.330514) (xy 43.661516 -131.288134) (xy 43.625029 -131.240584) (xy 43.595062 -131.188678)
			(xy 43.572126 -131.133305) (xy 43.556613 -131.075412) (xy 43.54879 -131.01599) (xy 42.981166 -131.01599)
			(xy 42.974568 -131.021053) (xy 42.922662 -131.05102) (xy 42.867289 -131.073956) (xy 42.809396 -131.089469)
			(xy 42.749974 -131.097292) (xy 42.690038 -131.097292) (xy 42.630616 -131.089469) (xy 42.572723 -131.073956)
			(xy 42.51735 -131.05102) (xy 42.465444 -131.021053) (xy 42.417894 -130.984566) (xy 42.375514 -130.942186)
			(xy 42.339027 -130.894636) (xy 42.30906 -130.84273) (xy 42.286124 -130.787357) (xy 42.270611 -130.729464)
			(xy 42.262788 -130.670042) (xy 40.983704 -130.670042) (xy 40.977751 -130.674154) (xy 40.944844 -130.707245)
			(xy 40.918537 -130.745792) (xy 40.899715 -130.788496) (xy 40.889012 -130.833921) (xy 40.886787 -130.880536)
			(xy 40.889428 -130.903726) (xy 40.892984 -130.933512) (xy 40.893246 -130.993498) (xy 40.885671 -131.053004)
			(xy 40.870388 -131.111012) (xy 40.847661 -131.166526) (xy 40.817877 -131.218597) (xy 40.781547 -131.266331)
			(xy 40.739295 -131.308912) (xy 40.691843 -131.345609) (xy 40.640004 -131.375794) (xy 40.584667 -131.398951)
			(xy 40.526779 -131.414681) (xy 40.467333 -131.422716) (xy 40.407347 -131.422918) (xy 40.347848 -131.415283)
			(xy 40.289856 -131.399943) (xy 40.234364 -131.37716) (xy 40.182323 -131.347325) (xy 40.134625 -131.310948)
			(xy 40.092086 -131.268653) (xy 40.055436 -131.221164) (xy 40.025303 -131.169295) (xy 40.002202 -131.113935)
			(xy 39.986529 -131.056032) (xy 39.978553 -130.996578) (xy 39.978411 -130.936592) (xy 35.676643 -130.936592)
			(xy 35.679116 -130.946056) (xy 35.698223 -130.987236) (xy 35.710876 -131.006088) (xy 35.72661 -131.029202)
			(xy 35.751755 -131.079145) (xy 35.769345 -131.132222) (xy 35.779002 -131.187298) (xy 35.780521 -131.243193)
			(xy 35.773869 -131.298712) (xy 35.759188 -131.352666) (xy 35.736792 -131.403901) (xy 35.70716 -131.45132)
			(xy 35.670927 -131.493908) (xy 35.628869 -131.530755) (xy 35.581885 -131.56107) (xy 35.53098 -131.584207)
			(xy 35.477245 -131.599669) (xy 35.421828 -131.607126) (xy 35.365917 -131.606418) (xy 35.310707 -131.59756)
			(xy 35.25738 -131.580742) (xy 35.207078 -131.556323) (xy 35.160877 -131.524827) (xy 35.119765 -131.486928)
			(xy 35.084622 -131.443435) (xy 35.056201 -131.395281) (xy 35.03511 -131.343495) (xy 35.0218 -131.289187)
			(xy 35.016556 -131.233517) (xy 32.34182 -131.233517) (xy 32.34182 -139.70127) (xy 33.389822 -139.70127)
			(xy 33.393893 -139.645648) (xy 33.406019 -139.591211) (xy 33.425942 -139.53912) (xy 33.453238 -139.490485)
			(xy 33.487324 -139.446342) (xy 33.527473 -139.407633) (xy 33.572831 -139.375182) (xy 33.622431 -139.349681)
			(xy 33.675215 -139.331674) (xy 33.730058 -139.321544) (xy 33.785792 -139.319507) (xy 33.841229 -139.325607)
			(xy 33.895186 -139.339713) (xy 33.946515 -139.361525) (xy 33.994121 -139.390579) (xy 34.036989 -139.426254)
			(xy 34.074206 -139.467791) (xy 34.104979 -139.514304) (xy 34.128651 -139.564801) (xy 34.144719 -139.618208)
			(xy 34.152839 -139.673384) (xy 34.153348 -139.70127) (xy 34.152839 -139.729156) (xy 34.144719 -139.784332)
			(xy 34.128651 -139.837739) (xy 34.104979 -139.888236) (xy 34.074206 -139.934749) (xy 34.036989 -139.976286)
			(xy 33.994121 -140.011961) (xy 33.946515 -140.041015) (xy 33.895186 -140.062827) (xy 33.841229 -140.076933)
			(xy 33.785792 -140.083033) (xy 33.730058 -140.080996) (xy 33.675215 -140.070866) (xy 33.622431 -140.052859)
			(xy 33.572831 -140.027358) (xy 33.527473 -139.994907) (xy 33.487324 -139.956198) (xy 33.453238 -139.912055)
			(xy 33.425942 -139.86342) (xy 33.406019 -139.811329) (xy 33.393893 -139.756892) (xy 33.389822 -139.70127)
			(xy 32.34182 -139.70127) (xy 32.34182 -140.98651) (xy 35.256216 -140.98651) (xy 35.256216 -134.325614)
			(xy 36.254182 -133.327648) (xy 38.563296 -133.327648) (xy 38.57994 -133.327054) (xy 38.612095 -133.318441)
			(xy 38.640926 -133.301801) (xy 38.664469 -133.278268) (xy 38.681121 -133.249443) (xy 38.689747 -133.217292)
			(xy 38.690296 -133.200648) (xy 38.690296 -133.200394) (xy 38.690746 -133.172391) (xy 38.69758 -133.116803)
			(xy 38.711144 -133.062464) (xy 38.731236 -133.010186) (xy 38.757556 -132.96075) (xy 38.789711 -132.914894)
			(xy 38.808152 -132.893816) (xy 38.822454 -132.877218) (xy 38.845744 -132.840114) (xy 38.862324 -132.799565)
			(xy 38.871703 -132.756773) (xy 38.873602 -132.713006) (xy 38.867965 -132.669562) (xy 38.85496 -132.627729)
			(xy 38.834971 -132.588747) (xy 38.808592 -132.553772) (xy 38.792912 -132.53847) (xy 38.773166 -132.519401)
			(xy 38.73902 -132.47642) (xy 38.711548 -132.428895) (xy 38.691345 -132.377854) (xy 38.678848 -132.324401)
			(xy 38.674327 -132.269694) (xy 38.677881 -132.214915) (xy 38.689433 -132.16125) (xy 38.708732 -132.109861)
			(xy 38.73536 -132.061858) (xy 38.768743 -132.018281) (xy 38.808157 -131.980072) (xy 38.852749 -131.948059)
			(xy 38.901556 -131.922934) (xy 38.95352 -131.90524) (xy 39.007518 -131.895361) (xy 39.06238 -131.89351)
			(xy 39.116921 -131.899727) (xy 39.16996 -131.913877) (xy 39.220349 -131.935655) (xy 39.266998 -131.96459)
			(xy 39.308898 -132.000055) (xy 39.345142 -132.041282) (xy 39.374946 -132.087381) (xy 39.397665 -132.137353)
			(xy 39.412807 -132.190117) (xy 39.420046 -132.244531) (xy 39.419224 -132.299419) (xy 39.410358 -132.353593)
			(xy 39.393642 -132.405879) (xy 39.369436 -132.455148) (xy 39.354252 -132.478018) (xy 39.342151 -132.496318)
			(xy 39.323775 -132.536152) (xy 39.317666 -132.559156) (xy 39.973236 -132.559156) (xy 39.977533 -132.49827)
			(xy 39.989883 -132.438495) (xy 40.010067 -132.380891) (xy 40.037728 -132.32648) (xy 40.072375 -132.276229)
			(xy 40.113392 -132.231027) (xy 40.160053 -132.191678) (xy 40.211529 -132.158878) (xy 40.266908 -132.133211)
			(xy 40.325206 -132.115131) (xy 40.385391 -132.104958) (xy 40.446393 -132.102875) (xy 40.507131 -132.108917)
			(xy 40.566527 -132.122977) (xy 40.623528 -132.144806) (xy 40.677122 -132.174017) (xy 40.726359 -132.210091)
			(xy 40.748712 -132.230876) (xy 40.766148 -132.24692) (xy 40.805766 -132.272902) (xy 40.849515 -132.291083)
			(xy 40.895878 -132.300833) (xy 40.943245 -132.301813) (xy 40.989971 -132.29399) (xy 41.034435 -132.277634)
			(xy 41.055036 -132.265928) (xy 41.07783 -132.252979) (xy 41.126369 -132.233187) (xy 41.177331 -132.220917)
			(xy 41.229559 -132.216448) (xy 41.281865 -132.219882) (xy 41.333061 -132.231141) (xy 41.381981 -132.249969)
			(xy 41.427515 -132.275938) (xy 41.468628 -132.308457) (xy 41.504384 -132.346788) (xy 41.53397 -132.390059)
			(xy 41.556715 -132.437285) (xy 41.572102 -132.487395) (xy 41.57978 -132.539249) (xy 41.579574 -132.591667)
			(xy 41.571491 -132.643459) (xy 41.555712 -132.693446) (xy 41.532598 -132.740494) (xy 41.502673 -132.783531)
			(xy 41.466618 -132.821581) (xy 41.425252 -132.853777) (xy 41.379516 -132.879388) (xy 41.330449 -132.897832)
			(xy 41.279167 -132.90869) (xy 41.226836 -132.911714) (xy 41.174645 -132.906836) (xy 41.12378 -132.894168)
			(xy 41.075398 -132.873996) (xy 41.05275 -132.860796) (xy 41.032263 -132.848904) (xy 40.98793 -132.832224)
			(xy 40.941274 -132.824042) (xy 40.893911 -132.824641) (xy 40.847478 -132.834) (xy 40.80358 -132.851797)
			(xy 40.763738 -132.877414) (xy 40.746172 -132.893308) (xy 40.723681 -132.913943) (xy 40.674171 -132.949641)
			(xy 40.620356 -132.978443) (xy 40.563191 -132.999838) (xy 40.503689 -133.013446) (xy 40.442907 -133.019025)
			(xy 40.381922 -133.016477) (xy 40.321817 -133.005848) (xy 40.263658 -132.987324) (xy 40.208476 -132.961236)
			(xy 40.157251 -132.928046) (xy 40.110891 -132.888343) (xy 40.070219 -132.84283) (xy 40.035956 -132.792316)
			(xy 40.00871 -132.737697) (xy 39.988964 -132.679941) (xy 39.977069 -132.620074) (xy 39.973236 -132.559156)
			(xy 39.317666 -132.559156) (xy 39.312516 -132.578551) (xy 39.308709 -132.622255) (xy 39.312466 -132.665962)
			(xy 39.323677 -132.708374) (xy 39.342007 -132.748229) (xy 39.366912 -132.784343) (xy 39.397652 -132.81564)
			(xy 39.415212 -132.828792) (xy 39.438731 -132.84635) (xy 39.48159 -132.886445) (xy 39.518976 -132.931688)
			(xy 39.550275 -132.981337) (xy 39.574975 -133.034577) (xy 39.592671 -133.090536) (xy 39.603072 -133.148298)
			(xy 39.606009 -133.206915) (xy 39.604188 -133.236208) (xy 39.603307 -133.25454) (xy 39.610913 -133.29043)
			(xy 39.628449 -133.322655) (xy 39.641018 -133.33603) (xy 39.89324 -133.587998) (xy 39.89324 -133.669786)
			(xy 39.893656 -133.684714) (xy 39.900635 -133.713744) (xy 39.914166 -133.740359) (xy 39.933511 -133.763102)
			(xy 39.957609 -133.78073) (xy 39.971218 -133.78688) (xy 40.037766 -133.814566) (xy 40.053028 -133.820414)
			(xy 40.085369 -133.825026) (xy 40.117818 -133.821245) (xy 40.148233 -133.809319) (xy 40.161718 -133.800088)
			(xy 40.186612 -133.782676) (xy 40.239975 -133.753651) (xy 40.296708 -133.731942) (xy 40.355815 -133.717929)
			(xy 40.416257 -133.711861) (xy 40.47697 -133.713843) (xy 40.536887 -133.72384) (xy 40.594954 -133.741677)
			(xy 40.650151 -133.767041) (xy 40.701507 -133.799484) (xy 40.748118 -133.838438) (xy 40.789166 -133.883216)
			(xy 40.823928 -133.933031) (xy 40.851794 -133.987008) (xy 40.872273 -134.044197) (xy 40.885005 -134.103593)
			(xy 40.889766 -134.164152) (xy 40.886473 -134.224808) (xy 40.875183 -134.284495) (xy 40.856096 -134.342163)
			(xy 40.829546 -134.396799) (xy 40.796 -134.447442) (xy 40.776398 -134.470648) (xy 40.761656 -134.488292)
			(xy 40.738164 -134.527809) (xy 40.722157 -134.570906) (xy 40.714155 -134.616177) (xy 40.71442 -134.662149)
			(xy 40.722943 -134.707326) (xy 40.739447 -134.750234) (xy 40.750998 -134.770114) (xy 40.7647 -134.79364)
			(xy 40.786019 -134.84373) (xy 40.799822 -134.89639) (xy 40.805814 -134.950498) (xy 40.803869 -135.004901)
			(xy 40.794026 -135.058443) (xy 40.776496 -135.109982) (xy 40.751653 -135.158421) (xy 40.720025 -135.202729)
			(xy 40.682285 -135.241962) (xy 40.670112 -135.251385) (xy 41.781551 -135.251385) (xy 41.783119 -135.192044)
			(xy 41.792345 -135.133404) (xy 41.809073 -135.076447) (xy 41.833023 -135.022131) (xy 41.863793 -134.971367)
			(xy 41.900866 -134.925005) (xy 41.943621 -134.883825) (xy 41.991341 -134.848516) (xy 42.043223 -134.819671)
			(xy 42.098399 -134.797775) (xy 42.155943 -134.783195) (xy 42.214888 -134.776174) (xy 42.274246 -134.776832)
			(xy 42.3037 -134.780528) (xy 42.325019 -134.783123) (xy 42.367946 -134.781889) (xy 42.410053 -134.773449)
			(xy 42.45014 -134.758045) (xy 42.487063 -134.736116) (xy 42.51977 -134.708287) (xy 42.547329 -134.675351)
			(xy 42.568953 -134.638248) (xy 42.584025 -134.598036) (xy 42.592117 -134.555861) (xy 42.593006 -134.534402)
			(xy 42.594286 -134.501324) (xy 42.605224 -134.43604) (xy 42.625454 -134.373012) (xy 42.654554 -134.313557)
			(xy 42.691917 -134.258915) (xy 42.71391 -134.234174) (xy 42.728896 -134.217065) (xy 42.753275 -134.178679)
			(xy 42.770426 -134.136564) (xy 42.779802 -134.092068) (xy 42.781102 -134.046613) (xy 42.774285 -134.001653)
			(xy 42.759568 -133.958627) (xy 42.737424 -133.91891) (xy 42.708558 -133.883772) (xy 42.673896 -133.854338)
			(xy 42.654474 -133.842506) (xy 42.632637 -133.829249) (xy 42.59269 -133.797411) (xy 42.557835 -133.760068)
			(xy 42.52882 -133.718025) (xy 42.506273 -133.672188) (xy 42.490678 -133.623545) (xy 42.482371 -133.573142)
			(xy 42.4815 -133.547612) (xy 42.480808 -133.531555) (xy 42.472206 -133.500594) (xy 42.45615 -133.472759)
			(xy 42.433655 -133.449812) (xy 42.406146 -133.433203) (xy 42.375363 -133.423985) (xy 42.359326 -133.422898)
			(xy 42.32919 -133.421233) (xy 42.2697 -133.411047) (xy 42.212065 -133.393131) (xy 42.157285 -133.367794)
			(xy 42.106311 -133.335478) (xy 42.060026 -133.296741) (xy 42.019235 -133.252257) (xy 41.984644 -133.202798)
			(xy 41.956854 -133.149221) (xy 41.936348 -133.092456) (xy 41.92348 -133.033488) (xy 41.918475 -132.97334)
			(xy 41.921419 -132.913057) (xy 41.932261 -132.853683) (xy 41.950813 -132.79625) (xy 41.976753 -132.741753)
			(xy 42.009631 -132.691139) (xy 42.048877 -132.645285) (xy 42.093809 -132.604988) (xy 42.143648 -132.570946)
			(xy 42.197529 -132.54375) (xy 42.254517 -132.523872) (xy 42.313623 -132.511657) (xy 42.373822 -132.507316)
			(xy 42.43407 -132.510926) (xy 42.49332 -132.522424) (xy 42.550545 -132.54161) (xy 42.604751 -132.56815)
			(xy 42.654999 -132.601586) (xy 42.700416 -132.641335) (xy 42.740215 -132.68671) (xy 42.773704 -132.736922)
			(xy 42.800303 -132.7911) (xy 42.81955 -132.848304) (xy 42.831112 -132.907542) (xy 42.834786 -132.967785)
			(xy 42.830511 -133.027989) (xy 42.824908 -133.057646) (xy 42.822048 -133.073498) (xy 42.823646 -133.105664)
			(xy 42.833245 -133.136406) (xy 42.850233 -133.163767) (xy 42.87353 -133.186004) (xy 42.901652 -133.201701)
			(xy 42.91711 -133.206236) (xy 42.929563 -133.209628) (xy 42.953972 -133.218019) (xy 42.965878 -133.223)
			(xy 42.990008 -133.233414) (xy 43.015916 -133.233414) (xy 43.032564 -133.232871) (xy 43.064725 -133.224251)
			(xy 43.093559 -133.207601) (xy 43.117102 -133.184057) (xy 43.133751 -133.155223) (xy 43.142371 -133.123062)
			(xy 43.142916 -133.106414) (xy 43.142916 -133.105144) (xy 43.681142 -132.566918) (xy 43.688254 -132.555742)
			(xy 43.701462 -132.536692) (xy 43.710663 -132.52315) (xy 43.722497 -132.492635) (xy 43.726186 -132.460114)
			(xy 43.721488 -132.427724) (xy 43.708711 -132.397592) (xy 43.688694 -132.371697) (xy 43.662753 -132.35174)
			(xy 43.647868 -132.344922) (xy 43.625332 -132.335022) (xy 43.583074 -132.309782) (xy 43.544801 -132.278831)
			(xy 43.527726 -132.261102) (xy 43.51681 -132.249981) (xy 43.490701 -132.232983) (xy 43.461253 -132.222812)
			(xy 43.430219 -132.220075) (xy 43.399446 -132.224933) (xy 43.370765 -132.237099) (xy 43.358054 -132.246116)
			(xy 43.333836 -132.263759) (xy 43.281716 -132.293318) (xy 43.226186 -132.315824) (xy 43.168194 -132.330892)
			(xy 43.108731 -132.338265) (xy 43.048815 -132.337816) (xy 42.989469 -132.329553) (xy 42.93171 -132.313617)
			(xy 42.876523 -132.290281) (xy 42.824852 -132.259944) (xy 42.777582 -132.223124) (xy 42.73552 -132.180452)
			(xy 42.699386 -132.132656) (xy 42.669797 -132.080554) (xy 42.647259 -132.025036) (xy 42.632157 -131.967052)
			(xy 42.624751 -131.907594) (xy 42.625165 -131.847678) (xy 42.633394 -131.788328) (xy 42.649297 -131.730558)
			(xy 42.672601 -131.675358) (xy 42.702908 -131.62367) (xy 42.739701 -131.576379) (xy 42.782349 -131.534293)
			(xy 42.830124 -131.498131) (xy 42.882209 -131.468512) (xy 42.937714 -131.445942) (xy 42.995689 -131.430807)
			(xy 43.055143 -131.423366) (xy 43.11506 -131.423746) (xy 43.174414 -131.431941) (xy 43.232193 -131.44781)
			(xy 43.287406 -131.471083) (xy 43.339111 -131.50136) (xy 43.386424 -131.538126) (xy 43.428535 -131.58075)
			(xy 43.464724 -131.628504) (xy 43.479974 -131.654296) (xy 43.488083 -131.66757) (xy 43.509604 -131.690016)
			(xy 43.535918 -131.706585) (xy 43.565461 -131.716293) (xy 43.596474 -131.718561) (xy 43.627115 -131.713255)
			(xy 43.641518 -131.707382) (xy 43.665094 -131.697397) (xy 43.714445 -131.683768) (xy 43.765263 -131.677531)
			(xy 43.816445 -131.678824) (xy 43.866884 -131.687617) (xy 43.915484 -131.703719) (xy 43.961194 -131.726783)
			(xy 44.003022 -131.756308) (xy 44.040063 -131.791654) (xy 44.071512 -131.832055) (xy 44.096689 -131.876636)
			(xy 44.115048 -131.92443) (xy 44.126191 -131.974402) (xy 44.129876 -132.025468) (xy 44.126024 -132.076522)
			(xy 44.120816 -132.10159) (xy 44.116498 -132.122845) (xy 44.114206 -132.166151) (xy 44.1193 -132.209218)
			(xy 44.13163 -132.250795) (xy 44.15084 -132.289675) (xy 44.176371 -132.32473) (xy 44.207483 -132.354942)
			(xy 44.243272 -132.379433) (xy 44.262802 -132.388864) (xy 44.292035 -132.402822) (xy 44.346569 -132.437786)
			(xy 44.395628 -132.480089) (xy 44.438231 -132.528888) (xy 44.45635 -132.555742) (xy 44.463462 -132.566918)
			(xy 44.544996 -132.648706) (xy 44.557134 -132.660163) (xy 44.586006 -132.676888) (xy 44.618229 -132.685545)
			(xy 44.634912 -132.686044) (xy 44.913296 -132.686044) (xy 44.936348 -132.685544) (xy 44.981699 -132.677248)
			(xy 45.02481 -132.660909) (xy 45.064267 -132.637062) (xy 45.098777 -132.60649) (xy 45.127207 -132.570196)
			(xy 45.148625 -132.529369) (xy 45.162328 -132.485349) (xy 45.167868 -132.43958) (xy 45.165062 -132.393562)
			(xy 45.154003 -132.348804) (xy 45.135053 -132.306775) (xy 45.108834 -132.268853) (xy 45.092874 -132.252212)
			(xy 44.919138 -132.078222) (xy 44.898021 -132.056371) (xy 44.861304 -132.007953) (xy 44.831521 -131.954985)
			(xy 44.809229 -131.898456) (xy 44.794842 -131.839418) (xy 44.788628 -131.77897) (xy 44.790702 -131.71824)
			(xy 44.801027 -131.658357) (xy 44.81941 -131.600439) (xy 44.845508 -131.545562) (xy 44.878835 -131.494751)
			(xy 44.918771 -131.448951) (xy 44.964571 -131.409015) (xy 45.015382 -131.375688) (xy 45.070259 -131.34959)
			(xy 45.128177 -131.331207) (xy 45.18806 -131.320882) (xy 45.24879 -131.318808) (xy 45.309238 -131.325022)
			(xy 45.368276 -131.339409) (xy 45.424805 -131.361701) (xy 45.477773 -131.391484) (xy 45.526191 -131.428201)
			(xy 45.548042 -131.449318) (xy 45.747432 -131.648708) (xy 45.881036 -131.648708) (xy 45.907491 -131.649074)
			(xy 45.96003 -131.655329) (xy 46.011457 -131.66777) (xy 46.061045 -131.686221) (xy 46.084744 -131.697984)
			(xy 46.112176 -131.712208) (xy 46.237144 -131.712208) (xy 46.237144 -131.737608) (xy 46.411896 -131.737608)
			(xy 46.442884 -131.717796) (xy 46.469726 -131.701417) (xy 46.527045 -131.675563) (xy 46.587437 -131.65805)
			(xy 46.649696 -131.649229) (xy 46.681136 -131.648708) (xy 46.77791 -131.648708) (xy 47.035466 -131.391152)
			(xy 47.049733 -131.377136) (xy 47.080386 -131.351442) (xy 47.09668 -131.339844) (xy 47.114585 -131.326954)
			(xy 47.146003 -131.295985) (xy 47.171601 -131.260055) (xy 47.19061 -131.220244) (xy 47.202458 -131.177749)
			(xy 47.20679 -131.133846) (xy 47.203476 -131.089855) (xy 47.192614 -131.047097) (xy 47.174532 -131.006857)
			(xy 47.149773 -130.970344) (xy 47.11908 -130.938655) (xy 47.101506 -130.925316) (xy 47.08739 -130.914829)
			(xy 47.06069 -130.89194) (xy 47.048166 -130.879596) (xy 46.579028 -130.410712) (xy 46.579028 -130.35026)
			(xy 46.50486 -130.276092) (xy 46.452028 -130.276092) (xy 46.435309 -130.276631) (xy 46.403021 -130.285332)
			(xy 46.3741 -130.302117) (xy 46.35053 -130.325836) (xy 46.341792 -130.3401) (xy 46.332301 -130.356317)
			(xy 46.310414 -130.386863) (xy 46.298104 -130.40106) (xy 46.283117 -130.418447) (xy 46.259123 -130.457579)
			(xy 46.24255 -130.500384) (xy 46.233934 -130.54547) (xy 46.233558 -130.59137) (xy 46.241432 -130.636592)
			(xy 46.257301 -130.679663) (xy 46.280649 -130.719183) (xy 46.29531 -130.736848) (xy 46.312109 -130.757026)
			(xy 46.340121 -130.80143) (xy 46.361128 -130.849546) (xy 46.37465 -130.900276) (xy 46.380378 -130.952464)
			(xy 46.378184 -131.004919) (xy 46.368116 -131.056446) (xy 46.350404 -131.10587) (xy 46.325452 -131.152063)
			(xy 46.293829 -131.193972) (xy 46.256256 -131.230641) (xy 46.21359 -131.261236) (xy 46.166804 -131.285056)
			(xy 46.116964 -131.301561) (xy 46.065207 -131.310372) (xy 46.012714 -131.31129) (xy 45.960681 -131.304293)
			(xy 45.910295 -131.289541) (xy 45.862704 -131.267371) (xy 45.818995 -131.238287) (xy 45.780163 -131.202953)
			(xy 45.747094 -131.162175) (xy 45.720543 -131.116883) (xy 45.701114 -131.068108) (xy 45.689251 -131.016965)
			(xy 45.685224 -130.964618) (xy 45.689125 -130.912262) (xy 45.700865 -130.86109) (xy 45.720176 -130.81227)
			(xy 45.746619 -130.766913) (xy 45.779589 -130.726056) (xy 45.818336 -130.690629) (xy 45.839888 -130.675634)
			(xy 45.853636 -130.665729) (xy 45.875839 -130.640154) (xy 45.890534 -130.60964) (xy 45.896688 -130.576336)
			(xy 45.893867 -130.542585) (xy 45.882269 -130.510765) (xy 45.862711 -130.483115) (xy 45.83657 -130.461581)
			(xy 45.821346 -130.454146) (xy 45.801789 -130.445886) (xy 45.760716 -130.435168) (xy 45.718432 -130.431435)
			(xy 45.676117 -130.434791) (xy 45.63495 -130.445143) (xy 45.59608 -130.462201) (xy 45.560591 -130.485491)
			(xy 45.54474 -130.499612) (xy 45.522146 -130.519846) (xy 45.472601 -130.554832) (xy 45.418871 -130.582969)
			(xy 45.361895 -130.603764) (xy 45.302673 -130.616853) (xy 45.24224 -130.622006) (xy 45.181656 -130.619135)
			(xy 45.121982 -130.608288) (xy 45.064263 -130.589655) (xy 45.00951 -130.563564) (xy 44.958682 -130.530471)
			(xy 44.912669 -130.490956) (xy 44.872277 -130.445711) (xy 44.838214 -130.395528) (xy 44.811076 -130.341286)
			(xy 44.791339 -130.283935) (xy 44.779347 -130.224481) (xy 44.775312 -130.163963) (xy 44.779304 -130.103443)
			(xy 44.791253 -130.04398) (xy 44.81095 -129.986615) (xy 44.838049 -129.932354) (xy 44.872077 -129.882147)
			(xy 44.912436 -129.836873) (xy 44.958421 -129.797325) (xy 45.009225 -129.764196) (xy 45.06396 -129.738065)
			(xy 45.121666 -129.719392) (xy 45.181332 -129.708503) (xy 45.241914 -129.705588) (xy 45.30235 -129.710698)
			(xy 45.361582 -129.723745) (xy 45.418572 -129.744499) (xy 45.472323 -129.772598) (xy 45.521892 -129.807548)
			(xy 45.544486 -129.827782) (xy 45.56201 -129.843366) (xy 45.601661 -129.8684) (xy 45.645235 -129.885727)
			(xy 45.69125 -129.894758) (xy 45.738141 -129.895185) (xy 45.784312 -129.886993) (xy 45.828194 -129.870462)
			(xy 45.848524 -129.85877) (xy 45.870867 -129.845806) (xy 45.91849 -129.825795) (xy 45.968504 -129.812873)
			(xy 46.01986 -129.807309) (xy 46.071481 -129.809222) (xy 46.122285 -129.81857) (xy 46.171206 -129.835157)
			(xy 46.217218 -129.858637) (xy 46.259356 -129.888515) (xy 46.296737 -129.924167) (xy 46.328577 -129.964844)
			(xy 46.341792 -129.98704) (xy 46.35881 -130.016758) (xy 46.417738 -130.051048) (xy 46.452028 -130.051048)
			(xy 46.468674 -130.050482) (xy 46.50083 -130.041861) (xy 46.52966 -130.025215) (xy 46.553203 -130.001676)
			(xy 46.569854 -129.972848) (xy 46.578479 -129.940693) (xy 46.579028 -129.924048) (xy 46.579028 -129.883662)
			(xy 46.579599 -129.851768) (xy 46.58871 -129.788634) (xy 46.606738 -129.727446) (xy 46.633316 -129.669459)
			(xy 46.650148 -129.642362) (xy 46.674532 -129.60477) (xy 46.66488 -129.515362) (xy 46.452028 -129.30251)
			(xy 46.452028 -128.359662) (xy 46.452615 -128.328216) (xy 46.461513 -128.265955) (xy 46.479083 -128.205566)
			(xy 46.504977 -128.148251) (xy 46.52137 -128.12141) (xy 46.540928 -128.090422) (xy 46.540928 -127.978408)
			(xy 46.665896 -127.978408) (xy 46.693328 -127.964184) (xy 46.720444 -127.950789) (xy 46.777467 -127.930634)
			(xy 46.836695 -127.91839) (xy 46.897036 -127.914284) (xy 46.957377 -127.91839) (xy 47.016605 -127.930634)
			(xy 47.073628 -127.950789) (xy 47.100744 -127.964184) (xy 47.128176 -127.978408) (xy 47.253144 -127.978408)
			(xy 47.253144 -128.090422) (xy 47.272702 -128.12141) (xy 47.2891 -128.14825) (xy 47.315011 -128.205561)
			(xy 47.332589 -128.26595) (xy 47.341483 -128.328214) (xy 47.342044 -128.359662) (xy 47.342044 -128.945132)
			(xy 47.358046 -128.974088) (xy 47.372666 -129.001301) (xy 47.395068 -129.05887) (xy 47.409284 -129.118986)
			(xy 47.415039 -129.180491) (xy 47.412222 -129.242201) (xy 47.400888 -129.302926) (xy 47.381254 -129.361497)
			(xy 47.367952 -129.389378) (xy 47.354744 -129.416048) (xy 47.354744 -129.582926) (xy 47.37989 -129.616708)
			(xy 47.396748 -129.639874) (xy 47.424983 -129.68973) (xy 47.446586 -129.742796) (xy 47.461201 -129.798197)
			(xy 47.468584 -129.855014) (xy 47.469044 -129.883662) (xy 47.469044 -130.042412) (xy 47.67707 -130.250692)
			(xy 47.697889 -130.272246) (xy 47.734213 -130.319906) (xy 47.763806 -130.372012) (xy 47.786133 -130.427622)
			(xy 47.800788 -130.485726) (xy 47.807507 -130.545272) (xy 47.806168 -130.605181) (xy 47.796795 -130.664367)
			(xy 47.779557 -130.721758) (xy 47.754768 -130.776314) (xy 47.722876 -130.827047) (xy 47.684459 -130.873036)
			(xy 47.640213 -130.913449) (xy 47.615856 -130.930904) (xy 47.598004 -130.943861) (xy 47.566595 -130.974825)
			(xy 47.541003 -131.010747) (xy 47.521998 -131.050548) (xy 47.51015 -131.093032) (xy 47.505815 -131.136924)
			(xy 47.509123 -131.180906) (xy 47.519974 -131.223656) (xy 47.538043 -131.26389) (xy 47.562788 -131.300401)
			(xy 47.593464 -131.332091) (xy 47.61103 -131.345432) (xy 47.634702 -131.363184) (xy 47.67756 -131.403981)
			(xy 47.714633 -131.450098) (xy 47.745266 -131.500722) (xy 47.768918 -131.55496) (xy 47.785173 -131.611854)
			(xy 47.793743 -131.670401) (xy 47.794477 -131.729567) (xy 47.787363 -131.788309) (xy 47.772525 -131.845589)
			(xy 47.750226 -131.900397) (xy 47.720859 -131.951766) (xy 47.684943 -131.998789) (xy 47.66437 -132.020056)
			(xy 47.14621 -132.538216) (xy 46.681136 -132.538216) (xy 46.659406 -132.537969) (xy 46.616148 -132.53377)
			(xy 46.594776 -132.529834) (xy 46.582584 -132.527548) (xy 46.570392 -132.527548) (xy 46.553733 -132.527988)
			(xy 46.521551 -132.536615) (xy 46.492699 -132.553279) (xy 46.469145 -132.576844) (xy 46.452494 -132.605703)
			(xy 46.443881 -132.637889) (xy 46.443392 -132.654548) (xy 46.443392 -132.830062) (xy 46.468538 -132.863844)
			(xy 46.48536 -132.887035) (xy 46.513603 -132.936883) (xy 46.535214 -132.989943) (xy 46.549836 -133.045338)
			(xy 46.557228 -133.102152) (xy 46.557692 -133.130798) (xy 46.557692 -134.268464) (xy 46.34738 -134.478522)
			(xy 46.326393 -134.498891) (xy 46.28 -134.534503) (xy 46.229338 -134.563726) (xy 46.175283 -134.586055)
			(xy 46.118767 -134.601106) (xy 46.060766 -134.608619) (xy 46.00228 -134.608464) (xy 45.973238 -134.605014)
			(xy 45.949725 -134.602426) (xy 45.902492 -134.604831) (xy 45.856519 -134.615931) (xy 45.813392 -134.635341)
			(xy 45.7746 -134.662394) (xy 45.74148 -134.696155) (xy 45.715175 -134.735459) (xy 45.696594 -134.77895)
			(xy 45.689324 -134.81181) (xy 47.558641 -134.81181) (xy 47.559302 -134.75822) (xy 47.567985 -134.705334)
			(xy 47.584495 -134.654346) (xy 47.596044 -134.63016) (xy 47.609252 -134.60349) (xy 47.609252 -133.6929)
			(xy 47.610522 -133.691884) (xy 47.612808 -133.642608) (xy 47.614688 -133.612812) (xy 47.625196 -133.554043)
			(xy 47.643257 -133.497139) (xy 47.668563 -133.443067) (xy 47.700686 -133.392743) (xy 47.739079 -133.347024)
			(xy 47.783091 -133.306686) (xy 47.831974 -133.272412) (xy 47.884899 -133.244786) (xy 47.940967 -133.224276)
			(xy 47.999225 -133.21123) (xy 48.058685 -133.20587) (xy 48.118338 -133.208288) (xy 48.17717 -133.218441)
			(xy 48.234182 -133.236158) (xy 48.288406 -133.261137) (xy 48.338922 -133.292955) (xy 48.384872 -133.331072)
			(xy 48.425476 -133.374839) (xy 48.460044 -133.423515) (xy 48.487989 -133.476272) (xy 48.508837 -133.532215)
			(xy 48.522234 -133.590394) (xy 48.527953 -133.649821) (xy 48.525896 -133.709487) (xy 48.516098 -133.768379)
			(xy 48.498726 -133.825497) (xy 48.474074 -133.879871) (xy 48.442561 -133.930578) (xy 48.404723 -133.976757)
			(xy 48.361201 -134.017624) (xy 48.312735 -134.052485) (xy 48.28667 -134.067042) (xy 48.286416 -134.067042)
			(xy 48.271666 -134.0757) (xy 48.247013 -134.099383) (xy 48.229517 -134.128753) (xy 48.220431 -134.161709)
			(xy 48.219868 -134.178802) (xy 48.219868 -134.320026) (xy 48.220323 -134.342798) (xy 48.228442 -134.387614)
			(xy 48.244416 -134.430266) (xy 48.267735 -134.469389) (xy 48.29765 -134.503731) (xy 48.333206 -134.532194)
			(xy 48.373264 -134.553867) (xy 48.416542 -134.568055) (xy 48.461656 -134.574305) (xy 48.507162 -134.572418)
			(xy 48.529494 -134.56793) (xy 48.559421 -134.561718) (xy 48.620305 -134.556338) (xy 48.681363 -134.55911)
			(xy 48.741508 -134.569985) (xy 48.799672 -134.588769) (xy 48.854817 -134.615127) (xy 48.905963 -134.648591)
			(xy 48.9522 -134.688565) (xy 48.992704 -134.734338) (xy 49.026756 -134.785095) (xy 49.053748 -134.839933)
			(xy 49.073201 -134.897875) (xy 49.084768 -134.957892) (xy 49.088244 -135.018914) (xy 49.083567 -135.079855)
			(xy 49.070819 -135.139632) (xy 49.050228 -135.19718) (xy 49.022161 -135.251476) (xy 48.987116 -135.301552)
			(xy 48.945717 -135.346518) (xy 48.898702 -135.385573) (xy 48.846906 -135.418023) (xy 48.791252 -135.44329)
			(xy 48.732731 -135.460924) (xy 48.672382 -135.470611) (xy 48.611281 -135.47218) (xy 48.550516 -135.465602)
			(xy 48.491166 -135.450993) (xy 48.434289 -135.428616) (xy 48.380897 -135.398866) (xy 48.331939 -135.362275)
			(xy 48.288288 -135.319492) (xy 48.25072 -135.27128) (xy 48.219903 -135.218496) (xy 48.207676 -135.190484)
			(xy 48.200828 -135.17556) (xy 48.180845 -135.149522) (xy 48.154888 -135.129433) (xy 48.12467 -135.116618)
			(xy 48.092185 -135.111923) (xy 48.059576 -135.115658) (xy 48.0441 -135.121142) (xy 48.018968 -135.130452)
			(xy 47.966686 -135.14224) (xy 47.913228 -135.146061) (xy 47.859801 -135.141829) (xy 47.807611 -135.129639)
			(xy 47.757838 -135.109766) (xy 47.711603 -135.08266) (xy 47.669953 -135.048932) (xy 47.633826 -135.009343)
			(xy 47.60404 -134.964789) (xy 47.581266 -134.916274) (xy 47.566018 -134.864894) (xy 47.558641 -134.81181)
			(xy 45.689324 -134.81181) (xy 45.686378 -134.825127) (xy 45.684878 -134.872398) (xy 45.687996 -134.895844)
			(xy 45.692307 -134.926084) (xy 45.693667 -134.987156) (xy 45.686892 -135.047865) (xy 45.672101 -135.107134)
			(xy 45.649559 -135.163908) (xy 45.619664 -135.21718) (xy 45.58295 -135.266002) (xy 45.540067 -135.309506)
			(xy 45.491779 -135.34692) (xy 45.438944 -135.377578) (xy 45.3825 -135.400936) (xy 45.32345 -135.416578)
			(xy 45.262845 -135.424227) (xy 45.20176 -135.423746) (xy 45.141283 -135.415144) (xy 45.082486 -135.398575)
			(xy 45.026417 -135.374332) (xy 44.97407 -135.342846) (xy 44.926377 -135.304677) (xy 44.904914 -135.28294)
			(xy 44.889025 -135.267073) (xy 44.852765 -135.240596) (xy 44.812419 -135.220898) (xy 44.76924 -135.208592)
			(xy 44.724572 -135.20406) (xy 44.679801 -135.207443) (xy 44.636321 -135.218636) (xy 44.595482 -135.237291)
			(xy 44.576746 -135.249666) (xy 44.555081 -135.264086) (xy 44.508371 -135.287027) (xy 44.45876 -135.30274)
			(xy 44.407359 -135.31087) (xy 44.355321 -135.311236) (xy 44.30381 -135.30383) (xy 44.253983 -135.288818)
			(xy 44.206954 -135.266536) (xy 44.163779 -135.237483) (xy 44.125425 -135.202311) (xy 44.09275 -135.161807)
			(xy 44.066488 -135.11688) (xy 44.047227 -135.068536) (xy 44.035398 -135.017858) (xy 44.031267 -134.965983)
			(xy 44.034926 -134.914072) (xy 44.046293 -134.863288) (xy 44.065113 -134.814771) (xy 44.077636 -134.791958)
			(xy 44.088488 -134.772066) (xy 44.10366 -134.72937) (xy 44.111024 -134.684662) (xy 44.110346 -134.639356)
			(xy 44.101649 -134.594888) (xy 44.085208 -134.552665) (xy 44.061544 -134.514025) (xy 44.031405 -134.480191)
			(xy 44.013882 -134.465822) (xy 43.997503 -134.45266) (xy 43.966976 -134.423784) (xy 43.952922 -134.408164)
			(xy 43.941253 -134.395731) (xy 43.912738 -134.377056) (xy 43.880298 -134.366595) (xy 43.846245 -134.365093)
			(xy 43.81301 -134.372659) (xy 43.797728 -134.380224) (xy 43.770778 -134.394011) (xy 43.713987 -134.414973)
			(xy 43.654879 -134.428045) (xy 43.624754 -134.431024) (xy 43.609306 -134.432669) (xy 43.579896 -134.442666)
			(xy 43.553779 -134.459482) (xy 43.532508 -134.482119) (xy 43.517346 -134.50923) (xy 43.509195 -134.539204)
			(xy 43.508422 -134.554722) (xy 43.507172 -134.584441) (xy 43.498104 -134.643224) (xy 43.4815 -134.700339)
			(xy 43.45764 -134.754823) (xy 43.426925 -134.805758) (xy 43.389874 -134.852287) (xy 43.347109 -134.893626)
			(xy 43.299351 -134.929079) (xy 43.247404 -134.958049) (xy 43.192143 -134.980049) (xy 43.134498 -134.994707)
			(xy 43.07544 -135.001777) (xy 43.015965 -135.00114) (xy 42.986452 -134.997444) (xy 42.965136 -134.994826)
			(xy 42.922209 -134.996068) (xy 42.880103 -135.004513) (xy 42.840018 -135.019921) (xy 42.803096 -135.041854)
			(xy 42.770389 -135.069685) (xy 42.742831 -135.102621) (xy 42.721207 -135.139724) (xy 42.706132 -135.179936)
			(xy 42.698037 -135.222111) (xy 42.697146 -135.24357) (xy 42.696047 -135.272336) (xy 42.687574 -135.329277)
			(xy 42.672028 -135.384705) (xy 42.649655 -135.437747) (xy 42.620807 -135.487564) (xy 42.58594 -135.533371)
			(xy 42.566082 -135.554212) (xy 42.550584 -135.570701) (xy 42.525108 -135.608094) (xy 42.506657 -135.649408)
			(xy 42.495816 -135.693336) (xy 42.492926 -135.738491) (xy 42.49808 -135.783443) (xy 42.511113 -135.826772)
			(xy 42.531615 -135.867107) (xy 42.558937 -135.903174) (xy 42.592215 -135.933831) (xy 42.61104 -135.946388)
			(xy 42.633852 -135.961525) (xy 42.674878 -135.997769) (xy 42.70971 -136.040002) (xy 42.737483 -136.087177)
			(xy 42.75751 -136.138126) (xy 42.769295 -136.191585) (xy 42.772546 -136.246232) (xy 42.767183 -136.300712)
			(xy 42.753337 -136.353676) (xy 42.731353 -136.403811) (xy 42.701775 -136.449876) (xy 42.683938 -136.470644)
			(xy 42.668994 -136.488283) (xy 42.645006 -136.527795) (xy 42.628558 -136.570994) (xy 42.620193 -136.616454)
			(xy 42.620187 -136.662677) (xy 42.62854 -136.70814) (xy 42.644976 -136.751343) (xy 42.668953 -136.790861)
			(xy 42.683938 -136.808464) (xy 42.702402 -136.830057) (xy 42.732781 -136.878063) (xy 42.754948 -136.930371)
			(xy 42.768313 -136.985587) (xy 42.772518 -137.042242) (xy 42.767453 -137.098827) (xy 42.7609 -137.126472)
			(xy 42.755728 -137.14861) (xy 42.752332 -137.193939) (xy 42.75706 -137.239148) (xy 42.769761 -137.282793)
			(xy 42.790029 -137.323479) (xy 42.817217 -137.359907) (xy 42.850457 -137.390913) (xy 42.888685 -137.415505)
			(xy 42.90949 -137.424668) (xy 42.937273 -137.436769) (xy 42.989671 -137.467212) (xy 43.037593 -137.504304)
			(xy 43.080202 -137.547395) (xy 43.11675 -137.595733) (xy 43.1466 -137.648471) (xy 43.169229 -137.704687)
			(xy 43.175097 -137.727636) (xy 43.875154 -137.727636) (xy 43.881425 -137.674487) (xy 43.895776 -137.622929)
			(xy 43.917865 -137.574182) (xy 43.947172 -137.529402) (xy 43.983001 -137.489647) (xy 44.024505 -137.45586)
			(xy 44.0707 -137.428839) (xy 44.095416 -137.418572) (xy 44.115274 -137.410183) (xy 44.152136 -137.387846)
			(xy 44.184703 -137.359612) (xy 44.212042 -137.32629) (xy 44.23337 -137.288836) (xy 44.248076 -137.24832)
			(xy 44.255739 -137.205905) (xy 44.256139 -137.162805) (xy 44.25315 -137.141458) (xy 44.24888 -137.111937)
			(xy 44.247307 -137.052311) (xy 44.253713 -136.993008) (xy 44.267982 -136.935093) (xy 44.289859 -136.879602)
			(xy 44.318952 -136.827531) (xy 44.336462 -136.803384) (xy 44.361608 -136.769602) (xy 44.361608 -136.714484)
			(xy 44.423076 -136.714484) (xy 44.454064 -136.694672) (xy 44.466002 -136.687306) (xy 44.501308 -136.666478)
			(xy 44.918376 -136.249664) (xy 44.940752 -136.227956) (xy 44.990563 -136.190462) (xy 45.045121 -136.160292)
			(xy 45.103359 -136.138037) (xy 45.164134 -136.124135) (xy 45.226255 -136.118857) (xy 45.288505 -136.122306)
			(xy 45.349662 -136.134417) (xy 45.408529 -136.15495) (xy 45.46395 -136.183503) (xy 45.514841 -136.219517)
			(xy 45.537882 -136.24052) (xy 45.555654 -136.256594) (xy 45.59606 -136.282346) (xy 45.640576 -136.300073)
			(xy 45.687624 -136.309146) (xy 45.735539 -136.309244) (xy 45.782624 -136.300363) (xy 45.827212 -136.282819)
			(xy 45.847762 -136.270492) (xy 45.869331 -136.257436) (xy 45.915422 -136.237) (xy 45.963981 -136.223437)
			(xy 46.01399 -136.217031) (xy 46.064399 -136.217916) (xy 46.114153 -136.226074) (xy 46.162205 -136.241333)
			(xy 46.185074 -136.25195) (xy 46.205459 -136.261316) (xy 46.248609 -136.273571) (xy 46.293238 -136.278072)
			(xy 46.337966 -136.27468) (xy 46.381407 -136.263499) (xy 46.422215 -136.244876) (xy 46.459126 -136.219389)
			(xy 46.475396 -136.203944) (xy 46.49978 -136.181084) (xy 46.515936 -136.166339) (xy 46.543538 -136.132415)
			(xy 46.564927 -136.094268) (xy 46.579471 -136.053022) (xy 46.58674 -136.009897) (xy 46.586521 -135.966163)
			(xy 46.57882 -135.923112) (xy 46.563864 -135.882014) (xy 46.553374 -135.862822) (xy 46.538593 -135.835976)
			(xy 46.515414 -135.779245) (xy 46.500013 -135.719929) (xy 46.492666 -135.659089) (xy 46.493504 -135.597811)
			(xy 46.502512 -135.537194) (xy 46.519528 -135.478322) (xy 46.54425 -135.422246) (xy 46.576233 -135.369972)
			(xy 46.614907 -135.322433) (xy 46.659579 -135.28048) (xy 46.709449 -135.244865) (xy 46.763627 -135.216223)
			(xy 46.821143 -135.195068) (xy 46.880967 -135.181777) (xy 46.94203 -135.176589) (xy 47.003239 -135.179597)
			(xy 47.063499 -135.190745) (xy 47.121732 -135.209836) (xy 47.176897 -135.236528) (xy 47.228006 -135.270343)
			(xy 47.274145 -135.310676) (xy 47.314489 -135.356805) (xy 47.348316 -135.407906) (xy 47.375022 -135.463064)
			(xy 47.394127 -135.521293) (xy 47.40529 -135.58155) (xy 47.408313 -135.642758) (xy 47.40314 -135.703822)
			(xy 47.389864 -135.76365) (xy 47.368722 -135.82117) (xy 47.340094 -135.875355) (xy 47.304491 -135.925235)
			(xy 47.283878 -135.947912) (xy 47.269321 -135.964064) (xy 47.245406 -136.000377) (xy 47.228015 -136.040228)
			(xy 47.217657 -136.082457) (xy 47.214632 -136.125832) (xy 47.219028 -136.169089) (xy 47.230718 -136.210969)
			(xy 47.249361 -136.25025) (xy 47.274414 -136.285787) (xy 47.289466 -136.30148) (xy 47.408955 -136.420969)
			(xy 50.224838 -136.420969) (xy 50.229652 -136.359942) (xy 50.242557 -136.3001) (xy 50.263325 -136.242513)
			(xy 50.291584 -136.188209) (xy 50.32683 -136.138156) (xy 50.368434 -136.093249) (xy 50.415653 -136.054289)
			(xy 50.467644 -136.021971) (xy 50.523479 -135.996872) (xy 50.582162 -135.97944) (xy 50.642645 -135.969987)
			(xy 50.703848 -135.968681) (xy 50.764679 -135.975545) (xy 50.824052 -135.990458) (xy 50.880908 -136.013152)
			(xy 50.93423 -136.043223) (xy 50.983068 -136.080133) (xy 51.02655 -136.123225) (xy 51.063899 -136.171728)
			(xy 51.094449 -136.224778) (xy 51.117654 -136.281426) (xy 51.133101 -136.340663) (xy 51.140513 -136.40143)
			(xy 51.139758 -136.462642) (xy 51.135788 -136.492996) (xy 51.132988 -136.514851) (xy 51.134131 -136.558894)
			(xy 51.142859 -136.602079) (xy 51.158911 -136.643109) (xy 51.181803 -136.680752) (xy 51.21085 -136.713879)
			(xy 51.245179 -136.741494) (xy 51.28376 -136.76277) (xy 51.304444 -136.770364) (xy 51.33298 -136.780813)
			(xy 51.386462 -136.809664) (xy 51.41087 -136.827768) (xy 51.423099 -136.836643) (xy 51.450689 -136.848939)
			(xy 51.480396 -136.85441) (xy 51.510557 -136.852747) (xy 51.539483 -136.844045) (xy 51.565555 -136.828791)
			(xy 51.576732 -136.818624) (xy 51.599403 -136.797515) (xy 51.64938 -136.76092) (xy 51.703836 -136.7314)
			(xy 51.761776 -136.709493) (xy 51.822141 -136.6956) (xy 51.883828 -136.689976) (xy 51.945711 -136.692722)
			(xy 52.006657 -136.703788) (xy 52.065554 -136.722974) (xy 52.121326 -136.749927) (xy 52.172953 -136.784155)
			(xy 52.219492 -136.825033) (xy 52.24018 -136.848088) (xy 52.251362 -136.860146) (xy 52.278569 -136.8786)
			(xy 52.309583 -136.889502) (xy 52.342352 -136.89213) (xy 52.374708 -136.886311) (xy 52.404508 -136.87243)
			(xy 52.417472 -136.862312) (xy 52.438008 -136.845775) (xy 52.482801 -136.817967) (xy 52.531068 -136.796753)
			(xy 52.581845 -136.782559) (xy 52.634115 -136.775668) (xy 52.686836 -136.776217) (xy 52.738952 -136.784196)
			(xy 52.789421 -136.799445) (xy 52.837236 -136.82166) (xy 52.88144 -136.850395) (xy 52.901596 -136.867392)
			(xy 52.913316 -136.876971) (xy 52.940179 -136.890899) (xy 52.969565 -136.898115) (xy 52.999823 -136.898212)
			(xy 53.029255 -136.891185) (xy 53.056206 -136.877428) (xy 53.067966 -136.8679) (xy 53.090033 -136.849602)
			(xy 53.138703 -136.819318) (xy 53.191442 -136.796856) (xy 53.247001 -136.782746) (xy 53.275484 -136.779508)
			(xy 53.297651 -136.776904) (xy 53.340636 -136.764902) (xy 53.380866 -136.745582) (xy 53.417107 -136.719537)
			(xy 53.448247 -136.687566) (xy 53.473328 -136.650652) (xy 53.491582 -136.609927) (xy 53.502449 -136.56664)
			(xy 53.505594 -136.522122) (xy 53.500921 -136.477738) (xy 53.495194 -136.456166) (xy 53.48727 -136.427081)
			(xy 53.478294 -136.36747) (xy 53.477222 -136.307197) (xy 53.484071 -136.247304) (xy 53.498724 -136.188829)
			(xy 53.520927 -136.132784) (xy 53.550294 -136.080138) (xy 53.586319 -136.031803) (xy 53.628378 -135.988616)
			(xy 53.675741 -135.951324) (xy 53.727591 -135.920573) (xy 53.783029 -135.896894) (xy 53.841095 -135.880698)
			(xy 53.900786 -135.872265) (xy 53.961066 -135.871741) (xy 54.020894 -135.879135) (xy 54.079233 -135.894319)
			(xy 54.135074 -135.917031) (xy 54.187451 -135.946876) (xy 54.235456 -135.983339) (xy 54.278258 -136.025789)
			(xy 54.315118 -136.07349) (xy 54.345397 -136.125617) (xy 54.36857 -136.181268) (xy 54.384237 -136.23948)
			(xy 54.392126 -136.299244) (xy 54.392102 -136.359527) (xy 54.384164 -136.419285) (xy 54.36845 -136.477484)
			(xy 54.345231 -136.533116) (xy 54.31491 -136.585219) (xy 54.278012 -136.63289) (xy 54.235175 -136.675305)
			(xy 54.18714 -136.711729) (xy 54.13474 -136.741532) (xy 54.07888 -136.764198) (xy 54.020528 -136.779335)
			(xy 53.960695 -136.78668) (xy 53.93055 -136.786874) (xy 53.90821 -136.787037) (xy 53.864146 -136.794388)
			(xy 53.822045 -136.80933) (xy 53.783206 -136.831403) (xy 53.748824 -136.859927) (xy 53.719958 -136.894022)
			(xy 53.697499 -136.932639) (xy 53.682137 -136.974589) (xy 53.674346 -137.018577) (xy 53.674366 -137.063251)
			(xy 53.67782 -137.085324) (xy 53.681996 -137.112019) (xy 53.683663 -137.166023) (xy 53.677511 -137.2197)
			(xy 53.663668 -137.271925) (xy 53.642425 -137.321603) (xy 53.614228 -137.36769) (xy 53.579669 -137.40922)
			(xy 53.539471 -137.445322) (xy 53.49448 -137.475237) (xy 53.445639 -137.498338) (xy 53.393973 -137.51414)
			(xy 53.340566 -137.522313) (xy 53.286538 -137.522684) (xy 53.233024 -137.515245) (xy 53.181146 -137.500152)
			(xy 53.131992 -137.477724) (xy 53.086595 -137.448429) (xy 53.065934 -137.431018) (xy 53.054266 -137.421371)
			(xy 53.027388 -137.407447) (xy 52.997988 -137.400241) (xy 52.967718 -137.400157) (xy 52.938279 -137.407199)
			(xy 52.911324 -137.420973) (xy 52.899564 -137.43051) (xy 52.879408 -137.447294) (xy 52.83523 -137.475567)
			(xy 52.787525 -137.49737) (xy 52.737235 -137.51227) (xy 52.685353 -137.519974) (xy 52.632903 -137.52033)
			(xy 52.580921 -137.513331) (xy 52.530433 -137.499115) (xy 52.482436 -137.477962) (xy 52.437878 -137.450291)
			(xy 52.417472 -137.433812) (xy 52.404554 -137.423612) (xy 52.374749 -137.409668) (xy 52.342366 -137.40382)
			(xy 52.309566 -137.406459) (xy 52.278536 -137.417408) (xy 52.251343 -137.435938) (xy 52.24018 -137.448036)
			(xy 52.220302 -137.4703) (xy 52.175656 -137.509916) (xy 52.12624 -137.543393) (xy 52.072891 -137.570162)
			(xy 52.016516 -137.589769) (xy 51.95807 -137.601883) (xy 51.898545 -137.606296) (xy 51.838952 -137.602934)
			(xy 51.780301 -137.591855) (xy 51.723589 -137.573246) (xy 51.669776 -137.547423) (xy 51.619776 -137.514824)
			(xy 51.574438 -137.476003) (xy 51.554126 -137.454132) (xy 51.543769 -137.443103) (xy 51.518859 -137.425939)
			(xy 51.490602 -137.415137) (xy 51.460595 -137.411308) (xy 51.430531 -137.414668) (xy 51.402109 -137.425026)
			(xy 51.38928 -137.43305) (xy 51.366771 -137.447445) (xy 51.318495 -137.470339) (xy 51.267444 -137.486102)
			(xy 51.214664 -137.494409) (xy 51.161239 -137.495091) (xy 51.108265 -137.488134) (xy 51.056827 -137.473681)
			(xy 51.007983 -137.452027) (xy 50.962732 -137.423618) (xy 50.922005 -137.389036) (xy 50.886635 -137.348989)
			(xy 50.857349 -137.304301) (xy 50.834748 -137.255888) (xy 50.819295 -137.204742) (xy 50.811307 -137.151913)
			(xy 50.810668 -137.125202) (xy 50.810019 -137.103181) (xy 50.802151 -137.059839) (xy 50.786927 -137.018503)
			(xy 50.764805 -136.980411) (xy 50.736445 -136.946704) (xy 50.702699 -136.918392) (xy 50.664576 -136.896322)
			(xy 50.623219 -136.881156) (xy 50.601626 -136.87679) (xy 50.571596 -136.870844) (xy 50.513343 -136.852027)
			(xy 50.458118 -136.825611) (xy 50.406908 -136.79207) (xy 50.360625 -136.752001) (xy 50.320098 -136.70612)
			(xy 50.286048 -136.655246) (xy 50.259084 -136.600287) (xy 50.239687 -136.542224) (xy 50.228204 -136.482094)
			(xy 50.224838 -136.420969) (xy 47.408955 -136.420969) (xy 47.659544 -136.671558) (xy 47.659544 -137.376662)
			(xy 47.659071 -137.406376) (xy 47.652096 -137.465394) (xy 47.638293 -137.523198) (xy 47.617853 -137.579002)
			(xy 47.591051 -137.632044) (xy 47.558254 -137.681604) (xy 47.539402 -137.704576) (xy 47.525727 -137.721375)
			(xy 47.503798 -137.758731) (xy 47.488523 -137.799266) (xy 47.480344 -137.841803) (xy 47.4795 -137.885112)
			(xy 47.486014 -137.927936) (xy 47.499697 -137.969035) (xy 47.520153 -138.007217) (xy 47.546789 -138.041377)
			(xy 47.578834 -138.070523) (xy 47.615357 -138.093812) (xy 47.63516 -138.102594) (xy 47.662557 -138.114607)
			(xy 47.71421 -138.144787) (xy 47.761491 -138.18144) (xy 47.803594 -138.22394) (xy 47.805709 -138.226722)
			(xy 54.392084 -138.226722) (xy 54.396075 -138.166852) (xy 54.407855 -138.108017) (xy 54.427222 -138.051225)
			(xy 54.453844 -137.997451) (xy 54.487264 -137.947616) (xy 54.526909 -137.902576) (xy 54.5721 -137.863102)
			(xy 54.622062 -137.829872) (xy 54.675937 -137.803455) (xy 54.732802 -137.784305) (xy 54.791681 -137.772749)
			(xy 54.851566 -137.768985) (xy 54.91143 -137.77308) (xy 54.970245 -137.784961) (xy 55.027003 -137.804426)
			(xy 55.080731 -137.83114) (xy 55.130508 -137.864646) (xy 55.153306 -137.884154) (xy 55.165353 -137.894192)
			(xy 55.193199 -137.908592) (xy 55.223714 -137.915775) (xy 55.255059 -137.915308) (xy 55.285347 -137.90722)
			(xy 55.312752 -137.891998) (xy 55.324502 -137.881614) (xy 55.344008 -137.86396) (xy 55.387282 -137.834049)
			(xy 55.434576 -137.811012) (xy 55.484804 -137.795376) (xy 55.536816 -137.7875) (xy 55.589422 -137.787563)
			(xy 55.641415 -137.795566) (xy 55.691605 -137.811323) (xy 55.738843 -137.834475) (xy 55.782045 -137.86449)
			(xy 55.820222 -137.900682) (xy 55.8525 -137.942221) (xy 55.878139 -137.988155) (xy 55.896552 -138.037433)
			(xy 55.907317 -138.088926) (xy 55.910188 -138.141453) (xy 55.905098 -138.193812) (xy 55.892164 -138.244802)
			(xy 55.871683 -138.293257) (xy 55.844124 -138.338066) (xy 55.810118 -138.378203) (xy 55.770444 -138.412747)
			(xy 55.726011 -138.440908) (xy 55.677836 -138.462041) (xy 55.627025 -138.475661) (xy 55.574739 -138.481457)
			(xy 55.522178 -138.479295) (xy 55.470545 -138.469226) (xy 55.421023 -138.451479) (xy 55.397654 -138.439398)
			(xy 55.383632 -138.432306) (xy 55.353196 -138.424531) (xy 55.321782 -138.424435) (xy 55.291299 -138.432022)
			(xy 55.263596 -138.446834) (xy 55.240356 -138.46797) (xy 55.231284 -138.4808) (xy 55.214296 -138.505532)
			(xy 55.174806 -138.550709) (xy 55.129751 -138.590338) (xy 55.079905 -138.62374) (xy 55.026121 -138.650342)
			(xy 54.969322 -138.669688) (xy 54.910482 -138.681447) (xy 54.850611 -138.685416) (xy 54.790734 -138.681528)
			(xy 54.731878 -138.669849) (xy 54.675053 -138.65058) (xy 54.621233 -138.624051) (xy 54.571341 -138.590717)
			(xy 54.526233 -138.551149) (xy 54.486682 -138.506026) (xy 54.453366 -138.456122) (xy 54.426856 -138.402292)
			(xy 54.407608 -138.34546) (xy 54.39595 -138.286601) (xy 54.392084 -138.226722) (xy 47.805709 -138.226722)
			(xy 47.839801 -138.271562) (xy 47.869496 -138.323495) (xy 47.892173 -138.378855) (xy 47.907444 -138.436697)
			(xy 47.91505 -138.496035) (xy 47.914861 -138.555858) (xy 47.906879 -138.615147) (xy 47.891243 -138.672891)
			(xy 47.868216 -138.728106) (xy 47.838193 -138.779851) (xy 47.801685 -138.827243) (xy 47.759314 -138.869475)
			(xy 47.711802 -138.905828) (xy 47.65996 -138.935681) (xy 47.651898 -138.939012) (xy 48.683146 -138.939012)
			(xy 48.683146 -138.879076) (xy 48.690969 -138.819654) (xy 48.706482 -138.761761) (xy 48.729418 -138.706388)
			(xy 48.759385 -138.654482) (xy 48.795872 -138.606932) (xy 48.838252 -138.564552) (xy 48.885802 -138.528065)
			(xy 48.937708 -138.498098) (xy 48.993081 -138.475162) (xy 49.050974 -138.459649) (xy 49.110396 -138.451826)
			(xy 49.170332 -138.451826) (xy 49.229754 -138.459649) (xy 49.287647 -138.475162) (xy 49.34302 -138.498098)
			(xy 49.394926 -138.528065) (xy 49.442476 -138.564552) (xy 49.484856 -138.606932) (xy 49.521343 -138.654482)
			(xy 49.55131 -138.706388) (xy 49.574246 -138.761761) (xy 49.589759 -138.819654) (xy 49.597582 -138.879076)
			(xy 49.598072 -138.909044) (xy 49.597582 -138.939012) (xy 49.589759 -138.998434) (xy 49.574246 -139.056327)
			(xy 49.55131 -139.1117) (xy 49.521343 -139.163606) (xy 49.484856 -139.211156) (xy 49.442476 -139.253536)
			(xy 49.394926 -139.290023) (xy 49.34302 -139.31999) (xy 49.287647 -139.342926) (xy 49.229754 -139.358439)
			(xy 49.170332 -139.366262) (xy 49.110396 -139.366262) (xy 49.050974 -139.358439) (xy 48.993081 -139.342926)
			(xy 48.937708 -139.31999) (xy 48.885802 -139.290023) (xy 48.838252 -139.253536) (xy 48.795872 -139.211156)
			(xy 48.759385 -139.163606) (xy 48.729418 -139.1117) (xy 48.706482 -139.056327) (xy 48.690969 -138.998434)
			(xy 48.683146 -138.939012) (xy 47.651898 -138.939012) (xy 47.60467 -138.958526) (xy 47.546875 -138.973974)
			(xy 47.48756 -138.981761) (xy 47.427736 -138.981754) (xy 47.368423 -138.973954) (xy 47.310632 -138.958493)
			(xy 47.255347 -138.935636) (xy 47.203511 -138.90577) (xy 47.156008 -138.869407) (xy 47.113646 -138.827165)
			(xy 47.077149 -138.779764) (xy 47.047138 -138.728013) (xy 47.024124 -138.672793) (xy 47.0085 -138.615046)
			(xy 47.000532 -138.555755) (xy 47.000357 -138.495931) (xy 47.007976 -138.436595) (xy 47.02326 -138.378757)
			(xy 47.045949 -138.323402) (xy 47.075656 -138.271476) (xy 47.093378 -138.247374) (xy 47.106185 -138.229915)
			(xy 47.12617 -138.191505) (xy 47.139359 -138.150264) (xy 47.14537 -138.107385) (xy 47.14403 -138.064107)
			(xy 47.135377 -138.021682) (xy 47.119661 -137.981336) (xy 47.097337 -137.944237) (xy 47.069051 -137.911455)
			(xy 47.035619 -137.88394) (xy 46.99801 -137.862486) (xy 46.977808 -137.85469) (xy 46.948716 -137.843664)
			(xy 46.89324 -137.815499) (xy 46.841615 -137.780775) (xy 46.794614 -137.74001) (xy 46.75294 -137.693813)
			(xy 46.717214 -137.642876) (xy 46.687972 -137.58796) (xy 46.66565 -137.529886) (xy 46.650583 -137.469522)
			(xy 46.642994 -137.40777) (xy 46.642528 -137.376662) (xy 46.642528 -137.09269) (xy 46.474126 -136.924034)
			(xy 46.460528 -136.910221) (xy 46.435226 -136.880854) (xy 46.42358 -136.86536) (xy 46.413152 -136.852093)
			(xy 46.386765 -136.831083) (xy 46.355793 -136.817723) (xy 46.322402 -136.812948) (xy 46.288927 -136.817093)
			(xy 46.257709 -136.829866) (xy 46.244002 -136.839706) (xy 46.221593 -136.856201) (xy 46.172594 -136.882563)
			(xy 46.120018 -136.900771) (xy 46.065209 -136.910359) (xy 46.009574 -136.91108) (xy 45.954536 -136.902916)
			(xy 45.901505 -136.886077) (xy 45.851839 -136.860994) (xy 45.806811 -136.828309) (xy 45.786802 -136.808972)
			(xy 45.775365 -136.798145) (xy 45.74834 -136.781991) (xy 45.718185 -136.772937) (xy 45.686732 -136.771532)
			(xy 45.655889 -136.777861) (xy 45.627532 -136.791541) (xy 45.60338 -136.811741) (xy 45.593762 -136.824212)
			(xy 45.583114 -136.838604) (xy 45.559843 -136.865813) (xy 45.54728 -136.878568) (xy 45.023024 -137.403078)
			(xy 45.023024 -137.426192) (xy 44.96435 -137.426192) (xy 44.91863 -137.45337) (xy 44.896439 -137.466062)
			(xy 44.849717 -137.486815) (xy 44.800925 -137.50208) (xy 44.775882 -137.507218) (xy 44.754821 -137.511755)
			(xy 44.71449 -137.52689) (xy 44.677292 -137.548614) (xy 44.644294 -137.576303) (xy 44.616441 -137.609164)
			(xy 44.594533 -137.646255) (xy 44.579199 -137.68651) (xy 44.570877 -137.728775) (xy 44.569888 -137.750296)
			(xy 44.568731 -137.777034) (xy 44.559215 -137.829699) (xy 44.541732 -137.880281) (xy 44.516697 -137.927582)
			(xy 44.484701 -137.970483) (xy 44.446504 -138.007967) (xy 44.403008 -138.039148) (xy 44.355243 -138.063288)
			(xy 44.304341 -138.079814) (xy 44.251506 -138.088336) (xy 44.197989 -138.088652) (xy 44.145057 -138.080754)
			(xy 44.093963 -138.06483) (xy 44.045917 -138.041256) (xy 44.002056 -138.010591) (xy 43.963418 -137.97356)
			(xy 43.930919 -137.931041) (xy 43.905326 -137.884038) (xy 43.887248 -137.833667) (xy 43.87711 -137.781118)
			(xy 43.875154 -137.727636) (xy 43.175097 -137.727636) (xy 43.184241 -137.763398) (xy 43.191374 -137.823577)
			(xy 43.190503 -137.88417) (xy 43.181643 -137.944119) (xy 43.164948 -138.002374) (xy 43.140712 -138.057916)
			(xy 43.109359 -138.109774) (xy 43.071435 -138.157041) (xy 43.064082 -138.164062) (xy 45.659812 -138.164062)
			(xy 45.663788 -138.109736) (xy 45.675631 -138.056567) (xy 45.69509 -138.00569) (xy 45.72175 -137.958188)
			(xy 45.755041 -137.915074) (xy 45.794255 -137.877267) (xy 45.838557 -137.845572) (xy 45.887 -137.820666)
			(xy 45.938554 -137.803078) (xy 45.99212 -137.793184) (xy 46.046555 -137.791194) (xy 46.1007 -137.797152)
			(xy 46.1534 -137.81093) (xy 46.203533 -137.832234) (xy 46.250029 -137.86061) (xy 46.291899 -137.895454)
			(xy 46.328248 -137.936023) (xy 46.358304 -137.981452) (xy 46.381425 -138.030773) (xy 46.397118 -138.082935)
			(xy 46.405049 -138.136826) (xy 46.405546 -138.164062) (xy 46.405049 -138.191298) (xy 46.397118 -138.245189)
			(xy 46.381425 -138.297351) (xy 46.358304 -138.346672) (xy 46.328248 -138.392101) (xy 46.291899 -138.43267)
			(xy 46.250029 -138.467514) (xy 46.203533 -138.49589) (xy 46.1534 -138.517194) (xy 46.1007 -138.530972)
			(xy 46.046555 -138.53693) (xy 45.99212 -138.53494) (xy 45.938554 -138.525046) (xy 45.887 -138.507458)
			(xy 45.838557 -138.482552) (xy 45.794255 -138.450857) (xy 45.755041 -138.41305) (xy 45.72175 -138.369936)
			(xy 45.69509 -138.322434) (xy 45.675631 -138.271557) (xy 45.663788 -138.218388) (xy 45.659812 -138.164062)
			(xy 43.064082 -138.164062) (xy 43.027606 -138.19889) (xy 42.978637 -138.234588) (xy 42.925385 -138.263512)
			(xy 42.868782 -138.285155) (xy 42.809818 -138.299139) (xy 42.749524 -138.305219) (xy 42.688955 -138.303289)
			(xy 42.62917 -138.293382) (xy 42.571216 -138.275673) (xy 42.516105 -138.25047) (xy 42.464803 -138.218214)
			(xy 42.418206 -138.179471) (xy 42.37713 -138.134917) (xy 42.342293 -138.085331) (xy 42.314304 -138.031582)
			(xy 42.293653 -137.97461) (xy 42.280702 -137.91541) (xy 42.275676 -137.855019) (xy 42.278665 -137.794493)
			(xy 42.289614 -137.734891) (xy 42.308334 -137.677255) (xy 42.320972 -137.649712) (xy 42.33034 -137.629009)
			(xy 42.342381 -137.585198) (xy 42.346431 -137.539943) (xy 42.342361 -137.49469) (xy 42.3303 -137.450884)
			(xy 42.310635 -137.409925) (xy 42.283993 -137.37312) (xy 42.251225 -137.341645) (xy 42.23258 -137.328656)
			(xy 42.21034 -137.313272) (xy 42.1705 -137.276709) (xy 42.13681 -137.23441) (xy 42.110087 -137.1874)
			(xy 42.090976 -137.136814) (xy 42.07994 -137.083877) (xy 42.077245 -137.029869) (xy 42.082957 -136.976097)
			(xy 42.096938 -136.92386) (xy 42.11885 -136.874423) (xy 42.148162 -136.828981) (xy 42.165778 -136.808464)
			(xy 42.180812 -136.790897) (xy 42.204794 -136.751369) (xy 42.221232 -136.708156) (xy 42.229586 -136.662683)
			(xy 42.22958 -136.616449) (xy 42.221214 -136.570978) (xy 42.204763 -136.527769) (xy 42.180771 -136.488247)
			(xy 42.165778 -136.470644) (xy 42.148517 -136.450654) (xy 42.119719 -136.406381) (xy 42.097959 -136.358256)
			(xy 42.08374 -136.307391) (xy 42.077391 -136.254959) (xy 42.079057 -136.20217) (xy 42.0887 -136.150243)
			(xy 42.106098 -136.100375) (xy 42.130849 -136.053719) (xy 42.14622 -136.03224) (xy 42.159305 -136.01377)
			(xy 42.17949 -135.973265) (xy 42.192178 -135.929823) (xy 42.196968 -135.884821) (xy 42.193709 -135.839682)
			(xy 42.182504 -135.795834) (xy 42.163706 -135.754666) (xy 42.137912 -135.71748) (xy 42.105936 -135.685453)
			(xy 42.068792 -135.659598) (xy 42.04843 -135.649716) (xy 42.021618 -135.63698) (xy 41.971331 -135.605435)
			(xy 41.925544 -135.567654) (xy 41.885025 -135.524272) (xy 41.850452 -135.476017) (xy 41.822408 -135.423697)
			(xy 41.801361 -135.368192) (xy 41.787665 -135.310431) (xy 41.781551 -135.251385) (xy 40.670112 -135.251385)
			(xy 40.639237 -135.275286) (xy 40.591798 -135.30199) (xy 40.540978 -135.321506) (xy 40.487859 -135.333418)
			(xy 40.433572 -135.337473) (xy 40.379272 -135.333584) (xy 40.326117 -135.321835) (xy 40.275237 -135.302475)
			(xy 40.227717 -135.275917) (xy 40.184567 -135.242725) (xy 40.146707 -135.203608) (xy 40.114943 -135.159397)
			(xy 40.089952 -135.111034) (xy 40.072264 -135.059549) (xy 40.062257 -135.006038) (xy 40.060145 -134.951641)
			(xy 40.065971 -134.897515) (xy 40.079612 -134.844813) (xy 40.100778 -134.794658) (xy 40.114474 -134.77113)
			(xy 40.12594 -134.751214) (xy 40.142308 -134.708277) (xy 40.150686 -134.663097) (xy 40.150798 -134.617147)
			(xy 40.142643 -134.571926) (xy 40.126486 -134.52891) (xy 40.102853 -134.489502) (xy 40.088058 -134.471918)
			(xy 40.074342 -134.455408) (xy 40.059853 -134.438115) (xy 40.025913 -134.408403) (xy 39.98726 -134.385148)
			(xy 39.945109 -134.369083) (xy 39.900784 -134.360712) (xy 39.855677 -134.360297) (xy 39.811206 -134.367852)
			(xy 39.768767 -134.38314) (xy 39.729693 -134.405679) (xy 39.712138 -134.419848) (xy 39.705026 -134.42569)
			(xy 39.693053 -134.43605) (xy 39.674107 -134.461401) (xy 39.662004 -134.490643) (xy 39.657493 -134.521967)
			(xy 39.660853 -134.553436) (xy 39.66591 -134.568438) (xy 39.676623 -134.599061) (xy 39.690308 -134.662476)
			(xy 39.694901 -134.727189) (xy 39.690311 -134.791901) (xy 39.67663 -134.855318) (xy 39.66591 -134.885938)
			(xy 39.660929 -134.900957) (xy 39.657605 -134.932412) (xy 39.662114 -134.963719) (xy 39.674179 -134.992958)
			(xy 39.693059 -135.018336) (xy 39.705026 -135.028686) (xy 39.72977 -135.04945) (xy 39.774379 -135.096166)
			(xy 39.812716 -135.148154) (xy 39.844163 -135.204576) (xy 39.868216 -135.264525) (xy 39.884486 -135.327037)
			(xy 39.892713 -135.391105) (xy 39.89324 -135.423402) (xy 39.89324 -135.59663) (xy 39.892725 -135.625463)
			(xy 39.883991 -135.682464) (xy 39.866756 -135.737495) (xy 39.841417 -135.789296) (xy 39.825422 -135.813292)
			(xy 39.825422 -135.813546) (xy 39.817495 -135.825909) (xy 39.806836 -135.853263) (xy 39.802727 -135.882331)
			(xy 39.805385 -135.911568) (xy 39.814669 -135.939418) (xy 39.830085 -135.964401) (xy 39.840154 -135.97509)
			(xy 39.917624 -136.052814) (xy 39.917624 -136.082532) (xy 39.958264 -136.14527) (xy 40.060118 -136.19099)
			(xy 40.074861 -136.197177) (xy 40.106349 -136.202672) (xy 40.138214 -136.200144) (xy 40.168442 -136.189752)
			(xy 40.182038 -136.181338) (xy 40.207357 -136.16534) (xy 40.2613 -136.139319) (xy 40.318177 -136.120556)
			(xy 40.377014 -136.10937) (xy 40.436808 -136.105953) (xy 40.496537 -136.110364) (xy 40.555181 -136.122525)
			(xy 40.611737 -136.142231) (xy 40.665241 -136.169145) (xy 40.714778 -136.202806) (xy 40.759502 -136.24264)
			(xy 40.798649 -136.287966) (xy 40.831551 -136.338011) (xy 40.857645 -136.391919) (xy 40.876487 -136.448769)
			(xy 40.887753 -136.507592) (xy 40.891251 -136.567381) (xy 40.886923 -136.627115) (xy 40.874841 -136.685776)
			(xy 40.855213 -136.742359) (xy 40.828373 -136.7959) (xy 40.79478 -136.845483) (xy 40.755007 -136.890261)
			(xy 40.709734 -136.929471) (xy 40.659735 -136.962441) (xy 40.605863 -136.988609) (xy 40.549038 -137.007528)
			(xy 40.490231 -137.018875) (xy 40.430447 -137.022455) (xy 40.370706 -137.018209) (xy 40.31203 -137.006208)
			(xy 40.255419 -136.986657) (xy 40.201842 -136.95989) (xy 40.152213 -136.926365) (xy 40.10738 -136.886653)
			(xy 40.068109 -136.841434) (xy 40.03507 -136.79148) (xy 40.02151 -136.764776) (xy 40.011487 -136.745207)
			(xy 39.985705 -136.709596) (xy 39.954181 -136.678952) (xy 39.917853 -136.654191) (xy 39.877806 -136.63605)
			(xy 39.835234 -136.625072) (xy 39.791409 -136.621583) (xy 39.747637 -136.625688) (xy 39.705224 -136.637265)
			(xy 39.665437 -136.655967) (xy 39.629461 -136.681237) (xy 39.613586 -136.69645) (xy 39.553896 -136.75614)
			(xy 39.294816 -136.75614) (xy 39.191184 -136.859772) (xy 39.191184 -137.14857) (xy 39.25697 -137.214356)
			(xy 39.422578 -137.214356) (xy 39.449813 -137.214829) (xy 39.503728 -137.222578) (xy 39.555991 -137.237922)
			(xy 39.605539 -137.260547) (xy 39.651362 -137.289994) (xy 39.692528 -137.325663) (xy 39.728198 -137.366828)
			(xy 39.757647 -137.41265) (xy 39.780274 -137.462197) (xy 39.795619 -137.51446) (xy 39.80337 -137.568375)
			(xy 39.803832 -137.59561) (xy 39.803832 -138.164206) (xy 40.059741 -138.164206) (xy 40.063735 -138.109749)
			(xy 40.075633 -138.056458) (xy 40.095182 -138.005473) (xy 40.121961 -137.957888) (xy 40.155398 -137.91472)
			(xy 40.194777 -137.876893) (xy 40.239254 -137.845219) (xy 40.287878 -137.820374) (xy 40.339606 -137.802891)
			(xy 40.393333 -137.793144) (xy 40.447906 -137.791343) (xy 40.502159 -137.797524) (xy 40.554928 -137.811557)
			(xy 40.605084 -137.83314) (xy 40.62857 -137.84707) (xy 40.648546 -137.858824) (xy 40.69176 -137.87557)
			(xy 40.737292 -137.884208) (xy 40.783637 -137.884452) (xy 40.829258 -137.876294) (xy 40.872646 -137.860004)
			(xy 40.912363 -137.836121) (xy 40.930068 -137.821162) (xy 40.952884 -137.80164) (xy 41.002705 -137.768116)
			(xy 41.056481 -137.741395) (xy 41.113289 -137.721933) (xy 41.172154 -137.710066) (xy 41.232065 -137.705996)
			(xy 41.291994 -137.709795) (xy 41.350912 -137.721396) (xy 41.407807 -137.740601) (xy 41.461703 -137.76708)
			(xy 41.511675 -137.800378) (xy 41.556864 -137.839924) (xy 41.596495 -137.885038) (xy 41.629887 -137.934946)
			(xy 41.656468 -137.988792) (xy 41.67578 -138.045651) (xy 41.687493 -138.104547) (xy 41.691405 -138.164469)
			(xy 41.687449 -138.224388) (xy 41.675693 -138.283275) (xy 41.656338 -138.34012) (xy 41.629718 -138.393946)
			(xy 41.596289 -138.44383) (xy 41.556625 -138.488915) (xy 41.511407 -138.528427) (xy 41.461411 -138.561688)
			(xy 41.407495 -138.588127) (xy 41.350586 -138.60729) (xy 41.291659 -138.618848) (xy 41.231727 -138.622603)
			(xy 41.171819 -138.618489) (xy 41.112963 -138.606579) (xy 41.056169 -138.587075) (xy 41.002413 -138.560314)
			(xy 40.952617 -138.526754) (xy 40.929814 -138.507216) (xy 40.91212 -138.49228) (xy 40.872437 -138.468428)
			(xy 40.82909 -138.452159) (xy 40.783513 -138.444012) (xy 40.737214 -138.444257) (xy 40.691725 -138.452884)
			(xy 40.648552 -138.469609) (xy 40.62857 -138.481308) (xy 40.605095 -138.495254) (xy 40.554939 -138.516839)
			(xy 40.50217 -138.530874) (xy 40.447918 -138.537057) (xy 40.393344 -138.535257) (xy 40.339618 -138.525512)
			(xy 40.287888 -138.508031) (xy 40.239264 -138.483187) (xy 40.194785 -138.451514) (xy 40.155406 -138.413689)
			(xy 40.121967 -138.370522) (xy 40.095186 -138.322937) (xy 40.075637 -138.271953) (xy 40.063737 -138.218663)
			(xy 40.059741 -138.164206) (xy 39.803832 -138.164206) (xy 39.803832 -138.856466) (xy 39.579296 -139.081256)
			(xy 39.29634 -139.081256) (xy 39.279697 -139.081878) (xy 39.247543 -139.090482) (xy 39.218711 -139.107116)
			(xy 39.195167 -139.130644) (xy 39.178514 -139.159465) (xy 39.169889 -139.191613) (xy 39.16934 -139.208256)
			(xy 39.16934 -139.517628) (xy 39.169771 -139.534287) (xy 39.178402 -139.566469) (xy 39.195068 -139.595319)
			(xy 39.218635 -139.618873) (xy 39.247494 -139.635524) (xy 39.27968 -139.644138) (xy 39.29634 -139.644628)
			(xy 39.6113 -139.644628) (xy 39.728372 -139.7617) (xy 40.775121 -139.7617) (xy 40.779385 -139.701882)
			(xy 40.791425 -139.643133) (xy 40.811034 -139.58646) (xy 40.837878 -139.532834) (xy 40.871495 -139.483173)
			(xy 40.911311 -139.438327) (xy 40.956642 -139.399066) (xy 41.006713 -139.366062) (xy 41.060665 -139.33988)
			(xy 41.117575 -139.320968) (xy 41.176467 -139.309652) (xy 41.236333 -139.306123) (xy 41.296147 -139.310444)
			(xy 41.354884 -139.322539) (xy 41.411538 -139.342203) (xy 41.465139 -139.369097) (xy 41.501369 -139.393672)
			(xy 42.50866 -139.393672) (xy 42.50866 -139.333736) (xy 42.516483 -139.274314) (xy 42.531996 -139.216421)
			(xy 42.554932 -139.161048) (xy 42.584899 -139.109142) (xy 42.621386 -139.061592) (xy 42.663766 -139.019212)
			(xy 42.711316 -138.982725) (xy 42.763222 -138.952758) (xy 42.818595 -138.929822) (xy 42.876488 -138.914309)
			(xy 42.93591 -138.906486) (xy 42.995846 -138.906486) (xy 43.055268 -138.914309) (xy 43.113161 -138.929822)
			(xy 43.168534 -138.952758) (xy 43.22044 -138.982725) (xy 43.236296 -138.994892) (xy 43.975002 -138.994892)
			(xy 43.975002 -138.934956) (xy 43.982825 -138.875534) (xy 43.998338 -138.817641) (xy 44.021274 -138.762268)
			(xy 44.051241 -138.710362) (xy 44.087728 -138.662812) (xy 44.130108 -138.620432) (xy 44.177658 -138.583945)
			(xy 44.229564 -138.553978) (xy 44.284937 -138.531042) (xy 44.34283 -138.515529) (xy 44.402252 -138.507706)
			(xy 44.462188 -138.507706) (xy 44.52161 -138.515529) (xy 44.579503 -138.531042) (xy 44.634876 -138.553978)
			(xy 44.686782 -138.583945) (xy 44.734332 -138.620432) (xy 44.776712 -138.662812) (xy 44.813199 -138.710362)
			(xy 44.843166 -138.762268) (xy 44.866102 -138.817641) (xy 44.881615 -138.875534) (xy 44.889438 -138.934956)
			(xy 44.889928 -138.964924) (xy 44.889438 -138.994892) (xy 44.881615 -139.054314) (xy 44.866102 -139.112207)
			(xy 44.843166 -139.16758) (xy 44.813199 -139.219486) (xy 44.776712 -139.267036) (xy 44.734332 -139.309416)
			(xy 44.686782 -139.345903) (xy 44.634876 -139.37587) (xy 44.579503 -139.398806) (xy 44.52161 -139.414319)
			(xy 44.462188 -139.422142) (xy 44.402252 -139.422142) (xy 44.34283 -139.414319) (xy 44.284937 -139.398806)
			(xy 44.229564 -139.37587) (xy 44.177658 -139.345903) (xy 44.130108 -139.309416) (xy 44.087728 -139.267036)
			(xy 44.051241 -139.219486) (xy 44.021274 -139.16758) (xy 43.998338 -139.112207) (xy 43.982825 -139.054314)
			(xy 43.975002 -138.994892) (xy 43.236296 -138.994892) (xy 43.26799 -139.019212) (xy 43.31037 -139.061592)
			(xy 43.346857 -139.109142) (xy 43.376824 -139.161048) (xy 43.39976 -139.216421) (xy 43.415273 -139.274314)
			(xy 43.423096 -139.333736) (xy 43.423586 -139.363704) (xy 43.423096 -139.393672) (xy 43.415273 -139.453094)
			(xy 43.39976 -139.510987) (xy 43.376824 -139.56636) (xy 43.346857 -139.618266) (xy 43.31037 -139.665816)
			(xy 43.26799 -139.708196) (xy 43.22044 -139.744683) (xy 43.168534 -139.77465) (xy 43.113161 -139.797586)
			(xy 43.055268 -139.813099) (xy 42.995846 -139.820922) (xy 42.93591 -139.820922) (xy 42.876488 -139.813099)
			(xy 42.818595 -139.797586) (xy 42.763222 -139.77465) (xy 42.711316 -139.744683) (xy 42.663766 -139.708196)
			(xy 42.621386 -139.665816) (xy 42.584899 -139.618266) (xy 42.554932 -139.56636) (xy 42.531996 -139.510987)
			(xy 42.516483 -139.453094) (xy 42.50866 -139.393672) (xy 41.501369 -139.393672) (xy 41.514769 -139.402761)
			(xy 41.559576 -139.442619) (xy 41.598795 -139.487987) (xy 41.631752 -139.538089) (xy 41.657883 -139.592066)
			(xy 41.676741 -139.648994) (xy 41.688002 -139.707897) (xy 41.691474 -139.767766) (xy 41.687097 -139.827575)
			(xy 41.674946 -139.886301) (xy 41.655229 -139.942937) (xy 41.628284 -139.996513) (xy 41.594573 -140.04611)
			(xy 41.574974 -140.068808) (xy 41.560006 -140.086372) (xy 41.536049 -140.125807) (xy 41.519593 -140.168915)
			(xy 41.511178 -140.214284) (xy 41.511079 -140.260426) (xy 41.519299 -140.30583) (xy 41.53557 -140.349009)
			(xy 41.547034 -140.369036) (xy 41.560695 -140.392617) (xy 41.581726 -140.442892) (xy 41.586604 -140.461996)
			(xy 41.987452 -140.461996) (xy 41.987452 -140.40206) (xy 41.995275 -140.342638) (xy 42.010788 -140.284745)
			(xy 42.033724 -140.229372) (xy 42.063691 -140.177466) (xy 42.100178 -140.129916) (xy 42.142558 -140.087536)
			(xy 42.190108 -140.051049) (xy 42.242014 -140.021082) (xy 42.297387 -139.998146) (xy 42.35528 -139.982633)
			(xy 42.414702 -139.97481) (xy 42.474638 -139.97481) (xy 42.53406 -139.982633) (xy 42.591953 -139.998146)
			(xy 42.647326 -140.021082) (xy 42.699232 -140.051049) (xy 42.746782 -140.087536) (xy 42.789162 -140.129916)
			(xy 42.825649 -140.177466) (xy 42.846354 -140.21333) (xy 43.526184 -140.21333) (xy 43.526184 -140.153394)
			(xy 43.534007 -140.093972) (xy 43.54952 -140.036079) (xy 43.572456 -139.980706) (xy 43.602423 -139.9288)
			(xy 43.63891 -139.88125) (xy 43.68129 -139.83887) (xy 43.72884 -139.802383) (xy 43.780746 -139.772416)
			(xy 43.836119 -139.74948) (xy 43.894012 -139.733967) (xy 43.953434 -139.726144) (xy 44.01337 -139.726144)
			(xy 44.072792 -139.733967) (xy 44.130685 -139.74948) (xy 44.186058 -139.772416) (xy 44.237964 -139.802383)
			(xy 44.285514 -139.83887) (xy 44.327894 -139.88125) (xy 44.364381 -139.9288) (xy 44.394348 -139.980706)
			(xy 44.417284 -140.036079) (xy 44.432797 -140.093972) (xy 44.44062 -140.153394) (xy 44.44111 -140.183362)
			(xy 44.44062 -140.21333) (xy 44.432797 -140.272752) (xy 44.417284 -140.330645) (xy 44.394348 -140.386018)
			(xy 44.364381 -140.437924) (xy 44.327894 -140.485474) (xy 44.285514 -140.527854) (xy 44.259153 -140.548082)
			(xy 44.77532 -140.548082) (xy 44.781437 -140.487804) (xy 44.795455 -140.428859) (xy 44.817128 -140.37228)
			(xy 44.846077 -140.319055) (xy 44.881796 -140.270116) (xy 44.902374 -140.247878) (xy 44.918268 -140.230551)
			(xy 44.943943 -140.191165) (xy 44.961938 -140.14773) (xy 44.971641 -140.101726) (xy 44.972721 -140.054723)
			(xy 44.965141 -140.008322) (xy 44.94916 -139.964106) (xy 44.93768 -139.943586) (xy 44.924698 -139.920425)
			(xy 44.905107 -139.871078) (xy 44.893256 -139.819325) (xy 44.889421 -139.766371) (xy 44.893691 -139.71345)
			(xy 44.905967 -139.661796) (xy 44.925962 -139.612613) (xy 44.953211 -139.567046) (xy 44.987078 -139.526157)
			(xy 45.026775 -139.490901) (xy 45.071375 -139.462097) (xy 45.11984 -139.440418) (xy 45.17104 -139.426369)
			(xy 45.223782 -139.420277) (xy 45.276837 -139.422284) (xy 45.328968 -139.432344) (xy 45.378961 -139.450222)
			(xy 45.425649 -139.4755) (xy 45.467946 -139.507591) (xy 45.504865 -139.545747) (xy 45.535546 -139.589077)
			(xy 45.559274 -139.636573) (xy 45.575496 -139.687126) (xy 45.583833 -139.73956) (xy 45.584093 -139.792653)
			(xy 45.576267 -139.845165) (xy 45.56054 -139.895875) (xy 45.537277 -139.9436) (xy 45.507021 -139.987228)
			(xy 45.489114 -140.006832) (xy 45.478815 -140.018271) (xy 45.463553 -140.044991) (xy 45.455149 -140.074592)
			(xy 45.454094 -140.105346) (xy 45.454659 -140.108021) (xy 50.353223 -140.108021) (xy 50.358877 -140.05413)
			(xy 50.372278 -140.001627) (xy 50.393144 -139.951618) (xy 50.421034 -139.90516) (xy 50.45536 -139.863232)
			(xy 50.495398 -139.826719) (xy 50.540303 -139.796391) (xy 50.589127 -139.772888) (xy 50.640841 -139.756706)
			(xy 50.694354 -139.748187) (xy 50.748537 -139.747509) (xy 50.802246 -139.754687) (xy 50.854349 -139.769571)
			(xy 50.879248 -139.780264) (xy 50.899619 -139.788978) (xy 50.94255 -139.799921) (xy 50.986728 -139.803252)
			(xy 51.030815 -139.798871) (xy 51.073474 -139.786909) (xy 51.113411 -139.76773) (xy 51.149417 -139.741914)
			(xy 51.165252 -139.726416) (xy 51.184031 -139.707827) (xy 51.225938 -139.675645) (xy 51.271974 -139.64971)
			(xy 51.321214 -139.630543) (xy 51.372669 -139.618529) (xy 51.425306 -139.61391) (xy 51.478067 -139.616778)
			(xy 51.529892 -139.627075) (xy 51.579742 -139.644596) (xy 51.626614 -139.668987) (xy 51.64836 -139.683998)
			(xy 51.660885 -139.692382) (xy 51.688837 -139.703633) (xy 51.718646 -139.70802) (xy 51.748654 -139.705299)
			(xy 51.777189 -139.69562) (xy 51.80266 -139.679525) (xy 51.81346 -139.669012) (xy 51.83481 -139.64762)
			(xy 51.882166 -139.610065) (xy 51.934052 -139.579069) (xy 51.989566 -139.555172) (xy 52.047742 -139.538788)
			(xy 52.107569 -139.530204) (xy 52.168005 -139.529568) (xy 52.227999 -139.536891) (xy 52.286507 -139.552046)
			(xy 52.342512 -139.574769) (xy 52.395039 -139.604666) (xy 52.443175 -139.641215) (xy 52.46497 -139.662154)
			(xy 52.476136 -139.672565) (xy 52.502258 -139.688338) (xy 52.531385 -139.697439) (xy 52.561841 -139.699344)
			(xy 52.591874 -139.693944) (xy 52.619759 -139.681549) (xy 52.632102 -139.672568) (xy 52.654018 -139.656207)
			(xy 52.701746 -139.629499) (xy 52.752866 -139.610056) (xy 52.806279 -139.598294) (xy 52.860838 -139.594467)
			(xy 52.91537 -139.598656) (xy 52.968703 -139.610772) (xy 53.019693 -139.630554) (xy 53.067243 -139.657577)
			(xy 53.110332 -139.691261) (xy 53.148035 -139.730882) (xy 53.17954 -139.775589) (xy 53.204172 -139.824421)
			(xy 53.2214 -139.876329) (xy 53.230856 -139.930198) (xy 53.232335 -139.984871) (xy 53.225807 -140.039172)
			(xy 53.21141 -140.091936) (xy 53.189455 -140.142029) (xy 53.160414 -140.188374) (xy 53.124909 -140.229976)
			(xy 53.083705 -140.265941) (xy 53.037685 -140.295496) (xy 52.98784 -140.318006) (xy 52.935239 -140.332988)
			(xy 52.881014 -140.34012) (xy 52.826328 -140.339249) (xy 52.772357 -140.330393) (xy 52.720261 -140.313742)
			(xy 52.671158 -140.289655) (xy 52.648358 -140.274548) (xy 52.635568 -140.266276) (xy 52.607088 -140.255489)
			(xy 52.576865 -140.251749) (xy 52.546615 -140.255269) (xy 52.518058 -140.265848) (xy 52.492816 -140.282886)
			(xy 52.482242 -140.293852) (xy 52.460858 -140.316665) (xy 52.413022 -140.356928) (xy 52.360149 -140.390304)
			(xy 52.303225 -140.416169) (xy 52.243309 -140.434044) (xy 52.181517 -140.443593) (xy 52.119 -140.444641)
			(xy 52.056923 -140.437167) (xy 51.996442 -140.42131) (xy 51.938683 -140.397366) (xy 51.884722 -140.365781)
			(xy 51.835563 -140.327143) (xy 51.81346 -140.305028) (xy 51.802653 -140.294511) (xy 51.777198 -140.278363)
			(xy 51.74866 -140.268652) (xy 51.718638 -140.265922) (xy 51.688817 -140.270326) (xy 51.660866 -140.281618)
			(xy 51.64836 -140.290042) (xy 51.625413 -140.305781) (xy 51.575839 -140.331048) (xy 51.523062 -140.34867)
			(xy 51.468252 -140.358255) (xy 51.412627 -140.359591) (xy 51.35742 -140.352647) (xy 51.303858 -140.337578)
			(xy 51.278282 -140.326618) (xy 51.257898 -140.317937) (xy 51.214971 -140.306991) (xy 51.170797 -140.303656)
			(xy 51.126713 -140.308033) (xy 51.084056 -140.319989) (xy 51.04412 -140.339162) (xy 51.008114 -140.364971)
			(xy 50.992278 -140.380466) (xy 50.973037 -140.399544) (xy 50.929921 -140.432367) (xy 50.882506 -140.458597)
			(xy 50.831791 -140.477682) (xy 50.778847 -140.489219) (xy 50.72479 -140.492964) (xy 50.67076 -140.488839)
			(xy 50.617898 -140.476931) (xy 50.567318 -140.45749) (xy 50.520088 -140.430927) (xy 50.477205 -140.397803)
			(xy 50.439572 -140.358815) (xy 50.407985 -140.314788) (xy 50.383108 -140.266648) (xy 50.365467 -140.215413)
			(xy 50.355435 -140.162163) (xy 50.353223 -140.108021) (xy 45.454659 -140.108021) (xy 45.46045 -140.135454)
			(xy 45.473846 -140.163157) (xy 45.493499 -140.186835) (xy 45.505624 -140.196316) (xy 45.531532 -140.217144)
			(xy 45.549269 -140.23179) (xy 45.58897 -140.255012) (xy 45.632203 -140.27071) (xy 45.677555 -140.278371)
			(xy 45.723546 -140.277745) (xy 45.768672 -140.268852) (xy 45.811462 -140.251983) (xy 45.831252 -140.240258)
			(xy 45.854065 -140.226561) (xy 45.902705 -140.204985) (xy 45.953871 -140.190377) (xy 46.006572 -140.183021)
			(xy 46.059782 -140.183059) (xy 46.112472 -140.190492) (xy 46.163617 -140.205174) (xy 46.212226 -140.226821)
			(xy 46.257355 -140.255013) (xy 46.278038 -140.271754) (xy 46.295111 -140.285376) (xy 46.332904 -140.307257)
			(xy 46.373881 -140.322357) (xy 46.416836 -140.330232) (xy 46.460504 -140.330651) (xy 46.503602 -140.3236)
			(xy 46.54486 -140.309288) (xy 46.583066 -140.288135) (xy 46.600364 -140.274802) (xy 46.62179 -140.258278)
			(xy 46.668401 -140.23081) (xy 46.718495 -140.210372) (xy 46.771019 -140.197396) (xy 46.824867 -140.192153)
			(xy 46.878907 -140.194754) (xy 46.932003 -140.205144) (xy 46.983038 -140.223105) (xy 47.030938 -140.248259)
			(xy 47.074696 -140.280076) (xy 47.113391 -140.317889) (xy 47.146211 -140.360901) (xy 47.172464 -140.408207)
			(xy 47.191598 -140.458814) (xy 47.203211 -140.511655) (xy 47.207059 -140.565621) (xy 47.20306 -140.619576)
			(xy 47.191299 -140.672385) (xy 47.172024 -140.722938) (xy 47.145639 -140.770171) (xy 47.112699 -140.813091)
			(xy 47.073898 -140.850795) (xy 47.030052 -140.882491) (xy 46.982082 -140.90751) (xy 46.930997 -140.925329)
			(xy 46.877872 -140.93557) (xy 46.823825 -140.93802) (xy 46.769991 -140.932627) (xy 46.717504 -140.919503)
			(xy 46.667467 -140.898926) (xy 46.620933 -140.871328) (xy 46.599602 -140.854684) (xy 46.582345 -140.841285)
			(xy 46.544177 -140.82003) (xy 46.502934 -140.805622) (xy 46.459834 -140.798486) (xy 46.416148 -140.798832)
			(xy 46.373167 -140.806651) (xy 46.332157 -140.821711) (xy 46.294331 -140.843569) (xy 46.277276 -140.857224)
			(xy 46.256589 -140.873867) (xy 46.211476 -140.901862) (xy 46.162919 -140.923334) (xy 46.111854 -140.93787)
			(xy 46.059268 -140.94519) (xy 46.006175 -140.945151) (xy 45.953599 -140.937755) (xy 45.902556 -140.923144)
			(xy 45.85403 -140.9016) (xy 45.831252 -140.887958) (xy 45.811446 -140.876265) (xy 45.768663 -140.859397)
			(xy 45.723542 -140.850505) (xy 45.677558 -140.849879) (xy 45.632212 -140.857539) (xy 45.588986 -140.873236)
			(xy 45.54929 -140.896456) (xy 45.531532 -140.911072) (xy 45.508278 -140.930492) (xy 45.457526 -140.963586)
			(xy 45.402851 -140.989693) (xy 45.345209 -141.008358) (xy 45.285609 -141.019253) (xy 45.225092 -141.022189)
			(xy 45.164716 -141.017113) (xy 45.105539 -141.004116) (xy 45.048594 -140.983423) (xy 44.994877 -140.955397)
			(xy 44.945328 -140.920528) (xy 44.900814 -140.879426) (xy 44.862112 -140.832809) (xy 44.8299 -140.781494)
			(xy 44.80474 -140.726376) (xy 44.787074 -140.668421) (xy 44.77721 -140.608641) (xy 44.77532 -140.548082)
			(xy 44.259153 -140.548082) (xy 44.237964 -140.564341) (xy 44.186058 -140.594308) (xy 44.130685 -140.617244)
			(xy 44.072792 -140.632757) (xy 44.01337 -140.64058) (xy 43.953434 -140.64058) (xy 43.894012 -140.632757)
			(xy 43.836119 -140.617244) (xy 43.780746 -140.594308) (xy 43.72884 -140.564341) (xy 43.68129 -140.527854)
			(xy 43.63891 -140.485474) (xy 43.602423 -140.437924) (xy 43.572456 -140.386018) (xy 43.54952 -140.330645)
			(xy 43.534007 -140.272752) (xy 43.526184 -140.21333) (xy 42.846354 -140.21333) (xy 42.855616 -140.229372)
			(xy 42.878552 -140.284745) (xy 42.894065 -140.342638) (xy 42.901888 -140.40206) (xy 42.902378 -140.432028)
			(xy 42.901888 -140.461996) (xy 42.894065 -140.521418) (xy 42.878552 -140.579311) (xy 42.855616 -140.634684)
			(xy 42.825649 -140.68659) (xy 42.789162 -140.73414) (xy 42.746782 -140.77652) (xy 42.699232 -140.813007)
			(xy 42.647326 -140.842974) (xy 42.591953 -140.86591) (xy 42.53406 -140.881423) (xy 42.474638 -140.889246)
			(xy 42.414702 -140.889246) (xy 42.35528 -140.881423) (xy 42.297387 -140.86591) (xy 42.242014 -140.842974)
			(xy 42.190108 -140.813007) (xy 42.142558 -140.77652) (xy 42.100178 -140.73414) (xy 42.063691 -140.68659)
			(xy 42.033724 -140.634684) (xy 42.010788 -140.579311) (xy 41.995275 -140.521418) (xy 41.987452 -140.461996)
			(xy 41.586604 -140.461996) (xy 41.595208 -140.495694) (xy 41.600853 -140.549897) (xy 41.598542 -140.604344)
			(xy 41.588323 -140.657874) (xy 41.570415 -140.709344) (xy 41.545199 -140.757656) (xy 41.513214 -140.801778)
			(xy 41.475142 -140.84077) (xy 41.431796 -140.8738) (xy 41.3841 -140.900162) (xy 41.333073 -140.919295)
			(xy 41.279802 -140.930789) (xy 41.225426 -140.9344) (xy 41.171103 -140.930051) (xy 41.117994 -140.917834)
			(xy 41.067231 -140.89801) (xy 41.019898 -140.871002) (xy 40.977005 -140.837387) (xy 40.939466 -140.797881)
			(xy 40.908083 -140.753328) (xy 40.883526 -140.704678) (xy 40.866319 -140.65297) (xy 40.856828 -140.599306)
			(xy 40.855257 -140.544832) (xy 40.861638 -140.490711) (xy 40.875836 -140.438097) (xy 40.897548 -140.388112)
			(xy 40.911526 -140.364718) (xy 40.92329 -140.344869) (xy 40.940155 -140.301927) (xy 40.948995 -140.256646)
			(xy 40.949519 -140.210514) (xy 40.94171 -140.165044) (xy 40.925824 -140.12173) (xy 40.902383 -140.081993)
			(xy 40.88765 -140.064236) (xy 40.868328 -140.041303) (xy 40.835276 -139.991263) (xy 40.809043 -139.937336)
			(xy 40.790078 -139.880444) (xy 40.778705 -139.821562) (xy 40.775121 -139.7617) (xy 39.728372 -139.7617)
			(xy 39.863268 -139.896596) (xy 39.863268 -140.620242) (xy 39.684706 -140.798804) (xy 39.29634 -140.798804)
			(xy 39.279687 -140.79933) (xy 39.247513 -140.807942) (xy 39.218665 -140.824589) (xy 39.195111 -140.848137)
			(xy 39.178455 -140.87698) (xy 39.169834 -140.909151) (xy 39.16934 -140.925804) (xy 39.16934 -141.419072)
			(xy 39.011102 -141.57731) (xy 41.264568 -141.57731) (xy 41.264568 -141.517374) (xy 41.272391 -141.457952)
			(xy 41.287904 -141.400059) (xy 41.31084 -141.344686) (xy 41.340807 -141.29278) (xy 41.377294 -141.24523)
			(xy 41.419674 -141.20285) (xy 41.467224 -141.166363) (xy 41.51913 -141.136396) (xy 41.574503 -141.11346)
			(xy 41.632396 -141.097947) (xy 41.691818 -141.090124) (xy 41.751754 -141.090124) (xy 41.811176 -141.097947)
			(xy 41.869069 -141.11346) (xy 41.924442 -141.136396) (xy 41.976348 -141.166363) (xy 42.023898 -141.20285)
			(xy 42.066278 -141.24523) (xy 42.102765 -141.29278) (xy 42.132732 -141.344686) (xy 42.155668 -141.400059)
			(xy 42.168555 -141.448151) (xy 47.365916 -141.448151) (xy 47.370254 -141.386602) (xy 47.382396 -141.326107)
			(xy 47.402142 -141.267651) (xy 47.429173 -141.212186) (xy 47.463047 -141.160614) (xy 47.48276 -141.136878)
			(xy 47.492201 -141.125165) (xy 47.505851 -141.098364) (xy 47.512843 -141.069113) (xy 47.51324 -141.054074)
			(xy 47.51324 -140.831824) (xy 47.50943 -140.81633) (xy 47.502614 -140.788222) (xy 47.494955 -140.730893)
			(xy 47.494191 -140.67306) (xy 47.500334 -140.615548) (xy 47.513296 -140.559181) (xy 47.532892 -140.504763)
			(xy 47.558841 -140.453072) (xy 47.574454 -140.428726) (xy 47.595536 -140.396976) (xy 47.595536 -140.339572)
			(xy 47.650654 -140.339572) (xy 47.672979 -140.319715) (xy 47.721669 -140.285085) (xy 47.774259 -140.256724)
			(xy 47.829944 -140.235065) (xy 47.887876 -140.220439) (xy 47.947169 -140.21307) (xy 48.006919 -140.21307)
			(xy 48.066212 -140.220439) (xy 48.124144 -140.235065) (xy 48.179829 -140.256724) (xy 48.232419 -140.285085)
			(xy 48.281109 -140.319715) (xy 48.303434 -140.339572) (xy 48.358552 -140.339572) (xy 48.358552 -140.393928)
			(xy 48.479456 -140.514832) (xy 48.479456 -141.504416) (xy 48.190912 -141.79296) (xy 48.168692 -141.814369)
			(xy 48.119853 -141.852076) (xy 48.06661 -141.883256) (xy 48.009829 -141.907402) (xy 47.950436 -141.924119)
			(xy 47.889397 -141.933137) (xy 47.827707 -141.934307) (xy 47.76637 -141.927611) (xy 47.706385 -141.913158)
			(xy 47.648729 -141.891184) (xy 47.594342 -141.862045) (xy 47.544108 -141.826218) (xy 47.498846 -141.784284)
			(xy 47.459293 -141.736928) (xy 47.426094 -141.68492) (xy 47.399788 -141.629107) (xy 47.380804 -141.570399)
			(xy 47.369452 -141.50975) (xy 47.365916 -141.448151) (xy 42.168555 -141.448151) (xy 42.171181 -141.457952)
			(xy 42.179004 -141.517374) (xy 42.179494 -141.547342) (xy 42.179004 -141.57731) (xy 42.171181 -141.636732)
			(xy 42.155668 -141.694625) (xy 42.132732 -141.749998) (xy 42.102765 -141.801904) (xy 42.066278 -141.849454)
			(xy 42.023898 -141.891834) (xy 41.976348 -141.928321) (xy 41.948859 -141.944191) (xy 42.581011 -141.944191)
			(xy 42.582343 -141.884139) (xy 42.591518 -141.824777) (xy 42.608379 -141.767125) (xy 42.632637 -141.712174)
			(xy 42.663874 -141.660868) (xy 42.701553 -141.614089) (xy 42.745028 -141.572641) (xy 42.793551 -141.537235)
			(xy 42.846289 -141.508481) (xy 42.902334 -141.486872) (xy 42.960725 -141.47278) (xy 43.020457 -141.466447)
			(xy 43.080504 -141.467981) (xy 43.139835 -141.477357) (xy 43.197429 -141.494413) (xy 43.252298 -141.518856)
			(xy 43.303498 -141.550266) (xy 43.350149 -141.588104) (xy 43.391451 -141.631719) (xy 43.426692 -141.680361)
			(xy 43.455268 -141.733196) (xy 43.476687 -141.789314) (xy 43.490581 -141.847752) (xy 43.496713 -141.907505)
			(xy 43.494975 -141.967547) (xy 43.485399 -142.026846) (xy 43.468148 -142.084382) (xy 43.44352 -142.139168)
			(xy 43.411936 -142.190261) (xy 43.373941 -142.236784) (xy 43.330187 -142.277938) (xy 43.281426 -142.313014)
			(xy 43.255184 -142.32763) (xy 43.241536 -142.335517) (xy 43.218237 -142.356729) (xy 43.200864 -142.383015)
			(xy 43.190482 -142.412764) (xy 43.187727 -142.444152) (xy 43.192768 -142.475254) (xy 43.205295 -142.504165)
			(xy 43.224542 -142.529111) (xy 43.236642 -142.539212) (xy 43.245331 -142.546216) (xy 43.26198 -142.561083)
			(xy 43.269916 -142.56893) (xy 43.28706 -142.585396) (xy 43.326346 -142.612152) (xy 43.369923 -142.631135)
			(xy 43.416271 -142.64168) (xy 43.463771 -142.643421) (xy 43.510766 -142.636297) (xy 43.555616 -142.620556)
			(xy 43.596756 -142.596747) (xy 43.615102 -142.58163) (xy 43.63836 -142.562271) (xy 43.689008 -142.52916)
			(xy 43.743579 -142.503013) (xy 43.80112 -142.484287) (xy 43.860627 -142.473309) (xy 43.921063 -142.47027)
			(xy 43.981371 -142.475223) (xy 44.0405 -142.488083) (xy 44.097419 -142.508623) (xy 44.151133 -142.536487)
			(xy 44.200707 -142.571188) (xy 44.245273 -142.61212) (xy 44.284056 -142.658569) (xy 44.316379 -142.709725)
			(xy 44.341676 -142.764695) (xy 44.359507 -142.82252) (xy 44.369561 -142.88219) (xy 44.371662 -142.942665)
			(xy 44.365774 -143.002889) (xy 44.352 -143.061812) (xy 44.330579 -143.118405) (xy 44.301885 -143.171681)
			(xy 44.26642 -143.22071) (xy 44.224801 -143.264637) (xy 44.177756 -143.302695) (xy 44.126105 -143.33422)
			(xy 44.07075 -143.358662) (xy 44.012655 -143.375594) (xy 43.952836 -143.384721) (xy 43.892336 -143.385885)
			(xy 43.83221 -143.379063) (xy 43.773508 -143.364376) (xy 43.717254 -143.34208) (xy 43.664429 -143.312564)
			(xy 43.615956 -143.276342) (xy 43.57268 -143.234048) (xy 43.553634 -143.210534) (xy 43.538588 -143.192137)
			(xy 43.502818 -143.160848) (xy 43.461856 -143.136751) (xy 43.417131 -143.120687) (xy 43.370198 -143.113214)
			(xy 43.322695 -143.114592) (xy 43.276275 -143.124774) (xy 43.232556 -143.143406) (xy 43.212512 -143.156178)
			(xy 43.189351 -143.171076) (xy 43.139634 -143.194761) (xy 43.087029 -143.211053) (xy 43.032628 -143.219612)
			(xy 42.977562 -143.220262) (xy 42.922975 -143.212988) (xy 42.87 -143.197942) (xy 42.819738 -143.175436)
			(xy 42.773235 -143.145939) (xy 42.731455 -143.110062) (xy 42.695267 -143.068551) (xy 42.665423 -143.022269)
			(xy 42.642543 -142.972177) (xy 42.627102 -142.919316) (xy 42.619421 -142.864784) (xy 42.619659 -142.809714)
			(xy 42.627812 -142.755251) (xy 42.643711 -142.702526) (xy 42.667024 -142.652634) (xy 42.697268 -142.606612)
			(xy 42.71518 -142.585694) (xy 42.730537 -142.567663) (xy 42.754861 -142.527026) (xy 42.77124 -142.482589)
			(xy 42.779109 -142.435887) (xy 42.778196 -142.388536) (xy 42.768533 -142.342172) (xy 42.750453 -142.298399)
			(xy 42.724581 -142.25873) (xy 42.708576 -142.24127) (xy 42.688136 -142.219259) (xy 42.652567 -142.170856)
			(xy 42.623634 -142.118216) (xy 42.601836 -142.062244) (xy 42.587547 -142.003902) (xy 42.581011 -141.944191)
			(xy 41.948859 -141.944191) (xy 41.924442 -141.958288) (xy 41.869069 -141.981224) (xy 41.811176 -141.996737)
			(xy 41.751754 -142.00456) (xy 41.691818 -142.00456) (xy 41.632396 -141.996737) (xy 41.574503 -141.981224)
			(xy 41.51913 -141.958288) (xy 41.467224 -141.928321) (xy 41.419674 -141.891834) (xy 41.377294 -141.849454)
			(xy 41.340807 -141.801904) (xy 41.31084 -141.749998) (xy 41.287904 -141.694625) (xy 41.272391 -141.636732)
			(xy 41.264568 -141.57731) (xy 39.011102 -141.57731) (xy 38.842696 -141.745716) (xy 37.794438 -141.745716)
			(xy 37.724334 -141.675612) (xy 37.712216 -141.664173) (xy 37.683377 -141.647497) (xy 37.651202 -141.638865)
			(xy 37.617888 -141.638865) (xy 37.585713 -141.647497) (xy 37.556874 -141.664173) (xy 37.544756 -141.675612)
			(xy 37.453824 -141.766544) (xy 36.03625 -141.766544) (xy 35.256216 -140.98651) (xy 32.34182 -140.98651)
			(xy 32.34182 -143.562578) (xy 33.37306 -144.593818) (xy 35.012376 -144.593818)
		)
		(stroke
			(width 0)
			(type solid)
		)
		(fill yes)
		(layer "B.Cu")
		(net "P1V538_BMC_NODE1")
	)
	(gr_poly
		(pts
			(xy 106.545634 -40.147748) (xy 106.562282 -40.147201) (xy 106.594441 -40.138578) (xy 106.623275 -40.121929)
			(xy 106.64682 -40.098387) (xy 106.663473 -40.069554) (xy 106.672099 -40.037396) (xy 106.672634 -40.020748)
			(xy 106.672634 -40.019986) (xy 106.673045 -39.992698) (xy 106.680714 -39.938664) (xy 106.696004 -39.886275)
			(xy 106.718603 -39.836599) (xy 106.74805 -39.79065) (xy 106.783744 -39.749366) (xy 106.824957 -39.713589)
			(xy 106.870847 -39.684051) (xy 106.920478 -39.661352) (xy 106.972836 -39.645958) (xy 107.026854 -39.638181)
			(xy 107.08143 -39.638181) (xy 107.135448 -39.645958) (xy 107.187806 -39.661352) (xy 107.237437 -39.684051)
			(xy 107.283327 -39.713589) (xy 107.32454 -39.749366) (xy 107.360234 -39.79065) (xy 107.389681 -39.836599)
			(xy 107.41228 -39.886275) (xy 107.42757 -39.938664) (xy 107.435239 -39.992698) (xy 107.43565 -40.019986)
			(xy 107.43565 -40.020748) (xy 107.43615 -40.037396) (xy 107.444781 -40.069555) (xy 107.46144 -40.098385)
			(xy 107.484993 -40.12192) (xy 107.513836 -40.138557) (xy 107.546001 -40.147162) (xy 107.56265 -40.147748)
			(xy 108.27766 -40.147748) (xy 108.83392 -39.591488) (xy 108.83392 -38.78199) (xy 111.4552 -38.78199)
			(xy 113.064036 -37.173154) (xy 113.073434 -37.15385) (xy 113.08492 -37.131185) (xy 113.113005 -37.088842)
			(xy 113.146463 -37.050601) (xy 113.184699 -37.017138) (xy 113.227039 -36.989046) (xy 113.24971 -36.977574)
			(xy 113.269014 -36.968176) (xy 119.23522 -31.00197) (xy 119.23522 -27.634438) (xy 117.540024 -25.939242)
			(xy 116.012722 -25.939242) (xy 115.56238 -26.389584) (xy 115.56238 -27.308302) (xy 115.4557 -27.414982)
			(xy 113.549684 -27.414982) (xy 113.42878 -27.294078) (xy 113.42878 -26.066242) (xy 113.42829 -26.049585)
			(xy 113.419676 -26.017403) (xy 113.403024 -25.988549) (xy 113.379469 -25.96499) (xy 113.350617 -25.948332)
			(xy 113.318437 -25.939712) (xy 113.30178 -25.939242) (xy 107.728258 -25.939242) (xy 106.815382 -25.026366)
			(xy 106.799645 -25.011239) (xy 106.763985 -24.986068) (xy 106.724549 -24.967362) (xy 106.682496 -24.955669)
			(xy 106.639064 -24.951334) (xy 106.59553 -24.954485) (xy 106.553174 -24.965029) (xy 106.513244 -24.982655)
			(xy 106.476912 -25.006845) (xy 106.445249 -25.036888) (xy 106.419185 -25.0719) (xy 106.399487 -25.110851)
			(xy 106.386735 -25.152594) (xy 106.383582 -25.174194) (xy 106.377557 -25.218018) (xy 106.358696 -25.30445)
			(xy 106.332209 -25.388858) (xy 106.298305 -25.47057) (xy 106.257255 -25.548935) (xy 106.209385 -25.623331)
			(xy 106.155077 -25.693165) (xy 106.094761 -25.757882) (xy 106.028918 -25.816967) (xy 105.958073 -25.86995)
			(xy 105.882788 -25.916409) (xy 105.803662 -25.955974) (xy 105.721326 -25.988331) (xy 105.636433 -26.013223)
			(xy 105.549661 -26.03045) (xy 105.461698 -26.039877) (xy 105.373246 -26.041428) (xy 105.285007 -26.035091)
			(xy 105.197684 -26.020917) (xy 105.111971 -25.999017) (xy 105.02855 -25.969566) (xy 104.948086 -25.9328)
			(xy 104.871219 -25.889009) (xy 104.798559 -25.838543) (xy 104.730685 -25.781803) (xy 104.668138 -25.71924)
			(xy 104.611414 -25.651353) (xy 104.560965 -25.578681) (xy 104.517193 -25.501803) (xy 104.480445 -25.42133)
			(xy 104.451014 -25.337903) (xy 104.429135 -25.252185) (xy 104.414981 -25.164858) (xy 104.408665 -25.076618)
			(xy 104.410237 -24.988166) (xy 104.419685 -24.900205) (xy 104.436934 -24.813437) (xy 104.461845 -24.728551)
			(xy 104.494222 -24.646222) (xy 104.533806 -24.567106) (xy 104.580283 -24.491832) (xy 104.633283 -24.420999)
			(xy 104.692383 -24.35517) (xy 104.757115 -24.29487) (xy 104.826962 -24.240578) (xy 104.901369 -24.192726)
			(xy 104.979745 -24.151694) (xy 105.061465 -24.11781) (xy 105.145879 -24.091343) (xy 105.232316 -24.072503)
			(xy 105.276142 -24.0665) (xy 105.297716 -24.063296) (xy 105.339402 -24.050479) (xy 105.378289 -24.030736)
			(xy 105.413236 -24.004646) (xy 105.443219 -23.972976) (xy 105.467358 -23.936654) (xy 105.484944 -23.896745)
			(xy 105.495462 -23.85442) (xy 105.498602 -23.810922) (xy 105.494274 -23.767525) (xy 105.482604 -23.725504)
			(xy 105.463935 -23.686091) (xy 105.438813 -23.650441) (xy 105.423716 -23.6347) (xy 104.193848 -22.404832)
			(xy 104.177206 -22.388866) (xy 104.139279 -22.362634) (xy 104.097243 -22.343673) (xy 104.052476 -22.332605)
			(xy 104.006448 -22.329793) (xy 103.960667 -22.335329) (xy 103.916635 -22.349032) (xy 103.875797 -22.370452)
			(xy 103.839493 -22.398887) (xy 103.808912 -22.433404) (xy 103.785059 -22.47287) (xy 103.768715 -22.515991)
			(xy 103.760417 -22.561353) (xy 103.760016 -22.58441) (xy 103.760016 -22.766782) (xy 103.760493 -22.788905)
			(xy 103.768158 -22.832483) (xy 103.783257 -22.874073) (xy 103.805336 -22.912418) (xy 103.833725 -22.946356)
			(xy 103.867565 -22.974862) (xy 103.905833 -22.997072) (xy 103.947371 -23.012315) (xy 103.969058 -23.016718)
			(xy 103.995581 -23.021984) (xy 104.046904 -23.039008) (xy 104.095309 -23.063109) (xy 104.139825 -23.093804)
			(xy 104.17956 -23.130479) (xy 104.213718 -23.172397) (xy 104.241614 -23.218719) (xy 104.262688 -23.268516)
			(xy 104.276519 -23.32079) (xy 104.282829 -23.374494) (xy 104.281492 -23.42855) (xy 104.272534 -23.481876)
			(xy 104.256136 -23.533402) (xy 104.232625 -23.582096) (xy 104.202472 -23.626982) (xy 104.166284 -23.66716)
			(xy 104.124784 -23.701825) (xy 104.078804 -23.730282) (xy 104.029267 -23.75196) (xy 104.003348 -23.759668)
			(xy 103.982438 -23.765972) (xy 103.942998 -23.784721) (xy 103.907339 -23.80993) (xy 103.876509 -23.840858)
			(xy 103.851414 -23.876597) (xy 103.83279 -23.916096) (xy 103.821186 -23.958195) (xy 103.816941 -24.001658)
			(xy 103.820181 -24.045208) (xy 103.82504 -24.0665) (xy 103.831334 -24.093442) (xy 103.836988 -24.148479)
			(xy 103.834633 -24.203756) (xy 103.82432 -24.258113) (xy 103.806263 -24.31041) (xy 103.780843 -24.359551)
			(xy 103.748592 -24.404505) (xy 103.710185 -24.44433) (xy 103.66643 -24.47819) (xy 103.618243 -24.505376)
			(xy 103.566635 -24.525316) (xy 103.512688 -24.537594) (xy 103.457533 -24.541951) (xy 103.402327 -24.538297)
			(xy 103.348228 -24.526707) (xy 103.29637 -24.507425) (xy 103.24784 -24.480856) (xy 103.203657 -24.447555)
			(xy 103.164747 -24.408223) (xy 103.131926 -24.363683) (xy 103.105882 -24.31487) (xy 103.09606 -24.289004)
			(xy 103.090106 -24.273867) (xy 103.071744 -24.247031) (xy 103.047194 -24.225709) (xy 103.018051 -24.211286)
			(xy 102.986208 -24.2047) (xy 102.953735 -24.206377) (xy 102.938072 -24.210772) (xy 102.91162 -24.218667)
			(xy 102.85715 -24.22763) (xy 102.801958 -24.228652) (xy 102.747194 -24.221711) (xy 102.694002 -24.206951)
			(xy 102.643492 -24.18468) (xy 102.596718 -24.155364) (xy 102.57536 -24.137874) (xy 102.558641 -24.124218)
			(xy 102.521509 -24.102207) (xy 102.48119 -24.086789) (xy 102.438846 -24.078409) (xy 102.395694 -24.077308)
			(xy 102.352977 -24.083516) (xy 102.311924 -24.096857) (xy 102.273717 -24.116944) (xy 102.256336 -24.129746)
			(xy 102.235615 -24.145093) (xy 102.190841 -24.170668) (xy 102.143033 -24.189986) (xy 102.09306 -24.202697)
			(xy 102.041832 -24.208569) (xy 101.990279 -24.207495) (xy 101.964744 -24.203914) (xy 101.943145 -24.200956)
			(xy 101.899558 -24.2016) (xy 101.856721 -24.209677) (xy 101.815892 -24.224949) (xy 101.77827 -24.246968)
			(xy 101.744959 -24.275087) (xy 101.716938 -24.308479) (xy 101.69503 -24.346166) (xy 101.679878 -24.38704)
			(xy 101.675438 -24.408384) (xy 101.673193 -24.419896) (xy 101.667473 -24.442645) (xy 101.664008 -24.45385)
			(xy 101.657361 -24.476667) (xy 101.651724 -24.52385) (xy 101.654962 -24.571259) (xy 101.666961 -24.617238)
			(xy 101.687303 -24.660183) (xy 101.715278 -24.698594) (xy 101.749909 -24.731132) (xy 101.789988 -24.756661)
			(xy 101.811836 -24.766016) (xy 101.839753 -24.777731) (xy 101.892492 -24.807466) (xy 101.940852 -24.843892)
			(xy 101.983989 -24.886374) (xy 102.02115 -24.934171) (xy 102.051688 -24.986449) (xy 102.075069 -25.042295)
			(xy 102.090886 -25.100736) (xy 102.098862 -25.160752) (xy 102.098859 -25.221296) (xy 102.090877 -25.281311)
			(xy 102.075054 -25.33975) (xy 102.051667 -25.395594) (xy 102.021123 -25.447869) (xy 101.983957 -25.495662)
			(xy 101.940815 -25.538139) (xy 101.892452 -25.57456) (xy 101.83971 -25.604289) (xy 101.78351 -25.626808)
			(xy 101.724832 -25.641723) (xy 101.664701 -25.648774) (xy 101.604165 -25.647838) (xy 101.54428 -25.638932)
			(xy 101.486091 -25.622211) (xy 101.430614 -25.597967) (xy 101.378816 -25.566622) (xy 101.331601 -25.528724)
			(xy 101.289792 -25.484934) (xy 101.254121 -25.436015) (xy 101.225207 -25.382822) (xy 101.203557 -25.326282)
			(xy 101.189547 -25.267381) (xy 101.183423 -25.207148) (xy 101.185291 -25.146634) (xy 101.195118 -25.086893)
			(xy 101.212733 -25.028969) (xy 101.224842 -25.00122) (xy 101.234211 -24.979386) (xy 101.245548 -24.93325)
			(xy 101.24812 -24.885812) (xy 101.241839 -24.838722) (xy 101.226922 -24.793617) (xy 101.203888 -24.752066)
			(xy 101.173539 -24.715516) (xy 101.136931 -24.685237) (xy 101.116384 -24.673306) (xy 101.092023 -24.659335)
			(xy 101.047319 -24.625347) (xy 101.00808 -24.585174) (xy 100.975153 -24.539683) (xy 100.94925 -24.489857)
			(xy 100.930929 -24.436772) (xy 100.920588 -24.381576) (xy 100.918448 -24.325459) (xy 100.924557 -24.269636)
			(xy 100.938782 -24.21531) (xy 100.960817 -24.163656) (xy 100.990184 -24.11579) (xy 101.026251 -24.072746)
			(xy 101.068237 -24.035453) (xy 101.115236 -24.004717) (xy 101.166232 -23.981201) (xy 101.220125 -23.965415)
			(xy 101.275749 -23.957698) (xy 101.331904 -23.958217) (xy 101.359716 -23.962106) (xy 101.381317 -23.965068)
			(xy 101.42491 -23.964429) (xy 101.467753 -23.956357) (xy 101.50859 -23.941088) (xy 101.54622 -23.919072)
			(xy 101.579538 -23.890954) (xy 101.607566 -23.85756) (xy 101.629481 -23.819871) (xy 101.64464 -23.778994)
			(xy 101.649022 -23.757636) (xy 101.654597 -23.730191) (xy 101.672719 -23.677202) (xy 101.698393 -23.627431)
			(xy 101.731066 -23.581947) (xy 101.770037 -23.541729) (xy 101.814469 -23.507639) (xy 101.863407 -23.480411)
			(xy 101.915799 -23.460629) (xy 101.97052 -23.448718) (xy 102.026395 -23.444935) (xy 102.082222 -23.44936)
			(xy 102.136803 -23.461899) (xy 102.188965 -23.482281) (xy 102.237587 -23.51007) (xy 102.259892 -23.527004)
			(xy 102.27833 -23.540867) (xy 102.319136 -23.562372) (xy 102.363153 -23.576159) (xy 102.408936 -23.581775)
			(xy 102.45498 -23.579034) (xy 102.499774 -23.568028) (xy 102.541845 -23.549117) (xy 102.579812 -23.522924)
			(xy 102.596442 -23.506938) (xy 102.884224 -23.218902) (xy 102.884224 -23.038816) (xy 102.883683 -23.022165)
			(xy 102.875068 -22.989997) (xy 102.858421 -22.961154) (xy 102.834877 -22.937603) (xy 102.80604 -22.920947)
			(xy 102.773875 -22.912322) (xy 102.757224 -22.911816) (xy 102.753414 -22.911816) (xy 102.726006 -22.91158)
			(xy 102.671694 -22.904209) (xy 102.618996 -22.889141) (xy 102.568996 -22.866688) (xy 102.522724 -22.837311)
			(xy 102.481132 -22.801614) (xy 102.445076 -22.760334) (xy 102.415298 -22.714319) (xy 102.392411 -22.664516)
			(xy 102.376886 -22.611951) (xy 102.369043 -22.557705) (xy 102.369043 -22.502895) (xy 102.376886 -22.448649)
			(xy 102.392411 -22.396084) (xy 102.415298 -22.346281) (xy 102.445076 -22.300266) (xy 102.481132 -22.258986)
			(xy 102.522724 -22.223289) (xy 102.568996 -22.193912) (xy 102.618996 -22.171459) (xy 102.671694 -22.156391)
			(xy 102.726006 -22.14902) (xy 102.753414 -22.1488) (xy 102.757224 -22.1488) (xy 102.77387 -22.148254)
			(xy 102.806027 -22.139632) (xy 102.834857 -22.122982) (xy 102.858397 -22.099438) (xy 102.875041 -22.070605)
			(xy 102.883657 -22.038446) (xy 102.884224 -22.0218) (xy 102.884224 -21.095208) (xy 100.56241 -18.773394)
			(xy 100.545983 -18.757678) (xy 100.508635 -18.731765) (xy 100.467273 -18.71291) (xy 100.423217 -18.701712)
			(xy 100.377872 -18.69853) (xy 100.332684 -18.703465) (xy 100.289094 -18.71636) (xy 100.248494 -18.736803)
			(xy 100.212177 -18.764143) (xy 100.196396 -18.780506) (xy 100.176106 -18.801591) (xy 100.13026 -18.837952)
			(xy 100.079403 -18.866891) (xy 100.024726 -18.887731) (xy 99.967509 -18.899983) (xy 99.909092 -18.903359)
			(xy 99.879912 -18.901156) (xy 99.857136 -18.899468) (xy 99.811632 -18.903327) (xy 99.76755 -18.915259)
			(xy 99.726312 -18.934879) (xy 99.689245 -18.961554) (xy 99.657544 -18.994426) (xy 99.63223 -19.032435)
			(xy 99.614118 -19.074357) (xy 99.603791 -19.118842) (xy 99.601584 -19.164456) (xy 99.604068 -19.18716)
			(xy 99.607543 -19.217267) (xy 99.607467 -19.277872) (xy 99.599396 -19.337937) (xy 99.583469 -19.396412)
			(xy 99.559967 -19.452275) (xy 99.529299 -19.504548) (xy 99.492001 -19.552317) (xy 99.448727 -19.594747)
			(xy 99.400232 -19.631097) (xy 99.347366 -19.66073) (xy 99.291051 -19.683128) (xy 99.232274 -19.697899)
			(xy 99.172061 -19.704787) (xy 99.111466 -19.703669) (xy 99.051549 -19.694565) (xy 98.993356 -19.677635)
			(xy 98.937906 -19.653175) (xy 98.886169 -19.621612) (xy 98.839048 -19.583498) (xy 98.797369 -19.539501)
			(xy 98.761859 -19.490388) (xy 98.73314 -19.437019) (xy 98.711714 -19.380328) (xy 98.697955 -19.321305)
			(xy 98.692105 -19.260983) (xy 98.694265 -19.200416) (xy 98.704398 -19.140664) (xy 98.722327 -19.082771)
			(xy 98.747737 -19.027751) (xy 98.780186 -18.976564) (xy 98.819104 -18.930106) (xy 98.863812 -18.889189)
			(xy 98.913529 -18.854529) (xy 98.967383 -18.826733) (xy 99.024435 -18.806285) (xy 99.083686 -18.793544)
			(xy 99.1441 -18.788732) (xy 99.20462 -18.791934) (xy 99.234498 -18.797016) (xy 99.257038 -18.800751)
			(xy 99.302722 -18.801007) (xy 99.347716 -18.793091) (xy 99.39057 -18.777259) (xy 99.429903 -18.754021)
			(xy 99.464448 -18.724126) (xy 99.493092 -18.688536) (xy 99.514912 -18.648399) (xy 99.529204 -18.605008)
			(xy 99.535509 -18.55976) (xy 99.53498 -18.53692) (xy 99.534339 -18.506395) (xy 99.541613 -18.445777)
			(xy 99.549458 -18.41627) (xy 99.555454 -18.393525) (xy 99.559891 -18.346702) (xy 99.555639 -18.299862)
			(xy 99.542843 -18.254603) (xy 99.521941 -18.212471) (xy 99.493644 -18.174902) (xy 99.45892 -18.143179)
			(xy 99.418954 -18.118385) (xy 99.375108 -18.101366) (xy 99.32888 -18.092703) (xy 99.305364 -18.092166)
			(xy 90.99931 -18.092166) (xy 90.673682 -17.766538) (xy 86.755986 -17.766538) (xy 86.732953 -17.76704)
			(xy 86.687643 -17.775346) (xy 86.644572 -17.791683) (xy 86.605152 -17.815517) (xy 86.570673 -17.846066)
			(xy 86.542266 -17.882329) (xy 86.520861 -17.923119) (xy 86.507159 -17.967099) (xy 86.50161 -18.012829)
			(xy 86.504394 -18.05881) (xy 86.515421 -18.103536) (xy 86.534329 -18.145542) (xy 86.5605 -18.183451)
			(xy 86.576408 -18.200116) (xy 86.65591 -18.279872) (xy 86.678145 -18.302816) (xy 86.717306 -18.353302)
			(xy 86.749831 -18.408298) (xy 86.775206 -18.466937) (xy 86.793032 -18.528294) (xy 86.803027 -18.591401)
			(xy 86.805034 -18.655263) (xy 86.799021 -18.718874) (xy 86.785083 -18.781228) (xy 86.76344 -18.841345)
			(xy 86.745294 -18.876959) (xy 89.096534 -18.876959) (xy 89.099723 -18.815816) (xy 89.111032 -18.755644)
			(xy 89.130261 -18.697516) (xy 89.157067 -18.642469) (xy 89.19097 -18.591487) (xy 89.231366 -18.545479)
			(xy 89.277535 -18.505266) (xy 89.328651 -18.471565) (xy 89.383803 -18.444979) (xy 89.442007 -18.425981)
			(xy 89.502224 -18.41491) (xy 89.563379 -18.411965) (xy 89.624381 -18.417197) (xy 89.684141 -18.430514)
			(xy 89.741593 -18.451677) (xy 89.795712 -18.48031) (xy 89.845531 -18.5159) (xy 89.890162 -18.557813)
			(xy 89.928808 -18.605301) (xy 89.94521 -18.631154) (xy 89.956945 -18.649387) (xy 89.985518 -18.681992)
			(xy 90.019212 -18.709274) (xy 90.057048 -18.730439) (xy 90.097928 -18.744874) (xy 90.140666 -18.75216)
			(xy 90.184019 -18.752084) (xy 90.226731 -18.744649) (xy 90.267561 -18.730072) (xy 90.305323 -18.708774)
			(xy 90.3224 -18.695416) (xy 90.343933 -18.678369) (xy 90.39101 -18.650082) (xy 90.441658 -18.628838)
			(xy 90.494828 -18.615077) (xy 90.549422 -18.609084) (xy 90.604311 -18.610982) (xy 90.658361 -18.620732)
			(xy 90.710454 -18.638133) (xy 90.759512 -18.662824) (xy 90.804523 -18.694296) (xy 90.844556 -18.731897)
			(xy 90.878782 -18.77485) (xy 90.906494 -18.822268) (xy 90.92712 -18.87317) (xy 90.940233 -18.926504)
			(xy 90.945561 -18.981167) (xy 90.942996 -19.036029) (xy 90.932589 -19.089956) (xy 90.914556 -19.141833)
			(xy 90.88927 -19.190588) (xy 90.857253 -19.235213) (xy 90.819167 -19.274784) (xy 90.775801 -19.308485)
			(xy 90.728049 -19.335619) (xy 90.6769 -19.355624) (xy 90.623411 -19.368087) (xy 90.568687 -19.37275)
			(xy 90.51386 -19.369517) (xy 90.460064 -19.358455) (xy 90.40841 -19.339792) (xy 90.359966 -19.313915)
			(xy 90.315734 -19.281358) (xy 90.276629 -19.242794) (xy 90.259662 -19.221196) (xy 90.246278 -19.20412)
			(xy 90.214618 -19.174457) (xy 90.178377 -19.150607) (xy 90.13861 -19.133264) (xy 90.096473 -19.122933)
			(xy 90.053193 -19.119913) (xy 90.01003 -19.124295) (xy 89.96824 -19.135948) (xy 89.929039 -19.154536)
			(xy 89.893567 -19.179516) (xy 89.8779 -19.194526) (xy 89.855854 -19.215772) (xy 89.807106 -19.252816)
			(xy 89.753855 -19.283032) (xy 89.697052 -19.30588) (xy 89.637711 -19.320954) (xy 89.57689 -19.327983)
			(xy 89.515674 -19.326842) (xy 89.455157 -19.317553) (xy 89.396418 -19.300279) (xy 89.340506 -19.275331)
			(xy 89.288418 -19.243153) (xy 89.241084 -19.204318) (xy 89.199348 -19.159522) (xy 89.163956 -19.109561)
			(xy 89.135539 -19.05533) (xy 89.114604 -18.997794) (xy 89.101524 -18.937981) (xy 89.096534 -18.876959)
			(xy 86.745294 -18.876959) (xy 86.734433 -18.898275) (xy 86.698519 -18.95112) (xy 86.656265 -18.999047)
			(xy 86.608338 -19.041301) (xy 86.555493 -19.077215) (xy 86.498563 -19.106222) (xy 86.438446 -19.127865)
			(xy 86.376092 -19.141803) (xy 86.312481 -19.147816) (xy 86.248619 -19.145809) (xy 86.185512 -19.135814)
			(xy 86.124155 -19.117988) (xy 86.065516 -19.092613) (xy 86.01052 -19.060088) (xy 85.960034 -19.020927)
			(xy 85.93709 -18.998692) (xy 85.184234 -18.245836) (xy 67.216528 -18.245836) (xy 67.199889 -18.246366)
			(xy 67.167763 -18.25505) (xy 67.138979 -18.271754) (xy 67.126866 -18.283174) (xy 66.759074 -18.650966)
			(xy 66.743835 -18.666868) (xy 66.718528 -18.70291) (xy 66.699813 -18.742775) (xy 66.688249 -18.785269)
			(xy 66.684184 -18.82912) (xy 66.687739 -18.873016) (xy 66.698808 -18.915642) (xy 66.717058 -18.955722)
			(xy 66.741945 -18.992055) (xy 66.757042 -19.00809) (xy 66.775643 -19.02776) (xy 66.807672 -19.071403)
			(xy 66.83321 -19.119137) (xy 66.851743 -19.170001) (xy 66.862898 -19.222975) (xy 66.866453 -19.276994)
			(xy 66.862335 -19.330973) (xy 66.850626 -19.383827) (xy 66.831564 -19.434495) (xy 66.805529 -19.48196)
			(xy 66.773046 -19.525266) (xy 66.734766 -19.563546) (xy 66.691459 -19.596029) (xy 66.643995 -19.622064)
			(xy 66.593326 -19.641127) (xy 66.540472 -19.652835) (xy 66.486493 -19.656953) (xy 66.432475 -19.653398)
			(xy 66.379501 -19.642243) (xy 66.328636 -19.62371) (xy 66.280903 -19.598172) (xy 66.237259 -19.566142)
			(xy 66.217546 -19.547586) (xy 66.201473 -19.53253) (xy 66.165148 -19.507635) (xy 66.125074 -19.489377)
			(xy 66.082453 -19.4783) (xy 66.03856 -19.474738) (xy 65.994711 -19.478797) (xy 65.952218 -19.490355)
			(xy 65.912353 -19.509066) (xy 65.876312 -19.534369) (xy 65.860422 -19.549618) (xy 65.416684 -19.993356)
			(xy 56.458104 -19.993356) (xy 56.388762 -20.062698) (xy 56.232298 -20.062698) (xy 55.34914 -20.945856)
			(xy 55.34914 -21.99259) (xy 55.394098 -22.057868) (xy 55.493158 -22.095714) (xy 55.506975 -22.100541)
			(xy 55.535973 -22.104452) (xy 55.565098 -22.101648) (xy 55.592817 -22.092277) (xy 55.617669 -22.076832)
			(xy 55.628286 -22.066758) (xy 55.775352 -21.919438) (xy 55.775352 -21.495766) (xy 55.775914 -21.462089)
			(xy 55.784839 -21.395329) (xy 55.802503 -21.330332) (xy 55.828595 -21.268236) (xy 55.862659 -21.210131)
			(xy 55.904098 -21.157032) (xy 55.927752 -21.133054) (xy 55.927752 -21.114258) (xy 55.945278 -21.114258)
			(xy 55.97906 -21.088858) (xy 56.005534 -21.06966) (xy 56.062469 -21.037489) (xy 56.12306 -21.012884)
			(xy 56.186306 -20.996251) (xy 56.251162 -20.987866) (xy 56.316558 -20.987866) (xy 56.381414 -20.996251)
			(xy 56.44466 -21.012884) (xy 56.505251 -21.037489) (xy 56.562186 -21.06966) (xy 56.58866 -21.088858)
			(xy 56.622442 -21.114258) (xy 57.440068 -21.114258) (xy 57.440068 -21.877274) (xy 57.389268 -21.928328)
			(xy 57.389268 -22.099778) (xy 57.53354 -22.244304) (xy 57.582816 -22.24659) (xy 57.617686 -22.24886)
			(xy 57.686186 -22.262653) (xy 57.751795 -22.286696) (xy 57.782714 -22.302978) (xy 57.803304 -22.313746)
			(xy 57.847383 -22.328426) (xy 57.893395 -22.334856) (xy 57.93981 -22.332823) (xy 57.985084 -22.322394)
			(xy 58.02771 -22.303915) (xy 58.066272 -22.278003) (xy 58.083196 -22.262084) (xy 58.103136 -22.243215)
			(xy 58.14745 -22.210813) (xy 58.195951 -22.185096) (xy 58.247636 -22.166596) (xy 58.30144 -22.155696)
			(xy 58.35625 -22.152619) (xy 58.410936 -22.15743) (xy 58.464367 -22.170029) (xy 58.515441 -22.190157)
			(xy 58.563103 -22.217396) (xy 58.606369 -22.251186) (xy 58.644345 -22.290828) (xy 58.676247 -22.335504)
			(xy 58.701416 -22.38429) (xy 58.719334 -22.436181) (xy 58.729628 -22.490104) (xy 58.732089 -22.544945)
			(xy 58.726663 -22.599573) (xy 58.720482 -22.62632) (xy 58.715791 -22.647086) (xy 58.712603 -22.689535)
			(xy 58.716537 -22.731922) (xy 58.727483 -22.77306) (xy 58.745136 -22.811796) (xy 58.769 -22.847047)
			(xy 58.798408 -22.877825) (xy 58.832536 -22.903269) (xy 58.851292 -22.91334) (xy 58.875548 -22.926296)
			(xy 58.920392 -22.958123) (xy 58.960197 -22.996063) (xy 58.994138 -23.039329) (xy 59.02151 -23.087023)
			(xy 59.041746 -23.138154) (xy 59.054426 -23.191663) (xy 59.059286 -23.246438) (xy 59.056225 -23.301342)
			(xy 59.05119 -23.328376) (xy 59.047143 -23.351076) (xy 59.046366 -23.397175) (xy 59.053914 -23.442658)
			(xy 59.06954 -23.486034) (xy 59.092732 -23.525881) (xy 59.122729 -23.560893) (xy 59.158549 -23.589922)
			(xy 59.199015 -23.612016) (xy 59.242802 -23.626451) (xy 59.265566 -23.630128) (xy 59.279934 -23.632133)
			(xy 59.308403 -23.637724) (xy 59.322462 -23.641304) (xy 59.356752 -23.629112) (xy 59.406536 -23.611586)
			(xy 59.452002 -23.51659) (xy 59.422284 -23.43277) (xy 59.411108 -23.41753) (xy 59.395176 -23.394966)
			(xy 59.369289 -23.346173) (xy 59.350708 -23.294157) (xy 59.339824 -23.240006) (xy 59.336862 -23.184851)
			(xy 59.341886 -23.129845) (xy 59.35479 -23.076138) (xy 59.375303 -23.024854) (xy 59.402999 -22.977065)
			(xy 59.437297 -22.933769) (xy 59.47748 -22.895872) (xy 59.522708 -22.864165) (xy 59.572036 -22.839313)
			(xy 59.598052 -22.830028) (xy 59.618155 -22.822858) (xy 59.655812 -22.802771) (xy 59.689584 -22.776676)
			(xy 59.718521 -22.745306) (xy 59.741811 -22.709542) (xy 59.758798 -22.67039) (xy 59.769006 -22.62895)
			(xy 59.772146 -22.586387) (xy 59.770518 -22.565106) (xy 59.768421 -22.537578) (xy 59.771231 -22.482443)
			(xy 59.781959 -22.428289) (xy 59.800382 -22.376247) (xy 59.826114 -22.327404) (xy 59.858619 -22.282781)
			(xy 59.897217 -22.24331) (xy 59.941102 -22.209815) (xy 59.989356 -22.182996) (xy 60.040973 -22.163413)
			(xy 60.094874 -22.151476) (xy 60.149932 -22.147433) (xy 60.204998 -22.15137) (xy 60.258922 -22.163203)
			(xy 60.310576 -22.182687) (xy 60.358883 -22.209413) (xy 60.402832 -22.242823) (xy 60.441505 -22.28222)
			(xy 60.474096 -22.32678) (xy 60.499923 -22.375573) (xy 60.518446 -22.42758) (xy 60.529278 -22.481713)
			(xy 60.532194 -22.536843) (xy 60.528517 -22.576786) (xy 61.359524 -22.576786) (xy 61.359524 -22.51685)
			(xy 61.367347 -22.457428) (xy 61.38286 -22.399535) (xy 61.405796 -22.344162) (xy 61.435763 -22.292256)
			(xy 61.47225 -22.244706) (xy 61.51463 -22.202326) (xy 61.56218 -22.165839) (xy 61.614086 -22.135872)
			(xy 61.669459 -22.112936) (xy 61.727352 -22.097423) (xy 61.786774 -22.0896) (xy 61.84671 -22.0896)
			(xy 61.906132 -22.097423) (xy 61.964025 -22.112936) (xy 62.019398 -22.135872) (xy 62.071304 -22.165839)
			(xy 62.118854 -22.202326) (xy 62.161234 -22.244706) (xy 62.197721 -22.292256) (xy 62.227688 -22.344162)
			(xy 62.250624 -22.399535) (xy 62.266137 -22.457428) (xy 62.27396 -22.51685) (xy 62.27445 -22.546818)
			(xy 62.27396 -22.576786) (xy 62.266137 -22.636208) (xy 62.250624 -22.694101) (xy 62.227688 -22.749474)
			(xy 62.197721 -22.80138) (xy 62.161234 -22.84893) (xy 62.118854 -22.89131) (xy 62.071304 -22.927797)
			(xy 62.019398 -22.957764) (xy 61.964025 -22.9807) (xy 61.906132 -22.996213) (xy 61.84671 -23.004036)
			(xy 61.786774 -23.004036) (xy 61.727352 -22.996213) (xy 61.669459 -22.9807) (xy 61.614086 -22.957764)
			(xy 61.56218 -22.927797) (xy 61.51463 -22.89131) (xy 61.47225 -22.84893) (xy 61.435763 -22.80138)
			(xy 61.405796 -22.749474) (xy 61.38286 -22.694101) (xy 61.367347 -22.636208) (xy 61.359524 -22.576786)
			(xy 60.528517 -22.576786) (xy 60.527133 -22.591817) (xy 60.514199 -22.645487) (xy 60.493664 -22.696732)
			(xy 60.465955 -22.744482) (xy 60.431653 -22.787739) (xy 60.391474 -22.825599) (xy 60.346256 -22.857271)
			(xy 60.296945 -22.882095) (xy 60.270898 -22.891242) (xy 60.250801 -22.898416) (xy 60.213158 -22.918508)
			(xy 60.1794 -22.944607) (xy 60.150477 -22.975979) (xy 60.127202 -23.011741) (xy 60.110229 -23.05089)
			(xy 60.100034 -23.092324) (xy 60.096905 -23.134878) (xy 60.098432 -23.156164) (xy 60.100462 -23.18185)
			(xy 60.098424 -23.233335) (xy 60.094368 -23.25878) (xy 60.090903 -23.281091) (xy 60.090985 -23.326237)
			(xy 60.099042 -23.370659) (xy 60.114819 -23.412958) (xy 60.13782 -23.451806) (xy 60.167322 -23.485979)
			(xy 60.184538 -23.500588) (xy 60.197337 -23.510352) (xy 60.226617 -23.52371) (xy 60.258309 -23.529314)
			(xy 60.290395 -23.526809) (xy 60.320832 -23.516353) (xy 60.347684 -23.498612) (xy 60.369241 -23.474715)
			(xy 60.384131 -23.446184) (xy 60.391407 -23.414834) (xy 60.391548 -23.398734) (xy 60.391304 -23.368367)
			(xy 60.39787 -23.307996) (xy 60.412363 -23.249023) (xy 60.43453 -23.192486) (xy 60.46398 -23.139377)
			(xy 60.500196 -23.090631) (xy 60.542541 -23.047103) (xy 60.590272 -23.009559) (xy 60.64255 -22.978658)
			(xy 60.698456 -22.954944) (xy 60.757007 -22.938832) (xy 60.817175 -22.930607) (xy 60.877902 -22.930413)
			(xy 60.938121 -22.938253) (xy 60.996774 -22.95399) (xy 61.05283 -22.977346) (xy 61.105305 -23.007912)
			(xy 61.153275 -23.04515) (xy 61.195898 -23.088406) (xy 61.232425 -23.13692) (xy 61.262214 -23.189839)
			(xy 61.284742 -23.246234) (xy 61.299612 -23.305112) (xy 61.306563 -23.365441) (xy 61.305474 -23.426158)
			(xy 61.296363 -23.486198) (xy 61.27939 -23.544506) (xy 61.254854 -23.600056) (xy 61.223186 -23.651872)
			(xy 61.184942 -23.699045) (xy 61.140795 -23.740744) (xy 61.09152 -23.776238) (xy 61.037983 -23.804901)
			(xy 60.981125 -23.826232) (xy 60.921945 -23.839854) (xy 60.861484 -23.845529) (xy 60.800803 -23.843157)
			(xy 60.740969 -23.832779) (xy 60.711842 -23.824184) (xy 60.690942 -23.818105) (xy 60.6478 -23.81236)
			(xy 60.604311 -23.81405) (xy 60.561745 -23.823124) (xy 60.521347 -23.839318) (xy 60.484299 -23.862158)
			(xy 60.451684 -23.890976) (xy 60.424455 -23.924929) (xy 60.40341 -23.963025) (xy 60.395866 -23.983442)
			(xy 60.386216 -24.00975) (xy 60.360307 -24.059434) (xy 60.327412 -24.104798) (xy 60.288241 -24.144865)
			(xy 60.243632 -24.178777) (xy 60.219336 -24.192738) (xy 60.200294 -24.20376) (xy 60.165992 -24.231306)
			(xy 60.13695 -24.264351) (xy 60.114037 -24.301907) (xy 60.097938 -24.34285) (xy 60.089136 -24.385954)
			(xy 60.087893 -24.42993) (xy 60.094247 -24.473462) (xy 60.100718 -24.49449) (xy 60.109141 -24.521742)
			(xy 60.11873 -24.577969) (xy 60.11984 -24.634997) (xy 60.112447 -24.691555) (xy 60.096716 -24.746382)
			(xy 60.072997 -24.798255) (xy 60.041818 -24.846018) (xy 60.003876 -24.888607) (xy 59.960016 -24.925072)
			(xy 59.935872 -24.94026) (xy 59.915923 -24.952911) (xy 59.880697 -24.984375) (xy 59.851897 -25.021811)
			(xy 59.830515 -25.063927) (xy 59.817291 -25.10927) (xy 59.812678 -25.156277) (xy 59.816838 -25.203326)
			(xy 59.829626 -25.248794) (xy 59.839606 -25.270206) (xy 59.851424 -25.295158) (xy 59.868548 -25.347645)
			(xy 59.877929 -25.402052) (xy 59.879371 -25.457243) (xy 59.872843 -25.512065) (xy 59.858483 -25.565375)
			(xy 59.83659 -25.616058) (xy 59.807621 -25.663057) (xy 59.77218 -25.70539) (xy 59.731009 -25.742174)
			(xy 59.684966 -25.77264) (xy 59.635013 -25.796152) (xy 59.582193 -25.812219) (xy 59.527609 -25.820506)
			(xy 59.4724 -25.82084) (xy 59.417719 -25.813213) (xy 59.364709 -25.797786) (xy 59.314475 -25.77488)
			(xy 59.268067 -25.744973) (xy 59.226454 -25.70869) (xy 59.190504 -25.666789) (xy 59.160969 -25.620144)
			(xy 59.138464 -25.569729) (xy 59.12346 -25.516597) (xy 59.11627 -25.461857) (xy 59.117045 -25.406653)
			(xy 59.125767 -25.352136) (xy 59.142255 -25.299446) (xy 59.166165 -25.249683) (xy 59.196998 -25.203884)
			(xy 59.234108 -25.163008) (xy 59.276723 -25.127906) (xy 59.30011 -25.113234) (xy 59.32006 -25.100584)
			(xy 59.355287 -25.06912) (xy 59.384089 -25.031685) (xy 59.405471 -24.989569) (xy 59.418696 -24.944225)
			(xy 59.423307 -24.897217) (xy 59.419146 -24.850168) (xy 59.406356 -24.8047) (xy 59.396376 -24.783288)
			(xy 59.385991 -24.761502) (xy 59.370193 -24.715898) (xy 59.36488 -24.692356) (xy 59.356244 -24.651716)
			(xy 59.234832 -24.542496) (xy 59.18835 -24.540972) (xy 59.158235 -24.53952) (xy 59.098752 -24.529682)
			(xy 59.041074 -24.51212) (xy 58.986202 -24.487137) (xy 58.935085 -24.455166) (xy 58.888608 -24.41676)
			(xy 58.847576 -24.372585) (xy 58.812699 -24.323404) (xy 58.784581 -24.270071) (xy 58.763708 -24.213507)
			(xy 58.750443 -24.154693) (xy 58.745014 -24.094646) (xy 58.747516 -24.034406) (xy 58.757905 -23.975016)
			(xy 58.766456 -23.946104) (xy 58.772929 -23.923959) (xy 58.778661 -23.878186) (xy 58.776031 -23.83213)
			(xy 58.765123 -23.787307) (xy 58.746298 -23.745192) (xy 58.720174 -23.70717) (xy 58.687611 -23.674494)
			(xy 58.649681 -23.648237) (xy 58.607632 -23.629265) (xy 58.585354 -23.62327) (xy 58.557874 -23.61591)
			(xy 58.505307 -23.594161) (xy 58.456554 -23.564845) (xy 58.412696 -23.528613) (xy 58.374707 -23.486268)
			(xy 58.343428 -23.43875) (xy 58.319555 -23.387113) (xy 58.303617 -23.332504) (xy 58.295966 -23.276132)
			(xy 58.296774 -23.21925) (xy 58.306022 -23.163118) (xy 58.323506 -23.108983) (xy 58.335672 -23.083266)
			(xy 58.342456 -23.06858) (xy 58.349142 -23.036939) (xy 58.347656 -23.004634) (xy 58.338094 -22.97374)
			(xy 58.32107 -22.946244) (xy 58.297679 -22.923913) (xy 58.269423 -22.908182) (xy 58.253884 -22.903688)
			(xy 58.218324 -22.892766) (xy 58.196346 -22.885246) (xy 58.150563 -22.877418) (xy 58.104119 -22.878033)
			(xy 58.05856 -22.88707) (xy 58.015398 -22.904229) (xy 57.976069 -22.928939) (xy 57.94188 -22.960379)
			(xy 57.927494 -22.978618) (xy 57.908476 -23.00309) (xy 57.864914 -23.047176) (xy 57.8158 -23.084978)
			(xy 57.762032 -23.115804) (xy 57.704595 -23.13909) (xy 57.644541 -23.154409) (xy 57.582968 -23.161482)
			(xy 57.521005 -23.160178) (xy 57.459784 -23.150522) (xy 57.400427 -23.13269) (xy 57.371996 -23.12035)
			(xy 57.350285 -23.111041) (xy 57.304419 -23.099756) (xy 57.257258 -23.09714) (xy 57.210425 -23.103282)
			(xy 57.165534 -23.117972) (xy 57.12413 -23.140703) (xy 57.087638 -23.170693) (xy 57.057316 -23.206909)
			(xy 57.034207 -23.248104) (xy 57.019108 -23.292859) (xy 57.01538 -23.316184) (xy 57.011062 -23.343399)
			(xy 56.995618 -23.396293) (xy 56.972729 -23.446416) (xy 56.942871 -23.492728) (xy 56.906664 -23.534265)
			(xy 56.86486 -23.570163) (xy 56.818329 -23.599678) (xy 56.768037 -23.622195) (xy 56.71503 -23.637247)
			(xy 56.66041 -23.644521) (xy 56.632856 -23.644606) (xy 56.610727 -23.644818) (xy 56.567058 -23.651958)
			(xy 56.525285 -23.666553) (xy 56.486672 -23.688164) (xy 56.452386 -23.716136) (xy 56.423463 -23.749624)
			(xy 56.400778 -23.787615) (xy 56.385016 -23.828962) (xy 56.38038 -23.8506) (xy 56.374164 -23.880384)
			(xy 56.354896 -23.938095) (xy 56.328155 -23.992746) (xy 56.294411 -24.043374) (xy 56.254259 -24.089087)
			(xy 56.208407 -24.12908) (xy 56.157661 -24.162647) (xy 56.102917 -24.189198) (xy 56.045139 -24.208265)
			(xy 55.985345 -24.219511) (xy 55.924588 -24.222739) (xy 55.863939 -24.217892) (xy 55.804465 -24.205055)
			(xy 55.747216 -24.184455) (xy 55.71998 -24.170894) (xy 55.700519 -24.161304) (xy 55.659172 -24.148173)
			(xy 55.616195 -24.142256) (xy 55.572838 -24.143725) (xy 55.53036 -24.152536) (xy 55.489996 -24.168435)
			(xy 55.452919 -24.190958) (xy 55.420207 -24.219452) (xy 55.392809 -24.253088) (xy 55.371523 -24.290889)
			(xy 55.356967 -24.331756) (xy 55.349563 -24.374501) (xy 55.34914 -24.396192) (xy 55.34914 -25.044654)
			(xy 55.349646 -25.067356) (xy 55.357721 -25.112037) (xy 55.373606 -25.154573) (xy 55.396794 -25.19361)
			(xy 55.426548 -25.227908) (xy 55.461921 -25.256374) (xy 55.501789 -25.278103) (xy 55.544883 -25.292404)
			(xy 55.589832 -25.298822) (xy 55.635206 -25.297153) (xy 55.657496 -25.292812) (xy 55.687295 -25.286788)
			(xy 55.747881 -25.281746) (xy 55.808602 -25.28477) (xy 55.868387 -25.295809) (xy 55.926184 -25.314666)
			(xy 55.980976 -25.341011) (xy 56.031796 -25.374379) (xy 56.07775 -25.414182) (xy 56.118029 -25.459721)
			(xy 56.151924 -25.510191) (xy 56.178837 -25.564706) (xy 56.198294 -25.622304) (xy 56.209953 -25.681971)
			(xy 56.213609 -25.742657) (xy 56.209197 -25.803292) (xy 56.196794 -25.862809) (xy 56.17662 -25.92016)
			(xy 56.149029 -25.974335) (xy 56.114508 -26.024379) (xy 56.073664 -26.069411) (xy 56.027217 -26.108638)
			(xy 55.975985 -26.14137) (xy 55.920869 -26.167029) (xy 55.862841 -26.185165) (xy 55.802923 -26.195457)
			(xy 55.74217 -26.197724) (xy 55.681651 -26.191926) (xy 55.651908 -26.185622) (xy 55.635605 -26.182394)
			(xy 55.602402 -26.183496) (xy 55.570606 -26.193123) (xy 55.542369 -26.210626) (xy 55.519602 -26.23482)
			(xy 55.503845 -26.264067) (xy 55.499508 -26.28011) (xy 55.492675 -26.306983) (xy 55.492491 -26.307449)
			(xy 60.012165 -26.307449) (xy 60.017499 -26.25198) (xy 60.030845 -26.197877) (xy 60.051917 -26.146289)
			(xy 60.080267 -26.098315) (xy 60.115294 -26.054974) (xy 60.156251 -26.017188) (xy 60.202269 -25.985761)
			(xy 60.252368 -25.96136) (xy 60.278772 -25.95245) (xy 60.299561 -25.945376) (xy 60.338524 -25.925129)
			(xy 60.373424 -25.898483) (xy 60.403221 -25.866232) (xy 60.427027 -25.829336) (xy 60.444132 -25.788896)
			(xy 60.454028 -25.746116) (xy 60.456418 -25.702272) (xy 60.454286 -25.680416) (xy 60.45156 -25.652688)
			(xy 60.453045 -25.596996) (xy 60.462614 -25.542113) (xy 60.480063 -25.489205) (xy 60.505021 -25.439397)
			(xy 60.536958 -25.393749) (xy 60.575193 -25.35323) (xy 60.618915 -25.318703) (xy 60.667194 -25.290902)
			(xy 60.719002 -25.270417) (xy 60.773239 -25.257685) (xy 60.828751 -25.252977) (xy 60.884357 -25.256391)
			(xy 60.938876 -25.267856) (xy 60.991147 -25.287129) (xy 61.04006 -25.313798) (xy 61.084574 -25.347298)
			(xy 61.123743 -25.386915) (xy 61.156734 -25.431807) (xy 61.182845 -25.48102) (xy 61.201522 -25.533507)
			(xy 61.212366 -25.588153) (xy 61.215148 -25.643795) (xy 61.209808 -25.699249) (xy 61.19646 -25.753338)
			(xy 61.175388 -25.80491) (xy 61.147039 -25.852869) (xy 61.112017 -25.896195) (xy 61.071066 -25.933967)
			(xy 61.025057 -25.965383) (xy 60.974968 -25.989772) (xy 60.94857 -25.998678) (xy 60.927779 -26.005749)
			(xy 60.888813 -26.025993) (xy 60.853911 -26.052637) (xy 60.824112 -26.084889) (xy 60.800305 -26.121786)
			(xy 60.7832 -26.162228) (xy 60.773307 -26.20501) (xy 60.770921 -26.248856) (xy 60.773056 -26.270712)
			(xy 60.775922 -26.298431) (xy 60.774448 -26.354136) (xy 60.764888 -26.409035) (xy 60.747444 -26.46196)
			(xy 60.72249 -26.511785) (xy 60.690554 -26.557451) (xy 60.652316 -26.597987) (xy 60.608589 -26.63253)
			(xy 60.560303 -26.660347) (xy 60.508485 -26.680846) (xy 60.454237 -26.69359) (xy 60.398712 -26.698309)
			(xy 60.343091 -26.694902) (xy 60.288557 -26.683443) (xy 60.23627 -26.664174) (xy 60.18734 -26.637505)
			(xy 60.14281 -26.604003) (xy 60.103626 -26.564382) (xy 60.07062 -26.519483) (xy 60.044496 -26.470261)
			(xy 60.025808 -26.417762) (xy 60.014954 -26.363105) (xy 60.012165 -26.307449) (xy 55.492491 -26.307449)
			(xy 55.472289 -26.358548) (xy 55.444643 -26.406612) (xy 55.41032 -26.45016) (xy 55.390542 -26.469594)
			(xy 55.389526 -26.47061) (xy 55.34914 -26.510996) (xy 55.34914 -27.125676) (xy 55.349632 -27.142331)
			(xy 55.35825 -27.174507) (xy 55.374904 -27.203354) (xy 55.398459 -27.226906) (xy 55.427308 -27.243557)
			(xy 55.459485 -27.25217) (xy 55.47614 -27.252676) (xy 55.499254 -27.252676) (xy 55.52059 -27.244802)
			(xy 55.54726 -27.236166) (xy 55.585106 -27.225498) (xy 55.678324 -27.113738) (xy 55.678324 -27.044396)
			(xy 55.677054 -27.035252) (xy 55.673102 -27.005142) (xy 55.672241 -26.944419) (xy 55.679419 -26.884115)
			(xy 55.694508 -26.825291) (xy 55.717245 -26.768979) (xy 55.74723 -26.716169) (xy 55.783935 -26.667788)
			(xy 55.826716 -26.624686) (xy 55.874822 -26.587621) (xy 55.927408 -26.557243) (xy 55.983549 -26.534087)
			(xy 56.042259 -26.518559) (xy 56.102507 -26.510932) (xy 56.163235 -26.51134) (xy 56.223375 -26.519776)
			(xy 56.281871 -26.536091) (xy 56.337696 -26.559999) (xy 56.389868 -26.59108) (xy 56.437472 -26.628788)
			(xy 56.479671 -26.672461) (xy 56.515723 -26.72133) (xy 56.544995 -26.774539) (xy 56.566973 -26.831151)
			(xy 56.581272 -26.890173) (xy 56.587638 -26.950567) (xy 56.585962 -27.011273) (xy 56.576272 -27.071224)
			(xy 56.558738 -27.129367) (xy 56.533669 -27.18468) (xy 56.501505 -27.236192) (xy 56.46281 -27.282997)
			(xy 56.418266 -27.324275) (xy 56.368654 -27.359298) (xy 56.314845 -27.387452) (xy 56.257786 -27.408243)
			(xy 56.228234 -27.415236) (xy 56.206002 -27.420627) (xy 56.163809 -27.438294) (xy 56.125455 -27.463221)
			(xy 56.092177 -27.494605) (xy 56.065049 -27.531435) (xy 56.053241 -27.555565) (xy 58.201236 -27.555565)
			(xy 58.20554 -27.500962) (xy 58.217609 -27.447536) (xy 58.237195 -27.396386) (xy 58.263895 -27.348562)
			(xy 58.297161 -27.305049) (xy 58.336308 -27.266742) (xy 58.380532 -27.234427) (xy 58.404506 -27.22118)
			(xy 58.425209 -27.209583) (xy 58.462268 -27.179954) (xy 58.493192 -27.143968) (xy 58.516908 -27.102873)
			(xy 58.532595 -27.058094) (xy 58.539709 -27.011183) (xy 58.538002 -26.963766) (xy 58.533284 -26.94051)
			(xy 58.527618 -26.91371) (xy 58.523203 -26.859112) (xy 58.526642 -26.804443) (xy 58.537864 -26.750827)
			(xy 58.55664 -26.699369) (xy 58.582582 -26.651124) (xy 58.615158 -26.607086) (xy 58.653697 -26.568159)
			(xy 58.697407 -26.535145) (xy 58.745389 -26.508721) (xy 58.796658 -26.489432) (xy 58.850158 -26.477673)
			(xy 58.90479 -26.473688) (xy 58.95943 -26.477556) (xy 59.012956 -26.4892) (xy 59.064265 -26.508379)
			(xy 59.112305 -26.534699) (xy 59.156086 -26.56762) (xy 59.194708 -26.606464) (xy 59.227378 -26.650432)
			(xy 59.253424 -26.698621) (xy 59.27231 -26.750039) (xy 59.283647 -26.80363) (xy 59.287204 -26.858292)
			(xy 59.282906 -26.9129) (xy 59.270842 -26.966332) (xy 59.25126 -27.017489) (xy 59.224563 -27.06532)
			(xy 59.1913 -27.108841) (xy 59.152154 -27.147157) (xy 59.10793 -27.179481) (xy 59.083956 -27.192732)
			(xy 59.063238 -27.204303) (xy 59.026181 -27.233939) (xy 58.99526 -27.26993) (xy 58.971546 -27.311029)
			(xy 58.955862 -27.355812) (xy 58.948751 -27.402726) (xy 58.950459 -27.450145) (xy 58.955178 -27.473402)
			(xy 58.960747 -27.500221) (xy 58.965158 -27.554815) (xy 58.961907 -27.606426) (xy 60.56692 -27.606426)
			(xy 60.573037 -27.545594) (xy 60.58678 -27.48602) (xy 60.60793 -27.428656) (xy 60.636149 -27.374418)
			(xy 60.670985 -27.324175) (xy 60.711882 -27.278728) (xy 60.758186 -27.238804) (xy 60.809157 -27.205042)
			(xy 60.863981 -27.17798) (xy 60.921781 -27.158052) (xy 60.981633 -27.145575) (xy 61.01207 -27.142694)
			(xy 61.033992 -27.140453) (xy 61.076659 -27.129454) (xy 61.11679 -27.111265) (xy 61.153186 -27.08643)
			(xy 61.184755 -27.055693) (xy 61.210553 -27.019973) (xy 61.229808 -26.980342) (xy 61.241942 -26.937984)
			(xy 61.244734 -26.916126) (xy 61.248137 -26.887716) (xy 61.261121 -26.831988) (xy 61.280956 -26.778316)
			(xy 61.307334 -26.727538) (xy 61.339842 -26.680449) (xy 61.377971 -26.637784) (xy 61.421126 -26.60021)
			(xy 61.444632 -26.583894) (xy 61.46388 -26.570415) (xy 61.497438 -26.537527) (xy 61.524373 -26.499027)
			(xy 61.543767 -26.456229) (xy 61.554957 -26.410594) (xy 61.557562 -26.36368) (xy 61.551491 -26.317087)
			(xy 61.544708 -26.294588) (xy 61.53665 -26.268539) (xy 61.527323 -26.214814) (xy 61.52574 -26.160308)
			(xy 61.531934 -26.106133) (xy 61.545778 -26.053391) (xy 61.56699 -26.003158) (xy 61.595139 -25.956456)
			(xy 61.62965 -25.914239) (xy 61.66982 -25.877365) (xy 61.714831 -25.846586) (xy 61.763766 -25.822529)
			(xy 61.815627 -25.805684) (xy 61.869359 -25.796396) (xy 61.923865 -25.794852) (xy 61.978036 -25.801084)
			(xy 62.030768 -25.814966) (xy 62.080986 -25.836215) (xy 62.127667 -25.864396) (xy 62.16986 -25.898938)
			(xy 62.206706 -25.939134) (xy 62.237452 -25.984168) (xy 62.261474 -26.03312) (xy 62.278281 -26.084993)
			(xy 62.287531 -26.138731) (xy 62.289036 -26.193239) (xy 62.282765 -26.247405) (xy 62.268845 -26.300127)
			(xy 62.247561 -26.35033) (xy 62.219346 -26.396991) (xy 62.184774 -26.439159) (xy 62.164976 -26.45791)
			(xy 62.148027 -26.4742) (xy 62.119764 -26.511755) (xy 62.098878 -26.55386) (xy 62.086077 -26.599085)
			(xy 62.081797 -26.645892) (xy 62.086184 -26.692688) (xy 62.099088 -26.737884) (xy 62.109096 -26.759154)
			(xy 62.122035 -26.786112) (xy 62.141621 -26.842608) (xy 62.149016 -26.878534) (xy 62.576962 -26.878534)
			(xy 62.581033 -26.822912) (xy 62.593159 -26.768475) (xy 62.613082 -26.716384) (xy 62.640378 -26.667749)
			(xy 62.674464 -26.623606) (xy 62.714613 -26.584897) (xy 62.759971 -26.552446) (xy 62.809571 -26.526945)
			(xy 62.862355 -26.508938) (xy 62.917198 -26.498808) (xy 62.972932 -26.496771) (xy 63.028369 -26.502871)
			(xy 63.082326 -26.516977) (xy 63.133655 -26.538789) (xy 63.181261 -26.567843) (xy 63.224129 -26.603518)
			(xy 63.261346 -26.645055) (xy 63.292119 -26.691568) (xy 63.315791 -26.742065) (xy 63.331859 -26.795472)
			(xy 63.339979 -26.850648) (xy 63.340488 -26.878534) (xy 63.339979 -26.90642) (xy 63.337953 -26.920186)
			(xy 63.724264 -26.920186) (xy 63.724264 -26.86025) (xy 63.732087 -26.800828) (xy 63.7476 -26.742935)
			(xy 63.770536 -26.687562) (xy 63.800503 -26.635656) (xy 63.83699 -26.588106) (xy 63.87937 -26.545726)
			(xy 63.92692 -26.509239) (xy 63.978826 -26.479272) (xy 64.034199 -26.456336) (xy 64.092092 -26.440823)
			(xy 64.151514 -26.433) (xy 64.21145 -26.433) (xy 64.270872 -26.440823) (xy 64.328765 -26.456336)
			(xy 64.384138 -26.479272) (xy 64.436044 -26.509239) (xy 64.483594 -26.545726) (xy 64.525974 -26.588106)
			(xy 64.562461 -26.635656) (xy 64.592428 -26.687562) (xy 64.615364 -26.742935) (xy 64.630877 -26.800828)
			(xy 64.6387 -26.86025) (xy 64.63919 -26.890218) (xy 64.6387 -26.920186) (xy 64.630877 -26.979608)
			(xy 64.615364 -27.037501) (xy 64.592428 -27.092874) (xy 64.562461 -27.14478) (xy 64.525974 -27.19233)
			(xy 64.483594 -27.23471) (xy 64.436044 -27.271197) (xy 64.384138 -27.301164) (xy 64.328765 -27.3241)
			(xy 64.270872 -27.339613) (xy 64.21145 -27.347436) (xy 64.151514 -27.347436) (xy 64.092092 -27.339613)
			(xy 64.034199 -27.3241) (xy 63.978826 -27.301164) (xy 63.92692 -27.271197) (xy 63.87937 -27.23471)
			(xy 63.83699 -27.19233) (xy 63.800503 -27.14478) (xy 63.770536 -27.092874) (xy 63.7476 -27.037501)
			(xy 63.732087 -26.979608) (xy 63.724264 -26.920186) (xy 63.337953 -26.920186) (xy 63.331859 -26.961596)
			(xy 63.315791 -27.015003) (xy 63.292119 -27.0655) (xy 63.261346 -27.112013) (xy 63.224129 -27.15355)
			(xy 63.181261 -27.189225) (xy 63.133655 -27.218279) (xy 63.082326 -27.240091) (xy 63.028369 -27.254197)
			(xy 62.972932 -27.260297) (xy 62.917198 -27.25826) (xy 62.862355 -27.24813) (xy 62.809571 -27.230123)
			(xy 62.759971 -27.204622) (xy 62.714613 -27.172171) (xy 62.674464 -27.133462) (xy 62.640378 -27.089319)
			(xy 62.613082 -27.040684) (xy 62.593159 -26.988593) (xy 62.581033 -26.934156) (xy 62.576962 -26.878534)
			(xy 62.149016 -26.878534) (xy 62.153677 -26.901175) (xy 62.157998 -26.960814) (xy 62.154508 -27.020507)
			(xy 62.143268 -27.079236) (xy 62.12447 -27.135999) (xy 62.098434 -27.189828) (xy 62.082426 -27.215084)
			(xy 62.070338 -27.234422) (xy 62.052507 -27.276392) (xy 62.042446 -27.320868) (xy 62.040477 -27.366425)
			(xy 62.046663 -27.411603) (xy 62.060806 -27.454954) (xy 62.082453 -27.495089) (xy 62.110909 -27.53072)
			(xy 62.145263 -27.560706) (xy 62.184414 -27.584086) (xy 62.227105 -27.600109) (xy 62.27197 -27.608263)
			(xy 62.29477 -27.608784) (xy 64.794892 -27.608784) (xy 64.823155 -27.609173) (xy 64.879297 -27.615745)
			(xy 64.934285 -27.628837) (xy 64.987366 -27.648268) (xy 65.03781 -27.673772) (xy 65.061592 -27.689048)
			(xy 65.093596 -27.71013) (xy 65.162684 -27.71013) (xy 65.179329 -27.709543) (xy 65.211486 -27.700932)
			(xy 65.240319 -27.684291) (xy 65.263863 -27.660756) (xy 65.280514 -27.631929) (xy 65.289137 -27.599775)
			(xy 65.289684 -27.58313) (xy 65.289684 -25.89784) (xy 65.085722 -25.693624) (xy 65.036446 -25.691338)
			(xy 65.006737 -25.689448) (xy 64.948133 -25.678998) (xy 64.891378 -25.661038) (xy 64.837431 -25.635872)
			(xy 64.787201 -25.603923) (xy 64.741538 -25.565733) (xy 64.701211 -25.521945) (xy 64.666902 -25.473298)
			(xy 64.639189 -25.420613) (xy 64.61854 -25.36478) (xy 64.605304 -25.306741) (xy 64.599704 -25.247477)
			(xy 64.601836 -25.187986) (xy 64.611661 -25.129274) (xy 64.629016 -25.072331) (xy 64.653607 -25.018119)
			(xy 64.668908 -24.992584) (xy 64.680377 -24.973188) (xy 64.697063 -24.931338) (xy 64.706106 -24.887201)
			(xy 64.707222 -24.84216) (xy 64.700377 -24.797629) (xy 64.685785 -24.755003) (xy 64.663904 -24.71562)
			(xy 64.635419 -24.680713) (xy 64.601224 -24.651377) (xy 64.562392 -24.628532) (xy 64.520138 -24.612895)
			(xy 64.475789 -24.604955) (xy 64.453262 -24.604472) (xy 63.443612 -24.604472) (xy 63.407544 -24.568658)
			(xy 63.333884 -24.55291) (xy 63.298832 -24.566626) (xy 63.271075 -24.576848) (xy 63.213611 -24.590875)
			(xy 63.154819 -24.597383) (xy 63.095679 -24.596264) (xy 63.037175 -24.587537) (xy 62.980283 -24.571346)
			(xy 62.92595 -24.547962) (xy 62.875082 -24.517775) (xy 62.828526 -24.481287) (xy 62.787058 -24.439106)
			(xy 62.751369 -24.391935) (xy 62.722053 -24.340559) (xy 62.699598 -24.285836) (xy 62.68438 -24.228676)
			(xy 62.676651 -24.170032) (xy 62.67654 -24.110881) (xy 62.679834 -24.081486) (xy 62.682164 -24.059282)
			(xy 62.679996 -24.014694) (xy 62.670073 -23.97117) (xy 62.6527 -23.930049) (xy 62.62841 -23.892596)
			(xy 62.597951 -23.859961) (xy 62.562259 -23.833149) (xy 62.522432 -23.812984) (xy 62.479696 -23.800087)
			(xy 62.457584 -23.797006) (xy 62.429823 -23.79329) (xy 62.375757 -23.778665) (xy 62.324409 -23.756294)
			(xy 62.276883 -23.726657) (xy 62.234199 -23.690391) (xy 62.197276 -23.648275) (xy 62.166906 -23.601214)
			(xy 62.143741 -23.550219) (xy 62.128279 -23.496386) (xy 62.120853 -23.440871) (xy 62.121622 -23.384866)
			(xy 62.130569 -23.329576) (xy 62.147503 -23.276187) (xy 62.172059 -23.225847) (xy 62.20371 -23.179638)
			(xy 62.241776 -23.138552) (xy 62.285438 -23.103471) (xy 62.33376 -23.07515) (xy 62.385703 -23.054197)
			(xy 62.440151 -23.041062) (xy 62.467998 -23.038054) (xy 62.483587 -23.036183) (xy 62.513213 -23.025811)
			(xy 62.539406 -23.008514) (xy 62.560579 -22.985341) (xy 62.575446 -22.957696) (xy 62.583107 -22.927257)
			(xy 62.583568 -22.911562) (xy 62.583568 -21.280628) (xy 62.968632 -20.895564) (xy 87.764112 -20.895564)
			(xy 88.776556 -21.908008) (xy 88.776556 -21.915882) (xy 88.776913 -21.930994) (xy 88.784024 -21.96037)
			(xy 88.79785 -21.987247) (xy 88.817615 -22.010113) (xy 88.842208 -22.027683) (xy 88.870246 -22.038971)
			(xy 88.900153 -22.04334) (xy 88.91524 -22.042374) (xy 88.943404 -22.040246) (xy 88.999796 -22.043403)
			(xy 89.055106 -22.054838) (xy 89.108127 -22.074301) (xy 89.1577 -22.101367) (xy 89.202741 -22.135444)
			(xy 89.242267 -22.175789) (xy 89.275415 -22.221519) (xy 89.30146 -22.271636) (xy 89.319832 -22.325044)
			(xy 89.330131 -22.380577) (xy 89.332132 -22.437022) (xy 89.325791 -22.493145) (xy 89.311247 -22.547721)
			(xy 89.288816 -22.599556) (xy 89.25899 -22.647518) (xy 89.22242 -22.69056) (xy 89.179904 -22.727742)
			(xy 89.132372 -22.75825) (xy 89.080863 -22.781418) (xy 89.026501 -22.796741) (xy 88.998552 -22.800818)
			(xy 88.975857 -22.804248) (xy 88.932106 -22.818103) (xy 88.891554 -22.839591) (xy 88.855521 -22.868012)
			(xy 88.825179 -22.902442) (xy 88.801513 -22.941763) (xy 88.785295 -22.984694) (xy 88.77705 -23.02984)
			(xy 88.776556 -23.052786) (xy 88.776556 -23.087058) (xy 90.561281 -23.087058) (xy 90.567183 -23.026239)
			(xy 90.581127 -22.966746) (xy 90.602864 -22.909638) (xy 90.632008 -22.855931) (xy 90.66804 -22.80658)
			(xy 90.710319 -22.762464) (xy 90.758094 -22.724367) (xy 90.810513 -22.692966) (xy 90.866646 -22.668821)
			(xy 90.895932 -22.660102) (xy 90.911922 -22.655066) (xy 90.940732 -22.637949) (xy 90.964084 -22.613914)
			(xy 90.980363 -22.584622) (xy 90.988443 -22.5521) (xy 90.987766 -22.518596) (xy 90.983562 -22.502368)
			(xy 90.976243 -22.475474) (xy 90.968686 -22.420252) (xy 90.969244 -22.364519) (xy 90.977905 -22.309459)
			(xy 90.994484 -22.256245) (xy 91.018629 -22.20601) (xy 91.049826 -22.159822) (xy 91.087411 -22.118665)
			(xy 91.130584 -22.083413) (xy 91.178426 -22.054818) (xy 91.22992 -22.033488) (xy 91.283969 -22.019877)
			(xy 91.339423 -22.014274) (xy 91.395102 -22.016799) (xy 91.449822 -22.027398) (xy 91.502417 -22.045846)
			(xy 91.551769 -22.071749) (xy 91.596826 -22.104557) (xy 91.636632 -22.143571) (xy 91.670337 -22.187962)
			(xy 91.697225 -22.236784) (xy 91.716724 -22.288998) (xy 91.728419 -22.343494) (xy 91.732061 -22.399111)
			(xy 91.730322 -22.42693) (xy 91.729022 -22.45017) (xy 91.730923 -22.468523) (xy 92.768159 -22.468523)
			(xy 92.772953 -22.412595) (xy 92.785889 -22.357972) (xy 92.80669 -22.305835) (xy 92.834906 -22.257308)
			(xy 92.869927 -22.213439) (xy 92.910998 -22.175175) (xy 92.957233 -22.143342) (xy 93.007633 -22.118627)
			(xy 93.06111 -22.101563) (xy 93.11651 -22.09252) (xy 93.172637 -22.091691) (xy 93.228281 -22.099095)
			(xy 93.282238 -22.114572) (xy 93.333346 -22.137788) (xy 93.3805 -22.168242) (xy 93.422683 -22.205277)
			(xy 93.458985 -22.248092) (xy 93.488621 -22.295765) (xy 93.510952 -22.347265) (xy 93.525496 -22.401482)
			(xy 93.53194 -22.457244) (xy 93.530143 -22.513349) (xy 93.520145 -22.568585) (xy 93.511624 -22.595332)
			(xy 93.50486 -22.61659) (xy 93.498159 -22.660691) (xy 93.499267 -22.705285) (xy 93.508148 -22.749)
			(xy 93.524529 -22.790491) (xy 93.547908 -22.828482) (xy 93.577564 -22.861804) (xy 93.612586 -22.889432)
			(xy 93.63202 -22.900386) (xy 93.658763 -22.915263) (xy 93.708314 -22.951182) (xy 93.752636 -22.993383)
			(xy 93.790938 -23.041115) (xy 93.822539 -23.093525) (xy 93.846874 -23.149678) (xy 93.863509 -23.208573)
			(xy 93.872147 -23.26916) (xy 93.872634 -23.330358) (xy 93.864962 -23.391075) (xy 93.849268 -23.450228)
			(xy 93.82583 -23.506762) (xy 93.795068 -23.559668) (xy 93.75753 -23.608003) (xy 93.713886 -23.650905)
			(xy 93.664914 -23.687608) (xy 93.611487 -23.717458) (xy 93.55456 -23.739922) (xy 93.495146 -23.7546)
			(xy 93.434307 -23.76123) (xy 93.373127 -23.759692) (xy 93.312697 -23.750016) (xy 93.254095 -23.732373)
			(xy 93.198368 -23.707079) (xy 93.146508 -23.674584) (xy 93.099441 -23.635468) (xy 93.058006 -23.590428)
			(xy 93.022942 -23.540269) (xy 92.994876 -23.485885) (xy 92.974307 -23.428245) (xy 92.961602 -23.368379)
			(xy 92.956989 -23.307353) (xy 92.960549 -23.246257) (xy 92.972219 -23.18618) (xy 92.99179 -23.128195)
			(xy 93.004894 -23.100538) (xy 93.01435 -23.08033) (xy 93.026908 -23.037523) (xy 93.031794 -22.993181)
			(xy 93.028858 -22.948667) (xy 93.01819 -22.905351) (xy 93.000119 -22.864565) (xy 92.975199 -22.827563)
			(xy 92.944198 -22.795485) (xy 92.926408 -22.782022) (xy 92.90393 -22.765209) (xy 92.863787 -22.725972)
			(xy 92.829827 -22.681277) (xy 92.802782 -22.632088) (xy 92.783236 -22.579467) (xy 92.771611 -22.524551)
			(xy 92.768159 -22.468523) (xy 91.730923 -22.468523) (xy 91.733816 -22.496463) (xy 91.746957 -22.541109)
			(xy 91.768006 -22.582617) (xy 91.796259 -22.6196) (xy 91.830772 -22.650823) (xy 91.870391 -22.675241)
			(xy 91.913794 -22.692039) (xy 91.95953 -22.700655) (xy 91.982798 -22.70125) (xy 92.01008 -22.701789)
			(xy 92.064069 -22.709703) (xy 92.116381 -22.725228) (xy 92.165947 -22.748047) (xy 92.211757 -22.777695)
			(xy 92.252876 -22.813565) (xy 92.288466 -22.854928) (xy 92.3178 -22.900939) (xy 92.340281 -22.95066)
			(xy 92.355449 -23.003075) (xy 92.362995 -23.057118) (xy 92.362766 -23.111684) (xy 92.354766 -23.165661)
			(xy 92.339158 -23.217947) (xy 92.31626 -23.267477) (xy 92.286541 -23.31324) (xy 92.250605 -23.354302)
			(xy 92.209186 -23.389826) (xy 92.163128 -23.419088) (xy 92.113372 -23.44149) (xy 92.060932 -23.456575)
			(xy 92.006878 -23.464036) (xy 91.952313 -23.46372) (xy 91.898349 -23.455634) (xy 91.846087 -23.439943)
			(xy 91.796593 -23.416967) (xy 91.750877 -23.387175) (xy 91.730068 -23.369524) (xy 91.712869 -23.355096)
			(xy 91.674478 -23.331839) (xy 91.632594 -23.315698) (xy 91.588524 -23.307177) (xy 91.543643 -23.306542)
			(xy 91.499349 -23.313812) (xy 91.457025 -23.32876) (xy 91.417991 -23.350921) (xy 91.383465 -23.379603)
			(xy 91.368626 -23.396448) (xy 91.348423 -23.419376) (xy 91.303098 -23.460356) (xy 91.252721 -23.49494)
			(xy 91.198191 -23.522512) (xy 91.140476 -23.542581) (xy 91.080603 -23.554791) (xy 91.019638 -23.558925)
			(xy 90.958665 -23.554908) (xy 90.89877 -23.542813) (xy 90.841016 -23.522854) (xy 90.786433 -23.495386)
			(xy 90.735991 -23.460899) (xy 90.690587 -23.420005) (xy 90.651029 -23.373433) (xy 90.618021 -23.32201)
			(xy 90.59215 -23.266652) (xy 90.573877 -23.208343) (xy 90.563525 -23.148122) (xy 90.561281 -23.087058)
			(xy 88.776556 -23.087058) (xy 88.776556 -23.223728) (xy 88.334001 -23.666446) (xy 89.385884 -23.666446)
			(xy 89.385884 -23.60651) (xy 89.393707 -23.547088) (xy 89.40922 -23.489195) (xy 89.432156 -23.433822)
			(xy 89.462123 -23.381916) (xy 89.49861 -23.334366) (xy 89.54099 -23.291986) (xy 89.58854 -23.255499)
			(xy 89.640446 -23.225532) (xy 89.695819 -23.202596) (xy 89.753712 -23.187083) (xy 89.813134 -23.17926)
			(xy 89.87307 -23.17926) (xy 89.932492 -23.187083) (xy 89.990385 -23.202596) (xy 90.045758 -23.225532)
			(xy 90.097664 -23.255499) (xy 90.145214 -23.291986) (xy 90.187594 -23.334366) (xy 90.224081 -23.381916)
			(xy 90.254048 -23.433822) (xy 90.276984 -23.489195) (xy 90.292497 -23.547088) (xy 90.30032 -23.60651)
			(xy 90.30081 -23.636478) (xy 90.30032 -23.666446) (xy 90.292497 -23.725868) (xy 90.276984 -23.783761)
			(xy 90.254048 -23.839134) (xy 90.224081 -23.89104) (xy 90.187594 -23.93859) (xy 90.145214 -23.98097)
			(xy 90.097664 -24.017457) (xy 90.045758 -24.047424) (xy 89.990385 -24.07036) (xy 89.932492 -24.085873)
			(xy 89.87307 -24.093696) (xy 89.813134 -24.093696) (xy 89.753712 -24.085873) (xy 89.695819 -24.07036)
			(xy 89.640446 -24.047424) (xy 89.58854 -24.017457) (xy 89.54099 -23.98097) (xy 89.49861 -23.93859)
			(xy 89.462123 -23.89104) (xy 89.432156 -23.839134) (xy 89.40922 -23.783761) (xy 89.393707 -23.725868)
			(xy 89.385884 -23.666446) (xy 88.334001 -23.666446) (xy 88.086184 -23.914354) (xy 88.075971 -23.925155)
			(xy 88.060403 -23.950471) (xy 88.051103 -23.978698) (xy 88.048575 -24.00831) (xy 88.05037 -24.023066)
			(xy 88.054406 -24.053371) (xy 88.055364 -24.114501) (xy 88.048176 -24.175214) (xy 88.03297 -24.23443)
			(xy 88.010017 -24.291096) (xy 87.979726 -24.344201) (xy 87.942634 -24.392802) (xy 87.899404 -24.436032)
			(xy 87.850804 -24.473124) (xy 87.797699 -24.503416) (xy 87.741034 -24.526369) (xy 87.681818 -24.541575)
			(xy 87.621104 -24.548763) (xy 87.559975 -24.547806) (xy 87.52967 -24.543766) (xy 87.51491 -24.541934)
			(xy 87.48528 -24.544412) (xy 87.457038 -24.553714) (xy 87.431736 -24.569331) (xy 87.420958 -24.57958)
			(xy 87.395812 -24.604472) (xy 85.957664 -24.604472) (xy 85.934737 -24.604952) (xy 85.889621 -24.613149)
			(xy 85.846708 -24.629306) (xy 85.80739 -24.652899) (xy 85.772942 -24.683163) (xy 85.744482 -24.719116)
			(xy 85.722933 -24.759591) (xy 85.708995 -24.803275) (xy 85.703119 -24.848751) (xy 85.705497 -24.894543)
			(xy 85.716051 -24.939166) (xy 85.734438 -24.981171) (xy 85.746844 -25.000458) (xy 85.761602 -25.023255)
			(xy 85.785246 -25.072144) (xy 85.801715 -25.123892) (xy 85.810674 -25.177453) (xy 85.811943 -25.231744)
			(xy 85.805497 -25.285666) (xy 85.791465 -25.338127) (xy 85.770132 -25.388067) (xy 85.741929 -25.434475)
			(xy 85.707427 -25.476412) (xy 85.667323 -25.513029) (xy 85.62243 -25.543586) (xy 85.598254 -25.555956)
			(xy 85.579075 -25.56584) (xy 85.54408 -25.591073) (xy 85.513846 -25.621851) (xy 85.489241 -25.657291)
			(xy 85.47097 -25.696375) (xy 85.459559 -25.737982) (xy 85.455334 -25.780918) (xy 85.458417 -25.823951)
			(xy 85.463126 -25.845008) (xy 85.469878 -25.874592) (xy 85.473538 -25.907889) (xy 86.016665 -25.907889)
			(xy 86.017825 -25.846919) (xy 86.027072 -25.786643) (xy 86.044242 -25.728129) (xy 86.069031 -25.672413)
			(xy 86.101001 -25.620483) (xy 86.139583 -25.573259) (xy 86.184096 -25.531577) (xy 86.23375 -25.496177)
			(xy 86.287665 -25.467684) (xy 86.344887 -25.446604) (xy 86.404402 -25.43331) (xy 86.465155 -25.428038)
			(xy 86.495636 -25.428956) (xy 86.517026 -25.429534) (xy 86.559502 -25.424375) (xy 86.600512 -25.412171)
			(xy 86.638897 -25.393266) (xy 86.673571 -25.368196) (xy 86.703552 -25.337669) (xy 86.727994 -25.30255)
			(xy 86.746204 -25.263831) (xy 86.757668 -25.222607) (xy 86.760304 -25.201372) (xy 86.763612 -25.174036)
			(xy 86.777074 -25.120645) (xy 86.798073 -25.069744) (xy 86.826171 -25.02239) (xy 86.860785 -24.979568)
			(xy 86.901195 -24.942166) (xy 86.946563 -24.910963) (xy 86.995945 -24.886606) (xy 87.048316 -24.869601)
			(xy 87.102587 -24.860302) (xy 87.157632 -24.858902) (xy 87.212306 -24.865429) (xy 87.265473 -24.879749)
			(xy 87.31603 -24.901563) (xy 87.362926 -24.930419) (xy 87.405186 -24.965717) (xy 87.441932 -25.006724)
			(xy 87.472402 -25.052588) (xy 87.495962 -25.102355) (xy 87.512122 -25.154993) (xy 87.520547 -25.209407)
			(xy 87.521288 -25.236932) (xy 87.521948 -25.259332) (xy 87.530262 -25.303364) (xy 87.546166 -25.345258)
			(xy 87.56917 -25.383713) (xy 87.59856 -25.41754) (xy 87.633425 -25.445689) (xy 87.672686 -25.46729)
			(xy 87.693754 -25.47493) (xy 87.719972 -25.484332) (xy 87.769583 -25.509645) (xy 87.814986 -25.541902)
			(xy 87.855218 -25.580418) (xy 87.889421 -25.624373) (xy 87.916871 -25.672835) (xy 87.936983 -25.724772)
			(xy 87.949331 -25.779082) (xy 87.953651 -25.83461) (xy 87.952876 -25.845944) (xy 91.355001 -25.845944)
			(xy 91.358965 -25.786147) (xy 91.370698 -25.727378) (xy 91.39 -25.670643) (xy 91.416539 -25.616911)
			(xy 91.449862 -25.567102) (xy 91.4894 -25.522067) (xy 91.534476 -25.482575) (xy 91.559126 -25.465532)
			(xy 91.578273 -25.452118) (xy 91.611755 -25.419501) (xy 91.638711 -25.381312) (xy 91.658231 -25.338839)
			(xy 91.669658 -25.293514) (xy 91.672605 -25.246863) (xy 91.666975 -25.200459) (xy 91.660472 -25.178004)
			(xy 91.652794 -25.151888) (xy 91.64396 -25.098178) (xy 91.64285 -25.043758) (xy 91.649487 -24.989732)
			(xy 91.663737 -24.937199) (xy 91.68531 -24.887224) (xy 91.713767 -24.840824) (xy 91.748531 -24.79894)
			(xy 91.788896 -24.762423) (xy 91.834042 -24.732015) (xy 91.883052 -24.708333) (xy 91.93493 -24.691858)
			(xy 91.988624 -24.682925) (xy 92.043042 -24.681715) (xy 92.09708 -24.688253) (xy 92.149639 -24.702406)
			(xy 92.199653 -24.723887) (xy 92.246106 -24.752259) (xy 92.288053 -24.786946) (xy 92.324644 -24.827244)
			(xy 92.355136 -24.872334) (xy 92.378907 -24.9213) (xy 92.395477 -24.973149) (xy 92.404509 -25.026826)
			(xy 92.405819 -25.081242) (xy 92.39938 -25.135291) (xy 92.385323 -25.187877) (xy 92.363934 -25.23793)
			(xy 92.335647 -25.284435) (xy 92.301037 -25.326446) (xy 92.281248 -25.345136) (xy 92.27849 -25.347764)
			(xy 93.514411 -25.347764) (xy 93.520156 -25.293384) (xy 93.533605 -25.240382) (xy 93.554485 -25.189843)
			(xy 93.582366 -25.142803) (xy 93.616679 -25.100225) (xy 93.656718 -25.062983) (xy 93.701665 -25.031839)
			(xy 93.750599 -25.007432) (xy 93.802515 -24.990262) (xy 93.856352 -24.98068) (xy 93.911004 -24.978883)
			(xy 93.965354 -24.984907) (xy 93.991938 -24.991314) (xy 94.014232 -24.996654) (xy 94.059949 -25.000019)
			(xy 94.105529 -24.99513) (xy 94.149492 -24.982146) (xy 94.190414 -24.961487) (xy 94.226967 -24.933823)
			(xy 94.257966 -24.900053) (xy 94.282406 -24.86127) (xy 94.291404 -24.840184) (xy 94.30166 -24.815834)
			(xy 94.32794 -24.769999) (xy 94.360287 -24.728222) (xy 94.398082 -24.691302) (xy 94.440606 -24.659943)
			(xy 94.487045 -24.634744) (xy 94.511622 -24.625046) (xy 94.532982 -24.616502) (xy 94.572443 -24.592865)
			(xy 94.607004 -24.562509) (xy 94.635535 -24.526427) (xy 94.657102 -24.485797) (xy 94.671002 -24.441948)
			(xy 94.676781 -24.396313) (xy 94.674248 -24.350384) (xy 94.663488 -24.305661) (xy 94.654624 -24.284432)
			(xy 94.644256 -24.259829) (xy 94.62972 -24.208456) (xy 94.622482 -24.155559) (xy 94.622683 -24.10217)
			(xy 94.630319 -24.04933) (xy 94.637352 -24.023574) (xy 94.643198 -24.001594) (xy 94.647895 -23.95636)
			(xy 94.644466 -23.911013) (xy 94.633021 -23.866999) (xy 94.613927 -23.825725) (xy 94.587792 -23.788508)
			(xy 94.555451 -23.756536) (xy 94.517937 -23.73083) (xy 94.497398 -23.72106) (xy 94.470128 -23.708303)
			(xy 94.41894 -23.676609) (xy 94.372347 -23.638479) (xy 94.331154 -23.594571) (xy 94.296072 -23.545642)
			(xy 94.267705 -23.492538) (xy 94.246543 -23.436173) (xy 94.232952 -23.377521) (xy 94.227165 -23.317594)
			(xy 94.229283 -23.257425) (xy 94.23927 -23.198053) (xy 94.256952 -23.140502) (xy 94.282024 -23.085765)
			(xy 94.314055 -23.034787) (xy 94.352492 -22.988446) (xy 94.39667 -22.947544) (xy 94.445829 -22.912784)
			(xy 94.472252 -22.898354) (xy 94.492297 -22.88731) (xy 94.528344 -22.859118) (xy 94.558757 -22.824925)
			(xy 94.582555 -22.785836) (xy 94.598965 -22.743118) (xy 94.607459 -22.698151) (xy 94.607761 -22.652389)
			(xy 94.59986 -22.607314) (xy 94.592394 -22.58568) (xy 94.58342 -22.559768) (xy 94.572001 -22.506136)
			(xy 94.568378 -22.451422) (xy 94.572625 -22.396754) (xy 94.584654 -22.343256) (xy 94.604219 -22.292031)
			(xy 94.630916 -22.244135) (xy 94.664194 -22.200555) (xy 94.703369 -22.162187) (xy 94.747633 -22.129824)
			(xy 94.796074 -22.10413) (xy 94.847695 -22.085636) (xy 94.901431 -22.074723) (xy 94.956177 -22.071615)
			(xy 95.010803 -22.076377) (xy 95.064185 -22.08891) (xy 95.115223 -22.108957) (xy 95.162865 -22.136103)
			(xy 95.206131 -22.169791) (xy 95.244127 -22.209325) (xy 95.276073 -22.253892) (xy 95.301308 -22.302574)
			(xy 95.319315 -22.354366) (xy 95.325437 -22.386036) (xy 96.368106 -22.386036) (xy 96.372177 -22.330414)
			(xy 96.384303 -22.275977) (xy 96.404226 -22.223886) (xy 96.431522 -22.175251) (xy 96.465608 -22.131108)
			(xy 96.505757 -22.092399) (xy 96.551115 -22.059948) (xy 96.600715 -22.034447) (xy 96.653499 -22.01644)
			(xy 96.708342 -22.00631) (xy 96.764076 -22.004273) (xy 96.819513 -22.010373) (xy 96.87347 -22.024479)
			(xy 96.924799 -22.046291) (xy 96.972405 -22.075345) (xy 97.015273 -22.11102) (xy 97.05249 -22.152557)
			(xy 97.083263 -22.19907) (xy 97.106935 -22.249567) (xy 97.123003 -22.302974) (xy 97.131123 -22.35815)
			(xy 97.131632 -22.386036) (xy 97.131123 -22.413922) (xy 97.123003 -22.469098) (xy 97.106935 -22.522505)
			(xy 97.083263 -22.573002) (xy 97.05249 -22.619515) (xy 97.015273 -22.661052) (xy 97.010615 -22.664928)
			(xy 98.525582 -22.664928) (xy 98.529653 -22.609306) (xy 98.541779 -22.554869) (xy 98.561702 -22.502778)
			(xy 98.588998 -22.454143) (xy 98.623084 -22.41) (xy 98.663233 -22.371291) (xy 98.708591 -22.33884)
			(xy 98.758191 -22.313339) (xy 98.810975 -22.295332) (xy 98.865818 -22.285202) (xy 98.921552 -22.283165)
			(xy 98.976989 -22.289265) (xy 99.030946 -22.303371) (xy 99.082275 -22.325183) (xy 99.129881 -22.354237)
			(xy 99.172749 -22.389912) (xy 99.209966 -22.431449) (xy 99.240739 -22.477962) (xy 99.264411 -22.528459)
			(xy 99.280479 -22.581866) (xy 99.288599 -22.637042) (xy 99.289108 -22.664928) (xy 99.288599 -22.692814)
			(xy 99.280479 -22.74799) (xy 99.264411 -22.801397) (xy 99.240739 -22.851894) (xy 99.209966 -22.898407)
			(xy 99.172749 -22.939944) (xy 99.129881 -22.975619) (xy 99.082275 -23.004673) (xy 99.061759 -23.013391)
			(xy 100.568415 -23.013391) (xy 100.574608 -22.959064) (xy 100.588492 -22.906177) (xy 100.609783 -22.855813)
			(xy 100.638044 -22.809003) (xy 100.672696 -22.766706) (xy 100.713031 -22.729788) (xy 100.758222 -22.699005)
			(xy 100.807344 -22.674987) (xy 100.85939 -22.658226) (xy 100.913297 -22.649065) (xy 100.940616 -22.64791)
			(xy 100.964165 -22.646806) (xy 101.010259 -22.636929) (xy 101.053742 -22.618724) (xy 101.093122 -22.592813)
			(xy 101.127051 -22.560087) (xy 101.154364 -22.521666) (xy 101.174126 -22.478868) (xy 101.180392 -22.45614)
			(xy 101.187565 -22.42976) (xy 101.208396 -22.379217) (xy 101.236228 -22.332165) (xy 101.270491 -22.289566)
			(xy 101.310483 -22.252294) (xy 101.355384 -22.221111) (xy 101.404277 -22.196656) (xy 101.456159 -22.17943)
			(xy 101.509969 -22.169784) (xy 101.564605 -22.167917) (xy 101.618948 -22.173868) (xy 101.671885 -22.187513)
			(xy 101.722333 -22.208573) (xy 101.769258 -22.236619) (xy 101.811701 -22.271074) (xy 101.848791 -22.311235)
			(xy 101.87977 -22.356277) (xy 101.904003 -22.40528) (xy 101.920994 -22.45724) (xy 101.930395 -22.511094)
			(xy 101.932014 -22.565737) (xy 101.925817 -22.620052) (xy 101.911932 -22.672927) (xy 101.890642 -22.723279)
			(xy 101.862385 -22.770077) (xy 101.827737 -22.812362) (xy 101.787409 -22.84927) (xy 101.742226 -22.880044)
			(xy 101.693113 -22.904054) (xy 101.641077 -22.920809) (xy 101.587181 -22.929966) (xy 101.559868 -22.93112)
			(xy 101.536322 -22.932262) (xy 101.490233 -22.942138) (xy 101.446755 -22.960341) (xy 101.407376 -22.986245)
			(xy 101.373447 -23.018964) (xy 101.346131 -23.057377) (xy 101.326363 -23.100166) (xy 101.320092 -23.12289)
			(xy 101.313022 -23.149302) (xy 101.292194 -23.199859) (xy 101.264364 -23.246926) (xy 101.2301 -23.289539)
			(xy 101.190106 -23.326825) (xy 101.145199 -23.358021) (xy 101.096299 -23.382488) (xy 101.044408 -23.399726)
			(xy 100.990588 -23.40938) (xy 100.935941 -23.411255) (xy 100.881586 -23.40531) (xy 100.828636 -23.391669)
			(xy 100.778175 -23.370609) (xy 100.731236 -23.342563) (xy 100.688781 -23.308105) (xy 100.651679 -23.26794)
			(xy 100.620689 -23.222891) (xy 100.596446 -23.173879) (xy 100.579446 -23.12191) (xy 100.570038 -23.068046)
			(xy 100.568415 -23.013391) (xy 99.061759 -23.013391) (xy 99.030946 -23.026485) (xy 98.976989 -23.040591)
			(xy 98.921552 -23.046691) (xy 98.865818 -23.044654) (xy 98.810975 -23.034524) (xy 98.758191 -23.016517)
			(xy 98.708591 -22.991016) (xy 98.663233 -22.958565) (xy 98.623084 -22.919856) (xy 98.588998 -22.875713)
			(xy 98.561702 -22.827078) (xy 98.541779 -22.774987) (xy 98.529653 -22.72055) (xy 98.525582 -22.664928)
			(xy 97.010615 -22.664928) (xy 96.972405 -22.696727) (xy 96.924799 -22.725781) (xy 96.87347 -22.747593)
			(xy 96.819513 -22.761699) (xy 96.764076 -22.767799) (xy 96.708342 -22.765762) (xy 96.653499 -22.755632)
			(xy 96.600715 -22.737625) (xy 96.551115 -22.712124) (xy 96.505757 -22.679673) (xy 96.465608 -22.640964)
			(xy 96.431522 -22.596821) (xy 96.404226 -22.548186) (xy 96.384303 -22.496095) (xy 96.372177 -22.441658)
			(xy 96.368106 -22.386036) (xy 95.325437 -22.386036) (xy 95.329722 -22.408203) (xy 95.332313 -22.462976)
			(xy 95.327037 -22.517555) (xy 95.314001 -22.570816) (xy 95.293475 -22.621663) (xy 95.265881 -22.669047)
			(xy 95.231787 -22.711993) (xy 95.191896 -22.749616) (xy 95.169736 -22.765766) (xy 95.151323 -22.779369)
			(xy 95.119176 -22.811952) (xy 95.093388 -22.849768) (xy 95.074794 -22.891593) (xy 95.063996 -22.936073)
			(xy 95.061344 -22.981769) (xy 95.066924 -23.027199) (xy 95.080554 -23.070895) (xy 95.090742 -23.091394)
			(xy 95.104928 -23.119734) (xy 95.126265 -23.179408) (xy 95.139166 -23.241455) (xy 95.143383 -23.304689)
			(xy 95.138838 -23.3679) (xy 95.125615 -23.429879) (xy 95.103968 -23.489442) (xy 95.074312 -23.545449)
			(xy 95.056198 -23.571454) (xy 95.047723 -23.583828) (xy 95.036298 -23.611552) (xy 95.031669 -23.641177)
			(xy 95.034091 -23.671065) (xy 95.043431 -23.699559) (xy 95.059171 -23.725081) (xy 95.080439 -23.746218)
			(xy 95.106059 -23.761799) (xy 95.120206 -23.76678) (xy 95.135844 -23.771967) (xy 95.166239 -23.784686)
			(xy 95.180912 -23.79218) (xy 95.195771 -23.799484) (xy 95.228037 -23.80687) (xy 95.261117 -23.805697)
			(xy 95.292779 -23.796044) (xy 95.320887 -23.778564) (xy 95.343546 -23.754434) (xy 95.351854 -23.74011)
			(xy 95.365566 -23.715651) (xy 95.399122 -23.670727) (xy 95.438892 -23.631198) (xy 95.484021 -23.597917)
			(xy 95.533535 -23.5716) (xy 95.586367 -23.552814) (xy 95.641381 -23.541964) (xy 95.69739 -23.539283)
			(xy 95.753188 -23.54483) (xy 95.807573 -23.558484) (xy 95.859374 -23.579952) (xy 95.907474 -23.608771)
			(xy 95.950838 -23.644321) (xy 95.988532 -23.685835) (xy 96.019742 -23.732419) (xy 96.043798 -23.783071)
			(xy 96.06018 -23.836697) (xy 96.068536 -23.892144) (xy 96.068686 -23.948217) (xy 96.060627 -24.003708)
			(xy 96.044532 -24.057422) (xy 96.020747 -24.108201) (xy 95.989786 -24.154952) (xy 95.952316 -24.196667)
			(xy 95.909143 -24.232448) (xy 95.861197 -24.261524) (xy 95.809512 -24.283269) (xy 95.7552 -24.297214)
			(xy 95.699433 -24.303059) (xy 95.64341 -24.300678) (xy 95.588339 -24.290123) (xy 95.535407 -24.271619)
			(xy 95.51035 -24.259032) (xy 95.495445 -24.251836) (xy 95.463199 -24.244447) (xy 95.430137 -24.245607)
			(xy 95.398488 -24.255239) (xy 95.370386 -24.272693) (xy 95.347723 -24.296793) (xy 95.339408 -24.311102)
			(xy 95.32598 -24.334972) (xy 95.293329 -24.378943) (xy 95.254729 -24.417796) (xy 95.210972 -24.450733)
			(xy 95.162957 -24.477077) (xy 95.137478 -24.487124) (xy 95.116134 -24.495704) (xy 95.076675 -24.519337)
			(xy 95.042115 -24.549688) (xy 95.013585 -24.585766) (xy 94.992016 -24.62639) (xy 94.978114 -24.670234)
			(xy 94.972332 -24.715864) (xy 94.97486 -24.76179) (xy 94.985615 -24.80651) (xy 94.994476 -24.827738)
			(xy 95.005425 -24.854072) (xy 95.020468 -24.909076) (xy 95.027159 -24.965706) (xy 95.025348 -25.022701)
			(xy 95.015075 -25.078792) (xy 94.996569 -25.13273) (xy 94.970242 -25.183313) (xy 94.936681 -25.229415)
			(xy 94.896632 -25.270008) (xy 94.850989 -25.30419) (xy 94.800766 -25.331199) (xy 94.747084 -25.350433)
			(xy 94.691137 -25.361464) (xy 94.634172 -25.364046) (xy 94.577456 -25.358122) (xy 94.549722 -25.351486)
			(xy 94.527414 -25.34621) (xy 94.481703 -25.342836) (xy 94.436128 -25.347715) (xy 94.392168 -25.36069)
			(xy 94.351248 -25.38134) (xy 94.314695 -25.408995) (xy 94.283696 -25.442758) (xy 94.259255 -25.481533)
			(xy 94.250256 -25.502616) (xy 94.239658 -25.527824) (xy 94.212263 -25.575149) (xy 94.178392 -25.618078)
			(xy 94.138738 -25.655731) (xy 94.094115 -25.687337) (xy 94.045436 -25.712247) (xy 93.993699 -25.729952)
			(xy 93.939965 -25.740089) (xy 93.885333 -25.74245) (xy 93.830925 -25.736986) (xy 93.777853 -25.72381)
			(xy 93.727207 -25.703191) (xy 93.680024 -25.675553) (xy 93.63727 -25.64146) (xy 93.599822 -25.601613)
			(xy 93.568447 -25.556827) (xy 93.543788 -25.508021) (xy 93.52635 -25.456193) (xy 93.51649 -25.402407)
			(xy 93.514411 -25.347764) (xy 92.27849 -25.347764) (xy 92.264325 -25.361259) (xy 92.23615 -25.398549)
			(xy 92.215264 -25.440359) (xy 92.202368 -25.485282) (xy 92.197898 -25.531804) (xy 92.202004 -25.578361)
			(xy 92.214548 -25.623383) (xy 92.224352 -25.644602) (xy 92.237056 -25.671745) (xy 92.25621 -25.728531)
			(xy 92.26779 -25.78733) (xy 92.271599 -25.847137) (xy 92.267571 -25.90693) (xy 92.255776 -25.965686)
			(xy 92.236416 -26.022401) (xy 92.20982 -26.076105) (xy 92.176445 -26.125879) (xy 92.13686 -26.170873)
			(xy 92.091742 -26.210317) (xy 92.041864 -26.243537) (xy 91.988077 -26.269964) (xy 91.931302 -26.289148)
			(xy 91.872509 -26.300759) (xy 91.812704 -26.304599) (xy 91.752908 -26.300603) (xy 91.694146 -26.288839)
			(xy 91.637421 -26.269508) (xy 91.583703 -26.242941) (xy 91.533911 -26.209591) (xy 91.488897 -26.17003)
			(xy 91.449429 -26.124933) (xy 91.416183 -26.075072) (xy 91.389727 -26.021299) (xy 91.370514 -25.964534)
			(xy 91.358872 -25.905747) (xy 91.355001 -25.845944) (xy 87.952876 -25.845944) (xy 87.949851 -25.890175)
			(xy 87.938014 -25.944598) (xy 87.918389 -25.996722) (xy 87.891395 -26.045439) (xy 87.857604 -26.089713)
			(xy 87.817736 -26.128604) (xy 87.772636 -26.161285) (xy 87.723265 -26.187062) (xy 87.67067 -26.205386)
			(xy 87.61597 -26.21587) (xy 87.560327 -26.218288) (xy 87.504924 -26.212592) (xy 87.450937 -26.1989)
			(xy 87.399515 -26.177505) (xy 87.35175 -26.148861) (xy 87.308657 -26.113576) (xy 87.271152 -26.072401)
			(xy 87.240032 -26.026211) (xy 87.215958 -25.975987) (xy 87.199442 -25.922796) (xy 87.190835 -25.86777)
			(xy 87.190072 -25.839928) (xy 87.189105 -25.812172) (xy 87.176535 -25.758086) (xy 87.16518 -25.73274)
			(xy 87.15752 -25.718051) (xy 87.136013 -25.692871) (xy 87.108749 -25.674076) (xy 87.077566 -25.662933)
			(xy 87.044565 -25.660193) (xy 87.011971 -25.66604) (xy 86.981981 -25.680081) (xy 86.956616 -25.701368)
			(xy 86.937585 -25.728468) (xy 86.926172 -25.759553) (xy 86.923146 -25.792529) (xy 86.925404 -25.80894)
			(xy 86.930035 -25.839081) (xy 86.932242 -25.900023) (xy 86.926336 -25.960718) (xy 86.912422 -26.02009)
			(xy 86.890747 -26.077089) (xy 86.861693 -26.130705) (xy 86.825776 -26.179987) (xy 86.783632 -26.224062)
			(xy 86.736008 -26.26215) (xy 86.683748 -26.293576) (xy 86.627777 -26.317782) (xy 86.569086 -26.334341)
			(xy 86.508717 -26.342959) (xy 86.447738 -26.343483) (xy 86.387229 -26.335904) (xy 86.328263 -26.320356)
			(xy 86.271885 -26.297114) (xy 86.219092 -26.266591) (xy 86.17082 -26.229327) (xy 86.127926 -26.185983)
			(xy 86.091167 -26.137325) (xy 86.061197 -26.084217) (xy 86.038544 -26.027599) (xy 86.023612 -25.968474)
			(xy 86.016665 -25.907889) (xy 85.473538 -25.907889) (xy 85.476508 -25.934909) (xy 85.475109 -25.995572)
			(xy 85.465705 -26.055519) (xy 85.448461 -26.113697) (xy 85.423679 -26.169086) (xy 85.391795 -26.220714)
			(xy 85.353367 -26.267675) (xy 85.30907 -26.309146) (xy 85.259681 -26.344399) (xy 85.206066 -26.372815)
			(xy 85.149165 -26.393896) (xy 85.089978 -26.407273) (xy 85.029542 -26.41271) (xy 84.968918 -26.410112)
			(xy 84.909169 -26.399525) (xy 84.851343 -26.381135) (xy 84.796455 -26.355264) (xy 84.745467 -26.322365)
			(xy 84.699274 -26.283017) (xy 84.658687 -26.237909) (xy 84.624417 -26.187833) (xy 84.597066 -26.133666)
			(xy 84.577113 -26.076361) (xy 84.564909 -26.016921) (xy 84.560667 -25.956389) (xy 84.564462 -25.895828)
			(xy 84.576228 -25.8363) (xy 84.595758 -25.778849) (xy 84.622709 -25.724482) (xy 84.656608 -25.674155)
			(xy 84.696862 -25.628749) (xy 84.742763 -25.589061) (xy 84.793507 -25.555787) (xy 84.848203 -25.529512)
			(xy 84.876894 -25.519634) (xy 84.897279 -25.512555) (xy 84.935453 -25.492436) (xy 84.96968 -25.466159)
			(xy 84.998977 -25.434478) (xy 85.022503 -25.398304) (xy 85.039581 -25.358677) (xy 85.049721 -25.316734)
			(xy 85.052631 -25.273681) (xy 85.050884 -25.252172) (xy 85.048657 -25.225776) (xy 85.050628 -25.172842)
			(xy 85.059896 -25.120688) (xy 85.076283 -25.070315) (xy 85.099476 -25.022691) (xy 85.113876 -25.000458)
			(xy 85.126244 -24.981156) (xy 85.144597 -24.939154) (xy 85.155124 -24.894541) (xy 85.157483 -24.848765)
			(xy 85.151598 -24.803307) (xy 85.137659 -24.75964) (xy 85.116119 -24.719179) (xy 85.087676 -24.683235)
			(xy 85.053249 -24.652971) (xy 85.013956 -24.629369) (xy 84.971068 -24.613192) (xy 84.925975 -24.604966)
			(xy 84.903056 -24.604472) (xy 83.466178 -24.604472) (xy 83.444035 -24.605005) (xy 83.400418 -24.61267)
			(xy 83.35879 -24.627781) (xy 83.320413 -24.649881) (xy 83.286449 -24.6783) (xy 83.257927 -24.712178)
			(xy 83.23571 -24.750487) (xy 83.220472 -24.792068) (xy 83.212674 -24.835662) (xy 83.212552 -24.879947)
			(xy 83.220111 -24.923583) (xy 83.227164 -24.944578) (xy 83.238346 -24.977807) (xy 83.251676 -25.046634)
			(xy 83.254376 -25.116688) (xy 83.25104 -25.151588) (xy 83.249691 -25.167761) (xy 83.25428 -25.199878)
			(xy 83.266813 -25.229802) (xy 83.286481 -25.255604) (xy 83.312016 -25.275617) (xy 83.341769 -25.288552)
			(xy 83.35772 -25.291542) (xy 83.385136 -25.296294) (xy 83.438299 -25.312713) (xy 83.488513 -25.336681)
			(xy 83.534712 -25.36769) (xy 83.575915 -25.405082) (xy 83.61125 -25.448063) (xy 83.639965 -25.495721)
			(xy 83.661452 -25.547046) (xy 83.675255 -25.600947) (xy 83.68108 -25.656282) (xy 83.678805 -25.711876)
			(xy 83.668477 -25.76655) (xy 83.650315 -25.819143) (xy 83.624706 -25.86854) (xy 83.592192 -25.913693)
			(xy 83.553463 -25.953642) (xy 83.53171 -25.970992) (xy 83.51981 -25.98072) (xy 83.50065 -26.004739)
			(xy 83.487796 -26.032647) (xy 83.481998 -26.062821) (xy 83.483593 -26.093506) (xy 83.492487 -26.122916)
			(xy 83.49996 -26.136346) (xy 83.515003 -26.162547) (xy 83.538713 -26.21812) (xy 83.554906 -26.276329)
			(xy 83.563302 -26.336163) (xy 83.563755 -26.39658) (xy 83.556257 -26.456533) (xy 83.540938 -26.514978)
			(xy 83.518065 -26.5709) (xy 83.488034 -26.623328) (xy 83.451368 -26.67135) (xy 83.408705 -26.714133)
			(xy 83.360784 -26.750931) (xy 83.30844 -26.781107) (xy 83.252581 -26.804135) (xy 83.194178 -26.819615)
			(xy 83.134247 -26.827279) (xy 83.073828 -26.826994) (xy 83.013972 -26.818763) (xy 82.955718 -26.802731)
			(xy 82.90008 -26.779175) (xy 82.848023 -26.748506) (xy 82.800452 -26.711256) (xy 82.758195 -26.668072)
			(xy 82.721985 -26.619706) (xy 82.692452 -26.566996) (xy 82.670108 -26.51086) (xy 82.655343 -26.452272)
			(xy 82.648412 -26.392252) (xy 82.649436 -26.331841) (xy 82.658398 -26.27209) (xy 82.675141 -26.214037)
			(xy 82.699375 -26.15869) (xy 82.730678 -26.107012) (xy 82.768507 -26.059901) (xy 82.812204 -26.018175)
			(xy 82.86101 -25.982559) (xy 82.887312 -25.96769) (xy 82.900624 -25.960013) (xy 82.923321 -25.939304)
			(xy 82.940402 -25.913765) (xy 82.950874 -25.884881) (xy 82.95413 -25.85433) (xy 82.949979 -25.823887)
			(xy 82.944716 -25.809448) (xy 82.933142 -25.778332) (xy 82.919731 -25.713318) (xy 82.918046 -25.680162)
			(xy 82.917002 -25.663981) (xy 82.90782 -25.632896) (xy 82.891104 -25.605126) (xy 82.867932 -25.582463)
			(xy 82.839798 -25.566368) (xy 82.808516 -25.557878) (xy 82.792316 -25.557226) (xy 82.76227 -25.55644)
			(xy 82.702755 -25.548041) (xy 82.644852 -25.531926) (xy 82.589556 -25.50837) (xy 82.53782 -25.477779)
			(xy 82.490532 -25.440679) (xy 82.448507 -25.39771) (xy 82.412468 -25.349609) (xy 82.383034 -25.297205)
			(xy 82.360713 -25.2414) (xy 82.345888 -25.183153) (xy 82.338815 -25.123466) (xy 82.339614 -25.063367)
			(xy 82.348273 -25.00389) (xy 82.364643 -24.946058) (xy 82.388441 -24.890866) (xy 82.403442 -24.864822)
			(xy 82.411062 -24.851188) (xy 82.420048 -24.821283) (xy 82.4215 -24.790091) (xy 82.41533 -24.75948)
			(xy 82.40903 -24.745188) (xy 82.376518 -24.676862) (xy 82.368238 -24.660953) (xy 82.344398 -24.634178)
			(xy 82.314072 -24.615058) (xy 82.279635 -24.605093) (xy 82.26171 -24.604472) (xy 82.15503 -24.604472)
			(xy 82.131717 -24.605055) (xy 82.085876 -24.613573) (xy 82.042357 -24.630311) (xy 82.002622 -24.654707)
			(xy 81.968005 -24.685942) (xy 81.939666 -24.722967) (xy 81.918557 -24.764541) (xy 81.905386 -24.809269)
			(xy 81.900595 -24.855648) (xy 81.904345 -24.902123) (xy 81.90992 -24.924766) (xy 81.91743 -24.954239)
			(xy 81.925345 -25.014545) (xy 81.925205 -25.075368) (xy 81.917011 -25.135636) (xy 81.900908 -25.194289)
			(xy 81.87718 -25.250293) (xy 81.846245 -25.302662) (xy 81.808646 -25.350472) (xy 81.765048 -25.392883)
			(xy 81.716218 -25.429146) (xy 81.663015 -25.458624) (xy 81.606377 -25.480796) (xy 81.547302 -25.495273)
			(xy 81.48683 -25.5018) (xy 81.426026 -25.50026) (xy 81.365962 -25.490683) (xy 81.307695 -25.473235)
			(xy 81.252251 -25.448225) (xy 81.200608 -25.416094) (xy 81.153675 -25.377406) (xy 81.112278 -25.332844)
			(xy 81.077147 -25.283192) (xy 81.048901 -25.229326) (xy 81.028037 -25.172193) (xy 81.014922 -25.1128)
			(xy 81.009788 -25.052194) (xy 81.01076 -25.021794) (xy 81.011313 -24.999104) (xy 81.005408 -24.95411)
			(xy 80.991605 -24.910879) (xy 80.970345 -24.870786) (xy 80.942304 -24.835106) (xy 80.908372 -24.804973)
			(xy 80.869628 -24.781345) (xy 80.827304 -24.764972) (xy 80.782745 -24.756375) (xy 80.760062 -24.755602)
			(xy 80.730308 -24.7547) (xy 80.671617 -24.744765) (xy 80.615179 -24.725843) (xy 80.562361 -24.698393)
			(xy 80.514442 -24.663079) (xy 80.493108 -24.642318) (xy 80.480951 -24.630706) (xy 80.451929 -24.613761)
			(xy 80.419488 -24.604985) (xy 80.402684 -24.604472) (xy 79.715868 -24.604472) (xy 79.655924 -24.640032)
			(xy 79.63916 -24.670512) (xy 79.626064 -24.693562) (xy 79.594461 -24.736127) (xy 79.557264 -24.773901)
			(xy 79.515192 -24.806156) (xy 79.492348 -24.81961) (xy 79.47274 -24.831252) (xy 79.437667 -24.860386)
			(xy 79.408361 -24.895317) (xy 79.385766 -24.93492) (xy 79.370608 -24.977923) (xy 79.363375 -25.022941)
			(xy 79.3643 -25.068528) (xy 79.373352 -25.113216) (xy 79.38135 -25.13457) (xy 79.39197 -25.162644)
			(xy 79.40664 -25.220849) (xy 79.413576 -25.280471) (xy 79.41266 -25.340488) (xy 79.403907 -25.399871)
			(xy 79.387468 -25.457601) (xy 79.363624 -25.512686) (xy 79.332785 -25.564183) (xy 79.29548 -25.611206)
			(xy 79.252349 -25.652951) (xy 79.204131 -25.6887) (xy 79.151655 -25.71784) (xy 79.09582 -25.739872)
			(xy 79.037584 -25.754416) (xy 78.977947 -25.761224) (xy 78.917932 -25.760179) (xy 78.858568 -25.751299)
			(xy 78.800874 -25.734736) (xy 78.74584 -25.710774) (xy 78.694409 -25.679825) (xy 78.647466 -25.642419)
			(xy 78.605814 -25.599198) (xy 78.570168 -25.550904) (xy 78.541141 -25.498365) (xy 78.519229 -25.442483)
			(xy 78.504809 -25.384216) (xy 78.498129 -25.324565) (xy 78.499303 -25.264552) (xy 78.508311 -25.205207)
			(xy 78.524997 -25.147549) (xy 78.549077 -25.092566) (xy 78.580137 -25.041203) (xy 78.598522 -25.017476)
			(xy 78.611915 -25.000056) (xy 78.633109 -24.961569) (xy 78.647368 -24.920011) (xy 78.654267 -24.876619)
			(xy 78.653601 -24.832687) (xy 78.645388 -24.789524) (xy 78.629875 -24.748417) (xy 78.607523 -24.710591)
			(xy 78.578998 -24.677173) (xy 78.545151 -24.649158) (xy 78.50699 -24.627382) (xy 78.465653 -24.612494)
			(xy 78.42237 -24.604937) (xy 78.400402 -24.604472) (xy 77.639164 -24.604472) (xy 77.616474 -24.604939)
			(xy 77.571807 -24.612953) (xy 77.529275 -24.628774) (xy 77.49023 -24.651899) (xy 77.455913 -24.681592)
			(xy 77.427416 -24.716908) (xy 77.405645 -24.756724) (xy 77.391294 -24.799775) (xy 77.384818 -24.84469)
			(xy 77.386423 -24.890041) (xy 77.390752 -24.91232) (xy 77.396134 -24.939325) (xy 77.399906 -24.99426)
			(xy 77.395743 -25.049166) (xy 77.383732 -25.102905) (xy 77.364121 -25.154358) (xy 77.337318 -25.202459)
			(xy 77.30388 -25.246208) (xy 77.264501 -25.284697) (xy 77.219999 -25.317126) (xy 77.171298 -25.342822)
			(xy 77.119409 -25.361251) (xy 77.06541 -25.372031) (xy 77.010423 -25.374937) (xy 76.955588 -25.36991)
			(xy 76.902046 -25.357054) (xy 76.850907 -25.336635) (xy 76.803235 -25.309078) (xy 76.760018 -25.274955)
			(xy 76.722154 -25.234975) (xy 76.69043 -25.189968) (xy 76.665504 -25.140868) (xy 76.647894 -25.088695)
			(xy 76.637966 -25.034533) (xy 76.635926 -24.979507) (xy 76.641816 -24.924759) (xy 76.655514 -24.871425)
			(xy 76.676736 -24.820615) (xy 76.690474 -24.79675) (xy 76.708508 -24.766778) (xy 76.708508 -24.731472)
			(xy 76.707981 -24.714823) (xy 76.699358 -24.682661) (xy 76.682705 -24.653826) (xy 76.659158 -24.630283)
			(xy 76.63032 -24.613635) (xy 76.598157 -24.605016) (xy 76.581508 -24.604472) (xy 76.496672 -24.604472)
			(xy 75.978512 -25.122632) (xy 75.490578 -25.122632) (xy 75.467078 -25.123102) (xy 75.420878 -25.131728)
			(xy 75.37705 -25.148699) (xy 75.337089 -25.173438) (xy 75.302357 -25.205101) (xy 75.274037 -25.24261)
			(xy 75.253095 -25.284685) (xy 75.240244 -25.329893) (xy 75.235923 -25.376692) (xy 75.240278 -25.423489)
			(xy 75.24623 -25.446228) (xy 75.249327 -25.457579) (xy 75.254285 -25.480582) (xy 75.256136 -25.492202)
			(xy 75.260217 -25.515355) (xy 75.275766 -25.559718) (xy 75.299217 -25.60046) (xy 75.329767 -25.636188)
			(xy 75.366373 -25.665681) (xy 75.407783 -25.687931) (xy 75.452581 -25.702177) (xy 75.475846 -25.705562)
			(xy 75.505538 -25.709805) (xy 75.563582 -25.724913) (xy 75.619154 -25.747473) (xy 75.671304 -25.7771)
			(xy 75.719137 -25.813284) (xy 75.761833 -25.855407) (xy 75.798661 -25.902746) (xy 75.828989 -25.954491)
			(xy 75.852299 -26.009754) (xy 75.86819 -26.067588) (xy 75.87639 -26.127002) (xy 75.876758 -26.186978)
			(xy 75.869289 -26.246489) (xy 75.85411 -26.304514) (xy 75.831482 -26.360059) (xy 75.801792 -26.412172)
			(xy 75.765548 -26.459961) (xy 75.723373 -26.502605) (xy 75.675989 -26.539375) (xy 75.624207 -26.56964)
			(xy 75.568916 -26.592882) (xy 75.511063 -26.608702) (xy 75.451638 -26.61683) (xy 75.391662 -26.617125)
			(xy 75.33216 -26.609583) (xy 75.274154 -26.594333) (xy 75.218636 -26.571636) (xy 75.16656 -26.541882)
			(xy 75.118816 -26.505581) (xy 75.076223 -26.463353) (xy 75.039511 -26.415924) (xy 75.009309 -26.364106)
			(xy 74.986135 -26.308786) (xy 74.970386 -26.250913) (xy 74.962331 -26.191479) (xy 74.96175 -26.161492)
			(xy 74.961122 -26.138006) (xy 74.952323 -26.091862) (xy 74.935193 -26.04812) (xy 74.910315 -26.008273)
			(xy 74.878536 -25.973677) (xy 74.840941 -25.945511) (xy 74.798809 -25.924735) (xy 74.77633 -25.917906)
			(xy 74.760074 -25.91308) (xy 74.744024 -25.908284) (xy 74.710581 -25.906483) (xy 74.677822 -25.913445)
			(xy 74.648003 -25.928691) (xy 74.623177 -25.951171) (xy 74.605056 -25.979336) (xy 74.594888 -26.011246)
			(xy 74.593372 -26.044703) (xy 74.596498 -26.061162) (xy 74.602562 -26.091126) (xy 74.607657 -26.152048)
			(xy 74.604598 -26.213106) (xy 74.593441 -26.273214) (xy 74.574383 -26.331302) (xy 74.547763 -26.386337)
			(xy 74.514056 -26.43734) (xy 74.473861 -26.483402) (xy 74.427892 -26.523706) (xy 74.376969 -26.557532)
			(xy 74.321996 -26.58428) (xy 74.263953 -26.603474) (xy 74.203871 -26.614772) (xy 74.14282 -26.617973)
			(xy 74.081887 -26.613021) (xy 74.022154 -26.600003) (xy 73.964686 -26.57915) (xy 73.910504 -26.550835)
			(xy 73.860573 -26.51556) (xy 73.81578 -26.473954) (xy 73.776924 -26.426757) (xy 73.744694 -26.374807)
			(xy 73.719666 -26.319031) (xy 73.702283 -26.26042) (xy 73.692856 -26.200016) (xy 73.691552 -26.138896)
			(xy 73.698394 -26.078145) (xy 73.71326 -26.018846) (xy 73.735887 -25.962052) (xy 73.765871 -25.908776)
			(xy 73.802678 -25.859963) (xy 73.845655 -25.816484) (xy 73.894036 -25.779112) (xy 73.946961 -25.748511)
			(xy 74.003488 -25.725226) (xy 74.06261 -25.709672) (xy 74.123277 -25.702124) (xy 74.184409 -25.702718)
			(xy 74.214736 -25.706578) (xy 74.236634 -25.70925) (xy 74.280724 -25.707863) (xy 74.323914 -25.698891)
			(xy 74.364908 -25.682602) (xy 74.402477 -25.659486) (xy 74.435496 -25.630234) (xy 74.462973 -25.595726)
			(xy 74.484085 -25.556994) (xy 74.498198 -25.515201) (xy 74.50201 -25.493472) (xy 74.506196 -25.468524)
			(xy 74.520342 -25.419954) (xy 74.540777 -25.373677) (xy 74.567143 -25.330503) (xy 74.59898 -25.291189)
			(xy 74.617072 -25.273508) (xy 74.633117 -25.257616) (xy 74.65992 -25.221276) (xy 74.679882 -25.180773)
			(xy 74.692376 -25.137381) (xy 74.697009 -25.092464) (xy 74.693635 -25.047435) (xy 74.68236 -25.00371)
			(xy 74.66354 -24.962664) (xy 74.637765 -24.925588) (xy 74.622152 -24.909272) (xy 74.317352 -24.604472)
			(xy 73.952354 -24.604472) (xy 73.9013 -24.628602) (xy 73.883012 -24.6507) (xy 73.864802 -24.671983)
			(xy 73.82321 -24.709497) (xy 73.776578 -24.740525) (xy 73.72591 -24.764399) (xy 73.672294 -24.780606)
			(xy 73.616886 -24.788798) (xy 73.560874 -24.788798) (xy 73.505466 -24.780606) (xy 73.45185 -24.764399)
			(xy 73.401182 -24.740525) (xy 73.35455 -24.709497) (xy 73.312958 -24.671983) (xy 73.294748 -24.6507)
			(xy 73.27646 -24.628602) (xy 73.225406 -24.604472) (xy 73.072498 -24.604472) (xy 73.039986 -24.626824)
			(xy 73.01605 -24.642601) (xy 72.964444 -24.667565) (xy 72.909685 -24.684527) (xy 72.853003 -24.693104)
			(xy 72.795677 -24.693104) (xy 72.738995 -24.684527) (xy 72.684236 -24.667565) (xy 72.63263 -24.642601)
			(xy 72.608694 -24.626824) (xy 72.576182 -24.604472) (xy 72.047354 -24.604472) (xy 72.024822 -24.604888)
			(xy 71.980468 -24.612862) (xy 71.938215 -24.628532) (xy 71.899388 -24.651409) (xy 71.865205 -24.680774)
			(xy 71.836736 -24.715708) (xy 71.814874 -24.755115) (xy 71.800305 -24.79776) (xy 71.793485 -24.842306)
			(xy 71.794629 -24.887357) (xy 71.798688 -24.909526) (xy 71.803696 -24.936911) (xy 71.806778 -24.992492)
			(xy 71.801751 -25.047931) (xy 71.78872 -25.102051) (xy 71.767963 -25.153702) (xy 71.73992 -25.201789)
			(xy 71.705187 -25.24529) (xy 71.664501 -25.283282) (xy 71.618725 -25.314958) (xy 71.568833 -25.339645)
			(xy 71.515882 -25.35682) (xy 71.460997 -25.366118) (xy 71.433182 -25.367234) (xy 71.410255 -25.368274)
			(xy 71.365309 -25.377524) (xy 71.322752 -25.39469) (xy 71.283967 -25.419215) (xy 71.250213 -25.450303)
			(xy 71.222588 -25.486945) (xy 71.201986 -25.527949) (xy 71.189079 -25.571985) (xy 71.184285 -25.617622)
			(xy 71.185532 -25.640538) (xy 71.187137 -25.668628) (xy 71.183093 -25.724743) (xy 71.170851 -25.779657)
			(xy 71.150677 -25.832177) (xy 71.123009 -25.881164) (xy 71.088446 -25.925557) (xy 71.068438 -25.945338)
			(xy 71.052687 -25.960997) (xy 71.026396 -25.99679) (xy 71.006726 -26.036608) (xy 70.994277 -26.079239)
			(xy 70.989428 -26.123385) (xy 70.992326 -26.167702) (xy 71.002882 -26.210841) (xy 71.020776 -26.251488)
			(xy 71.045463 -26.288406) (xy 71.076191 -26.320471) (xy 71.093838 -26.333958) (xy 71.115698 -26.350547)
			(xy 71.154885 -26.388962) (xy 71.188162 -26.432597) (xy 71.214843 -26.48055) (xy 71.234377 -26.531831)
			(xy 71.246361 -26.585382) (xy 71.250547 -26.640098) (xy 71.246848 -26.694849) (xy 71.235343 -26.748505)
			(xy 71.216266 -26.799958) (xy 71.190014 -26.848147) (xy 71.157127 -26.892077) (xy 71.118284 -26.93084)
			(xy 71.074287 -26.963637) (xy 71.035951 -26.98442) (xy 71.67868 -26.98442) (xy 71.678682 -26.918958)
			(xy 71.687087 -26.854037) (xy 71.703757 -26.790732) (xy 71.728416 -26.730092) (xy 71.760655 -26.673119)
			(xy 71.779892 -26.646632) (xy 71.805292 -26.61285) (xy 71.805292 -26.595832) (xy 71.820532 -26.595832)
			(xy 71.856346 -26.565352) (xy 71.879415 -26.546228) (xy 71.929223 -26.512913) (xy 71.982603 -26.485687)
			(xy 72.038815 -26.464929) (xy 72.097079 -26.450925) (xy 72.156585 -26.443871) (xy 72.186546 -26.443432)
			(xy 73.04913 -26.443432) (xy 73.081073 -26.443963) (xy 73.144455 -26.451974) (xy 73.206333 -26.467865)
			(xy 73.265732 -26.491385) (xy 73.321714 -26.522165) (xy 73.373398 -26.559718) (xy 73.419967 -26.603452)
			(xy 73.460688 -26.652678) (xy 73.494919 -26.70662) (xy 73.522119 -26.764426) (xy 73.541861 -26.825186)
			(xy 73.553831 -26.88794) (xy 73.557843 -26.9517) (xy 73.553831 -27.01546) (xy 73.550832 -27.031184)
			(xy 85.300802 -27.031184) (xy 85.300802 -26.971248) (xy 85.308625 -26.911826) (xy 85.324138 -26.853933)
			(xy 85.347074 -26.79856) (xy 85.377041 -26.746654) (xy 85.413528 -26.699104) (xy 85.455908 -26.656724)
			(xy 85.503458 -26.620237) (xy 85.555364 -26.59027) (xy 85.610737 -26.567334) (xy 85.66863 -26.551821)
			(xy 85.728052 -26.543998) (xy 85.787988 -26.543998) (xy 85.84741 -26.551821) (xy 85.905303 -26.567334)
			(xy 85.960676 -26.59027) (xy 86.012582 -26.620237) (xy 86.060132 -26.656724) (xy 86.102512 -26.699104)
			(xy 86.138999 -26.746654) (xy 86.151497 -26.768301) (xy 88.973378 -26.768301) (xy 88.977898 -26.713851)
			(xy 88.990139 -26.660602) (xy 89.009851 -26.609644) (xy 89.03663 -26.562018) (xy 89.069929 -26.5187)
			(xy 89.109066 -26.480575) (xy 89.153242 -26.448422) (xy 89.201552 -26.4229) (xy 89.253009 -26.40453)
			(xy 89.306561 -26.393689) (xy 89.361111 -26.390597) (xy 89.415544 -26.395318) (xy 89.468747 -26.407756)
			(xy 89.49436 -26.41727) (xy 89.516449 -26.425401) (xy 89.562685 -26.434194) (xy 89.60975 -26.43432)
			(xy 89.656033 -26.425777) (xy 89.699951 -26.408855) (xy 89.740001 -26.384134) (xy 89.774813 -26.35246)
			(xy 89.803196 -26.314916) (xy 89.814146 -26.29408) (xy 89.826704 -26.269919) (xy 89.857706 -26.225153)
			(xy 89.894756 -26.185249) (xy 89.937103 -26.151017) (xy 89.983887 -26.123153) (xy 90.034157 -26.102223)
			(xy 90.086891 -26.088652) (xy 90.141019 -26.082716) (xy 90.195442 -26.084535) (xy 90.249053 -26.094072)
			(xy 90.300763 -26.111134) (xy 90.349523 -26.135374) (xy 90.394342 -26.1663) (xy 90.434308 -26.203283)
			(xy 90.468612 -26.245572) (xy 90.496555 -26.292308) (xy 90.51757 -26.342542) (xy 90.531231 -26.395253)
			(xy 90.537259 -26.449371) (xy 90.535532 -26.503797) (xy 90.526086 -26.557424) (xy 90.509112 -26.609163)
			(xy 90.484955 -26.657964) (xy 90.454105 -26.702835) (xy 90.41719 -26.742865) (xy 90.374959 -26.77724)
			(xy 90.351864 -26.791666) (xy 90.332381 -26.803868) (xy 90.297852 -26.834211) (xy 90.269345 -26.870272)
			(xy 90.247791 -26.910873) (xy 90.233893 -26.954689) (xy 90.228105 -27.000291) (xy 90.230615 -27.04619)
			(xy 90.241343 -27.090889) (xy 90.259936 -27.132928) (xy 90.28579 -27.170936) (xy 90.301572 -27.187652)
			(xy 90.320297 -27.207438) (xy 90.352611 -27.251292) (xy 90.378359 -27.299295) (xy 90.397017 -27.350473)
			(xy 90.408207 -27.403784) (xy 90.4117 -27.458145) (xy 90.407426 -27.51245) (xy 90.395471 -27.565595)
			(xy 90.394016 -27.569414) (xy 91.26804 -27.569414) (xy 91.272111 -27.513792) (xy 91.284237 -27.459355)
			(xy 91.30416 -27.407264) (xy 91.331456 -27.358629) (xy 91.365542 -27.314486) (xy 91.405691 -27.275777)
			(xy 91.451049 -27.243326) (xy 91.500649 -27.217825) (xy 91.553433 -27.199818) (xy 91.608276 -27.189688)
			(xy 91.66401 -27.187651) (xy 91.719447 -27.193751) (xy 91.773404 -27.207857) (xy 91.824733 -27.229669)
			(xy 91.872339 -27.258723) (xy 91.915207 -27.294398) (xy 91.952424 -27.335935) (xy 91.983197 -27.382448)
			(xy 92.006869 -27.432945) (xy 92.022937 -27.486352) (xy 92.031057 -27.541528) (xy 92.031566 -27.569414)
			(xy 92.031057 -27.5973) (xy 92.025345 -27.636116) (xy 95.147495 -27.636116) (xy 95.150646 -27.580771)
			(xy 95.161776 -27.526466) (xy 95.180649 -27.474343) (xy 95.206868 -27.425501) (xy 95.23988 -27.380969)
			(xy 95.278992 -27.341685) (xy 95.323377 -27.308475) (xy 95.372103 -27.282041) (xy 95.424142 -27.262937)
			(xy 95.478397 -27.251568) (xy 95.506032 -27.249374) (xy 95.528778 -27.247551) (xy 95.57309 -27.236656)
			(xy 95.614744 -27.218025) (xy 95.652403 -27.192257) (xy 95.684856 -27.160179) (xy 95.711061 -27.122823)
			(xy 95.730176 -27.081389) (xy 95.741586 -27.037208) (xy 95.744925 -26.991699) (xy 95.743014 -26.968958)
			(xy 95.740268 -26.938225) (xy 95.742064 -26.876549) (xy 95.75213 -26.815674) (xy 95.770282 -26.756702)
			(xy 95.796192 -26.700704) (xy 95.829389 -26.648694) (xy 95.869273 -26.601614) (xy 95.891858 -26.580592)
			(xy 95.908282 -26.565139) (xy 95.935988 -26.529564) (xy 95.956971 -26.489653) (xy 95.970571 -26.446662)
			(xy 95.97636 -26.401944) (xy 95.974156 -26.356908) (xy 95.964028 -26.312969) (xy 95.955612 -26.292048)
			(xy 95.945392 -26.266866) (xy 95.931419 -26.214345) (xy 95.925038 -26.160374) (xy 95.926377 -26.106043)
			(xy 95.935409 -26.052452) (xy 95.951951 -26.000684) (xy 95.975669 -25.951785) (xy 96.006083 -25.906745)
			(xy 96.042578 -25.866475) (xy 96.084417 -25.831789) (xy 96.130752 -25.803387) (xy 96.15551 -25.792176)
			(xy 96.175872 -25.782843) (xy 96.213231 -25.758139) (xy 96.245681 -25.727269) (xy 96.272218 -25.691189)
			(xy 96.292021 -25.651017) (xy 96.304475 -25.607996) (xy 96.309196 -25.563457) (xy 96.306038 -25.518781)
			(xy 96.295097 -25.47535) (xy 96.276714 -25.434508) (xy 96.264476 -25.415748) (xy 96.247956 -25.390551)
			(xy 96.220843 -25.336746) (xy 96.201024 -25.27985) (xy 96.188842 -25.220844) (xy 96.184507 -25.160751)
			(xy 96.188094 -25.100608) (xy 96.199541 -25.041456) (xy 96.218651 -24.984317) (xy 96.245092 -24.930179)
			(xy 96.278408 -24.879979) (xy 96.318022 -24.834584) (xy 96.363251 -24.794779) (xy 96.413311 -24.761252)
			(xy 96.467337 -24.734584) (xy 96.524395 -24.715234) (xy 96.583499 -24.703539) (xy 96.643626 -24.699699)
			(xy 96.703737 -24.703782) (xy 96.762793 -24.715716) (xy 96.819772 -24.735296) (xy 96.87369 -24.762182)
			(xy 96.923614 -24.795911) (xy 96.946466 -24.815546) (xy 96.964601 -24.830995) (xy 97.005463 -24.855479)
			(xy 97.050172 -24.871915) (xy 97.097162 -24.879727) (xy 97.144785 -24.878641) (xy 97.191371 -24.868695)
			(xy 97.235284 -24.850237) (xy 97.274987 -24.823916) (xy 97.292414 -24.807672) (xy 97.308416 -24.79294)
			(xy 97.324691 -24.778142) (xy 97.352345 -24.74394) (xy 97.373703 -24.70549) (xy 97.388127 -24.663939)
			(xy 97.395187 -24.620526) (xy 97.394673 -24.576545) (xy 97.3866 -24.533309) (xy 97.371209 -24.492106)
			(xy 97.360486 -24.4729) (xy 97.345419 -24.44637) (xy 97.321769 -24.390128) (xy 97.305799 -24.331242)
			(xy 97.297793 -24.270757) (xy 97.297893 -24.209745) (xy 97.306097 -24.149287) (xy 97.32226 -24.090454)
			(xy 97.346094 -24.034289) (xy 97.377179 -23.981789) (xy 97.414962 -23.933883) (xy 97.458774 -23.891421)
			(xy 97.507838 -23.855155) (xy 97.561285 -23.825728) (xy 97.618168 -23.803662) (xy 97.677477 -23.789348)
			(xy 97.738163 -23.783039) (xy 97.799149 -23.784848) (xy 97.859353 -23.794742) (xy 97.917711 -23.812546)
			(xy 97.973185 -23.837944) (xy 98.024795 -23.870487) (xy 98.071623 -23.909597) (xy 98.112842 -23.954581)
			(xy 98.147719 -24.004642) (xy 98.175638 -24.058892) (xy 98.196102 -24.116371) (xy 98.208749 -24.176058)
			(xy 98.213356 -24.236896) (xy 98.209839 -24.297807) (xy 98.198263 -24.357712) (xy 98.178831 -24.415547)
			(xy 98.151889 -24.470289) (xy 98.117914 -24.520966) (xy 98.077508 -24.566681) (xy 98.031387 -24.606624)
			(xy 98.006154 -24.623776) (xy 97.987961 -24.63618) (xy 97.95583 -24.666283) (xy 97.929374 -24.701478)
			(xy 97.909385 -24.74071) (xy 97.896464 -24.782801) (xy 97.890997 -24.82649) (xy 97.893148 -24.870467)
			(xy 97.897377 -24.889179) (xy 98.388644 -24.889179) (xy 98.393466 -24.833676) (xy 98.40631 -24.779465)
			(xy 98.426902 -24.727699) (xy 98.454805 -24.679479) (xy 98.489426 -24.63583) (xy 98.530027 -24.597681)
			(xy 98.575745 -24.565844) (xy 98.625608 -24.540995) (xy 98.678556 -24.523664) (xy 98.733461 -24.514218)
			(xy 98.761296 -24.513032) (xy 98.785089 -24.511938) (xy 98.831656 -24.501956) (xy 98.875552 -24.483482)
			(xy 98.915243 -24.457163) (xy 98.949343 -24.423916) (xy 98.97666 -24.384905) (xy 98.99624 -24.341492)
			(xy 99.002342 -24.318468) (xy 99.008811 -24.293277) (xy 99.027705 -24.244819) (xy 99.053002 -24.199375)
			(xy 99.084233 -24.157785) (xy 99.12082 -24.120819) (xy 99.162087 -24.089161) (xy 99.18446 -24.075898)
			(xy 99.202948 -24.064887) (xy 99.236234 -24.037622) (xy 99.264448 -24.005136) (xy 99.286782 -23.968359)
			(xy 99.302598 -23.928344) (xy 99.311441 -23.886235) (xy 99.31306 -23.843238) (xy 99.307408 -23.800583)
			(xy 99.294647 -23.759491) (xy 99.285298 -23.74011) (xy 99.271967 -23.712742) (xy 99.25177 -23.655315)
			(xy 99.239362 -23.595718) (xy 99.234962 -23.535003) (xy 99.238646 -23.47424) (xy 99.25035 -23.414501)
			(xy 99.269868 -23.35684) (xy 99.296854 -23.302274) (xy 99.330834 -23.251765) (xy 99.371208 -23.206205)
			(xy 99.417263 -23.166397) (xy 99.468187 -23.133044) (xy 99.523082 -23.106733) (xy 99.58098 -23.087929)
			(xy 99.640859 -23.076964) (xy 99.701663 -23.07403) (xy 99.762319 -23.07918) (xy 99.821758 -23.092323)
			(xy 99.878931 -23.113227) (xy 99.93283 -23.141523) (xy 99.982504 -23.176712) (xy 100.027076 -23.218174)
			(xy 100.06576 -23.265177) (xy 100.097874 -23.316891) (xy 100.122852 -23.372406) (xy 100.140253 -23.43074)
			(xy 100.14977 -23.490867) (xy 100.151234 -23.551724) (xy 100.144622 -23.612238) (xy 100.130048 -23.671343)
			(xy 100.107769 -23.727994) (xy 100.07818 -23.781194) (xy 100.041802 -23.830004) (xy 99.999277 -23.873562)
			(xy 99.951354 -23.9111) (xy 99.898879 -23.941957) (xy 99.871022 -23.954232) (xy 99.85138 -23.963018)
			(xy 99.815115 -23.986167) (xy 99.783271 -24.015098) (xy 99.756759 -24.048983) (xy 99.736338 -24.086851)
			(xy 99.722592 -24.12762) (xy 99.715915 -24.170123) (xy 99.716498 -24.213143) (xy 99.724324 -24.255449)
			(xy 99.731322 -24.275796) (xy 99.740109 -24.301) (xy 99.75138 -24.353172) (xy 99.755264 -24.406406)
			(xy 99.751685 -24.459661) (xy 99.740714 -24.511897) (xy 99.722565 -24.562092) (xy 99.697592 -24.609265)
			(xy 99.6823 -24.631142) (xy 99.66942 -24.649782) (xy 99.649855 -24.690644) (xy 99.637844 -24.734327)
			(xy 99.633767 -24.779448) (xy 99.637754 -24.824576) (xy 99.649679 -24.868283) (xy 99.669163 -24.909184)
			(xy 99.69559 -24.945982) (xy 99.71151 -24.962104) (xy 99.733172 -24.983842) (xy 99.771105 -25.032083)
			(xy 99.802253 -25.08496) (xy 99.826057 -25.141525) (xy 99.842089 -25.200762) (xy 99.850063 -25.261611)
			(xy 99.849836 -25.322979) (xy 99.841411 -25.383767) (xy 99.82494 -25.442884) (xy 99.800717 -25.499271)
			(xy 99.769178 -25.551915) (xy 99.730888 -25.599874) (xy 99.686534 -25.642286) (xy 99.63691 -25.678392)
			(xy 99.582908 -25.707544) (xy 99.525494 -25.72922) (xy 99.465699 -25.74303) (xy 99.404595 -25.748727)
			(xy 99.343278 -25.746208) (xy 99.282847 -25.73552) (xy 99.224386 -25.716853) (xy 99.168943 -25.690543)
			(xy 99.117513 -25.657061) (xy 99.071017 -25.617007) (xy 99.03029 -25.5711) (xy 98.996061 -25.520163)
			(xy 98.968946 -25.46511) (xy 98.949429 -25.406927) (xy 98.94316 -25.376886) (xy 98.939787 -25.361601)
			(xy 98.926621 -25.333212) (xy 98.906933 -25.308889) (xy 98.88191 -25.290099) (xy 98.853062 -25.277975)
			(xy 98.822128 -25.273249) (xy 98.806508 -25.27427) (xy 98.77872 -25.276305) (xy 98.723083 -25.273425)
			(xy 98.668457 -25.262482) (xy 98.616003 -25.24371) (xy 98.566838 -25.217507) (xy 98.522007 -25.184432)
			(xy 98.482463 -25.145188) (xy 98.449049 -25.100609) (xy 98.422474 -25.051644) (xy 98.403304 -24.999335)
			(xy 98.391947 -24.944793) (xy 98.388644 -24.889179) (xy 97.897377 -24.889179) (xy 97.902854 -24.913414)
			(xy 97.910904 -24.93391) (xy 97.920988 -24.959241) (xy 97.93462 -25.012029) (xy 97.940597 -25.066221)
			(xy 97.938799 -25.120711) (xy 97.929262 -25.17439) (xy 97.912179 -25.226165) (xy 97.8879 -25.274981)
			(xy 97.856918 -25.319843) (xy 97.819865 -25.359837) (xy 97.777496 -25.394148) (xy 97.730673 -25.422078)
			(xy 97.680351 -25.443057) (xy 97.627555 -25.456659) (xy 97.57336 -25.462606) (xy 97.51887 -25.460776)
			(xy 97.465196 -25.451208) (xy 97.413431 -25.434096) (xy 97.36463 -25.409788) (xy 97.341944 -25.394666)
			(xy 97.32207 -25.381557) (xy 97.278535 -25.362291) (xy 97.232178 -25.351457) (xy 97.184614 -25.349431)
			(xy 97.137504 -25.356286) (xy 97.092489 -25.371781) (xy 97.051141 -25.395377) (xy 97.014902 -25.426249)
			(xy 96.999552 -25.44445) (xy 96.98082 -25.467073) (xy 96.938505 -25.507809) (xy 96.891323 -25.542792)
			(xy 96.840051 -25.571447) (xy 96.785531 -25.593301) (xy 96.728663 -25.607995) (xy 96.699578 -25.61209)
			(xy 96.682369 -25.614782) (xy 96.65027 -25.628277) (xy 96.623027 -25.649962) (xy 96.602678 -25.678217)
			(xy 96.5962 -25.694386) (xy 96.570546 -25.76449) (xy 96.56515 -25.780586) (xy 96.562272 -25.814401)
			(xy 96.568425 -25.847776) (xy 96.583173 -25.878342) (xy 96.593914 -25.89149) (xy 96.602804 -25.902158)
			(xy 96.617974 -25.920103) (xy 96.653769 -25.950537) (xy 96.694552 -25.973868) (xy 96.738931 -25.989297)
			(xy 96.785392 -25.996299) (xy 96.832347 -25.994635) (xy 96.878195 -25.984361) (xy 96.899984 -25.975564)
			(xy 96.925587 -25.965063) (xy 96.979072 -25.950866) (xy 97.034048 -25.944544) (xy 97.089361 -25.946229)
			(xy 97.14385 -25.955886) (xy 97.196372 -25.973313) (xy 97.245827 -25.998144) (xy 97.291175 -26.029858)
			(xy 97.331468 -26.067789) (xy 97.365858 -26.111144) (xy 97.393626 -26.159011) (xy 97.414188 -26.210387)
			(xy 97.427113 -26.264195) (xy 97.43213 -26.319305) (xy 97.429133 -26.374562) (xy 97.418187 -26.428807)
			(xy 97.40703 -26.459942) (xy 98.980242 -26.459942) (xy 98.984313 -26.40432) (xy 98.996439 -26.349883)
			(xy 99.016362 -26.297792) (xy 99.043658 -26.249157) (xy 99.077744 -26.205014) (xy 99.117893 -26.166305)
			(xy 99.163251 -26.133854) (xy 99.212851 -26.108353) (xy 99.265635 -26.090346) (xy 99.320478 -26.080216)
			(xy 99.376212 -26.078179) (xy 99.431649 -26.084279) (xy 99.485606 -26.098385) (xy 99.536935 -26.120197)
			(xy 99.584541 -26.149251) (xy 99.627409 -26.184926) (xy 99.664626 -26.226463) (xy 99.695399 -26.272976)
			(xy 99.719071 -26.323473) (xy 99.735139 -26.37688) (xy 99.743259 -26.432056) (xy 99.743768 -26.459942)
			(xy 99.743259 -26.487828) (xy 99.735139 -26.543004) (xy 99.719071 -26.596411) (xy 99.717847 -26.599021)
			(xy 101.119992 -26.599021) (xy 101.121694 -26.54345) (xy 101.131443 -26.488715) (xy 101.149033 -26.435975)
			(xy 101.174092 -26.386345) (xy 101.206088 -26.340879) (xy 101.244344 -26.300537) (xy 101.288051 -26.266175)
			(xy 101.336281 -26.23852) (xy 101.388015 -26.218158) (xy 101.442156 -26.20552) (xy 101.497558 -26.200874)
			(xy 101.553048 -26.204318) (xy 101.607451 -26.215779) (xy 101.659614 -26.235015) (xy 101.708433 -26.261618)
			(xy 101.752873 -26.295024) (xy 101.791995 -26.334527) (xy 101.82497 -26.379289) (xy 101.851098 -26.428363)
			(xy 101.869828 -26.48071) (xy 101.880761 -26.535221) (xy 101.883668 -26.590742) (xy 101.878485 -26.646096)
			(xy 101.865323 -26.700112) (xy 101.844461 -26.751646) (xy 101.816341 -26.799607) (xy 101.781557 -26.842978)
			(xy 101.761544 -26.862278) (xy 101.744697 -26.878654) (xy 101.716797 -26.916451) (xy 101.696317 -26.958731)
			(xy 101.683955 -27.004054) (xy 101.680131 -27.050877) (xy 101.684975 -27.097606) (xy 101.698324 -27.142648)
			(xy 101.719721 -27.184471) (xy 101.748439 -27.221651) (xy 101.765608 -27.23769) (xy 101.786055 -27.256536)
			(xy 101.821783 -27.299146) (xy 101.850949 -27.34649) (xy 101.872934 -27.397566) (xy 101.887273 -27.451292)
			(xy 101.893663 -27.506531) (xy 101.891967 -27.562111) (xy 101.882222 -27.616858) (xy 101.864635 -27.66961)
			(xy 101.839577 -27.71925) (xy 101.836879 -27.723084) (xy 103.26827 -27.723084) (xy 103.272341 -27.667462)
			(xy 103.284467 -27.613025) (xy 103.30439 -27.560934) (xy 103.331686 -27.512299) (xy 103.365772 -27.468156)
			(xy 103.405921 -27.429447) (xy 103.451279 -27.396996) (xy 103.500879 -27.371495) (xy 103.553663 -27.353488)
			(xy 103.608506 -27.343358) (xy 103.66424 -27.341321) (xy 103.719677 -27.347421) (xy 103.773634 -27.361527)
			(xy 103.824963 -27.383339) (xy 103.872569 -27.412393) (xy 103.915437 -27.448068) (xy 103.952654 -27.489605)
			(xy 103.983427 -27.536118) (xy 104.007099 -27.586615) (xy 104.023167 -27.640022) (xy 104.031287 -27.695198)
			(xy 104.031796 -27.723084) (xy 104.031287 -27.75097) (xy 104.023167 -27.806146) (xy 104.007099 -27.859553)
			(xy 103.983427 -27.91005) (xy 103.952654 -27.956563) (xy 103.915437 -27.9981) (xy 103.872569 -28.033775)
			(xy 103.824963 -28.062829) (xy 103.773634 -28.084641) (xy 103.719677 -28.098747) (xy 103.66424 -28.104847)
			(xy 103.608506 -28.10281) (xy 103.553663 -28.09268) (xy 103.500879 -28.074673) (xy 103.451279 -28.049172)
			(xy 103.405921 -28.016721) (xy 103.365772 -27.978012) (xy 103.331686 -27.933869) (xy 103.30439 -27.885234)
			(xy 103.284467 -27.833143) (xy 103.272341 -27.778706) (xy 103.26827 -27.723084) (xy 101.836879 -27.723084)
			(xy 101.807579 -27.764729) (xy 101.76932 -27.805081) (xy 101.725609 -27.839453) (xy 101.677372 -27.867117)
			(xy 101.62563 -27.887487) (xy 101.57148 -27.900131) (xy 101.516069 -27.904782) (xy 101.460568 -27.901341)
			(xy 101.406155 -27.889881) (xy 101.353982 -27.870645) (xy 101.305153 -27.844041) (xy 101.260702 -27.81063)
			(xy 101.221572 -27.771122) (xy 101.188589 -27.726353) (xy 101.162455 -27.67727) (xy 101.14372 -27.624915)
			(xy 101.132783 -27.570394) (xy 101.129875 -27.514864) (xy 101.135058 -27.459499) (xy 101.148222 -27.405473)
			(xy 101.169087 -27.353929) (xy 101.197213 -27.30596) (xy 101.232003 -27.262581) (xy 101.25202 -27.243278)
			(xy 101.268838 -27.226871) (xy 101.296747 -27.18908) (xy 101.317235 -27.146804) (xy 101.329606 -27.101483)
			(xy 101.333437 -27.054661) (xy 101.328599 -27.007932) (xy 101.315256 -26.962887) (xy 101.293862 -26.921062)
			(xy 101.265147 -26.883881) (xy 101.247956 -26.867866) (xy 101.227547 -26.848985) (xy 101.191831 -26.806378)
			(xy 101.162678 -26.759038) (xy 101.140703 -26.707968) (xy 101.126374 -26.65425) (xy 101.119992 -26.599021)
			(xy 99.717847 -26.599021) (xy 99.695399 -26.646908) (xy 99.664626 -26.693421) (xy 99.627409 -26.734958)
			(xy 99.584541 -26.770633) (xy 99.536935 -26.799687) (xy 99.485606 -26.821499) (xy 99.431649 -26.835605)
			(xy 99.376212 -26.841705) (xy 99.320478 -26.839668) (xy 99.265635 -26.829538) (xy 99.212851 -26.811531)
			(xy 99.163251 -26.78603) (xy 99.117893 -26.753579) (xy 99.077744 -26.71487) (xy 99.043658 -26.670727)
			(xy 99.016362 -26.622092) (xy 98.996439 -26.570001) (xy 98.984313 -26.515564) (xy 98.980242 -26.459942)
			(xy 97.40703 -26.459942) (xy 97.39952 -26.480901) (xy 97.373523 -26.529753) (xy 97.340743 -26.574337)
			(xy 97.301866 -26.613719) (xy 97.257708 -26.647071) (xy 97.209196 -26.673696) (xy 97.157347 -26.693034)
			(xy 97.103248 -26.704679) (xy 97.048034 -26.708388) (xy 96.992864 -26.704082) (xy 96.96577 -26.698448)
			(xy 96.943872 -26.693986) (xy 96.899238 -26.691861) (xy 96.85492 -26.697575) (xy 96.812285 -26.71095)
			(xy 96.772644 -26.731574) (xy 96.737222 -26.758813) (xy 96.707108 -26.791827) (xy 96.683232 -26.829597)
			(xy 96.666328 -26.870961) (xy 96.656918 -26.914644) (xy 96.655636 -26.936954) (xy 96.654143 -26.967103)
			(xy 96.644077 -27.026624) (xy 96.626274 -27.084305) (xy 96.601045 -27.139146) (xy 96.568828 -27.190196)
			(xy 96.53018 -27.236569) (xy 96.485773 -27.27746) (xy 96.436377 -27.312159) (xy 96.382849 -27.340066)
			(xy 96.326117 -27.360696) (xy 96.267166 -27.37369) (xy 96.207019 -27.378824) (xy 96.176846 -27.377898)
			(xy 96.15403 -27.377426) (xy 96.108804 -27.383453) (xy 96.065381 -27.397458) (xy 96.025157 -27.418991)
			(xy 95.989423 -27.44736) (xy 95.959329 -27.481654) (xy 95.935842 -27.520769) (xy 95.919716 -27.56345)
			(xy 95.91147 -27.608324) (xy 95.910908 -27.631136) (xy 95.910639 -27.64282) (xy 97.268282 -27.64282)
			(xy 97.272353 -27.587198) (xy 97.284479 -27.532761) (xy 97.304402 -27.48067) (xy 97.331698 -27.432035)
			(xy 97.365784 -27.387892) (xy 97.405933 -27.349183) (xy 97.451291 -27.316732) (xy 97.500891 -27.291231)
			(xy 97.553675 -27.273224) (xy 97.608518 -27.263094) (xy 97.664252 -27.261057) (xy 97.719689 -27.267157)
			(xy 97.773646 -27.281263) (xy 97.824975 -27.303075) (xy 97.872581 -27.332129) (xy 97.915449 -27.367804)
			(xy 97.952666 -27.409341) (xy 97.983439 -27.455854) (xy 98.007111 -27.506351) (xy 98.023179 -27.559758)
			(xy 98.031299 -27.614934) (xy 98.031808 -27.64282) (xy 98.031299 -27.670706) (xy 98.029422 -27.68346)
			(xy 99.068126 -27.68346) (xy 99.072197 -27.627838) (xy 99.084323 -27.573401) (xy 99.104246 -27.52131)
			(xy 99.131542 -27.472675) (xy 99.165628 -27.428532) (xy 99.205777 -27.389823) (xy 99.251135 -27.357372)
			(xy 99.300735 -27.331871) (xy 99.353519 -27.313864) (xy 99.408362 -27.303734) (xy 99.464096 -27.301697)
			(xy 99.519533 -27.307797) (xy 99.57349 -27.321903) (xy 99.624819 -27.343715) (xy 99.672425 -27.372769)
			(xy 99.715293 -27.408444) (xy 99.75251 -27.449981) (xy 99.783283 -27.496494) (xy 99.806955 -27.546991)
			(xy 99.823023 -27.600398) (xy 99.831143 -27.655574) (xy 99.831652 -27.68346) (xy 99.831143 -27.711346)
			(xy 99.823023 -27.766522) (xy 99.806955 -27.819929) (xy 99.783283 -27.870426) (xy 99.75251 -27.916939)
			(xy 99.715293 -27.958476) (xy 99.672425 -27.994151) (xy 99.624819 -28.023205) (xy 99.57349 -28.045017)
			(xy 99.519533 -28.059123) (xy 99.464096 -28.065223) (xy 99.408362 -28.063186) (xy 99.353519 -28.053056)
			(xy 99.300735 -28.035049) (xy 99.251135 -28.009548) (xy 99.205777 -27.977097) (xy 99.165628 -27.938388)
			(xy 99.131542 -27.894245) (xy 99.104246 -27.84561) (xy 99.084323 -27.793519) (xy 99.072197 -27.739082)
			(xy 99.068126 -27.68346) (xy 98.029422 -27.68346) (xy 98.023179 -27.725882) (xy 98.007111 -27.779289)
			(xy 97.983439 -27.829786) (xy 97.952666 -27.876299) (xy 97.915449 -27.917836) (xy 97.872581 -27.953511)
			(xy 97.824975 -27.982565) (xy 97.773646 -28.004377) (xy 97.719689 -28.018483) (xy 97.664252 -28.024583)
			(xy 97.608518 -28.022546) (xy 97.553675 -28.012416) (xy 97.500891 -27.994409) (xy 97.451291 -27.968908)
			(xy 97.405933 -27.936457) (xy 97.365784 -27.897748) (xy 97.331698 -27.853605) (xy 97.304402 -27.80497)
			(xy 97.284479 -27.752879) (xy 97.272353 -27.698442) (xy 97.268282 -27.64282) (xy 95.910639 -27.64282)
			(xy 95.910269 -27.658852) (xy 95.902096 -27.71368) (xy 95.886072 -27.766748) (xy 95.862536 -27.816938)
			(xy 95.831982 -27.863192) (xy 95.795055 -27.904536) (xy 95.752532 -27.940099) (xy 95.705309 -27.969133)
			(xy 95.654381 -27.991026) (xy 95.600821 -28.005316) (xy 95.545755 -28.011702) (xy 95.490346 -28.010051)
			(xy 95.435759 -28.000396) (xy 95.383144 -27.982941) (xy 95.33361 -27.958054) (xy 95.2882 -27.926259)
			(xy 95.247871 -27.888226) (xy 95.213472 -27.844756) (xy 95.185728 -27.796764) (xy 95.165222 -27.745262)
			(xy 95.152388 -27.691334) (xy 95.147495 -27.636116) (xy 92.025345 -27.636116) (xy 92.022937 -27.652476)
			(xy 92.006869 -27.705883) (xy 91.983197 -27.75638) (xy 91.952424 -27.802893) (xy 91.915207 -27.84443)
			(xy 91.872339 -27.880105) (xy 91.824733 -27.909159) (xy 91.773404 -27.930971) (xy 91.719447 -27.945077)
			(xy 91.66401 -27.951177) (xy 91.608276 -27.94914) (xy 91.553433 -27.93901) (xy 91.500649 -27.921003)
			(xy 91.451049 -27.895502) (xy 91.405691 -27.863051) (xy 91.365542 -27.824342) (xy 91.331456 -27.780199)
			(xy 91.30416 -27.731564) (xy 91.284237 -27.679473) (xy 91.272111 -27.625036) (xy 91.26804 -27.569414)
			(xy 90.394016 -27.569414) (xy 90.376079 -27.616499) (xy 90.349644 -27.664128) (xy 90.316703 -27.707512)
			(xy 90.277927 -27.745771) (xy 90.234103 -27.778124) (xy 90.186123 -27.803916) (xy 90.134962 -27.822621)
			(xy 90.081661 -27.833859) (xy 90.027303 -27.837402) (xy 89.972994 -27.833178) (xy 89.919838 -27.821271)
			(xy 89.868916 -27.801926) (xy 89.821264 -27.775534) (xy 89.777849 -27.742633) (xy 89.739556 -27.703891)
			(xy 89.707162 -27.660097) (xy 89.681327 -27.61214) (xy 89.662575 -27.560997) (xy 89.651288 -27.507706)
			(xy 89.647696 -27.453352) (xy 89.6493 -27.426158) (xy 89.650535 -27.404444) (xy 89.646418 -27.361149)
			(xy 89.634987 -27.319187) (xy 89.616577 -27.279786) (xy 89.591727 -27.244094) (xy 89.561161 -27.213157)
			(xy 89.525773 -27.187876) (xy 89.486597 -27.168991) (xy 89.444777 -27.157053) (xy 89.401535 -27.152412)
			(xy 89.379806 -27.153362) (xy 89.352513 -27.154635) (xy 89.298046 -27.150316) (xy 89.244752 -27.138272)
			(xy 89.193722 -27.118749) (xy 89.145998 -27.092146) (xy 89.102557 -27.059008) (xy 89.064287 -27.020011)
			(xy 89.031972 -26.975955) (xy 89.006271 -26.927739) (xy 88.987711 -26.87635) (xy 88.976672 -26.822839)
			(xy 88.973378 -26.768301) (xy 86.151497 -26.768301) (xy 86.168966 -26.79856) (xy 86.191902 -26.853933)
			(xy 86.207415 -26.911826) (xy 86.215238 -26.971248) (xy 86.215728 -27.001216) (xy 86.215238 -27.031184)
			(xy 86.207415 -27.090606) (xy 86.191902 -27.148499) (xy 86.168966 -27.203872) (xy 86.138999 -27.255778)
			(xy 86.102512 -27.303328) (xy 86.060132 -27.345708) (xy 86.012582 -27.382195) (xy 85.960676 -27.412162)
			(xy 85.905303 -27.435098) (xy 85.84741 -27.450611) (xy 85.787988 -27.458434) (xy 85.728052 -27.458434)
			(xy 85.66863 -27.450611) (xy 85.610737 -27.435098) (xy 85.555364 -27.412162) (xy 85.503458 -27.382195)
			(xy 85.455908 -27.345708) (xy 85.413528 -27.303328) (xy 85.377041 -27.255778) (xy 85.347074 -27.203872)
			(xy 85.324138 -27.148499) (xy 85.308625 -27.090606) (xy 85.300802 -27.031184) (xy 73.550832 -27.031184)
			(xy 73.541861 -27.078214) (xy 73.522119 -27.138974) (xy 73.494919 -27.19678) (xy 73.460688 -27.250722)
			(xy 73.419967 -27.299948) (xy 73.373398 -27.343682) (xy 73.321714 -27.381235) (xy 73.265732 -27.412015)
			(xy 73.206333 -27.435535) (xy 73.144455 -27.451426) (xy 73.081073 -27.459437) (xy 73.04913 -27.45994)
			(xy 72.186546 -27.45994) (xy 72.156584 -27.45948) (xy 72.097075 -27.452444) (xy 72.038807 -27.438454)
			(xy 71.982591 -27.417702) (xy 71.929208 -27.390479) (xy 71.8794 -27.357162) (xy 71.856346 -27.33802)
			(xy 71.820532 -27.30754) (xy 71.805292 -27.30754) (xy 71.805292 -27.290522) (xy 71.779892 -27.25674)
			(xy 71.760643 -27.230263) (xy 71.728406 -27.173288) (xy 71.70375 -27.112646) (xy 71.687083 -27.049341)
			(xy 71.67868 -26.98442) (xy 71.035951 -26.98442) (xy 71.026045 -26.98979) (xy 70.974552 -27.008761)
			(xy 70.920873 -27.020156) (xy 70.866115 -27.023742) (xy 70.811407 -27.019444) (xy 70.757881 -27.007351)
			(xy 70.70664 -26.987712) (xy 70.658742 -26.960932) (xy 70.615175 -26.927566) (xy 70.57684 -26.8883)
			(xy 70.544528 -26.843947) (xy 70.518905 -26.79542) (xy 70.5005 -26.743723) (xy 70.489693 -26.689922)
			(xy 70.486708 -26.635128) (xy 70.491606 -26.580471) (xy 70.504285 -26.52708) (xy 70.524485 -26.476057)
			(xy 70.551787 -26.428456) (xy 70.58563 -26.385258) (xy 70.605142 -26.365962) (xy 70.620896 -26.350305)
			(xy 70.647189 -26.314512) (xy 70.66686 -26.274694) (xy 70.67931 -26.232062) (xy 70.68416 -26.187915)
			(xy 70.681262 -26.143597) (xy 70.670705 -26.100458) (xy 70.652809 -26.05981) (xy 70.62812 -26.022892)
			(xy 70.59739 -25.990828) (xy 70.579742 -25.977342) (xy 70.557502 -25.960432) (xy 70.517704 -25.921225)
			(xy 70.48405 -25.876633) (xy 70.457258 -25.82761) (xy 70.437903 -25.775203) (xy 70.426397 -25.720534)
			(xy 70.422988 -25.664771) (xy 70.427747 -25.609108) (xy 70.440574 -25.554733) (xy 70.461194 -25.502811)
			(xy 70.489165 -25.454451) (xy 70.52389 -25.410688) (xy 70.564627 -25.372457) (xy 70.610503 -25.340575)
			(xy 70.660539 -25.315725) (xy 70.713664 -25.298438) (xy 70.768742 -25.289084) (xy 70.796658 -25.287986)
			(xy 70.819585 -25.28696) (xy 70.86453 -25.277704) (xy 70.907086 -25.260534) (xy 70.945869 -25.236006)
			(xy 70.979621 -25.204916) (xy 71.007246 -25.168274) (xy 71.027847 -25.12727) (xy 71.040756 -25.083235)
			(xy 71.045553 -25.037598) (xy 71.044308 -25.014682) (xy 71.04275 -24.988288) (xy 71.046071 -24.935519)
			(xy 71.050912 -24.909526) (xy 71.054913 -24.887357) (xy 71.056021 -24.842328) (xy 71.049179 -24.797809)
			(xy 71.034599 -24.755191) (xy 71.012739 -24.715809) (xy 70.984282 -24.680895) (xy 70.950119 -24.651541)
			(xy 70.911318 -24.628665) (xy 70.869093 -24.612983) (xy 70.824766 -24.604987) (xy 70.802246 -24.604472)
			(xy 70.22211 -24.604472) (xy 70.198571 -24.605028) (xy 70.152298 -24.613695) (xy 70.108413 -24.630735)
			(xy 70.068415 -24.655564) (xy 70.033674 -24.687335) (xy 70.005377 -24.724959) (xy 69.984493 -24.767151)
			(xy 69.971735 -24.812467) (xy 69.969126 -24.835866) (xy 69.966075 -24.863639) (xy 69.953024 -24.917962)
			(xy 69.932189 -24.969801) (xy 69.904015 -25.018046) (xy 69.869106 -25.061667) (xy 69.828208 -25.099728)
			(xy 69.782196 -25.131418) (xy 69.732054 -25.156057) (xy 69.678854 -25.17312) (xy 69.623734 -25.18224)
			(xy 69.567874 -25.183223) (xy 69.512467 -25.176048) (xy 69.4587 -25.160868) (xy 69.407722 -25.138008)
			(xy 69.38391 -25.123394) (xy 69.364506 -25.111676) (xy 69.322591 -25.094439) (xy 69.278284 -25.084907)
			(xy 69.232989 -25.083382) (xy 69.188141 -25.089911) (xy 69.145161 -25.104288) (xy 69.105411 -25.126058)
			(xy 69.07015 -25.15453) (xy 69.040496 -25.188802) (xy 69.017388 -25.227789) (xy 69.001558 -25.270256)
			(xy 68.993508 -25.314856) (xy 68.993004 -25.337516) (xy 68.993004 -25.473406) (xy 68.992512 -25.506133)
			(xy 68.984116 -25.571045) (xy 68.967464 -25.634345) (xy 68.942831 -25.694986) (xy 68.910624 -25.751967)
			(xy 68.891404 -25.77846) (xy 68.866004 -25.812242) (xy 68.866004 -25.82926) (xy 68.850764 -25.82926)
			(xy 68.81495 -25.85974) (xy 68.789773 -25.880593) (xy 68.735041 -25.916344) (xy 68.676176 -25.944783)
			(xy 68.614151 -25.965438) (xy 68.549989 -25.977969) (xy 68.48475 -25.982169) (xy 68.419511 -25.977969)
			(xy 68.355349 -25.965438) (xy 68.293324 -25.944783) (xy 68.234459 -25.916344) (xy 68.179727 -25.880593)
			(xy 68.15455 -25.85974) (xy 68.118736 -25.82926) (xy 68.020184 -25.82926) (xy 68.003538 -25.829829)
			(xy 67.971382 -25.838447) (xy 67.94255 -25.855092) (xy 67.919007 -25.878631) (xy 67.902356 -25.907459)
			(xy 67.893732 -25.939614) (xy 67.893184 -25.95626) (xy 67.893184 -25.968452) (xy 67.89547 -25.980136)
			(xy 67.900166 -26.006808) (xy 67.902716 -26.060907) (xy 67.89759 -26.114823) (xy 67.884891 -26.167473)
			(xy 67.864875 -26.217797) (xy 67.837943 -26.264786) (xy 67.804637 -26.307493) (xy 67.765627 -26.345062)
			(xy 67.721696 -26.376736) (xy 67.673727 -26.40188) (xy 67.622685 -26.419988) (xy 67.569594 -26.430695)
			(xy 67.515524 -26.433788) (xy 67.461559 -26.429203) (xy 67.408785 -26.417033) (xy 67.358262 -26.397522)
			(xy 67.311006 -26.371063) (xy 67.267967 -26.338188) (xy 67.230009 -26.299556) (xy 67.197895 -26.255945)
			(xy 67.172272 -26.208231) (xy 67.153653 -26.157372) (xy 67.142413 -26.104392) (xy 67.138778 -26.050355)
			(xy 67.140328 -26.023316) (xy 67.141589 -25.999415) (xy 67.136177 -25.951867) (xy 67.121961 -25.906172)
			(xy 67.099442 -25.863945) (xy 67.069418 -25.82668) (xy 67.032949 -25.795693) (xy 66.991324 -25.77208)
			(xy 66.946015 -25.756676) (xy 66.922396 -25.752806) (xy 66.895804 -25.748621) (xy 66.844082 -25.733706)
			(xy 66.794969 -25.711668) (xy 66.749443 -25.682943) (xy 66.708408 -25.648104) (xy 66.672678 -25.607841)
			(xy 66.642964 -25.562954) (xy 66.619856 -25.514336) (xy 66.603813 -25.462952) (xy 66.595153 -25.409823)
			(xy 66.594049 -25.356003) (xy 66.600523 -25.302564) (xy 66.614446 -25.250565) (xy 66.635541 -25.20104)
			(xy 66.663389 -25.154973) (xy 66.697437 -25.113279) (xy 66.71691 -25.094692) (xy 66.733984 -25.078285)
			(xy 66.762256 -25.040303) (xy 66.783013 -24.997747) (xy 66.795539 -24.952085) (xy 66.7994 -24.904894)
			(xy 66.794463 -24.857803) (xy 66.780899 -24.812438) (xy 66.770504 -24.791162) (xy 66.759936 -24.770017)
			(xy 66.7435 -24.725695) (xy 66.737738 -24.70277) (xy 66.733363 -24.686247) (xy 66.717093 -24.656201)
			(xy 66.693429 -24.631553) (xy 66.664071 -24.614074) (xy 66.631124 -24.605017) (xy 66.61404 -24.604472)
			(xy 65.662302 -24.604472) (xy 65.639779 -24.604978) (xy 65.595443 -24.612936) (xy 65.553203 -24.628585)
			(xy 65.514383 -24.651435) (xy 65.480199 -24.68077) (xy 65.451722 -24.715672) (xy 65.429843 -24.755047)
			(xy 65.415248 -24.797662) (xy 65.408394 -24.842183) (xy 65.409496 -24.887215) (xy 65.418518 -24.931348)
			(xy 65.435179 -24.973199) (xy 65.446656 -24.992584) (xy 65.461649 -25.017583) (xy 65.485857 -25.070612)
			(xy 65.50313 -25.126288) (xy 65.513186 -25.183707) (xy 65.514982 -25.212802) (xy 65.517268 -25.262078)
			(xy 65.9003 -25.644856) (xy 65.9003 -27.191966) (xy 66.210924 -27.191966) (xy 66.210924 -27.13203)
			(xy 66.218747 -27.072608) (xy 66.23426 -27.014715) (xy 66.257196 -26.959342) (xy 66.287163 -26.907436)
			(xy 66.32365 -26.859886) (xy 66.36603 -26.817506) (xy 66.41358 -26.781019) (xy 66.465486 -26.751052)
			(xy 66.520859 -26.728116) (xy 66.578752 -26.712603) (xy 66.638174 -26.70478) (xy 66.69811 -26.70478)
			(xy 66.757532 -26.712603) (xy 66.815425 -26.728116) (xy 66.870798 -26.751052) (xy 66.922704 -26.781019)
			(xy 66.970254 -26.817506) (xy 67.012634 -26.859886) (xy 67.049121 -26.907436) (xy 67.079088 -26.959342)
			(xy 67.102024 -27.014715) (xy 67.117537 -27.072608) (xy 67.12536 -27.13203) (xy 67.12585 -27.161998)
			(xy 67.12536 -27.191966) (xy 67.117537 -27.251388) (xy 67.102024 -27.309281) (xy 67.079088 -27.364654)
			(xy 67.049121 -27.41656) (xy 67.012634 -27.46411) (xy 66.991912 -27.484832) (xy 82.785202 -27.484832)
			(xy 82.789273 -27.42921) (xy 82.801399 -27.374773) (xy 82.821322 -27.322682) (xy 82.848618 -27.274047)
			(xy 82.882704 -27.229904) (xy 82.922853 -27.191195) (xy 82.968211 -27.158744) (xy 83.017811 -27.133243)
			(xy 83.070595 -27.115236) (xy 83.125438 -27.105106) (xy 83.181172 -27.103069) (xy 83.236609 -27.109169)
			(xy 83.290566 -27.123275) (xy 83.341895 -27.145087) (xy 83.389501 -27.174141) (xy 83.432369 -27.209816)
			(xy 83.469586 -27.251353) (xy 83.500359 -27.297866) (xy 83.524031 -27.348363) (xy 83.540099 -27.40177)
			(xy 83.548219 -27.456946) (xy 83.548728 -27.484832) (xy 83.548219 -27.512718) (xy 83.540099 -27.567894)
			(xy 83.524031 -27.621301) (xy 83.500359 -27.671798) (xy 83.469586 -27.718311) (xy 83.432369 -27.759848)
			(xy 83.389501 -27.795523) (xy 83.341895 -27.824577) (xy 83.290566 -27.846389) (xy 83.236609 -27.860495)
			(xy 83.181172 -27.866595) (xy 83.125438 -27.864558) (xy 83.070595 -27.854428) (xy 83.017811 -27.836421)
			(xy 82.968211 -27.81092) (xy 82.922853 -27.778469) (xy 82.882704 -27.73976) (xy 82.848618 -27.695617)
			(xy 82.821322 -27.646982) (xy 82.801399 -27.594891) (xy 82.789273 -27.540454) (xy 82.785202 -27.484832)
			(xy 66.991912 -27.484832) (xy 66.970254 -27.50649) (xy 66.922704 -27.542977) (xy 66.870798 -27.572944)
			(xy 66.815425 -27.59588) (xy 66.757532 -27.611393) (xy 66.69811 -27.619216) (xy 66.638174 -27.619216)
			(xy 66.578752 -27.611393) (xy 66.520859 -27.59588) (xy 66.465486 -27.572944) (xy 66.41358 -27.542977)
			(xy 66.36603 -27.50649) (xy 66.32365 -27.46411) (xy 66.287163 -27.41656) (xy 66.257196 -27.364654)
			(xy 66.23426 -27.309281) (xy 66.218747 -27.251388) (xy 66.210924 -27.191966) (xy 65.9003 -27.191966)
			(xy 65.9003 -27.659076) (xy 65.9511 -27.71013) (xy 65.9511 -28.473146) (xy 65.093596 -28.473146)
			(xy 65.061592 -28.494228) (xy 65.037806 -28.509494) (xy 64.987351 -28.534969) (xy 64.93427 -28.554388)
			(xy 64.879287 -28.567487) (xy 64.823153 -28.574086) (xy 64.794892 -28.574492) (xy 64.042544 -28.574492)
			(xy 64.021004 -28.575007) (xy 63.978537 -28.582235) (xy 63.937898 -28.596525) (xy 63.900253 -28.617467)
			(xy 63.866681 -28.644461) (xy 63.838146 -28.676733) (xy 63.815465 -28.713356) (xy 63.799288 -28.753282)
			(xy 63.790081 -28.795365) (xy 63.788106 -28.838398) (xy 63.793421 -28.881147) (xy 63.799212 -28.901898)
			(xy 63.807525 -28.931216) (xy 63.817214 -28.99138) (xy 63.818833 -29.052297) (xy 63.812352 -29.11289)
			(xy 63.797886 -29.172088) (xy 63.775692 -29.228841) (xy 63.746161 -29.282147) (xy 63.709818 -29.331062)
			(xy 63.667303 -29.374721) (xy 63.619371 -29.412351) (xy 63.566868 -29.443286) (xy 63.510723 -29.46698)
			(xy 63.451931 -29.483013) (xy 63.391531 -29.491101) (xy 63.330593 -29.491101) (xy 63.270193 -29.483013)
			(xy 63.211401 -29.46698) (xy 63.155256 -29.443286) (xy 63.102753 -29.412351) (xy 63.054821 -29.374721)
			(xy 63.012306 -29.331062) (xy 62.975963 -29.282147) (xy 62.946432 -29.228841) (xy 62.924238 -29.172088)
			(xy 62.909772 -29.11289) (xy 62.903291 -29.052297) (xy 62.90491 -28.99138) (xy 62.914599 -28.931216)
			(xy 62.922912 -28.901898) (xy 62.929259 -28.879064) (xy 62.934265 -28.831942) (xy 62.930459 -28.784707)
			(xy 62.917972 -28.738994) (xy 62.897235 -28.696385) (xy 62.868966 -28.658352) (xy 62.834144 -28.626212)
			(xy 62.793971 -28.601077) (xy 62.749839 -28.583816) (xy 62.703274 -28.575026) (xy 62.67958 -28.574492)
			(xy 61.317378 -28.574492) (xy 60.70854 -27.965908) (xy 60.687279 -27.943937) (xy 60.649851 -27.895593)
			(xy 60.618822 -27.842914) (xy 60.594687 -27.78674) (xy 60.577832 -27.72797) (xy 60.568527 -27.667544)
			(xy 60.56692 -27.606426) (xy 58.961907 -27.606426) (xy 58.961715 -27.609479) (xy 58.95049 -27.663089)
			(xy 58.931712 -27.714542) (xy 58.905769 -27.76278) (xy 58.873192 -27.806812) (xy 58.834654 -27.845732)
			(xy 58.790945 -27.878739) (xy 58.742964 -27.905156) (xy 58.691699 -27.92444) (xy 58.638202 -27.936192)
			(xy 58.583575 -27.940173) (xy 58.52894 -27.936299) (xy 58.47542 -27.924652) (xy 58.424117 -27.905469)
			(xy 58.376085 -27.879147) (xy 58.332311 -27.846225) (xy 58.293696 -27.80738) (xy 58.261034 -27.763413)
			(xy 58.234995 -27.715225) (xy 58.216117 -27.66381) (xy 58.204786 -27.610222) (xy 58.201236 -27.555565)
			(xy 56.053241 -27.555565) (xy 56.044943 -27.572522) (xy 56.032509 -27.616542) (xy 56.02986 -27.639264)
			(xy 56.026867 -27.665998) (xy 56.014328 -27.718312) (xy 55.994567 -27.768345) (xy 55.967976 -27.815109)
			(xy 55.935082 -27.857675) (xy 55.896537 -27.8952) (xy 55.853104 -27.926941) (xy 55.805644 -27.952269)
			(xy 55.755098 -27.970681) (xy 55.702468 -27.981813) (xy 55.648796 -27.985444) (xy 55.621936 -27.983942)
			(xy 55.598739 -27.982745) (xy 55.552568 -27.987792) (xy 55.508083 -28.001142) (xy 55.466764 -28.022351)
			(xy 55.429985 -28.050714) (xy 55.39897 -28.085286) (xy 55.374753 -28.124918) (xy 55.358138 -28.168289)
			(xy 55.349678 -28.213958) (xy 55.34914 -28.23718) (xy 55.34914 -30.969976) (xy 57.203555 -30.969976)
			(xy 57.210419 -30.915074) (xy 57.225142 -30.861739) (xy 57.247414 -30.811089) (xy 57.276768 -30.764188)
			(xy 57.312588 -30.722018) (xy 57.354124 -30.685465) (xy 57.400504 -30.655294) (xy 57.450756 -30.632139)
			(xy 57.503825 -30.616485) (xy 57.558599 -30.608661) (xy 57.613928 -30.608829) (xy 57.668653 -30.616988)
			(xy 57.721626 -30.632966) (xy 57.771735 -30.656428) (xy 57.81793 -30.686881) (xy 57.859242 -30.723688)
			(xy 57.894804 -30.766075) (xy 57.923871 -30.813155) (xy 57.945834 -30.863939) (xy 57.96023 -30.917363)
			(xy 57.966759 -30.972306) (xy 57.965284 -31.027617) (xy 57.955835 -31.082134) (xy 57.93861 -31.134714)
			(xy 57.926732 -31.159704) (xy 57.917384 -31.179708) (xy 57.904812 -31.222027) (xy 57.899749 -31.265883)
			(xy 57.90235 -31.309953) (xy 57.912534 -31.352909) (xy 57.929995 -31.393456) (xy 57.954207 -31.430371)
			(xy 57.984439 -31.462542) (xy 58.01978 -31.488998) (xy 58.059166 -31.508942) (xy 58.080148 -31.515812)
			(xy 58.108689 -31.524965) (xy 58.163273 -31.549728) (xy 58.214158 -31.581404) (xy 58.260472 -31.619451)
			(xy 58.301423 -31.663219) (xy 58.336311 -31.711957) (xy 58.364537 -31.764833) (xy 58.38562 -31.820942)
			(xy 58.399198 -31.879322) (xy 58.405038 -31.938975) (xy 58.404057 -31.968405) (xy 58.759224 -31.968405)
			(xy 58.761227 -31.908462) (xy 58.771044 -31.849293) (xy 58.788507 -31.791915) (xy 58.813316 -31.737309)
			(xy 58.845046 -31.686413) (xy 58.883154 -31.640098) (xy 58.926985 -31.599158) (xy 58.951114 -31.581344)
			(xy 58.968846 -31.568057) (xy 58.999892 -31.536449) (xy 59.024986 -31.499936) (xy 59.043367 -31.459624)
			(xy 59.054477 -31.416735) (xy 59.057982 -31.372569) (xy 59.053773 -31.328464) (xy 59.041979 -31.285758)
			(xy 59.022957 -31.245745) (xy 58.997284 -31.209637) (xy 58.981848 -31.19374) (xy 58.962512 -31.173916)
			(xy 58.929183 -31.129693) (xy 58.902598 -31.081115) (xy 58.883316 -31.029205) (xy 58.871742 -30.975051)
			(xy 58.868119 -30.919794) (xy 58.872524 -30.864593) (xy 58.884864 -30.810609) (xy 58.90488 -30.758977)
			(xy 58.932151 -30.710781) (xy 58.966103 -30.667035) (xy 59.006024 -30.628657) (xy 59.051075 -30.596455)
			(xy 59.100308 -30.571104) (xy 59.152689 -30.553139) (xy 59.207117 -30.542936) (xy 59.262448 -30.540709)
			(xy 59.31752 -30.546506) (xy 59.371175 -30.560205) (xy 59.422286 -30.581518) (xy 59.469778 -30.609997)
			(xy 59.512653 -30.645043) (xy 59.550011 -30.68592) (xy 59.581066 -30.731769) (xy 59.605165 -30.781626)
			(xy 59.621803 -30.834444) (xy 59.630629 -30.889112) (xy 59.631457 -30.944482) (xy 59.624272 -30.99939)
			(xy 59.609223 -31.052682) (xy 59.586627 -31.103239) (xy 59.556958 -31.149997) (xy 59.520841 -31.191974)
			(xy 59.500262 -31.210504) (xy 59.483816 -31.225339) (xy 59.455933 -31.259748) (xy 59.434435 -31.29847)
			(xy 59.419975 -31.340332) (xy 59.412989 -31.384067) (xy 59.413689 -31.42835) (xy 59.422054 -31.471842)
			(xy 59.43783 -31.513226) (xy 59.46054 -31.551249) (xy 59.489497 -31.58476) (xy 59.506358 -31.599124)
			(xy 59.5293 -31.618442) (xy 59.570423 -31.662102) (xy 59.60549 -31.71076) (xy 59.633899 -31.763582)
			(xy 59.655164 -31.819662) (xy 59.668921 -31.878041) (xy 59.674933 -31.937716) (xy 59.673097 -31.997665)
			(xy 59.669455 -32.020002) (xy 64.921892 -32.020002) (xy 64.921892 -30.486096) (xy 65.129664 -30.278578)
			(xy 65.129664 -29.41447) (xy 65.352676 -29.191204) (xy 65.897506 -29.191204) (xy 66.57721 -28.5115)
			(xy 68.154296 -28.5115) (xy 68.171822 -28.506674) (xy 68.206609 -28.497132) (xy 68.277997 -28.486805)
			(xy 68.314062 -28.4861) (xy 69.330062 -28.4861) (xy 69.360033 -28.486549) (xy 69.419557 -28.493618)
			(xy 69.477834 -28.50765) (xy 69.534053 -28.528449) (xy 69.587429 -28.555727) (xy 69.63722 -28.589103)
			(xy 69.660262 -28.608274) (xy 69.696076 -28.6385) (xy 69.711316 -28.6385) (xy 69.711316 -28.655772)
			(xy 69.736716 -28.689554) (xy 69.754518 -28.714051) (xy 69.784813 -28.766486) (xy 69.808673 -28.822145)
			(xy 69.825761 -28.880241) (xy 69.835834 -28.939955) (xy 69.838752 -29.000442) (xy 69.837046 -29.030676)
			(xy 69.835844 -29.053854) (xy 69.841004 -29.099977) (xy 69.854445 -29.144398) (xy 69.87572 -29.185645)
			(xy 69.904124 -29.222349) (xy 69.938713 -29.253292) (xy 69.978342 -29.277448) (xy 70.021694 -29.294015)
			(xy 70.067333 -29.302444) (xy 70.090538 -29.302964) (xy 70.8025 -29.302964) (xy 70.87697 -29.377386)
			(xy 79.194152 -29.377386) (xy 79.194152 -28.923234) (xy 79.194623 -28.892518) (xy 79.202024 -28.831533)
			(xy 79.216723 -28.771884) (xy 79.238504 -28.714443) (xy 79.267051 -28.660046) (xy 79.301947 -28.609487)
			(xy 79.342683 -28.563503) (xy 79.388665 -28.522764) (xy 79.439222 -28.487866) (xy 79.493617 -28.459316)
			(xy 79.551058 -28.437531) (xy 79.610705 -28.422829) (xy 79.67169 -28.415425) (xy 79.702406 -28.41498)
			(xy 83.67776 -28.41498) (xy 84.266532 -29.003752) (xy 84.266532 -29.339032) (xy 84.291932 -29.339032)
			(xy 84.291932 -30.401006) (xy 84.47024 -30.579314) (xy 84.51215 -30.58541) (xy 84.543314 -30.590436)
			(xy 84.604088 -30.607504) (xy 84.633308 -30.619446) (xy 84.654484 -30.627985) (xy 84.698985 -30.638191)
			(xy 84.744593 -30.640282) (xy 84.78984 -30.634191) (xy 84.833272 -30.620116) (xy 84.87349 -30.598507)
			(xy 84.909201 -30.570061) (xy 84.939256 -30.535693) (xy 84.962687 -30.496508) (xy 84.97874 -30.453768)
			(xy 84.9869 -30.408848) (xy 84.987384 -30.38602) (xy 84.987384 -30.226) (xy 84.936584 -30.174946)
			(xy 84.936584 -29.41193) (xy 85.794088 -29.41193) (xy 85.826092 -29.390848) (xy 85.852552 -29.373923)
			(xy 85.908971 -29.346316) (xy 85.968493 -29.326257) (xy 86.030113 -29.314084) (xy 86.092792 -29.310004)
			(xy 86.155471 -29.314084) (xy 86.217091 -29.326257) (xy 86.276613 -29.346316) (xy 86.333032 -29.373923)
			(xy 86.359492 -29.390848) (xy 86.391496 -29.41193) (xy 86.4489 -29.41193) (xy 86.4489 -29.464254)
			(xy 86.475316 -29.498544) (xy 86.494275 -29.523999) (xy 86.526122 -29.578902) (xy 86.550511 -29.637499)
			(xy 86.567024 -29.698784) (xy 86.575376 -29.761703) (xy 86.5759 -29.793438) (xy 86.5759 -31.110936)
			(xy 86.578694 -31.113984) (xy 86.787736 -31.113984) (xy 86.804387 -31.113488) (xy 86.836553 -31.10486)
			(xy 86.86539 -31.088202) (xy 86.888934 -31.064649) (xy 86.90558 -31.035805) (xy 86.914195 -31.003635)
			(xy 86.914736 -30.986984) (xy 86.914736 -30.957012) (xy 86.901274 -30.930088) (xy 86.888078 -30.902553)
			(xy 86.868302 -30.844787) (xy 86.856382 -30.784903) (xy 86.852531 -30.723966) (xy 86.856817 -30.663058)
			(xy 86.869163 -30.603261) (xy 86.889351 -30.545637) (xy 86.917022 -30.491209) (xy 86.951685 -30.440943)
			(xy 86.992723 -30.395733) (xy 87.039409 -30.356381) (xy 87.090913 -30.323586) (xy 87.14632 -30.297931)
			(xy 87.204646 -30.279871) (xy 87.264856 -30.269727) (xy 87.32588 -30.26768) (xy 87.386634 -30.273764)
			(xy 87.44604 -30.287873) (xy 87.503042 -30.309756) (xy 87.556629 -30.339024) (xy 87.605847 -30.375158)
			(xy 87.649825 -30.417515) (xy 87.687779 -30.465344) (xy 87.719036 -30.517795) (xy 87.743042 -30.573936)
			(xy 87.75937 -30.632771) (xy 87.767729 -30.693255) (xy 87.767971 -30.754312) (xy 87.760093 -30.81486)
			(xy 87.744234 -30.873823) (xy 87.720675 -30.930154) (xy 87.705692 -30.956758) (xy 87.694258 -30.977362)
			(xy 87.678349 -31.021711) (xy 87.670878 -31.06823) (xy 87.6721 -31.11533) (xy 87.681974 -31.1614)
			(xy 87.700161 -31.204863) (xy 87.726041 -31.244235) (xy 87.742014 -31.261558) (xy 87.76346 -31.284464)
			(xy 87.800809 -31.334887) (xy 87.831312 -31.389723) (xy 87.854455 -31.448048) (xy 87.869848 -31.50888)
			(xy 87.877231 -31.571193) (xy 87.876481 -31.633938) (xy 87.86761 -31.696057) (xy 87.850768 -31.756503)
			(xy 87.826237 -31.814259) (xy 87.794432 -31.86835) (xy 87.755889 -31.917866) (xy 87.711256 -31.961973)
			(xy 87.661286 -31.999926) (xy 87.606821 -32.031087) (xy 87.548778 -32.05493) (xy 87.488136 -32.071055)
			(xy 87.425916 -32.079188) (xy 87.394542 -32.079692) (xy 86.17839 -32.079692) (xy 85.813138 -31.71444)
			(xy 85.801006 -31.702979) (xy 85.772127 -31.68627) (xy 85.739904 -31.677619) (xy 85.70654 -31.677619)
			(xy 85.674317 -31.68627) (xy 85.645438 -31.702979) (xy 85.633306 -31.71444) (xy 84.851192 -32.496554)
			(xy 88.823473 -32.496554) (xy 88.828569 -32.436244) (xy 88.841567 -32.377131) (xy 88.862242 -32.320246)
			(xy 88.890233 -32.266582) (xy 88.925051 -32.217075) (xy 88.945212 -32.1945) (xy 88.961179 -32.176457)
			(xy 88.986592 -32.135529) (xy 89.003828 -32.090542) (xy 89.012266 -32.043111) (xy 89.011605 -31.99494)
			(xy 89.001867 -31.947758) (xy 88.983403 -31.903261) (xy 88.970612 -31.882842) (xy 88.955875 -31.859608)
			(xy 88.932542 -31.809781) (xy 88.916609 -31.757119) (xy 88.908405 -31.702714) (xy 88.908101 -31.647695)
			(xy 88.915704 -31.593203) (xy 88.931054 -31.540368) (xy 88.953835 -31.490286) (xy 88.983573 -31.443996)
			(xy 89.019652 -31.402457) (xy 89.061323 -31.366531) (xy 89.107723 -31.336964) (xy 89.157888 -31.314368)
			(xy 89.210779 -31.299212) (xy 89.265299 -31.29181) (xy 89.320316 -31.292317) (xy 89.37469 -31.300721)
			(xy 89.427294 -31.316848) (xy 89.477035 -31.340364) (xy 89.522882 -31.37078) (xy 89.563885 -31.407467)
			(xy 89.599193 -31.449663) (xy 89.619401 -31.48243) (xy 92.848736 -31.48243) (xy 92.852144 -31.421506)
			(xy 92.863617 -31.361575) (xy 92.882952 -31.303701) (xy 92.909806 -31.248908) (xy 92.943702 -31.19817)
			(xy 92.963492 -31.174944) (xy 92.973053 -31.163492) (xy 92.986999 -31.137126) (xy 92.99445 -31.108244)
			(xy 92.994998 -31.078421) (xy 92.988615 -31.049284) (xy 92.975647 -31.022423) (xy 92.96654 -31.010606)
			(xy 92.94631 -30.985072) (xy 92.911892 -30.929759) (xy 92.884822 -30.870503) (xy 92.865543 -30.808274)
			(xy 92.854372 -30.744093) (xy 92.851493 -30.67901) (xy 92.856951 -30.614092) (xy 92.870657 -30.550404)
			(xy 92.892387 -30.488988) (xy 92.921786 -30.430852) (xy 92.95837 -30.376948) (xy 93.001541 -30.328159)
			(xy 93.05059 -30.285285) (xy 93.104716 -30.249028) (xy 93.163029 -30.219983) (xy 93.224575 -30.198625)
			(xy 93.256354 -30.191456) (xy 93.293438 -30.183582) (xy 94.06001 -29.417264) (xy 95.340932 -29.417264)
			(xy 95.373625 -29.417758) (xy 95.438476 -29.42611) (xy 95.501721 -29.44271) (xy 95.562313 -29.467284)
			(xy 95.619254 -29.499426) (xy 95.645732 -29.51861) (xy 95.679514 -29.54401) (xy 96.49714 -29.54401)
			(xy 96.49714 -29.849572) (xy 96.736408 -30.088586) (xy 96.736408 -31.408366) (xy 106.703604 -31.408366)
			(xy 106.703604 -31.34843) (xy 106.711427 -31.289008) (xy 106.72694 -31.231115) (xy 106.749876 -31.175742)
			(xy 106.779843 -31.123836) (xy 106.81633 -31.076286) (xy 106.85871 -31.033906) (xy 106.90626 -30.997419)
			(xy 106.958166 -30.967452) (xy 107.013539 -30.944516) (xy 107.071432 -30.929003) (xy 107.130854 -30.92118)
			(xy 107.19079 -30.92118) (xy 107.250212 -30.929003) (xy 107.308105 -30.944516) (xy 107.363478 -30.967452)
			(xy 107.415384 -30.997419) (xy 107.462934 -31.033906) (xy 107.505314 -31.076286) (xy 107.541801 -31.123836)
			(xy 107.571768 -31.175742) (xy 107.594704 -31.231115) (xy 107.610217 -31.289008) (xy 107.61804 -31.34843)
			(xy 107.61853 -31.378398) (xy 107.61804 -31.408366) (xy 107.610217 -31.467788) (xy 107.594704 -31.525681)
			(xy 107.571768 -31.581054) (xy 107.541801 -31.63296) (xy 107.505314 -31.68051) (xy 107.462934 -31.72289)
			(xy 107.415384 -31.759377) (xy 107.373277 -31.783687) (xy 109.894252 -31.783687) (xy 109.896861 -31.727631)
			(xy 109.907653 -31.672562) (xy 109.926396 -31.619669) (xy 109.952686 -31.570092) (xy 109.985955 -31.524901)
			(xy 110.005368 -31.504636) (xy 110.016621 -31.492481) (xy 110.033098 -31.463765) (xy 110.041627 -31.431774)
			(xy 110.041632 -31.398666) (xy 110.033113 -31.366672) (xy 110.016645 -31.337951) (xy 110.005368 -31.32582)
			(xy 109.985955 -31.305555) (xy 109.952686 -31.260364) (xy 109.926396 -31.210787) (xy 109.907653 -31.157894)
			(xy 109.896861 -31.102825) (xy 109.894252 -31.046769) (xy 109.899884 -30.990936) (xy 109.913635 -30.93653)
			(xy 109.935207 -30.884726) (xy 109.964136 -30.836641) (xy 109.999797 -30.793312) (xy 110.041421 -30.755676)
			(xy 110.088109 -30.724543) (xy 110.138855 -30.700586) (xy 110.192563 -30.684322) (xy 110.248074 -30.676101)
			(xy 110.30419 -30.676101) (xy 110.359701 -30.684322) (xy 110.413409 -30.700586) (xy 110.464155 -30.724543)
			(xy 110.510843 -30.755676) (xy 110.552467 -30.793312) (xy 110.588128 -30.836641) (xy 110.617057 -30.884726)
			(xy 110.638629 -30.93653) (xy 110.65238 -30.990936) (xy 110.657249 -31.039201) (xy 111.763733 -31.039201)
			(xy 111.769184 -30.984475) (xy 111.782436 -30.931099) (xy 111.803216 -30.880179) (xy 111.831092 -30.83277)
			(xy 111.865487 -30.789856) (xy 111.905687 -30.752325) (xy 111.95086 -30.720956) (xy 112.00007 -30.696398)
			(xy 112.052296 -30.679161) (xy 112.106456 -30.669602) (xy 112.161427 -30.667919) (xy 112.21607 -30.674147)
			(xy 112.269252 -30.688157) (xy 112.319872 -30.709659) (xy 112.366879 -30.738206) (xy 112.388396 -30.755336)
			(xy 112.406457 -30.769551) (xy 112.446591 -30.791938) (xy 112.490095 -30.806749) (xy 112.535552 -30.813502)
			(xy 112.581482 -30.811977) (xy 112.626391 -30.802224) (xy 112.668817 -30.78456) (xy 112.707378 -30.759561)
			(xy 112.724438 -30.74416) (xy 112.744777 -30.725506) (xy 112.789948 -30.693793) (xy 112.839217 -30.668921)
			(xy 112.891555 -30.651407) (xy 112.945871 -30.641617) (xy 113.001031 -30.639756) (xy 113.055883 -30.645862)
			(xy 113.109283 -30.659808) (xy 113.160116 -30.681304) (xy 113.207322 -30.709899) (xy 113.249914 -30.744998)
			(xy 113.287005 -30.785868) (xy 113.317819 -30.831656) (xy 113.341714 -30.881406) (xy 113.358192 -30.93408)
			(xy 113.366907 -30.988579) (xy 113.367679 -31.043764) (xy 113.36537 -31.06134) (xy 114.120796 -31.06134)
			(xy 114.12359 -31.005552) (xy 114.134489 -30.950767) (xy 114.153262 -30.898158) (xy 114.179505 -30.848849)
			(xy 114.212659 -30.803894) (xy 114.252015 -30.764255) (xy 114.29673 -30.730778) (xy 114.345849 -30.704181)
			(xy 114.398322 -30.685031) (xy 114.453027 -30.673737) (xy 114.508793 -30.670543) (xy 114.56443 -30.675515)
			(xy 114.618746 -30.688547) (xy 114.670581 -30.709361) (xy 114.718827 -30.737512) (xy 114.740944 -30.754574)
			(xy 114.754692 -30.76483) (xy 114.786217 -30.77831) (xy 114.820192 -30.782914) (xy 114.854167 -30.77831)
			(xy 114.885692 -30.76483) (xy 114.89944 -30.754574) (xy 114.920853 -30.737993) (xy 114.967507 -30.710489)
			(xy 115.017581 -30.689858) (xy 115.07007 -30.676517) (xy 115.123918 -30.670731) (xy 115.178043 -30.672619)
			(xy 115.231357 -30.682141) (xy 115.282788 -30.699107) (xy 115.331304 -30.723175) (xy 115.375929 -30.753862)
			(xy 115.415765 -30.790551) (xy 115.450014 -30.832505) (xy 115.477985 -30.878881) (xy 115.499117 -30.928745)
			(xy 115.512985 -30.981097) (xy 115.519311 -31.034884) (xy 115.517967 -31.089026) (xy 115.508981 -31.142433)
			(xy 115.492532 -31.194032) (xy 115.468953 -31.242787) (xy 115.438715 -31.287718) (xy 115.402428 -31.327921)
			(xy 115.36082 -31.362588) (xy 115.314728 -31.391024) (xy 115.290092 -31.402274) (xy 115.276612 -31.40865)
			(xy 115.252827 -31.42662) (xy 115.233869 -31.449624) (xy 115.220774 -31.476404) (xy 115.21426 -31.505494)
			(xy 115.214683 -31.535301) (xy 115.217956 -31.549848) (xy 115.224316 -31.576593) (xy 115.230067 -31.631266)
			(xy 115.227913 -31.686198) (xy 115.217898 -31.740253) (xy 115.200229 -31.792311) (xy 115.175272 -31.841294)
			(xy 115.148574 -31.87907) (xy 116.158291 -31.87907) (xy 116.159104 -31.824046) (xy 116.167813 -31.769709)
			(xy 116.184236 -31.717186) (xy 116.208034 -31.667567) (xy 116.238712 -31.621882) (xy 116.256816 -31.601156)
			(xy 116.272059 -31.583451) (xy 116.296567 -31.543688) (xy 116.313383 -31.50011) (xy 116.321939 -31.454191)
			(xy 116.321946 -31.407481) (xy 116.313403 -31.36156) (xy 116.296599 -31.317977) (xy 116.272103 -31.278207)
			(xy 116.256816 -31.260542) (xy 116.238712 -31.239816) (xy 116.208034 -31.194131) (xy 116.184236 -31.144512)
			(xy 116.167813 -31.091989) (xy 116.159104 -31.037652) (xy 116.158291 -30.982628) (xy 116.165391 -30.928057)
			(xy 116.180255 -30.875073) (xy 116.202577 -30.824773) (xy 116.231892 -30.7782) (xy 116.267593 -30.736322)
			(xy 116.308939 -30.700006) (xy 116.355073 -30.670007) (xy 116.405038 -30.646945) (xy 116.457797 -30.631299)
			(xy 116.512257 -30.623394) (xy 116.567287 -30.623394) (xy 116.621747 -30.631299) (xy 116.674506 -30.646945)
			(xy 116.724471 -30.670007) (xy 116.770605 -30.700006) (xy 116.811951 -30.736322) (xy 116.847652 -30.7782)
			(xy 116.876967 -30.824773) (xy 116.899289 -30.875073) (xy 116.914153 -30.928057) (xy 116.921253 -30.982628)
			(xy 116.92044 -31.037652) (xy 116.911731 -31.091989) (xy 116.895308 -31.144512) (xy 116.87151 -31.194131)
			(xy 116.840832 -31.239816) (xy 116.822728 -31.260542) (xy 116.807423 -31.278184) (xy 116.782982 -31.317979)
			(xy 116.766219 -31.361568) (xy 116.757698 -31.407486) (xy 116.757705 -31.454187) (xy 116.766239 -31.500102)
			(xy 116.783015 -31.543686) (xy 116.807467 -31.583475) (xy 116.822728 -31.601156) (xy 116.840832 -31.621882)
			(xy 116.87151 -31.667567) (xy 116.895308 -31.717186) (xy 116.911731 -31.769709) (xy 116.92044 -31.824046)
			(xy 116.921253 -31.87907) (xy 116.914153 -31.933641) (xy 116.899289 -31.986625) (xy 116.876967 -32.036925)
			(xy 116.847652 -32.083498) (xy 116.811951 -32.125376) (xy 116.770605 -32.161692) (xy 116.724471 -32.191691)
			(xy 116.674506 -32.214753) (xy 116.621747 -32.230399) (xy 116.567287 -32.238304) (xy 116.512257 -32.238304)
			(xy 116.457797 -32.230399) (xy 116.405038 -32.214753) (xy 116.355073 -32.191691) (xy 116.308939 -32.161692)
			(xy 116.267593 -32.125376) (xy 116.231892 -32.083498) (xy 116.202577 -32.036925) (xy 116.180255 -31.986625)
			(xy 116.165391 -31.933641) (xy 116.158291 -31.87907) (xy 115.148574 -31.87907) (xy 115.143543 -31.886188)
			(xy 115.1057 -31.926065) (xy 115.062526 -31.960097) (xy 115.014915 -31.987582) (xy 114.963852 -32.007949)
			(xy 114.910395 -32.020777) (xy 114.855651 -32.0258) (xy 114.800752 -32.022915) (xy 114.746835 -32.012181)
			(xy 114.695017 -31.993821) (xy 114.646371 -31.968214) (xy 114.601902 -31.935891) (xy 114.562533 -31.897521)
			(xy 114.529078 -31.853898) (xy 114.50223 -31.805925) (xy 114.482544 -31.754596) (xy 114.470429 -31.700973)
			(xy 114.466134 -31.646166) (xy 114.46975 -31.59131) (xy 114.475006 -31.564326) (xy 114.47782 -31.548898)
			(xy 114.47669 -31.517568) (xy 114.467954 -31.487459) (xy 114.452141 -31.460389) (xy 114.430204 -31.437991)
			(xy 114.403469 -31.421618) (xy 114.388646 -31.416498) (xy 114.362134 -31.407704) (xy 114.311836 -31.383407)
			(xy 114.26562 -31.352036) (xy 114.224473 -31.31426) (xy 114.189274 -31.270887) (xy 114.160777 -31.222845)
			(xy 114.139591 -31.171161) (xy 114.126168 -31.116939) (xy 114.120796 -31.06134) (xy 113.36537 -31.06134)
			(xy 113.360491 -31.098485) (xy 113.345493 -31.1516) (xy 113.322999 -31.201998) (xy 113.293477 -31.24863)
			(xy 113.257544 -31.290521) (xy 113.21595 -31.326798) (xy 113.169562 -31.356702) (xy 113.11935 -31.379611)
			(xy 113.092992 -31.387796) (xy 113.077439 -31.392821) (xy 113.049386 -31.409571) (xy 113.026515 -31.432904)
			(xy 113.010329 -31.461286) (xy 113.001892 -31.492851) (xy 113.00176 -31.525524) (xy 113.005362 -31.541466)
			(xy 113.011752 -31.568453) (xy 113.017599 -31.6236) (xy 113.0154 -31.679013) (xy 113.005201 -31.733524)
			(xy 112.987218 -31.785984) (xy 112.961828 -31.835287) (xy 112.929567 -31.880394) (xy 112.891114 -31.920355)
			(xy 112.847282 -31.954327) (xy 112.798992 -31.981595) (xy 112.747263 -32.001584) (xy 112.693185 -32.013872)
			(xy 112.637898 -32.018201) (xy 112.582566 -32.01448) (xy 112.528356 -32.002786) (xy 112.476411 -31.983367)
			(xy 112.427825 -31.956631) (xy 112.383622 -31.923142) (xy 112.344733 -31.883605) (xy 112.311979 -31.838855)
			(xy 112.286049 -31.789834) (xy 112.26749 -31.737575) (xy 112.256693 -31.68318) (xy 112.254792 -31.655512)
			(xy 112.253056 -31.632144) (xy 112.242143 -31.58658) (xy 112.223064 -31.543788) (xy 112.196466 -31.505217)
			(xy 112.163249 -31.472175) (xy 112.124538 -31.445781) (xy 112.081646 -31.426928) (xy 112.058958 -31.42107)
			(xy 112.032274 -31.414412) (xy 111.981064 -31.394359) (xy 111.933264 -31.367159) (xy 111.889865 -31.333378)
			(xy 111.851766 -31.293715) (xy 111.819758 -31.248992) (xy 111.794503 -31.200137) (xy 111.776525 -31.148161)
			(xy 111.766197 -31.094143) (xy 111.763733 -31.039201) (xy 110.657249 -31.039201) (xy 110.658012 -31.046769)
			(xy 110.655403 -31.102825) (xy 110.644611 -31.157894) (xy 110.625868 -31.210787) (xy 110.599578 -31.260364)
			(xy 110.566309 -31.305555) (xy 110.546896 -31.32582) (xy 110.535591 -31.337928) (xy 110.519122 -31.366659)
			(xy 110.510603 -31.398662) (xy 110.510608 -31.431778) (xy 110.519137 -31.463778) (xy 110.535615 -31.492504)
			(xy 110.546896 -31.504636) (xy 110.566309 -31.524901) (xy 110.599578 -31.570092) (xy 110.625868 -31.619669)
			(xy 110.644611 -31.672562) (xy 110.655403 -31.727631) (xy 110.658012 -31.783687) (xy 110.65238 -31.83952)
			(xy 110.638629 -31.893926) (xy 110.617057 -31.94573) (xy 110.588128 -31.993815) (xy 110.552467 -32.037144)
			(xy 110.510843 -32.07478) (xy 110.464155 -32.105913) (xy 110.413409 -32.12987) (xy 110.359701 -32.146134)
			(xy 110.30419 -32.154355) (xy 110.248074 -32.154355) (xy 110.192563 -32.146134) (xy 110.138855 -32.12987)
			(xy 110.088109 -32.105913) (xy 110.041421 -32.07478) (xy 109.999797 -32.037144) (xy 109.964136 -31.993815)
			(xy 109.935207 -31.94573) (xy 109.913635 -31.893926) (xy 109.899884 -31.83952) (xy 109.894252 -31.783687)
			(xy 107.373277 -31.783687) (xy 107.363478 -31.789344) (xy 107.308105 -31.81228) (xy 107.250212 -31.827793)
			(xy 107.19079 -31.835616) (xy 107.130854 -31.835616) (xy 107.071432 -31.827793) (xy 107.013539 -31.81228)
			(xy 106.958166 -31.789344) (xy 106.90626 -31.759377) (xy 106.85871 -31.72289) (xy 106.81633 -31.68051)
			(xy 106.779843 -31.63296) (xy 106.749876 -31.581054) (xy 106.72694 -31.525681) (xy 106.711427 -31.467788)
			(xy 106.703604 -31.408366) (xy 96.736408 -31.408366) (xy 96.736408 -31.47949) (xy 96.517968 -31.697676)
			(xy 96.515682 -31.746952) (xy 96.513841 -31.777229) (xy 96.503033 -31.836919) (xy 96.484435 -31.894658)
			(xy 96.458374 -31.949435) (xy 96.425306 -32.000289) (xy 96.385811 -32.046331) (xy 96.340581 -32.086753)
			(xy 96.290409 -32.120846) (xy 96.236172 -32.148014) (xy 96.178823 -32.16778) (xy 96.119365 -32.179799)
			(xy 96.058841 -32.183859) (xy 95.998311 -32.179889) (xy 95.938835 -32.167959) (xy 95.881456 -32.148278)
			(xy 95.82718 -32.121191) (xy 95.776956 -32.087172) (xy 95.731666 -32.046818) (xy 95.692103 -32.000835)
			(xy 95.658959 -31.950029) (xy 95.632817 -31.895291) (xy 95.614133 -31.83758) (xy 95.603236 -31.777907)
			(xy 95.600316 -31.717317) (xy 95.605424 -31.656872) (xy 95.618471 -31.597631) (xy 95.639229 -31.540633)
			(xy 95.652844 -31.513526) (xy 95.663214 -31.492693) (xy 95.676884 -31.448213) (xy 95.682228 -31.401988)
			(xy 95.679065 -31.355562) (xy 95.667502 -31.310488) (xy 95.647925 -31.268273) (xy 95.62099 -31.230329)
			(xy 95.587595 -31.197922) (xy 95.568516 -31.184596) (xy 95.547733 -31.170379) (xy 95.5088 -31.138442)
			(xy 95.490792 -31.120842) (xy 94.803722 -30.433772) (xy 94.481142 -30.433772) (xy 93.728032 -31.187136)
			(xy 93.7133 -31.263082) (xy 93.728286 -31.298896) (xy 93.739731 -31.327182) (xy 93.755867 -31.386029)
			(xy 93.76404 -31.446498) (xy 93.764106 -31.507517) (xy 93.756063 -31.568004) (xy 93.740054 -31.626885)
			(xy 93.716363 -31.683118) (xy 93.685409 -31.735703) (xy 93.647743 -31.783709) (xy 93.604032 -31.826284)
			(xy 93.555051 -31.862674) (xy 93.501669 -31.892232) (xy 93.444833 -31.914435) (xy 93.385551 -31.928889)
			(xy 93.324873 -31.935337) (xy 93.263877 -31.933666) (xy 93.203644 -31.923904) (xy 93.145242 -31.906225)
			(xy 93.089707 -31.880942) (xy 93.038024 -31.848504) (xy 92.99111 -31.809486) (xy 92.949797 -31.764581)
			(xy 92.914816 -31.714584) (xy 92.88679 -31.660382) (xy 92.866214 -31.602936) (xy 92.853454 -31.543266)
			(xy 92.848736 -31.48243) (xy 89.619401 -31.48243) (xy 89.628074 -31.496493) (xy 89.649929 -31.546986)
			(xy 89.664304 -31.600095) (xy 89.670902 -31.654717) (xy 89.669585 -31.709721) (xy 89.660381 -31.763966)
			(xy 89.643481 -31.816325) (xy 89.619235 -31.865715) (xy 89.604088 -31.888684) (xy 89.590983 -31.908899)
			(xy 89.571774 -31.953072) (xy 89.561225 -32.000071) (xy 89.559713 -32.048216) (xy 89.567293 -32.095785)
			(xy 89.583694 -32.141076) (xy 89.608328 -32.182469) (xy 89.6239 -32.20085) (xy 89.643364 -32.223557)
			(xy 89.676947 -32.273044) (xy 89.703798 -32.326483) (xy 89.723458 -32.382965) (xy 89.735593 -32.441526)
			(xy 89.739996 -32.50117) (xy 89.737568 -32.54375) (xy 92.399864 -32.54375) (xy 92.403935 -32.488128)
			(xy 92.416061 -32.433691) (xy 92.435984 -32.3816) (xy 92.46328 -32.332965) (xy 92.497366 -32.288822)
			(xy 92.537515 -32.250113) (xy 92.582873 -32.217662) (xy 92.632473 -32.192161) (xy 92.685257 -32.174154)
			(xy 92.7401 -32.164024) (xy 92.795834 -32.161987) (xy 92.851271 -32.168087) (xy 92.905228 -32.182193)
			(xy 92.956557 -32.204005) (xy 93.004163 -32.233059) (xy 93.047031 -32.268734) (xy 93.084248 -32.310271)
			(xy 93.115021 -32.356784) (xy 93.138693 -32.407281) (xy 93.154761 -32.460688) (xy 93.162881 -32.515864)
			(xy 93.16339 -32.54375) (xy 93.162881 -32.571636) (xy 93.154761 -32.626812) (xy 93.138693 -32.680219)
			(xy 93.115021 -32.730716) (xy 93.084248 -32.777229) (xy 93.047031 -32.818766) (xy 93.004163 -32.854441)
			(xy 92.956557 -32.883495) (xy 92.905228 -32.905307) (xy 92.851271 -32.919413) (xy 92.795834 -32.925513)
			(xy 92.7401 -32.923476) (xy 92.685257 -32.913346) (xy 92.632473 -32.895339) (xy 92.582873 -32.869838)
			(xy 92.537515 -32.837387) (xy 92.497366 -32.798678) (xy 92.46328 -32.754535) (xy 92.435984 -32.7059)
			(xy 92.416061 -32.653809) (xy 92.403935 -32.599372) (xy 92.399864 -32.54375) (xy 89.737568 -32.54375)
			(xy 89.736591 -32.560878) (xy 89.725437 -32.619635) (xy 89.706724 -32.676437) (xy 89.680771 -32.730318)
			(xy 89.64802 -32.780359) (xy 89.609029 -32.825707) (xy 89.58707 -32.84601) (xy 89.575277 -32.857263)
			(xy 89.557261 -32.884412) (xy 89.546733 -32.915246) (xy 89.544381 -32.947743) (xy 89.550362 -32.979772)
			(xy 89.564281 -33.009231) (xy 89.57437 -33.022032) (xy 89.591319 -33.042925) (xy 89.619717 -33.088619)
			(xy 89.641415 -33.13785) (xy 89.65598 -33.18964) (xy 89.663124 -33.242964) (xy 89.662706 -33.296762)
			(xy 89.654733 -33.349968) (xy 89.639364 -33.401526) (xy 89.629671 -33.422625) (xy 99.156445 -33.422625)
			(xy 99.164185 -33.368697) (xy 99.179518 -33.316419) (xy 99.202132 -33.266853) (xy 99.231565 -33.221008)
			(xy 99.267221 -33.179817) (xy 99.308374 -33.144116) (xy 99.331018 -33.128966) (xy 99.349662 -33.116411)
			(xy 99.382557 -33.085781) (xy 99.409555 -33.049847) (xy 99.429818 -33.009727) (xy 99.442714 -32.96667)
			(xy 99.447841 -32.922017) (xy 99.44504 -32.877157) (xy 99.434397 -32.833489) (xy 99.42576 -32.812736)
			(xy 99.413795 -32.784496) (xy 99.396698 -32.725595) (xy 99.38762 -32.664938) (xy 99.386725 -32.603612)
			(xy 99.394028 -32.542715) (xy 99.409398 -32.48334) (xy 99.432561 -32.426549) (xy 99.4631 -32.373361)
			(xy 99.50047 -32.324728) (xy 99.544 -32.281521) (xy 99.592911 -32.244515) (xy 99.646325 -32.214373)
			(xy 99.703287 -32.191634) (xy 99.762775 -32.176707) (xy 99.823724 -32.169859) (xy 99.885042 -32.171211)
			(xy 99.94563 -32.180741) (xy 100.004402 -32.198277) (xy 100.060305 -32.223506) (xy 100.112339 -32.255974)
			(xy 100.15957 -32.295101) (xy 100.201152 -32.340185) (xy 100.236341 -32.390419) (xy 100.264505 -32.444903)
			(xy 100.285141 -32.50266) (xy 100.297878 -32.562655) (xy 100.302058 -32.618112) (xy 100.656231 -32.618112)
			(xy 100.661354 -32.558531) (xy 100.674192 -32.500124) (xy 100.694527 -32.443887) (xy 100.722011 -32.390776)
			(xy 100.756177 -32.341696) (xy 100.796444 -32.297483) (xy 100.842124 -32.25889) (xy 100.892442 -32.226574)
			(xy 100.946538 -32.201085) (xy 101.003494 -32.182857) (xy 101.062338 -32.172201) (xy 101.122068 -32.169299)
			(xy 101.181668 -32.174198) (xy 101.240122 -32.186817) (xy 101.296436 -32.206941) (xy 101.34965 -32.234225)
			(xy 101.398857 -32.268207) (xy 101.443221 -32.308307) (xy 101.481985 -32.353843) (xy 101.51449 -32.404038)
			(xy 101.540182 -32.458039) (xy 101.558623 -32.514926) (xy 101.5695 -32.573729) (xy 101.572627 -32.633448)
			(xy 101.567951 -32.693066) (xy 101.555551 -32.751568) (xy 101.53564 -32.807956) (xy 101.52253 -32.834834)
			(xy 101.512694 -32.855314) (xy 101.499591 -32.89881) (xy 101.494439 -32.943943) (xy 101.4974 -32.989273)
			(xy 101.508381 -33.033352) (xy 101.527032 -33.074773) (xy 101.552756 -33.112214) (xy 101.584733 -33.14448)
			(xy 101.603048 -33.157922) (xy 101.625184 -33.173974) (xy 101.66502 -33.211429) (xy 101.699101 -33.254187)
			(xy 101.726729 -33.301374) (xy 101.747336 -33.352021) (xy 101.760502 -33.405092) (xy 101.765956 -33.459498)
			(xy 101.763586 -33.514126) (xy 101.753442 -33.567856) (xy 101.73573 -33.619587) (xy 101.710815 -33.66826)
			(xy 101.679205 -33.712877) (xy 101.64155 -33.752524) (xy 101.598619 -33.786388) (xy 101.551294 -33.813777)
			(xy 101.500544 -33.834129) (xy 101.447407 -33.847026) (xy 101.392974 -33.852205) (xy 101.338359 -33.84956)
			(xy 101.28468 -33.839144) (xy 101.233039 -33.821172) (xy 101.184493 -33.796011) (xy 101.140036 -33.764177)
			(xy 101.10058 -33.726321) (xy 101.066933 -33.683221) (xy 101.039783 -33.635758) (xy 101.019688 -33.584905)
			(xy 101.007059 -33.531704) (xy 101.002155 -33.477245) (xy 101.005076 -33.422644) (xy 101.015762 -33.369019)
			(xy 101.024436 -33.343088) (xy 101.031513 -33.321499) (xy 101.038825 -33.276665) (xy 101.038046 -33.231246)
			(xy 101.029202 -33.186689) (xy 101.012573 -33.144416) (xy 100.988692 -33.105774) (xy 100.958318 -33.071996)
			(xy 100.922421 -33.044159) (xy 100.902516 -33.033208) (xy 100.876205 -33.018998) (xy 100.827254 -32.984647)
			(xy 100.783192 -32.944215) (xy 100.744771 -32.89839) (xy 100.712644 -32.847952) (xy 100.687358 -32.79376)
			(xy 100.669344 -32.736737) (xy 100.658909 -32.677853) (xy 100.656231 -32.618112) (xy 100.302058 -32.618112)
			(xy 100.302488 -32.623814) (xy 100.298889 -32.685041) (xy 100.287145 -32.745239) (xy 100.267467 -32.803329)
			(xy 100.240207 -32.85827) (xy 100.205853 -32.909079) (xy 100.165021 -32.954844) (xy 100.118443 -32.994746)
			(xy 100.066953 -33.02807) (xy 100.039424 -33.04159) (xy 100.0193 -33.051652) (xy 99.982603 -33.07767)
			(xy 99.951059 -33.109742) (xy 99.925653 -33.146866) (xy 99.907179 -33.187882) (xy 99.896214 -33.23151)
			(xy 99.8931 -33.276387) (xy 99.897935 -33.321111) (xy 99.903788 -33.342834) (xy 99.910909 -33.369132)
			(xy 99.918587 -33.423069) (xy 99.918514 -33.477549) (xy 99.910692 -33.531465) (xy 99.89528 -33.58372)
			(xy 99.872593 -33.633252) (xy 99.84309 -33.679052) (xy 99.807372 -33.72019) (xy 99.766165 -33.755829)
			(xy 99.720308 -33.785244) (xy 99.670733 -33.807837) (xy 99.618449 -33.823148) (xy 99.564518 -33.830866)
			(xy 99.510038 -33.830835) (xy 99.456116 -33.823053) (xy 99.403849 -33.807681) (xy 99.354301 -33.785031)
			(xy 99.308478 -33.755562) (xy 99.267313 -33.719875) (xy 99.231643 -33.678696) (xy 99.202194 -33.632861)
			(xy 99.179564 -33.583303) (xy 99.164213 -33.53103) (xy 99.156454 -33.477105) (xy 99.156445 -33.422625)
			(xy 89.629671 -33.422625) (xy 89.616904 -33.450413) (xy 89.587798 -33.49566) (xy 89.57056 -33.516316)
			(xy 89.55592 -33.534016) (xy 89.532663 -33.573624) (xy 89.516895 -33.616764) (xy 89.509129 -33.662034)
			(xy 89.509618 -33.707963) (xy 89.518345 -33.753058) (xy 89.535026 -33.795853) (xy 89.55912 -33.834957)
			(xy 89.574116 -33.852358) (xy 89.593121 -33.874163) (xy 89.625644 -33.921994) (xy 89.65133 -33.973818)
			(xy 89.669697 -34.028665) (xy 89.680402 -34.085507) (xy 89.683243 -34.143277) (xy 89.678168 -34.200895)
			(xy 89.665272 -34.25728) (xy 89.644796 -34.311375) (xy 89.617123 -34.362166) (xy 89.582774 -34.408703)
			(xy 89.54239 -34.450112) (xy 89.49673 -34.485618) (xy 89.446648 -34.514555) (xy 89.393083 -34.536381)
			(xy 89.33704 -34.550687) (xy 89.279568 -34.557206) (xy 89.221744 -34.555814) (xy 89.164652 -34.546538)
			(xy 89.109361 -34.529551) (xy 89.056909 -34.505173) (xy 89.008278 -34.473859) (xy 88.964379 -34.436198)
			(xy 88.926034 -34.392893) (xy 88.893964 -34.344758) (xy 88.868767 -34.292694) (xy 88.850918 -34.237676)
			(xy 88.840749 -34.180736) (xy 88.838452 -34.122941) (xy 88.84407 -34.065374) (xy 88.857498 -34.009113)
			(xy 88.878483 -33.955214) (xy 88.906633 -33.904685) (xy 88.94142 -33.858475) (xy 88.961468 -33.837626)
			(xy 88.977277 -33.820958) (xy 89.003237 -33.783061) (xy 89.02197 -33.741119) (xy 89.032868 -33.696495)
			(xy 89.035578 -33.650639) (xy 89.03001 -33.605042) (xy 89.016346 -33.561186) (xy 88.995029 -33.520496)
			(xy 88.98128 -33.502092) (xy 88.963941 -33.479013) (xy 88.935626 -33.428713) (xy 88.915207 -33.374723)
			(xy 88.903152 -33.318274) (xy 88.899735 -33.260654) (xy 88.905033 -33.203175) (xy 88.918927 -33.147151)
			(xy 88.941099 -33.093857) (xy 88.971043 -33.044509) (xy 88.989154 -33.022032) (xy 88.999222 -33.009223)
			(xy 89.013096 -32.979755) (xy 89.019054 -32.947735) (xy 89.016709 -32.915249) (xy 89.006214 -32.884416)
			(xy 88.988252 -32.857247) (xy 88.976454 -32.84601) (xy 88.954198 -32.8255) (xy 88.914806 -32.779547)
			(xy 88.881814 -32.728804) (xy 88.855796 -32.674157) (xy 88.837206 -32.616557) (xy 88.826369 -32.55701)
			(xy 88.823473 -32.496554) (xy 84.851192 -32.496554) (xy 84.681568 -32.666178) (xy 84.679282 -32.715454)
			(xy 84.677388 -32.745611) (xy 84.66665 -32.805074) (xy 84.648182 -32.862608) (xy 84.622303 -32.91721)
			(xy 84.589463 -32.967933) (xy 84.550235 -33.013893) (xy 84.5053 -33.054291) (xy 84.45544 -33.088425)
			(xy 84.401522 -33.115702) (xy 84.344483 -33.135646) (xy 84.285316 -33.147911) (xy 84.22505 -33.152283)
			(xy 84.164732 -33.148687) (xy 84.105412 -33.137185) (xy 84.048121 -33.117977) (xy 83.993856 -33.091397)
			(xy 83.94356 -33.057908) (xy 83.898109 -33.018091) (xy 83.858292 -32.97264) (xy 83.824803 -32.922344)
			(xy 83.798223 -32.868079) (xy 83.779015 -32.810788) (xy 83.767513 -32.751468) (xy 83.763917 -32.69115)
			(xy 83.768289 -32.630884) (xy 83.780554 -32.571717) (xy 83.800498 -32.514678) (xy 83.827775 -32.46076)
			(xy 83.861909 -32.4109) (xy 83.902307 -32.365965) (xy 83.948267 -32.326737) (xy 83.99899 -32.293897)
			(xy 84.053592 -32.268018) (xy 84.111126 -32.24955) (xy 84.170589 -32.238812) (xy 84.200746 -32.236918)
			(xy 84.250022 -32.234632) (xy 84.768944 -31.71571) (xy 84.780359 -31.703573) (xy 84.797032 -31.674738)
			(xy 84.805665 -31.642569) (xy 84.805669 -31.609261) (xy 84.797044 -31.577089) (xy 84.780378 -31.548251)
			(xy 84.768944 -31.536132) (xy 84.741512 -31.5087) (xy 84.66582 -31.493714) (xy 84.630006 -31.5087)
			(xy 84.600294 -31.520607) (xy 84.538518 -31.537362) (xy 84.475067 -31.545791) (xy 84.443062 -31.546292)
			(xy 84.071206 -31.546292) (xy 83.275424 -30.75051) (xy 83.275424 -30.356048) (xy 83.224624 -30.305248)
			(xy 83.224624 -29.558488) (xy 83.224139 -29.541827) (xy 83.215547 -29.509633) (xy 83.198902 -29.480768)
			(xy 83.175342 -29.457205) (xy 83.146478 -29.440558) (xy 83.114285 -29.431963) (xy 83.097624 -29.431488)
			(xy 80.26908 -29.431488) (xy 80.20177 -29.48178) (xy 80.189578 -29.52242) (xy 80.1806 -29.551072)
			(xy 80.156838 -29.606214) (xy 80.126726 -29.658161) (xy 80.10906 -29.68244) (xy 80.08366 -29.716222)
			(xy 80.08366 -29.73324) (xy 80.06842 -29.73324) (xy 80.032606 -29.76372) (xy 80.007429 -29.784573)
			(xy 79.952697 -29.820324) (xy 79.893832 -29.848763) (xy 79.831807 -29.869418) (xy 79.767645 -29.881949)
			(xy 79.702406 -29.886149) (xy 79.637167 -29.881949) (xy 79.573005 -29.869418) (xy 79.51098 -29.848763)
			(xy 79.452115 -29.820324) (xy 79.397383 -29.784573) (xy 79.372206 -29.76372) (xy 79.336392 -29.73324)
			(xy 79.321152 -29.73324) (xy 79.321152 -29.716222) (xy 79.295752 -29.68244) (xy 79.27653 -29.655947)
			(xy 79.2443 -29.598976) (xy 79.219658 -29.538336) (xy 79.203013 -29.475032) (xy 79.194642 -29.410114)
			(xy 79.194152 -29.377386) (xy 70.87697 -29.377386) (xy 71.196708 -29.696918) (xy 71.196708 -31.492444)
			(xy 70.969886 -31.719012) (xy 66.849244 -31.719012) (xy 66.832608 -31.719616) (xy 66.80048 -31.728269)
			(xy 66.771674 -31.744923) (xy 66.748143 -31.768448) (xy 66.731482 -31.79725) (xy 66.72282 -31.829376)
			(xy 66.722244 -31.846012) (xy 66.722244 -31.93796) (xy 66.36385 -32.296608) (xy 65.198498 -32.296608)
			(xy 64.921892 -32.020002) (xy 59.669455 -32.020002) (xy 59.663446 -32.05686) (xy 59.646143 -32.114287)
			(xy 59.621487 -32.168962) (xy 59.589899 -32.219947) (xy 59.551921 -32.266368) (xy 59.508204 -32.30743)
			(xy 59.459497 -32.342429) (xy 59.406636 -32.370764) (xy 59.350526 -32.391951) (xy 59.292128 -32.405626)
			(xy 59.232445 -32.411555) (xy 59.172498 -32.409635) (xy 59.113317 -32.399901) (xy 59.055914 -32.382519)
			(xy 59.001273 -32.357786) (xy 58.950333 -32.326127) (xy 58.903965 -32.288084) (xy 58.862964 -32.24431)
			(xy 58.828033 -32.195554) (xy 58.799771 -32.142653) (xy 58.778663 -32.086513) (xy 58.76507 -32.028097)
			(xy 58.759224 -31.968405) (xy 58.404057 -31.968405) (xy 58.403042 -31.99888) (xy 58.393243 -32.058012)
			(xy 58.375808 -32.115359) (xy 58.351037 -32.169939) (xy 58.319353 -32.220819) (xy 58.281298 -32.267127)
			(xy 58.237523 -32.308071) (xy 58.188779 -32.34295) (xy 58.135898 -32.371168) (xy 58.079787 -32.392242)
			(xy 58.021404 -32.40581) (xy 57.96175 -32.411641) (xy 57.901845 -32.409635) (xy 57.842715 -32.399826)
			(xy 57.785371 -32.382382) (xy 57.730795 -32.357602) (xy 57.67992 -32.325909) (xy 57.633619 -32.287847)
			(xy 57.592682 -32.244066) (xy 57.55781 -32.195315) (xy 57.529601 -32.14243) (xy 57.508537 -32.086315)
			(xy 57.494978 -32.02793) (xy 57.489157 -31.968275) (xy 57.491173 -31.908371) (xy 57.500991 -31.849242)
			(xy 57.518445 -31.791901) (xy 57.543234 -31.737329) (xy 57.558686 -31.711646) (xy 57.569983 -31.692676)
			(xy 57.586498 -31.651732) (xy 57.595686 -31.608549) (xy 57.597269 -31.564428) (xy 57.5912 -31.520698)
			(xy 57.577663 -31.478675) (xy 57.557064 -31.439626) (xy 57.530024 -31.404726) (xy 57.497357 -31.375027)
			(xy 57.460048 -31.351422) (xy 57.439814 -31.342584) (xy 57.414413 -31.331612) (xy 57.366832 -31.303374)
			(xy 57.323828 -31.268559) (xy 57.286304 -31.227898) (xy 57.255047 -31.182243) (xy 57.230711 -31.132553)
			(xy 57.213808 -31.079868) (xy 57.204693 -31.025294) (xy 57.203555 -30.969976) (xy 55.34914 -30.969976)
			(xy 55.34914 -33.283652) (xy 74.097896 -33.283652) (xy 74.097896 -30.71114) (xy 74.098344 -30.681178)
			(xy 74.105381 -30.621668) (xy 74.119373 -30.563399) (xy 74.140127 -30.507183) (xy 74.167353 -30.453801)
			(xy 74.200673 -30.403994) (xy 74.219816 -30.38094) (xy 74.250296 -30.345126) (xy 74.250296 -30.329632)
			(xy 74.267314 -30.329632) (xy 74.301096 -30.304486) (xy 74.327583 -30.285252) (xy 74.384557 -30.253017)
			(xy 74.445197 -30.228362) (xy 74.508501 -30.211695) (xy 74.57342 -30.203292) (xy 74.63888 -30.203292)
			(xy 74.703799 -30.211695) (xy 74.767103 -30.228362) (xy 74.827743 -30.253017) (xy 74.884717 -30.285252)
			(xy 74.911204 -30.304486) (xy 74.944986 -30.329632) (xy 74.962004 -30.329632) (xy 74.962004 -30.345126)
			(xy 74.992484 -30.38094) (xy 75.011611 -30.404006) (xy 75.044924 -30.453815) (xy 75.072149 -30.507197)
			(xy 75.092907 -30.563409) (xy 75.10691 -30.621673) (xy 75.113964 -30.681179) (xy 75.114404 -30.71114)
			(xy 75.114404 -32.917638) (xy 75.122024 -32.938466) (xy 75.132104 -32.968017) (xy 75.145891 -33.028913)
			(xy 75.152115 -33.091039) (xy 75.150682 -33.15346) (xy 75.141615 -33.215236) (xy 75.12505 -33.275435)
			(xy 75.101235 -33.333152) (xy 75.070531 -33.387518) (xy 75.033398 -33.437714) (xy 74.990397 -33.482983)
			(xy 74.942175 -33.522645) (xy 74.889458 -33.556101) (xy 74.83304 -33.582848) (xy 74.773771 -33.602484)
			(xy 74.712543 -33.614712) (xy 74.650278 -33.619348) (xy 74.587914 -33.616323) (xy 74.526391 -33.605683)
			(xy 74.466633 -33.587586) (xy 74.409543 -33.562306) (xy 74.355978 -33.530224) (xy 74.306747 -33.491823)
			(xy 74.284332 -33.470088) (xy 74.097896 -33.283652) (xy 55.34914 -33.283652) (xy 55.34914 -33.540954)
			(xy 55.61863 -33.810444) (xy 76.487002 -33.810444) (xy 76.487002 -33.750508) (xy 76.494825 -33.691086)
			(xy 76.510338 -33.633193) (xy 76.533274 -33.57782) (xy 76.563241 -33.525914) (xy 76.599728 -33.478364)
			(xy 76.642108 -33.435984) (xy 76.689658 -33.399497) (xy 76.741564 -33.36953) (xy 76.796937 -33.346594)
			(xy 76.85483 -33.331081) (xy 76.914252 -33.323258) (xy 76.974188 -33.323258) (xy 77.03361 -33.331081)
			(xy 77.091503 -33.346594) (xy 77.146876 -33.36953) (xy 77.198782 -33.399497) (xy 77.246332 -33.435984)
			(xy 77.288712 -33.478364) (xy 77.325199 -33.525914) (xy 77.355166 -33.57782) (xy 77.378102 -33.633193)
			(xy 77.393615 -33.691086) (xy 77.401438 -33.750508) (xy 77.401928 -33.780476) (xy 77.401438 -33.810444)
			(xy 77.393615 -33.869866) (xy 77.378102 -33.927759) (xy 77.355166 -33.983132) (xy 77.325199 -34.035038)
			(xy 77.288712 -34.082588) (xy 77.246332 -34.124968) (xy 77.198782 -34.161455) (xy 77.146876 -34.191422)
			(xy 77.091503 -34.214358) (xy 77.03361 -34.229871) (xy 76.974188 -34.237694) (xy 76.914252 -34.237694)
			(xy 76.85483 -34.229871) (xy 76.796937 -34.214358) (xy 76.741564 -34.191422) (xy 76.689658 -34.161455)
			(xy 76.642108 -34.124968) (xy 76.599728 -34.082588) (xy 76.563241 -34.035038) (xy 76.533274 -33.983132)
			(xy 76.510338 -33.927759) (xy 76.494825 -33.869866) (xy 76.487002 -33.810444) (xy 55.61863 -33.810444)
			(xy 55.815992 -34.007806) (xy 55.815992 -34.70783) (xy 57.6199 -36.511738) (xy 72.8853 -40.147748)
		)
		(stroke
			(width 0)
			(type solid)
		)
		(fill yes)
		(layer "B.Cu")
		(net "PV_VDDR_NODE1")
	)
	(gr_line
		(start -18.237962 -206.70012)
		(end -18.237962 -1.999996)
		(stroke
			(width 1.016)
			(type default)
		)
		(layer "In1.Cu")
	)
	(gr_arc
		(start -18.237962 -206.70012)
		(mid -17.652177 -208.114331)
		(end -16.237966 -208.700116)
		(stroke
			(width 1.016)
			(type default)
		)
		(layer "In1.Cu")
	)
	(gr_line
		(start -18.237962 -2.44602)
		(end -18.237962 -11.170158)
		(stroke
			(width 0.2)
			(type default)
		)
		(layer "In1.Cu")
	)
	(gr_arc
		(start -16.237966 0)
		(mid -17.652177 -0.585785)
		(end -18.237962 -1.999996)
		(stroke
			(width 1.016)
			(type default)
		)
		(layer "In1.Cu")
	)
	(gr_line
		(start -16.237966 0)
		(end -1.999996 0)
		(stroke
			(width 1.016)
			(type default)
		)
		(layer "In1.Cu")
	)
	(gr_line
		(start -1.999996 -160.375092)
		(end -1.999742 -160.375092)
		(stroke
			(width 1.016)
			(type default)
		)
		(layer "In1.Cu")
	)
	(gr_line
		(start -1.999996 0)
		(end -1.999996 -160.375092)
		(stroke
			(width 1.016)
			(type default)
		)
		(layer "In1.Cu")
	)
	(gr_line
		(start -1.999742 -208.700116)
		(end -16.237966 -208.700116)
		(stroke
			(width 1.016)
			(type default)
		)
		(layer "In1.Cu")
	)
	(gr_line
		(start -1.999742 -208.700116)
		(end -1.999742 -167.421814)
		(stroke
			(width 1.016)
			(type default)
		)
		(layer "In1.Cu")
	)
	(gr_line
		(start -1.999742 -167.421814)
		(end 0 -167.421814)
		(stroke
			(width 1.016)
			(type default)
		)
		(layer "In1.Cu")
	)
	(gr_line
		(start -1.999742 -165.176708)
		(end 0 -165.176708)
		(stroke
			(width 1.016)
			(type default)
		)
		(layer "In1.Cu")
	)
	(gr_line
		(start -1.999742 -160.375092)
		(end -1.999742 -165.176708)
		(stroke
			(width 1.016)
			(type default)
		)
		(layer "In1.Cu")
	)
	(gr_line
		(start -1.999234 -76.864972)
		(end -2.003806 -76.864972)
		(stroke
			(width 0.2)
			(type default)
		)
		(layer "In1.Cu")
	)
	(gr_arc
		(start 0 -168.699942)
		(mid 0.585785 -170.114153)
		(end 1.999996 -170.699938)
		(stroke
			(width 1.016)
			(type default)
		)
		(layer "In1.Cu")
	)
	(gr_line
		(start 0 -167.581834)
		(end 0 -168.699942)
		(stroke
			(width 1.016)
			(type default)
		)
		(layer "In1.Cu")
	)
	(gr_line
		(start 0 -72.300084)
		(end 0 -164.964364)
		(stroke
			(width 1.016)
			(type default)
		)
		(layer "In1.Cu")
	)
	(gr_line
		(start 0 -29.299916)
		(end 0 -1.999996)
		(stroke
			(width 1.016)
			(type default)
		)
		(layer "In1.Cu")
	)
	(gr_arc
		(start 0 -29.299916)
		(mid 0.439376 -30.360664)
		(end 1.500124 -30.80004)
		(stroke
			(width 1.016)
			(type default)
		)
		(layer "In1.Cu")
	)
	(gr_poly
		(pts
			(xy 64.48806 -68.33489)
			(arc
				(start 64.48806 -68.050918)
				(mid 64.352706 -67.705478)
				(end 64.48806 -67.360038)
			)
			(arc
				(start 64.48806 -66.638678)
				(mid 64.479101 -66.591825)
				(end 64.453516 -66.551556)
			)
			(arc
				(start 64.453516 -66.551556)
				(mid 64.3146 -66.202306)
				(end 64.453516 -65.853056)
			)
			(arc
				(start 64.453516 -65.853056)
				(mid 64.479136 -65.812801)
				(end 64.48806 -65.765934)
			)
			(xy 64.48806 -64.483742) (xy 64.92621 -64.045592)
			(arc
				(start 65.442084 -64.045592)
				(mid 65.514291 -64.023243)
				(end 65.560956 -63.963804)
			)
			(arc
				(start 65.560956 -63.96355)
				(mid 65.746375 -63.758059)
				(end 66.021966 -63.731902)
			)
			(arc
				(start 66.021966 -63.731902)
				(mid 66.088746 -63.732807)
				(end 66.14668 -63.699644)
			)
			(xy 66.71691 -63.129414) (xy 66.71691 -62.172088) (xy 68.00596 -60.883038) (xy 68.00596 -59.558428)
			(xy 68.401692 -59.162696) (xy 72.09917 -59.162696) (xy 75.827128 -55.434738) (xy 76.712572 -55.434738)
			(xy 84.47278 -47.67453) (xy 84.47278 -31.516828) (xy 84.414868 -31.44647)
			(arc
				(start 84.370164 -31.437834)
				(mid 84.107279 -31.24437)
				(end 84.090256 -30.918404)
			)
			(xy 84.104988 -30.882844) (xy 84.089748 -30.807406) (xy 82.935572 -29.65323) (xy 82.493866 -29.65323)
			(xy 82.056986 -29.21635) (xy 82.056986 -27.005788) (xy 82.455004 -26.60777) (xy 82.455004 -25.27173)
			(arc
				(start 82.445098 -25.248108)
				(mid 82.414964 -25.099518)
				(end 82.445098 -24.950928)
			)
			(xy 82.455004 -24.927306) (xy 82.455004 -24.44369)
			(arc
				(start 82.344768 -24.333454)
				(mid 82.277374 -24.298357)
				(end 82.20202 -24.308054)
			)
			(arc
				(start 82.201766 -24.308054)
				(mid 81.772225 -24.231373)
				(end 81.695544 -23.801832)
			)
			(arc
				(start 81.695544 -23.801578)
				(mid 81.705209 -23.72623)
				(end 81.670144 -23.65883)
			)
			(xy 81.534508 -23.523194) (xy 81.534254 -23.523194) (xy 81.459832 -23.448772) (xy 81.459832 -22.850602)
			(xy 81.43494 -22.798532)
			(arc
				(start 81.412334 -22.780498)
				(mid 81.270072 -22.483318)
				(end 81.412334 -22.186138)
			)
			(xy 81.43494 -22.168104) (xy 81.459832 -22.116034) (xy 81.459832 -19.783298) (xy 81.42859 -19.726402)
			(arc
				(start 81.400904 -19.708876)
				(mid 81.224329 -19.387058)
				(end 81.400904 -19.06524)
			)
			(xy 81.42859 -19.047714) (xy 81.459832 -18.990818) (xy 81.459832 -18.631916) (xy 81.339436 -18.51152)
			(xy 68.316602 -18.51152) (xy 67.678046 -19.150076) (xy 67.678046 -20.501102) (xy 67.98056 -20.803616)
			(xy 67.98056 -25.37968) (xy 67.510914 -25.849326) (xy 67.510914 -27.061414) (xy 67.52336 -27.07386)
			(xy 67.52336 -29.28874) (xy 66.979546 -29.832554) (xy 64.090804 -29.832554) (xy 63.53048 -30.392878)
			(xy 63.53048 -34.165032) (xy 58.204608 -39.490904) (xy 58.204608 -50.400204) (xy 56.79948 -51.805332)
			(xy 56.79948 -58.586878) (xy 56.43118 -58.955178) (xy 56.43118 -63.467742) (xy 57.293256 -64.329818)
			(xy 59.805316 -64.329818)
			(arc
				(start 60.545218 -65.06972)
				(mid 60.612892 -65.104867)
				(end 60.688474 -65.094866)
			)
			(arc
				(start 60.688728 -65.094866)
				(mid 61.120255 -65.170577)
				(end 61.195966 -65.602104)
			)
			(arc
				(start 61.195966 -65.602358)
				(mid 61.186014 -65.677932)
				(end 61.221112 -65.745614)
			)
			(xy 61.238384 -65.762886) (xy 61.238384 -66.43878) (xy 61.179456 -66.497708) (xy 61.179456 -66.684398)
			(xy 61.348874 -66.853816) (xy 61.348874 -67.147186) (xy 61.275468 -67.220592)
			(arc
				(start 61.188346 -67.335908)
				(mid 61.165964 -67.383324)
				(end 61.164724 -67.43573)
			)
			(xy 61.167518 -67.451224) (xy 61.314584 -67.647566) (xy 61.231526 -67.93484) (xy 61.10605 -68.155566)
			(arc
				(start 61.108844 -68.207636)
				(mid 61.180689 -68.297146)
				(end 61.222636 -68.403978)
			)
			(arc
				(start 61.222636 -68.403978)
				(mid 61.269433 -68.476993)
				(end 61.352176 -68.503038)
			)
			(arc
				(start 61.352176 -68.503038)
				(mid 61.428933 -68.507211)
				(end 61.503306 -68.52666)
			)
			(xy 61.524896 -68.534788) (xy 64.288162 -68.534788)
		)
		(stroke
			(width 0)
			(type solid)
		)
		(fill yes)
		(layer "In1.Cu")
		(net "PV_VDDR_NODE1")
	)
	(gr_poly
		(pts
			(xy -2.634742 -208.192116) (xy -2.618087 -208.191622) (xy -2.585913 -208.183001) (xy -2.557066 -208.166346)
			(xy -2.533512 -208.142792) (xy -2.516857 -208.113945) (xy -2.508236 -208.081771) (xy -2.507742 -208.065116)
			(xy -2.507742 -166.913814) (xy 0.210312 -166.913814) (xy 0.508 -167.211502) (xy 0.508 -167.433752)
			(xy 0.509016 -167.433752) (xy 0.509016 -168.699942) (xy 0.509537 -168.755711) (xy 0.517873 -168.866937)
			(xy 0.534497 -168.977229) (xy 0.559316 -169.085971) (xy 0.592193 -169.192554) (xy 0.632942 -169.296382)
			(xy 0.681337 -169.396874) (xy 0.737106 -169.493469) (xy 0.799937 -169.585626) (xy 0.86948 -169.67283)
			(xy 0.945345 -169.754593) (xy 1.027108 -169.830458) (xy 1.114312 -169.900001) (xy 1.206469 -169.962832)
			(xy 1.303064 -170.018601) (xy 1.403556 -170.066996) (xy 1.507384 -170.107745) (xy 1.613967 -170.140622)
			(xy 1.722709 -170.165441) (xy 1.833001 -170.182065) (xy 1.944227 -170.190401) (xy 1.999996 -170.190922)
			(xy 10.359898 -170.190922) (xy 10.43028 -170.191416) (xy 10.570824 -170.199308) (xy 10.710703 -170.215069)
			(xy 10.849479 -170.238648) (xy 10.986714 -170.269971) (xy 11.121978 -170.308939) (xy 11.254843 -170.35543)
			(xy 11.384893 -170.409299) (xy 11.511717 -170.470374) (xy 11.634918 -170.538464) (xy 11.754107 -170.613356)
			(xy 11.868909 -170.694812) (xy 11.978964 -170.782577) (xy 12.083924 -170.876375) (xy 12.18346 -170.97591)
			(xy 12.277258 -171.08087) (xy 12.365023 -171.190924) (xy 12.44648 -171.305726) (xy 12.521372 -171.424915)
			(xy 12.589462 -171.548115) (xy 12.650538 -171.67494) (xy 12.704407 -171.804989) (xy 12.750899 -171.937855)
			(xy 12.789867 -172.073118) (xy 12.821191 -172.210353) (xy 12.84477 -172.349129) (xy 12.860531 -172.489008)
			(xy 12.868424 -172.629552) (xy 12.86891 -172.699934) (xy 12.86891 -202.876404) (xy 12.869405 -202.893058)
			(xy 12.878027 -202.925231) (xy 12.894682 -202.954075) (xy 12.918236 -202.977626) (xy 12.947082 -202.994278)
			(xy 12.979256 -203.002897) (xy 12.99591 -203.003404) (xy 82.923888 -203.003404) (xy 82.940544 -203.002911)
			(xy 82.972722 -202.994292) (xy 83.001572 -202.977638) (xy 83.025128 -202.954084) (xy 83.041786 -202.925236)
			(xy 83.050409 -202.89306) (xy 83.050888 -202.876404) (xy 83.050888 -201.250042) (xy 83.051381 -201.195462)
			(xy 83.05953 -201.086606) (xy 83.075791 -200.978664) (xy 83.100073 -200.872238) (xy 83.132241 -200.767925)
			(xy 83.172115 -200.666308) (xy 83.219472 -200.567955) (xy 83.274047 -200.473416) (xy 83.335534 -200.38322)
			(xy 83.40359 -200.297872) (xy 83.477835 -200.217848) (xy 83.557852 -200.143597) (xy 83.643194 -200.075534)
			(xy 83.733385 -200.014038) (xy 83.827919 -199.959456) (xy 83.926268 -199.91209) (xy 84.027881 -199.872207)
			(xy 84.132192 -199.84003) (xy 84.238615 -199.815738) (xy 84.346556 -199.799468) (xy 84.455411 -199.79131)
			(xy 84.564571 -199.79131) (xy 84.673426 -199.799468) (xy 84.781367 -199.815738) (xy 84.88779 -199.84003)
			(xy 84.992101 -199.872207) (xy 85.093714 -199.91209) (xy 85.192063 -199.959456) (xy 85.286597 -200.014038)
			(xy 85.376788 -200.075534) (xy 85.46213 -200.143597) (xy 85.542147 -200.217848) (xy 85.616392 -200.297872)
			(xy 85.684448 -200.38322) (xy 85.745935 -200.473416) (xy 85.80051 -200.567955) (xy 85.847867 -200.666308)
			(xy 85.887741 -200.767925) (xy 85.919909 -200.872238) (xy 85.944191 -200.978664) (xy 85.960452 -201.086606)
			(xy 85.968601 -201.195462) (xy 85.969094 -201.250042) (xy 85.969094 -202.876404) (xy 85.969638 -202.893052)
			(xy 85.978256 -202.925214) (xy 85.994905 -202.95405) (xy 86.018449 -202.977594) (xy 86.047284 -202.994243)
			(xy 86.079446 -203.002862) (xy 86.096094 -203.003404) (xy 96.023938 -203.003404) (xy 96.040583 -203.002856)
			(xy 96.072738 -202.994232) (xy 96.101565 -202.977581) (xy 96.125102 -202.954038) (xy 96.141745 -202.925206)
			(xy 96.150361 -202.893049) (xy 96.150938 -202.876404) (xy 96.150938 -188.250068) (xy 96.151438 -188.162213)
			(xy 96.159435 -187.986685) (xy 96.175414 -187.811703) (xy 96.199339 -187.637629) (xy 96.231163 -187.464825)
			(xy 96.27082 -187.293648) (xy 96.318226 -187.124454) (xy 96.373283 -186.957593) (xy 96.435879 -186.79341)
			(xy 96.505882 -186.632247) (xy 96.583147 -186.474437) (xy 96.667516 -186.320307) (xy 96.758812 -186.170177)
			(xy 96.856847 -186.024358) (xy 96.961417 -185.883151) (xy 97.072305 -185.746851) (xy 97.189283 -185.615739)
			(xy 97.312106 -185.490087) (xy 97.440521 -185.370156) (xy 97.574262 -185.256193) (xy 97.713051 -185.148436)
			(xy 97.856601 -185.047107) (xy 98.004614 -184.952418) (xy 98.156784 -184.864562) (xy 98.312794 -184.783724)
			(xy 98.472322 -184.710071) (xy 98.635037 -184.643754) (xy 98.800602 -184.584913) (xy 98.968673 -184.533668)
			(xy 99.138903 -184.490125) (xy 99.310938 -184.454376) (xy 99.484422 -184.426494) (xy 99.658995 -184.406537)
			(xy 99.834295 -184.394546) (xy 100.00996 -184.390546) (xy 100.185625 -184.394546) (xy 100.360925 -184.406537)
			(xy 100.535498 -184.426494) (xy 100.708982 -184.454376) (xy 100.881017 -184.490125) (xy 101.051247 -184.533668)
			(xy 101.219318 -184.584913) (xy 101.384883 -184.643754) (xy 101.547598 -184.710071) (xy 101.707126 -184.783724)
			(xy 101.863136 -184.864562) (xy 102.015306 -184.952418) (xy 102.163319 -185.047107) (xy 102.306869 -185.148436)
			(xy 102.445658 -185.256193) (xy 102.579399 -185.370156) (xy 102.707814 -185.490087) (xy 102.830637 -185.615739)
			(xy 102.947615 -185.746851) (xy 103.058503 -185.883151) (xy 103.163073 -186.024358) (xy 103.261108 -186.170177)
			(xy 103.352404 -186.320307) (xy 103.436773 -186.474437) (xy 103.514038 -186.632247) (xy 103.584041 -186.79341)
			(xy 103.646637 -186.957593) (xy 103.701694 -187.124454) (xy 103.7491 -187.293648) (xy 103.788757 -187.464825)
			(xy 103.820581 -187.637629) (xy 103.844506 -187.811703) (xy 103.860485 -187.986685) (xy 103.868482 -188.162213)
			(xy 103.868982 -188.250068) (xy 103.868982 -202.876404) (xy 103.869526 -202.893053) (xy 103.878144 -202.925216)
			(xy 103.894792 -202.954053) (xy 103.918336 -202.9776) (xy 103.947171 -202.994251) (xy 103.979333 -203.002873)
			(xy 103.995982 -203.003404) (xy 173.92396 -203.003404) (xy 173.940618 -203.002914) (xy 173.972802 -202.9943)
			(xy 174.001659 -202.977648) (xy 174.025221 -202.954094) (xy 174.041883 -202.925243) (xy 174.050508 -202.893062)
			(xy 174.05096 -202.876404) (xy 174.05096 -201.250042) (xy 174.05147 -201.19547) (xy 174.059626 -201.086631)
			(xy 174.075893 -200.978707) (xy 174.10018 -200.872299) (xy 174.132351 -200.768004) (xy 174.172226 -200.666405)
			(xy 174.219582 -200.56807) (xy 174.274153 -200.473548) (xy 174.335636 -200.383369) (xy 174.403687 -200.298037)
			(xy 174.477923 -200.218029) (xy 174.557931 -200.143793) (xy 174.643263 -200.075742) (xy 174.733442 -200.014259)
			(xy 174.827964 -199.959688) (xy 174.926299 -199.912332) (xy 175.027898 -199.872457) (xy 175.132193 -199.840286)
			(xy 175.238601 -199.815999) (xy 175.346525 -199.799732) (xy 175.455364 -199.791576) (xy 175.564508 -199.791576)
			(xy 175.673347 -199.799732) (xy 175.781271 -199.815999) (xy 175.887679 -199.840286) (xy 175.991974 -199.872457)
			(xy 176.093573 -199.912332) (xy 176.191908 -199.959688) (xy 176.28643 -200.014259) (xy 176.376609 -200.075742)
			(xy 176.461941 -200.143793) (xy 176.541949 -200.218029) (xy 176.616185 -200.298037) (xy 176.684236 -200.383369)
			(xy 176.745719 -200.473548) (xy 176.80029 -200.56807) (xy 176.847646 -200.666405) (xy 176.887521 -200.768004)
			(xy 176.919692 -200.872299) (xy 176.943979 -200.978707) (xy 176.960246 -201.086631) (xy 176.968402 -201.19547)
			(xy 176.968912 -201.250042) (xy 176.968912 -202.876404) (xy 176.969407 -202.893058) (xy 176.978029 -202.92523)
			(xy 176.994684 -202.954075) (xy 177.018238 -202.977625) (xy 177.047085 -202.994277) (xy 177.079258 -203.002895)
			(xy 177.095912 -203.003404) (xy 187.02401 -203.003404) (xy 187.040658 -203.00286) (xy 187.072818 -202.99424)
			(xy 187.101652 -202.977591) (xy 187.125195 -202.954047) (xy 187.141842 -202.925213) (xy 187.15046 -202.893052)
			(xy 187.15101 -202.876404) (xy 187.15101 -172.699934) (xy 187.151494 -172.629551) (xy 187.159385 -172.489007)
			(xy 187.175144 -172.349126) (xy 187.198721 -172.210349) (xy 187.230043 -172.073112) (xy 187.269011 -171.937847)
			(xy 187.315502 -171.804981) (xy 187.369369 -171.67493) (xy 187.430445 -171.548104) (xy 187.498535 -171.424902)
			(xy 187.573426 -171.305711) (xy 187.654883 -171.190908) (xy 187.742648 -171.080853) (xy 187.836447 -170.975891)
			(xy 187.935983 -170.876355) (xy 188.040943 -170.782556) (xy 188.150998 -170.69479) (xy 188.265801 -170.613333)
			(xy 188.384991 -170.538441) (xy 188.508193 -170.47035) (xy 188.635019 -170.409274) (xy 188.765069 -170.355406)
			(xy 188.897936 -170.308915) (xy 189.0332 -170.269946) (xy 189.170437 -170.238624) (xy 189.309214 -170.215046)
			(xy 189.449095 -170.199286) (xy 189.589639 -170.191394) (xy 189.660022 -170.190922) (xy 198.000112 -170.190922)
			(xy 198.055881 -170.1904) (xy 198.167108 -170.182064) (xy 198.277401 -170.16544) (xy 198.386143 -170.14062)
			(xy 198.492726 -170.107743) (xy 198.596554 -170.066993) (xy 198.697047 -170.018599) (xy 198.793643 -169.96283)
			(xy 198.885801 -169.899998) (xy 198.973006 -169.830456) (xy 199.05477 -169.754591) (xy 199.130636 -169.672828)
			(xy 199.200181 -169.585625) (xy 199.263014 -169.493468) (xy 199.318785 -169.396874) (xy 199.367181 -169.296382)
			(xy 199.407933 -169.192554) (xy 199.440812 -169.085972) (xy 199.465634 -168.97723) (xy 199.482261 -168.866938)
			(xy 199.490599 -168.755711) (xy 199.491092 -168.699942) (xy 199.491092 -75.65009) (xy 199.490579 -75.604293)
			(xy 199.482127 -75.513089) (xy 199.465295 -75.423053) (xy 199.440228 -75.334955) (xy 199.407139 -75.249546)
			(xy 199.366311 -75.167554) (xy 199.318091 -75.089679) (xy 199.262892 -75.016586) (xy 199.201184 -74.948897)
			(xy 199.133494 -74.887191) (xy 199.060399 -74.831994) (xy 198.982523 -74.783776) (xy 198.90053 -74.74295)
			(xy 198.81512 -74.709864) (xy 198.727021 -74.684799) (xy 198.636986 -74.66797) (xy 198.545781 -74.65952)
			(xy 198.499984 -74.658982) (xy 198.20001 -74.658982) (xy 198.13689 -74.658487) (xy 198.0109 -74.650562)
			(xy 197.885655 -74.634742) (xy 197.761651 -74.611089) (xy 197.639377 -74.579698) (xy 197.519314 -74.540692)
			(xy 197.401938 -74.494225) (xy 197.287711 -74.44048) (xy 197.177083 -74.379669) (xy 197.070492 -74.312032)
			(xy 196.968357 -74.237837) (xy 196.871082 -74.157375) (xy 196.779051 -74.070965) (xy 196.692627 -73.978947)
			(xy 196.612151 -73.881685) (xy 196.53794 -73.779562) (xy 196.470287 -73.67298) (xy 196.409459 -73.562362)
			(xy 196.355697 -73.448143) (xy 196.309212 -73.330774) (xy 196.270187 -73.210717) (xy 196.238777 -73.088448)
			(xy 196.215106 -72.964447) (xy 196.199267 -72.839205) (xy 196.191323 -72.713216) (xy 196.19087 -72.650096)
			(xy 196.19087 -33.64992) (xy 196.191374 -33.586802) (xy 196.199318 -33.460815) (xy 196.215155 -33.335575)
			(xy 196.238825 -33.211577) (xy 196.270233 -33.08931) (xy 196.309256 -32.969256) (xy 196.35574 -32.851889)
			(xy 196.4095 -32.737672) (xy 196.470326 -32.627055) (xy 196.537977 -32.520476) (xy 196.612186 -32.418354)
			(xy 196.69266 -32.321094) (xy 196.779082 -32.229077) (xy 196.871111 -32.142669) (xy 196.968384 -32.062208)
			(xy 197.070516 -31.988014) (xy 197.177105 -31.920379) (xy 197.28773 -31.859569) (xy 197.401955 -31.805825)
			(xy 197.519329 -31.759358) (xy 197.639389 -31.720352) (xy 197.76166 -31.688962) (xy 197.885662 -31.66531)
			(xy 198.010904 -31.64949) (xy 198.136892 -31.641565) (xy 198.20001 -31.641034) (xy 198.499984 -31.641034)
			(xy 198.545782 -31.640506) (xy 198.636988 -31.632056) (xy 198.727025 -31.615227) (xy 198.815125 -31.590162)
			(xy 198.900537 -31.557075) (xy 198.982531 -31.516249) (xy 199.060409 -31.468031) (xy 199.133505 -31.412833)
			(xy 199.201197 -31.351127) (xy 199.262907 -31.283438) (xy 199.318107 -31.210343) (xy 199.366328 -31.132468)
			(xy 199.407158 -31.050475) (xy 199.440249 -30.965065) (xy 199.465317 -30.876966) (xy 199.48215 -30.78693)
			(xy 199.490604 -30.695724) (xy 199.491092 -30.649926) (xy 199.491092 -1.999996) (xy 199.49057 -1.944227)
			(xy 199.482235 -1.833001) (xy 199.465611 -1.722708) (xy 199.440791 -1.613967) (xy 199.407915 -1.507384)
			(xy 199.367165 -1.403556) (xy 199.31877 -1.303063) (xy 199.263001 -1.206468) (xy 199.20017 -1.114311)
			(xy 199.130627 -1.027107) (xy 199.054762 -0.945344) (xy 198.972999 -0.869478) (xy 198.885795 -0.799935)
			(xy 198.793638 -0.737103) (xy 198.697044 -0.681333) (xy 198.596552 -0.632938) (xy 198.492724 -0.592188)
			(xy 198.386141 -0.559311) (xy 198.2774 -0.534491) (xy 198.167107 -0.517866) (xy 198.055881 -0.50953)
			(xy 198.000112 -0.509016) (xy 1.999996 -0.509016) (xy 1.944227 -0.509538) (xy 1.833001 -0.517873)
			(xy 1.722709 -0.534497) (xy 1.613967 -0.559317) (xy 1.507385 -0.592194) (xy 1.403557 -0.632943) (xy 1.303065 -0.681338)
			(xy 1.20647 -0.737107) (xy 1.114313 -0.799938) (xy 1.027109 -0.869481) (xy 0.945346 -0.945346) (xy 0.869481 -1.027109)
			(xy 0.799938 -1.114313) (xy 0.737107 -1.20647) (xy 0.681338 -1.303065) (xy 0.632943 -1.403557) (xy 0.592194 -1.507385)
			(xy 0.559317 -1.613967) (xy 0.534497 -1.722709) (xy 0.517873 -1.833001) (xy 0.509538 -1.944227) (xy 0.509016 -1.999996)
			(xy 0.509016 -9.750405) (xy 89.064349 -9.750405) (xy 89.072055 -9.665303) (xy 89.08745 -9.58125)
			(xy 89.110408 -9.498942) (xy 89.140739 -9.419055) (xy 89.178194 -9.342251) (xy 89.222464 -9.269162)
			(xy 89.273182 -9.20039) (xy 89.329931 -9.136505) (xy 89.360756 -9.106916) (xy 89.44864 -9.106916)
			(xy 89.465289 -9.106392) (xy 89.49745 -9.097766) (xy 89.526284 -9.081112) (xy 89.549827 -9.057565)
			(xy 89.566475 -9.028728) (xy 89.575095 -8.996565) (xy 89.57564 -8.979916) (xy 89.57564 -8.955532)
			(xy 89.615755 -8.935545) (xy 89.69906 -8.902468) (xy 89.785135 -8.877468) (xy 89.873199 -8.860773)
			(xy 89.962451 -8.852535) (xy 90.052082 -8.852827) (xy 90.141279 -8.861648) (xy 90.229232 -8.878917)
			(xy 90.315142 -8.904478) (xy 90.398229 -8.938099) (xy 90.438224 -8.958326) (xy 90.438224 -8.979408)
			(xy 90.438688 -8.996065) (xy 90.447313 -9.028243) (xy 90.463973 -9.057093) (xy 90.487533 -9.080646)
			(xy 90.516386 -9.097299) (xy 90.548567 -9.105916) (xy 90.565224 -9.106408) (xy 90.647266 -9.106408)
			(xy 90.678125 -9.135996) (xy 90.734975 -9.199856) (xy 90.785794 -9.268611) (xy 90.830163 -9.341696)
			(xy 90.867716 -9.418505) (xy 90.898142 -9.498406) (xy 90.921191 -9.580739) (xy 90.936672 -9.664824)
			(xy 90.944458 -9.749967) (xy 90.944463 -9.750405) (xy 99.064304 -9.750405) (xy 99.07201 -9.665301)
			(xy 99.087407 -9.581247) (xy 99.110367 -9.498937) (xy 99.140701 -9.41905) (xy 99.178159 -9.342246)
			(xy 99.222432 -9.269157) (xy 99.273155 -9.200387) (xy 99.329909 -9.136503) (xy 99.360736 -9.106916)
			(xy 99.44862 -9.106916) (xy 99.465268 -9.106374) (xy 99.497428 -9.097753) (xy 99.526262 -9.081103)
			(xy 99.549806 -9.057559) (xy 99.566455 -9.028725) (xy 99.575075 -8.996564) (xy 99.57562 -8.979916)
			(xy 99.57562 -8.955532) (xy 99.615743 -8.935561) (xy 99.699047 -8.902482) (xy 99.78512 -8.877481)
			(xy 99.873182 -8.860785) (xy 99.962434 -8.852545) (xy 100.052064 -8.852835) (xy 100.14126 -8.861655)
			(xy 100.229212 -8.878922) (xy 100.315122 -8.904481) (xy 100.398209 -8.9381) (xy 100.438204 -8.958326)
			(xy 100.438204 -8.979408) (xy 100.438736 -8.996057) (xy 100.447356 -9.02822) (xy 100.464007 -9.057056)
			(xy 100.487553 -9.0806) (xy 100.516391 -9.097248) (xy 100.548555 -9.105865) (xy 100.565204 -9.106408)
			(xy 100.647246 -9.106408) (xy 100.678101 -9.136) (xy 100.734952 -9.199859) (xy 100.785772 -9.268614)
			(xy 100.830141 -9.341697) (xy 100.867694 -9.418507) (xy 100.898121 -9.498407) (xy 100.92117 -9.58074)
			(xy 100.936652 -9.664824) (xy 100.944438 -9.749967) (xy 100.944934 -9.792716) (xy 100.94442 -9.835465)
			(xy 100.936641 -9.920609) (xy 100.921165 -10.004695) (xy 100.898121 -10.08703) (xy 100.867699 -10.166933)
			(xy 100.83015 -10.243745) (xy 100.785784 -10.316831) (xy 100.734968 -10.38559) (xy 100.67812 -10.449452)
			(xy 100.647246 -10.479024) (xy 100.565204 -10.479024) (xy 100.548547 -10.479498) (xy 100.516369 -10.488121)
			(xy 100.48752 -10.504778) (xy 100.463966 -10.528336) (xy 100.447313 -10.557188) (xy 100.438696 -10.589367)
			(xy 100.438204 -10.606024) (xy 100.438204 -10.627106) (xy 100.39822 -10.647284) (xy 100.315185 -10.680859)
			(xy 100.229335 -10.706392) (xy 100.141446 -10.72365) (xy 100.052316 -10.732478) (xy 99.96275 -10.732795)
			(xy 99.873559 -10.724599) (xy 99.78555 -10.707965) (xy 99.699521 -10.683041) (xy 99.61625 -10.650055)
			(xy 99.576128 -10.630154) (xy 99.576128 -10.606024) (xy 99.575536 -10.589379) (xy 99.566926 -10.557222)
			(xy 99.550287 -10.528389) (xy 99.526753 -10.504845) (xy 99.497926 -10.488194) (xy 99.465773 -10.479571)
			(xy 99.449128 -10.479024) (xy 99.361498 -10.479024) (xy 99.33065 -10.449458) (xy 99.273824 -10.385638)
			(xy 99.223024 -10.316926) (xy 99.178669 -10.243887) (xy 99.141124 -10.167125) (xy 99.110699 -10.087272)
			(xy 99.087646 -10.004988) (xy 99.072154 -9.920952) (xy 99.064352 -9.835857) (xy 99.064304 -9.750405)
			(xy 90.944463 -9.750405) (xy 90.944954 -9.792716) (xy 90.944434 -9.835465) (xy 90.936654 -9.920608)
			(xy 90.921179 -10.004694) (xy 90.898135 -10.087029) (xy 90.867714 -10.166931) (xy 90.830166 -10.243743)
			(xy 90.785801 -10.31683) (xy 90.734986 -10.385589) (xy 90.67814 -10.449451) (xy 90.647266 -10.479024)
			(xy 90.565224 -10.479024) (xy 90.548568 -10.479516) (xy 90.516391 -10.488133) (xy 90.487542 -10.504787)
			(xy 90.463987 -10.528342) (xy 90.447333 -10.557191) (xy 90.438716 -10.589368) (xy 90.438224 -10.606024)
			(xy 90.438224 -10.627106) (xy 90.398233 -10.647268) (xy 90.315199 -10.680845) (xy 90.22935 -10.706379)
			(xy 90.141463 -10.723638) (xy 90.052333 -10.732468) (xy 89.962768 -10.732787) (xy 89.873578 -10.724593)
			(xy 89.78557 -10.70796) (xy 89.699541 -10.683038) (xy 89.61627 -10.650054) (xy 89.576148 -10.630154)
			(xy 89.576148 -10.606024) (xy 89.575536 -10.589381) (xy 89.566928 -10.557227) (xy 89.550292 -10.528395)
			(xy 89.526762 -10.504852) (xy 89.49794 -10.488199) (xy 89.465791 -10.479573) (xy 89.449148 -10.479024)
			(xy 89.361518 -10.479024) (xy 89.330672 -10.449456) (xy 89.273851 -10.385635) (xy 89.223055 -10.316921)
			(xy 89.178703 -10.243882) (xy 89.141162 -10.16712) (xy 89.11074 -10.087268) (xy 89.087689 -10.004985)
			(xy 89.072199 -9.92095) (xy 89.064398 -9.835856) (xy 89.064349 -9.750405) (xy 0.509016 -9.750405)
			(xy 0.509016 -17.571212) (xy 147.308316 -17.571212) (xy 147.308773 -17.52685) (xy 147.316505 -17.438465)
			(xy 147.331911 -17.351089) (xy 147.354874 -17.265389) (xy 147.385219 -17.182016) (xy 147.422715 -17.101605)
			(xy 147.467076 -17.024769) (xy 147.517966 -16.952091) (xy 147.574997 -16.884125) (xy 147.637734 -16.821389)
			(xy 147.7057 -16.764359) (xy 147.778379 -16.71347) (xy 147.855216 -16.669109) (xy 147.935627 -16.631614)
			(xy 148.019 -16.60127) (xy 148.104701 -16.578309) (xy 148.192076 -16.562904) (xy 148.280462 -16.555173)
			(xy 148.324824 -16.554704) (xy 148.370622 -16.555198) (xy 148.461827 -16.563651) (xy 148.551863 -16.580484)
			(xy 148.639962 -16.605552) (xy 148.725372 -16.638643) (xy 148.807365 -16.679472) (xy 148.88524 -16.727693)
			(xy 148.958334 -16.782893) (xy 149.026023 -16.844602) (xy 149.08773 -16.912294) (xy 149.142928 -16.98539)
			(xy 149.191145 -17.063267) (xy 149.231972 -17.145261) (xy 149.265059 -17.230672) (xy 149.290124 -17.318772)
			(xy 149.306954 -17.408809) (xy 149.315404 -17.500014) (xy 149.315932 -17.545812) (xy 149.315932 -17.571212)
			(xy 153.571448 -17.571212) (xy 153.571987 -17.526853) (xy 153.579718 -17.438472) (xy 153.595123 -17.351101)
			(xy 153.618083 -17.265406) (xy 153.648425 -17.182037) (xy 153.685918 -17.10163) (xy 153.730275 -17.024797)
			(xy 153.78116 -16.952122) (xy 153.838185 -16.884158) (xy 153.900917 -16.821423) (xy 153.968877 -16.764394)
			(xy 154.04155 -16.713505) (xy 154.118381 -16.669144) (xy 154.198785 -16.631647) (xy 154.282152 -16.6013)
			(xy 154.367847 -16.578335) (xy 154.455216 -16.562926) (xy 154.543597 -16.55519) (xy 154.587956 -16.554704)
			(xy 154.633754 -16.555247) (xy 154.724958 -16.563695) (xy 154.814995 -16.580522) (xy 154.903094 -16.605585)
			(xy 154.988505 -16.63867) (xy 155.070499 -16.679496) (xy 155.148376 -16.727712) (xy 155.221471 -16.782909)
			(xy 155.289162 -16.844615) (xy 155.35087 -16.912304) (xy 155.40607 -16.985398) (xy 155.454289 -17.063273)
			(xy 155.495117 -17.145266) (xy 155.528205 -17.230676) (xy 155.553271 -17.318774) (xy 155.570101 -17.40881)
			(xy 155.578551 -17.500014) (xy 155.579064 -17.545812) (xy 155.579064 -17.571212) (xy 155.578559 -17.61627)
			(xy 155.570481 -17.706024) (xy 155.55439 -17.794693) (xy 155.530415 -17.881562) (xy 155.498751 -17.965933)
			(xy 155.45965 -18.047125) (xy 155.41343 -18.124486) (xy 155.36046 -18.197392) (xy 155.301169 -18.265256)
			(xy 155.236033 -18.327532) (xy 155.165577 -18.383719) (xy 155.090368 -18.433364) (xy 155.011012 -18.476068)
			(xy 154.928147 -18.511486) (xy 154.842441 -18.539333) (xy 154.754583 -18.559386) (xy 154.665282 -18.571483)
			(xy 154.575256 -18.575526) (xy 154.48523 -18.571483) (xy 154.395929 -18.559386) (xy 154.308071 -18.539333)
			(xy 154.222365 -18.511486) (xy 154.1395 -18.476068) (xy 154.060144 -18.433364) (xy 153.984935 -18.383719)
			(xy 153.914479 -18.327532) (xy 153.849343 -18.265256) (xy 153.790052 -18.197392) (xy 153.737082 -18.124486)
			(xy 153.690862 -18.047125) (xy 153.651761 -17.965933) (xy 153.620097 -17.881562) (xy 153.596122 -17.794693)
			(xy 153.580031 -17.706024) (xy 153.571953 -17.61627) (xy 153.571448 -17.571212) (xy 149.315932 -17.571212)
			(xy 149.315427 -17.61627) (xy 149.307349 -17.706024) (xy 149.291258 -17.794693) (xy 149.267283 -17.881562)
			(xy 149.235619 -17.965933) (xy 149.196518 -18.047125) (xy 149.150298 -18.124486) (xy 149.097328 -18.197392)
			(xy 149.038037 -18.265256) (xy 148.972901 -18.327532) (xy 148.902445 -18.383719) (xy 148.827236 -18.433364)
			(xy 148.74788 -18.476068) (xy 148.665015 -18.511486) (xy 148.579309 -18.539333) (xy 148.491451 -18.559386)
			(xy 148.40215 -18.571483) (xy 148.312124 -18.575526) (xy 148.222098 -18.571483) (xy 148.132797 -18.559386)
			(xy 148.044939 -18.539333) (xy 147.959233 -18.511486) (xy 147.876368 -18.476068) (xy 147.797012 -18.433364)
			(xy 147.721803 -18.383719) (xy 147.651347 -18.327532) (xy 147.586211 -18.265256) (xy 147.52692 -18.197392)
			(xy 147.47395 -18.124486) (xy 147.42773 -18.047125) (xy 147.388629 -17.965933) (xy 147.356965 -17.881562)
			(xy 147.33299 -17.794693) (xy 147.316899 -17.706024) (xy 147.308821 -17.61627) (xy 147.308316 -17.571212)
			(xy 0.509016 -17.571212) (xy 0.509016 -25.099673) (xy 37.367202 -25.099673) (xy 37.367202 -25.000303)
			(xy 37.375198 -24.901255) (xy 37.391138 -24.803171) (xy 37.414919 -24.706689) (xy 37.446387 -24.612432)
			(xy 37.485336 -24.521014) (xy 37.531516 -24.433026) (xy 37.584626 -24.349039) (xy 37.644322 -24.269598)
			(xy 37.710217 -24.195218) (xy 37.781883 -24.126382) (xy 37.858855 -24.063536) (xy 37.940636 -24.007087)
			(xy 38.026693 -23.957402) (xy 38.116469 -23.914803) (xy 38.209382 -23.879566) (xy 38.304829 -23.851919)
			(xy 38.402191 -23.832042) (xy 38.500836 -23.820065) (xy 38.600126 -23.816064) (xy 38.699416 -23.820065)
			(xy 38.798061 -23.832042) (xy 38.895423 -23.851919) (xy 38.99087 -23.879566) (xy 39.083783 -23.914803)
			(xy 39.173559 -23.957402) (xy 39.259616 -24.007087) (xy 39.341397 -24.063536) (xy 39.418369 -24.126382)
			(xy 39.490035 -24.195218) (xy 39.55593 -24.269598) (xy 39.615626 -24.349039) (xy 39.668736 -24.433026)
			(xy 39.714916 -24.521014) (xy 39.753865 -24.612432) (xy 39.785333 -24.706689) (xy 39.809114 -24.803171)
			(xy 39.825054 -24.901255) (xy 39.83305 -25.000303) (xy 39.83355 -25.049988) (xy 39.83305 -25.099673)
			(xy 39.825054 -25.198721) (xy 39.809114 -25.296805) (xy 39.785333 -25.393287) (xy 39.753865 -25.487544)
			(xy 39.714916 -25.578962) (xy 39.668736 -25.66695) (xy 39.615626 -25.750937) (xy 39.55593 -25.830378)
			(xy 39.490035 -25.904758) (xy 39.418369 -25.973594) (xy 39.341397 -26.03644) (xy 39.259616 -26.092889)
			(xy 39.173559 -26.142574) (xy 39.083783 -26.185173) (xy 38.99087 -26.22041) (xy 38.895423 -26.248057)
			(xy 38.798061 -26.267934) (xy 38.699416 -26.279911) (xy 38.600126 -26.283913) (xy 38.500836 -26.279911)
			(xy 38.402191 -26.267934) (xy 38.304829 -26.248057) (xy 38.209382 -26.22041) (xy 38.116469 -26.185173)
			(xy 38.026693 -26.142574) (xy 37.940636 -26.092889) (xy 37.858855 -26.03644) (xy 37.781883 -25.973594)
			(xy 37.710217 -25.904758) (xy 37.644322 -25.830378) (xy 37.584626 -25.750937) (xy 37.531516 -25.66695)
			(xy 37.485336 -25.578962) (xy 37.446387 -25.487544) (xy 37.414919 -25.393287) (xy 37.391138 -25.296805)
			(xy 37.375198 -25.198721) (xy 37.367202 -25.099673) (xy 0.509016 -25.099673) (xy 0.509016 -29.299916)
			(xy 0.509545 -29.345713) (xy 0.517996 -29.436917) (xy 0.534827 -29.526952) (xy 0.559893 -29.61505)
			(xy 0.59298 -29.700459) (xy 0.633808 -29.782451) (xy 0.682026 -29.860326) (xy 0.737224 -29.93342)
			(xy 0.798931 -30.001109) (xy 0.86662 -30.062816) (xy 0.939714 -30.118014) (xy 1.017589 -30.166232)
			(xy 1.099581 -30.20706) (xy 1.18499 -30.240147) (xy 1.273088 -30.265213) (xy 1.363123 -30.282044)
			(xy 1.454327 -30.290495) (xy 1.500124 -30.291024) (xy 6.500114 -30.291024) (xy 6.56323 -30.29152)
			(xy 6.689213 -30.299446) (xy 6.81445 -30.315267) (xy 6.938446 -30.338921) (xy 7.060713 -30.370314)
			(xy 7.180767 -30.409322) (xy 7.298135 -30.455792) (xy 7.412353 -30.509539) (xy 7.522971 -30.570352)
			(xy 7.629552 -30.637991) (xy 7.731676 -30.712188) (xy 7.82894 -30.792652) (xy 7.920959 -30.879064)
			(xy 8.007371 -30.971083) (xy 8.087834 -31.068347) (xy 8.162032 -31.170471) (xy 8.22967 -31.277053)
			(xy 8.290483 -31.387671) (xy 8.34423 -31.501889) (xy 8.390699 -31.619257) (xy 8.429707 -31.739311)
			(xy 8.4611 -31.861577) (xy 8.484753 -31.985574) (xy 8.500574 -32.110811) (xy 8.5085 -32.236794) (xy 8.509 -32.29991)
			(xy 8.509 -42.857998) (xy 9.994124 -42.857998) (xy 9.994124 -42.762354) (xy 10.002022 -42.667038)
			(xy 10.017765 -42.572699) (xy 10.041244 -42.479982) (xy 10.072299 -42.389521) (xy 10.110719 -42.301933)
			(xy 10.15624 -42.217817) (xy 10.208552 -42.137748) (xy 10.267297 -42.062272) (xy 10.332075 -41.991905)
			(xy 10.402442 -41.927127) (xy 10.477918 -41.868382) (xy 10.557987 -41.81607) (xy 10.642103 -41.770549)
			(xy 10.729691 -41.732129) (xy 10.820152 -41.701074) (xy 10.912869 -41.677595) (xy 11.007208 -41.661852)
			(xy 11.102524 -41.653954) (xy 11.198168 -41.653954) (xy 11.293484 -41.661852) (xy 11.387823 -41.677595)
			(xy 11.48054 -41.701074) (xy 11.571001 -41.732129) (xy 11.658589 -41.770549) (xy 11.742705 -41.81607)
			(xy 11.822774 -41.868382) (xy 11.89825 -41.927127) (xy 11.968617 -41.991905) (xy 12.033395 -42.062272)
			(xy 12.09214 -42.137748) (xy 12.144452 -42.217817) (xy 12.189973 -42.301933) (xy 12.228393 -42.389521)
			(xy 12.259448 -42.479982) (xy 12.282927 -42.572699) (xy 12.29867 -42.667038) (xy 12.306568 -42.762354)
			(xy 12.307062 -42.810176) (xy 12.306568 -42.857998) (xy 12.29867 -42.953314) (xy 12.282927 -43.047653)
			(xy 12.259448 -43.14037) (xy 12.228393 -43.230831) (xy 12.189973 -43.318419) (xy 12.144452 -43.402535)
			(xy 12.09214 -43.482604) (xy 12.033395 -43.55808) (xy 11.968617 -43.628447) (xy 11.89825 -43.693225)
			(xy 11.822774 -43.75197) (xy 11.742705 -43.804282) (xy 11.658589 -43.849803) (xy 11.571001 -43.888223)
			(xy 11.48054 -43.919278) (xy 11.387823 -43.942757) (xy 11.293484 -43.9585) (xy 11.198168 -43.966398)
			(xy 11.102524 -43.966398) (xy 11.007208 -43.9585) (xy 10.912869 -43.942757) (xy 10.820152 -43.919278)
			(xy 10.729691 -43.888223) (xy 10.642103 -43.849803) (xy 10.557987 -43.804282) (xy 10.477918 -43.75197)
			(xy 10.402442 -43.693225) (xy 10.332075 -43.628447) (xy 10.267297 -43.55808) (xy 10.208552 -43.482604)
			(xy 10.15624 -43.402535) (xy 10.110719 -43.318419) (xy 10.072299 -43.230831) (xy 10.041244 -43.14037)
			(xy 10.017765 -43.047653) (xy 10.002022 -42.953314) (xy 9.994124 -42.857998) (xy 8.509 -42.857998)
			(xy 8.509 -58.8379) (xy 9.994124 -58.8379) (xy 9.994124 -58.742256) (xy 10.002022 -58.64694) (xy 10.017765 -58.552601)
			(xy 10.041244 -58.459884) (xy 10.072299 -58.369423) (xy 10.110719 -58.281835) (xy 10.15624 -58.197719)
			(xy 10.208552 -58.11765) (xy 10.267297 -58.042174) (xy 10.332075 -57.971807) (xy 10.402442 -57.907029)
			(xy 10.477918 -57.848284) (xy 10.557987 -57.795972) (xy 10.642103 -57.750451) (xy 10.729691 -57.712031)
			(xy 10.820152 -57.680976) (xy 10.912869 -57.657497) (xy 11.007208 -57.641754) (xy 11.102524 -57.633856)
			(xy 11.198168 -57.633856) (xy 11.293484 -57.641754) (xy 11.387823 -57.657497) (xy 11.48054 -57.680976)
			(xy 11.571001 -57.712031) (xy 11.658589 -57.750451) (xy 11.742705 -57.795972) (xy 11.822774 -57.848284)
			(xy 11.89825 -57.907029) (xy 11.968617 -57.971807) (xy 12.033395 -58.042174) (xy 12.09214 -58.11765)
			(xy 12.144452 -58.197719) (xy 12.189973 -58.281835) (xy 12.228393 -58.369423) (xy 12.259448 -58.459884)
			(xy 12.282927 -58.552601) (xy 12.29867 -58.64694) (xy 12.306568 -58.742256) (xy 12.307062 -58.790078)
			(xy 12.306568 -58.8379) (xy 12.29867 -58.933216) (xy 12.282927 -59.027555) (xy 12.259448 -59.120272)
			(xy 12.228393 -59.210733) (xy 12.189973 -59.298321) (xy 12.144452 -59.382437) (xy 12.09214 -59.462506)
			(xy 12.033395 -59.537982) (xy 11.968617 -59.608349) (xy 11.89825 -59.673127) (xy 11.822774 -59.731872)
			(xy 11.742705 -59.784184) (xy 11.658589 -59.829705) (xy 11.571001 -59.868125) (xy 11.48054 -59.89918)
			(xy 11.387823 -59.922659) (xy 11.293484 -59.938402) (xy 11.198168 -59.9463) (xy 11.102524 -59.9463)
			(xy 11.007208 -59.938402) (xy 10.912869 -59.922659) (xy 10.820152 -59.89918) (xy 10.729691 -59.868125)
			(xy 10.642103 -59.829705) (xy 10.557987 -59.784184) (xy 10.477918 -59.731872) (xy 10.402442 -59.673127)
			(xy 10.332075 -59.608349) (xy 10.267297 -59.537982) (xy 10.208552 -59.462506) (xy 10.15624 -59.382437)
			(xy 10.110719 -59.298321) (xy 10.072299 -59.210733) (xy 10.041244 -59.120272) (xy 10.017765 -59.027555)
			(xy 10.002022 -58.933216) (xy 9.994124 -58.8379) (xy 8.509 -58.8379) (xy 8.509 -62.863044) (xy 23.993081 -62.863044)
			(xy 23.993081 -62.736908) (xy 24.001001 -62.61102) (xy 24.016811 -62.485878) (xy 24.040446 -62.361975)
			(xy 24.071815 -62.239802) (xy 24.110793 -62.119839) (xy 24.157227 -62.00256) (xy 24.210934 -61.888428)
			(xy 24.271701 -61.777893) (xy 24.339288 -61.671393) (xy 24.413429 -61.569346) (xy 24.493832 -61.472156)
			(xy 24.580178 -61.380206) (xy 24.672128 -61.29386) (xy 24.769318 -61.213457) (xy 24.871365 -61.139316)
			(xy 24.977865 -61.071729) (xy 25.0884 -61.010962) (xy 25.202532 -60.957255) (xy 25.319811 -60.910821)
			(xy 25.439774 -60.871843) (xy 25.561947 -60.840474) (xy 25.68585 -60.816839) (xy 25.810992 -60.801029)
			(xy 25.93688 -60.793109) (xy 26.063016 -60.793109) (xy 26.188904 -60.801029) (xy 26.314046 -60.816839)
			(xy 26.437949 -60.840474) (xy 26.560122 -60.871843) (xy 26.680085 -60.910821) (xy 26.797364 -60.957255)
			(xy 26.911496 -61.010962) (xy 27.022031 -61.071729) (xy 27.128531 -61.139316) (xy 27.230578 -61.213457)
			(xy 27.327768 -61.29386) (xy 27.419718 -61.380206) (xy 27.506064 -61.472156) (xy 27.586467 -61.569346)
			(xy 27.660608 -61.671393) (xy 27.728195 -61.777893) (xy 27.788962 -61.888428) (xy 27.842669 -62.00256)
			(xy 27.889103 -62.119839) (xy 27.928081 -62.239802) (xy 27.95945 -62.361975) (xy 27.983085 -62.485878)
			(xy 27.998895 -62.61102) (xy 28.006815 -62.736908) (xy 28.00731 -62.799976) (xy 28.006815 -62.863044)
			(xy 27.998895 -62.988932) (xy 27.983085 -63.114074) (xy 27.95945 -63.237977) (xy 27.928081 -63.36015)
			(xy 27.889103 -63.480113) (xy 27.852266 -63.573152) (xy 56.176672 -63.573152) (xy 56.176672 -58.849768)
			(xy 56.544972 -58.481468) (xy 56.544972 -51.699922) (xy 57.9501 -50.294794) (xy 57.9501 -39.385494)
			(xy 63.275972 -34.059622) (xy 63.275972 -30.287468) (xy 63.985394 -29.5783) (xy 66.874136 -29.5783)
			(xy 67.256914 -29.195522) (xy 67.256914 -27.167078) (xy 67.25666 -27.166824) (xy 67.25666 -26.330656)
			(xy 67.227196 -26.29535) (xy 67.21063 -26.274748) (xy 67.182819 -26.229788) (xy 67.161481 -26.181418)
			(xy 67.147026 -26.130566) (xy 67.139731 -26.078206) (xy 67.139735 -26.025339) (xy 67.147038 -25.972979)
			(xy 67.1615 -25.922129) (xy 67.182845 -25.873763) (xy 67.210663 -25.828807) (xy 67.227196 -25.808178)
			(xy 67.25666 -25.772872) (xy 67.25666 -25.743916) (xy 67.726052 -25.27427) (xy 67.726052 -22.979634)
			(xy 67.698366 -22.944836) (xy 67.680979 -22.922161) (xy 67.652394 -22.872689) (xy 67.631505 -22.819508)
			(xy 67.618781 -22.763806) (xy 67.614504 -22.70683) (xy 67.618772 -22.649853) (xy 67.631488 -22.594149)
			(xy 67.652368 -22.540964) (xy 67.680945 -22.491488) (xy 67.698366 -22.46884) (xy 67.726052 -22.434042)
			(xy 67.726052 -20.909026) (xy 67.423792 -20.606512) (xy 67.423792 -19.044666) (xy 68.211192 -18.257012)
			(xy 81.444846 -18.257012) (xy 81.71434 -18.526506) (xy 81.71434 -18.971768) (xy 81.750916 -19.032474)
			(xy 81.782412 -19.048984) (xy 81.806715 -19.062316) (xy 81.851619 -19.09481) (xy 81.891346 -19.133462)
			(xy 81.925058 -19.177459) (xy 81.952046 -19.225873) (xy 81.971741 -19.277683) (xy 81.983727 -19.331799)
			(xy 81.987753 -19.387081) (xy 81.983733 -19.442362) (xy 81.971752 -19.496479) (xy 81.952062 -19.548292)
			(xy 81.92508 -19.596709) (xy 81.891372 -19.640709) (xy 81.851649 -19.679365) (xy 81.806748 -19.711864)
			(xy 81.782412 -19.725132) (xy 81.767341 -19.733721) (xy 81.742093 -19.757483) (xy 81.724171 -19.787163)
			(xy 81.714897 -19.820571) (xy 81.71434 -19.837908) (xy 81.714086 -22.011386) (xy 81.714487 -22.026513)
			(xy 81.721633 -22.055911) (xy 81.735504 -22.082798) (xy 81.755319 -22.105661) (xy 81.779961 -22.123213)
			(xy 81.793842 -22.129242) (xy 81.819982 -22.140267) (xy 81.868914 -22.168978) (xy 81.913056 -22.204616)
			(xy 81.951435 -22.246397) (xy 81.983205 -22.293399) (xy 82.007666 -22.344587) (xy 82.024279 -22.398833)
			(xy 82.032677 -22.45494) (xy 82.032676 -22.511673) (xy 82.024276 -22.56778) (xy 82.007661 -22.622025)
			(xy 81.983198 -22.673212) (xy 81.951426 -22.720214) (xy 81.913046 -22.761993) (xy 81.868903 -22.79763)
			(xy 81.81997 -22.826338) (xy 81.793842 -22.837394) (xy 81.75752 -22.851872) (xy 81.71434 -22.916134)
			(xy 81.71434 -23.343108) (xy 81.915254 -23.544276) (xy 81.928523 -23.556765) (xy 81.960498 -23.574213)
			(xy 81.996108 -23.581881) (xy 82.014314 -23.581106) (xy 82.041567 -23.579592) (xy 82.096015 -23.58343)
			(xy 82.149359 -23.594989) (xy 82.200512 -23.614032) (xy 82.248429 -23.64017) (xy 82.292132 -23.672871)
			(xy 82.330727 -23.711467) (xy 82.363429 -23.755169) (xy 82.389568 -23.803086) (xy 82.408611 -23.854239)
			(xy 82.420169 -23.907583) (xy 82.424008 -23.962031) (xy 82.422492 -23.989284) (xy 82.421823 -24.007476)
			(xy 82.429546 -24.043035) (xy 82.446941 -24.074996) (xy 82.459322 -24.088344) (xy 82.709512 -24.33828)
			(xy 82.709512 -25.094511) (xy 104.408723 -25.094511) (xy 104.408723 -25.005465) (xy 104.416705 -24.916779)
			(xy 104.432605 -24.829165) (xy 104.456294 -24.743329) (xy 104.487582 -24.659962) (xy 104.526217 -24.579735)
			(xy 104.571889 -24.503294) (xy 104.624228 -24.431255) (xy 104.682814 -24.364198) (xy 104.747175 -24.302662)
			(xy 104.816794 -24.247144) (xy 104.891108 -24.198089) (xy 104.969521 -24.155894) (xy 105.0514 -24.120897)
			(xy 105.136087 -24.09338) (xy 105.222899 -24.073566) (xy 105.311139 -24.061613) (xy 105.400094 -24.057618)
			(xy 105.489049 -24.061613) (xy 105.577289 -24.073566) (xy 105.664101 -24.09338) (xy 105.748788 -24.120897)
			(xy 105.830667 -24.155894) (xy 105.90908 -24.198089) (xy 105.983394 -24.247144) (xy 106.053013 -24.302662)
			(xy 106.117374 -24.364198) (xy 106.17596 -24.431255) (xy 106.228299 -24.503294) (xy 106.273971 -24.579735)
			(xy 106.312606 -24.659962) (xy 106.343894 -24.743329) (xy 106.367583 -24.829165) (xy 106.383483 -24.916779)
			(xy 106.391465 -25.005465) (xy 106.391964 -25.049988) (xy 106.391465 -25.094511) (xy 106.383483 -25.183197)
			(xy 106.367583 -25.270811) (xy 106.343894 -25.356647) (xy 106.312606 -25.440014) (xy 106.273971 -25.520241)
			(xy 106.228299 -25.596682) (xy 106.17596 -25.668721) (xy 106.117374 -25.735778) (xy 106.053013 -25.797314)
			(xy 105.983394 -25.852832) (xy 105.90908 -25.901887) (xy 105.830667 -25.944082) (xy 105.748788 -25.979079)
			(xy 105.664101 -26.006596) (xy 105.577289 -26.02641) (xy 105.489049 -26.038363) (xy 105.400094 -26.042358)
			(xy 105.311139 -26.038363) (xy 105.222899 -26.02641) (xy 105.136087 -26.006596) (xy 105.0514 -25.979079)
			(xy 104.969521 -25.944082) (xy 104.891108 -25.901887) (xy 104.816794 -25.852832) (xy 104.747175 -25.797314)
			(xy 104.682814 -25.735778) (xy 104.624228 -25.668721) (xy 104.571889 -25.596682) (xy 104.526217 -25.520241)
			(xy 104.487582 -25.440014) (xy 104.456294 -25.356647) (xy 104.432605 -25.270811) (xy 104.416705 -25.183197)
			(xy 104.408723 -25.094511) (xy 82.709512 -25.094511) (xy 82.709512 -26.71318) (xy 82.31124 -27.111198)
			(xy 82.31124 -29.11094) (xy 82.599276 -29.398976) (xy 83.040982 -29.398976) (xy 84.31149 -30.669484)
			(xy 84.366862 -30.688534) (xy 84.396072 -30.684724) (xy 84.423634 -30.681778) (xy 84.47905 -30.683006)
			(xy 84.533705 -30.692238) (xy 84.58645 -30.709281) (xy 84.636174 -30.733776) (xy 84.681831 -30.765207)
			(xy 84.722459 -30.802913) (xy 84.757205 -30.846101) (xy 84.785337 -30.893861) (xy 84.806263 -30.945189)
			(xy 84.819543 -30.999005) (xy 84.824897 -31.054176) (xy 84.822212 -31.10954) (xy 84.811546 -31.163934)
			(xy 84.793121 -31.216212) (xy 84.767328 -31.265275) (xy 84.751418 -31.287974) (xy 84.727288 -31.321502)
			(xy 84.727288 -47.517812) (xy 154.521408 -47.517812) (xy 154.521408 -45.112686) (xy 155.019756 -44.614338)
			(xy 155.72486 -44.614338) (xy 156.223208 -45.112686) (xy 156.223208 -47.146464) (xy 158.2928 -47.146464)
			(xy 158.2928 -45.53966) (xy 158.530798 -45.301662) (xy 158.867602 -45.301662) (xy 159.1056 -45.53966)
			(xy 159.1056 -47.146464) (xy 158.867602 -47.384462) (xy 158.530798 -47.384462) (xy 158.2928 -47.146464)
			(xy 156.223208 -47.146464) (xy 156.223208 -47.517812) (xy 155.72486 -48.01616) (xy 155.019756 -48.01616)
			(xy 154.521408 -47.517812) (xy 84.727288 -47.517812) (xy 84.727288 -47.77994) (xy 81.179302 -51.327812)
			(xy 154.521408 -51.327812) (xy 154.521408 -48.922686) (xy 155.019756 -48.424338) (xy 155.72486 -48.424338)
			(xy 156.223208 -48.922686) (xy 156.223208 -50.999136) (xy 160.873948 -50.999136) (xy 160.873948 -49.392332)
			(xy 161.111946 -49.154334) (xy 161.44875 -49.154334) (xy 161.686748 -49.392332) (xy 161.686748 -50.999136)
			(xy 161.44875 -51.237134) (xy 161.111946 -51.237134) (xy 160.873948 -50.999136) (xy 156.223208 -50.999136)
			(xy 156.223208 -51.327812) (xy 155.72486 -51.82616) (xy 155.019756 -51.82616) (xy 154.521408 -51.327812)
			(xy 81.179302 -51.327812) (xy 76.817982 -55.688992) (xy 75.932538 -55.688992) (xy 72.486124 -59.135641)
			(xy 109.258352 -59.135641) (xy 109.258352 -59.045479) (xy 109.266434 -58.955679) (xy 109.282533 -58.866966)
			(xy 109.306519 -58.780053) (xy 109.3382 -58.69564) (xy 109.37732 -58.614406) (xy 109.423564 -58.537007)
			(xy 109.476561 -58.464064) (xy 109.535882 -58.396165) (xy 109.601051 -58.333857) (xy 109.671542 -58.277642)
			(xy 109.74679 -58.227972) (xy 109.826186 -58.185247) (xy 109.909093 -58.149811) (xy 109.994842 -58.121949)
			(xy 110.082744 -58.101886) (xy 110.17209 -58.089783) (xy 110.262162 -58.085738) (xy 110.352234 -58.089783)
			(xy 110.44158 -58.101886) (xy 110.529482 -58.121949) (xy 110.615231 -58.149811) (xy 110.698138 -58.185247)
			(xy 110.777534 -58.227972) (xy 110.852782 -58.277642) (xy 110.923273 -58.333857) (xy 110.988442 -58.396165)
			(xy 111.047763 -58.464064) (xy 111.10076 -58.537007) (xy 111.147004 -58.614406) (xy 111.186124 -58.69564)
			(xy 111.217805 -58.780053) (xy 111.241791 -58.866966) (xy 111.25789 -58.955679) (xy 111.265972 -59.045479)
			(xy 111.266478 -59.09056) (xy 111.265972 -59.135641) (xy 111.25789 -59.225441) (xy 111.241791 -59.314154)
			(xy 111.217805 -59.401067) (xy 111.186124 -59.48548) (xy 111.147004 -59.566714) (xy 111.10076 -59.644113)
			(xy 111.047763 -59.717056) (xy 110.988442 -59.784955) (xy 110.923273 -59.847263) (xy 110.852782 -59.903478)
			(xy 110.777534 -59.953148) (xy 110.698138 -59.995873) (xy 110.615231 -60.031309) (xy 110.529482 -60.059171)
			(xy 110.44158 -60.079234) (xy 110.352234 -60.091337) (xy 110.262162 -60.095382) (xy 110.17209 -60.091337)
			(xy 110.082744 -60.079234) (xy 109.994842 -60.059171) (xy 109.909093 -60.031309) (xy 109.826186 -59.995873)
			(xy 109.74679 -59.953148) (xy 109.671542 -59.903478) (xy 109.601051 -59.847263) (xy 109.535882 -59.784955)
			(xy 109.476561 -59.717056) (xy 109.423564 -59.644113) (xy 109.37732 -59.566714) (xy 109.3382 -59.48548)
			(xy 109.306519 -59.401067) (xy 109.282533 -59.314154) (xy 109.266434 -59.225441) (xy 109.258352 -59.135641)
			(xy 72.486124 -59.135641) (xy 72.20458 -59.417204) (xy 68.507102 -59.417204) (xy 68.260468 -59.663838)
			(xy 68.260468 -60.988448) (xy 66.971164 -62.277498) (xy 66.971164 -62.863044) (xy 87.993207 -62.863044)
			(xy 87.993207 -62.736908) (xy 88.001127 -62.61102) (xy 88.016937 -62.485878) (xy 88.040572 -62.361975)
			(xy 88.071941 -62.239802) (xy 88.110919 -62.119839) (xy 88.157353 -62.00256) (xy 88.21106 -61.888428)
			(xy 88.271827 -61.777893) (xy 88.339414 -61.671393) (xy 88.413555 -61.569346) (xy 88.493958 -61.472156)
			(xy 88.580304 -61.380206) (xy 88.672254 -61.29386) (xy 88.769444 -61.213457) (xy 88.871491 -61.139316)
			(xy 88.977991 -61.071729) (xy 89.088526 -61.010962) (xy 89.202658 -60.957255) (xy 89.319937 -60.910821)
			(xy 89.4399 -60.871843) (xy 89.562073 -60.840474) (xy 89.685976 -60.816839) (xy 89.811118 -60.801029)
			(xy 89.937006 -60.793109) (xy 90.063142 -60.793109) (xy 90.18903 -60.801029) (xy 90.314172 -60.816839)
			(xy 90.438075 -60.840474) (xy 90.560248 -60.871843) (xy 90.680211 -60.910821) (xy 90.79749 -60.957255)
			(xy 90.911622 -61.010962) (xy 91.022157 -61.071729) (xy 91.128657 -61.139316) (xy 91.230704 -61.213457)
			(xy 91.327894 -61.29386) (xy 91.419844 -61.380206) (xy 91.50619 -61.472156) (xy 91.586593 -61.569346)
			(xy 91.660734 -61.671393) (xy 91.728321 -61.777893) (xy 91.789088 -61.888428) (xy 91.842795 -62.00256)
			(xy 91.889229 -62.119839) (xy 91.928207 -62.239802) (xy 91.959576 -62.361975) (xy 91.983211 -62.485878)
			(xy 91.999021 -62.61102) (xy 92.006941 -62.736908) (xy 92.007436 -62.799976) (xy 92.006941 -62.863044)
			(xy 91.999021 -62.988932) (xy 91.983211 -63.114074) (xy 91.959576 -63.237977) (xy 91.928207 -63.36015)
			(xy 91.889229 -63.480113) (xy 91.842795 -63.597392) (xy 91.789088 -63.711524) (xy 91.728321 -63.822059)
			(xy 91.660734 -63.928559) (xy 91.586593 -64.030606) (xy 91.50619 -64.127796) (xy 91.419844 -64.219746)
			(xy 91.327894 -64.306092) (xy 91.230704 -64.386495) (xy 91.128657 -64.460636) (xy 91.022157 -64.528223)
			(xy 90.911622 -64.58899) (xy 90.79749 -64.642697) (xy 90.680211 -64.689131) (xy 90.560248 -64.728109)
			(xy 90.438075 -64.759478) (xy 90.314172 -64.783113) (xy 90.18903 -64.798923) (xy 90.063142 -64.806843)
			(xy 89.937006 -64.806843) (xy 89.811118 -64.798923) (xy 89.685976 -64.783113) (xy 89.562073 -64.759478)
			(xy 89.4399 -64.728109) (xy 89.319937 -64.689131) (xy 89.202658 -64.642697) (xy 89.088526 -64.58899)
			(xy 88.977991 -64.528223) (xy 88.871491 -64.460636) (xy 88.769444 -64.386495) (xy 88.672254 -64.306092)
			(xy 88.580304 -64.219746) (xy 88.493958 -64.127796) (xy 88.413555 -64.030606) (xy 88.339414 -63.928559)
			(xy 88.271827 -63.822059) (xy 88.21106 -63.711524) (xy 88.157353 -63.597392) (xy 88.110919 -63.480113)
			(xy 88.071941 -63.36015) (xy 88.040572 -63.237977) (xy 88.016937 -63.114074) (xy 88.001127 -62.988932)
			(xy 87.993207 -62.863044) (xy 66.971164 -62.863044) (xy 66.971164 -63.234824) (xy 66.297048 -63.90894)
			(xy 66.279268 -63.973202) (xy 66.28765 -64.005968) (xy 66.293851 -64.032241) (xy 66.29949 -64.085931)
			(xy 66.297507 -64.139879) (xy 66.28794 -64.19301) (xy 66.270981 -64.244262) (xy 66.246969 -64.292612)
			(xy 66.216382 -64.337096) (xy 66.179832 -64.376826) (xy 66.138047 -64.411008) (xy 66.091862 -64.43896)
			(xy 66.042199 -64.460125) (xy 65.990049 -64.474079) (xy 65.936452 -64.480545) (xy 65.88248 -64.479393)
			(xy 65.829208 -64.470646) (xy 65.777701 -64.454479) (xy 65.728986 -64.431215) (xy 65.684036 -64.401317)
			(xy 65.643748 -64.365383) (xy 65.62598 -64.345058) (xy 65.613589 -64.331397) (xy 65.582719 -64.311243)
			(xy 65.547385 -64.300723) (xy 65.528952 -64.3001) (xy 65.03162 -64.3001) (xy 64.742568 -64.589152)
			(xy 64.742568 -64.857122) (xy 148.93925 -64.857122) (xy 148.93925 -64.271398) (xy 149.006814 -64.203834)
			(xy 150.166578 -64.203834) (xy 150.234142 -64.271398) (xy 150.234142 -64.840612) (xy 150.176992 -64.897762)
			(xy 148.97989 -64.897762) (xy 148.93925 -64.857122) (xy 64.742568 -64.857122) (xy 64.742568 -66.075306)
			(xy 148.925534 -66.075306) (xy 148.925534 -65.489582) (xy 148.993098 -65.422018) (xy 150.152862 -65.422018)
			(xy 150.220426 -65.489582) (xy 150.220426 -66.058796) (xy 150.163276 -66.115946) (xy 148.966174 -66.115946)
			(xy 148.925534 -66.075306) (xy 64.742568 -66.075306) (xy 64.742568 -68.4403) (xy 64.393572 -68.789296)
			(xy 61.217556 -68.789296) (xy 60.866782 -68.439538) (xy 60.847986 -68.09486) (xy 60.99556 -67.835272)
			(xy 61.017404 -67.75958) (xy 61.021087 -67.745337) (xy 61.022613 -67.715969) (xy 61.017348 -67.687035)
			(xy 61.005573 -67.660087) (xy 60.997084 -67.648074) (xy 60.92825 -67.556634) (xy 60.92825 -67.556126)
			(xy 60.927742 -67.553332) (xy 60.883546 -67.316604) (xy 61.061854 -67.0814) (xy 61.070643 -67.069022)
			(xy 61.082684 -67.041163) (xy 61.087808 -67.01125) (xy 61.085728 -66.980972) (xy 61.07656 -66.95204)
			(xy 61.060823 -66.92609) (xy 61.050424 -66.91503) (xy 60.924948 -66.789808) (xy 60.924948 -66.392298)
			(xy 60.983876 -66.33337) (xy 60.983876 -65.948814) (xy 60.983386 -65.93203) (xy 60.974635 -65.899623)
			(xy 60.957735 -65.87062) (xy 60.933856 -65.847028) (xy 60.904651 -65.83048) (xy 60.872141 -65.822121)
			(xy 60.855352 -65.821814) (xy 60.826738 -65.821654) (xy 60.770058 -65.81383) (xy 60.715181 -65.79763)
			(xy 60.663338 -65.773416) (xy 60.615693 -65.741732) (xy 60.573313 -65.703289) (xy 60.537149 -65.658948)
			(xy 60.508012 -65.609704) (xy 60.486555 -65.556661) (xy 60.47326 -65.501009) (xy 60.468424 -65.443996)
			(xy 60.46978 -65.415414) (xy 60.471558 -65.387728) (xy 60.452508 -65.336674) (xy 59.699906 -64.584072)
			(xy 59.444636 -64.584072) (xy 59.43981 -64.58458) (xy 59.425728 -64.585496) (xy 59.397504 -64.585496)
			(xy 59.383422 -64.58458) (xy 59.378596 -64.584072) (xy 57.187846 -64.584072) (xy 56.176672 -63.573152)
			(xy 27.852266 -63.573152) (xy 27.842669 -63.597392) (xy 27.788962 -63.711524) (xy 27.728195 -63.822059)
			(xy 27.660608 -63.928559) (xy 27.586467 -64.030606) (xy 27.506064 -64.127796) (xy 27.419718 -64.219746)
			(xy 27.327768 -64.306092) (xy 27.230578 -64.386495) (xy 27.128531 -64.460636) (xy 27.022031 -64.528223)
			(xy 26.911496 -64.58899) (xy 26.797364 -64.642697) (xy 26.680085 -64.689131) (xy 26.560122 -64.728109)
			(xy 26.437949 -64.759478) (xy 26.314046 -64.783113) (xy 26.188904 -64.798923) (xy 26.063016 -64.806843)
			(xy 25.93688 -64.806843) (xy 25.810992 -64.798923) (xy 25.68585 -64.783113) (xy 25.561947 -64.759478)
			(xy 25.439774 -64.728109) (xy 25.319811 -64.689131) (xy 25.202532 -64.642697) (xy 25.0884 -64.58899)
			(xy 24.977865 -64.528223) (xy 24.871365 -64.460636) (xy 24.769318 -64.386495) (xy 24.672128 -64.306092)
			(xy 24.580178 -64.219746) (xy 24.493832 -64.127796) (xy 24.413429 -64.030606) (xy 24.339288 -63.928559)
			(xy 24.271701 -63.822059) (xy 24.210934 -63.711524) (xy 24.157227 -63.597392) (xy 24.110793 -63.480113)
			(xy 24.071815 -63.36015) (xy 24.040446 -63.237977) (xy 24.016811 -63.114074) (xy 24.001001 -62.988932)
			(xy 23.993081 -62.863044) (xy 8.509 -62.863044) (xy 8.509 -69.30009) (xy 8.508504 -69.363206) (xy 8.500578 -69.48919)
			(xy 8.484757 -69.614427) (xy 8.461104 -69.738423) (xy 8.429711 -69.86069) (xy 8.390703 -69.980744)
			(xy 8.344234 -70.098112) (xy 8.290487 -70.212331) (xy 8.229674 -70.32295) (xy 8.162035 -70.429531)
			(xy 8.087837 -70.531656) (xy 8.007374 -70.628919) (xy 7.920962 -70.720939) (xy 7.828942 -70.807351)
			(xy 7.731679 -70.887815) (xy 7.629555 -70.962013) (xy 7.522973 -71.029652) (xy 7.412355 -71.090465)
			(xy 7.298136 -71.144212) (xy 7.180768 -71.190682) (xy 7.060714 -71.22969) (xy 6.938447 -71.261083)
			(xy 6.814451 -71.284737) (xy 6.689214 -71.300558) (xy 6.56323 -71.308484) (xy 6.500114 -71.308976)
			(xy 1.500124 -71.308976) (xy 1.454327 -71.309505) (xy 1.363123 -71.317956) (xy 1.273088 -71.334787)
			(xy 1.18499 -71.359853) (xy 1.099581 -71.39294) (xy 1.017589 -71.433768) (xy 0.939714 -71.481986)
			(xy 0.86662 -71.537184) (xy 0.798931 -71.598891) (xy 0.737224 -71.66658) (xy 0.682026 -71.739674)
			(xy 0.633808 -71.817549) (xy 0.59298 -71.899541) (xy 0.559893 -71.98495) (xy 0.534827 -72.073048)
			(xy 0.517996 -72.163083) (xy 0.509545 -72.254287) (xy 0.509016 -72.300084) (xy 0.509016 -77.082841)
			(xy 4.534904 -77.082841) (xy 4.534904 -76.959015) (xy 4.542837 -76.835444) (xy 4.558672 -76.712636)
			(xy 4.582342 -76.591094) (xy 4.613751 -76.471318) (xy 4.652769 -76.353801) (xy 4.699237 -76.239025)
			(xy 4.752963 -76.127462) (xy 4.813726 -76.019571) (xy 4.881277 -75.915794) (xy 4.955339 -75.816559)
			(xy 5.035606 -75.722272) (xy 5.121749 -75.633322) (xy 5.213414 -75.550074) (xy 5.310225 -75.472871)
			(xy 5.411783 -75.402028) (xy 5.517671 -75.337838) (xy 5.627455 -75.280564) (xy 5.740682 -75.230441)
			(xy 5.856889 -75.187676) (xy 5.975596 -75.152445) (xy 6.096317 -75.124891) (xy 6.218555 -75.105128)
			(xy 6.341808 -75.093238) (xy 6.46557 -75.08927) (xy 6.589332 -75.093238) (xy 6.712585 -75.105128)
			(xy 6.834823 -75.124891) (xy 6.955544 -75.152445) (xy 7.074251 -75.187676) (xy 7.190458 -75.230441)
			(xy 7.303685 -75.280564) (xy 7.413469 -75.337838) (xy 7.519357 -75.402028) (xy 7.620915 -75.472871)
			(xy 7.717726 -75.550074) (xy 7.809391 -75.633322) (xy 7.895534 -75.722272) (xy 7.975801 -75.816559)
			(xy 8.049863 -75.915794) (xy 8.117414 -76.019571) (xy 8.178177 -76.127462) (xy 8.231903 -76.239025)
			(xy 8.278371 -76.353801) (xy 8.317389 -76.471318) (xy 8.348798 -76.591094) (xy 8.372468 -76.712636)
			(xy 8.388303 -76.835444) (xy 8.396236 -76.959015) (xy 8.396732 -77.020928) (xy 8.396236 -77.082841)
			(xy 8.388303 -77.206412) (xy 8.372468 -77.32922) (xy 8.348798 -77.450762) (xy 8.317389 -77.570538)
			(xy 8.278371 -77.688055) (xy 8.231903 -77.802831) (xy 8.178177 -77.914394) (xy 8.117414 -78.022285)
			(xy 8.049863 -78.126062) (xy 7.975801 -78.225297) (xy 7.895534 -78.319584) (xy 7.809391 -78.408534)
			(xy 7.717726 -78.491782) (xy 7.620915 -78.568985) (xy 7.519357 -78.639828) (xy 7.413469 -78.704018)
			(xy 7.303685 -78.761292) (xy 7.190458 -78.811415) (xy 7.074251 -78.85418) (xy 6.955544 -78.889411)
			(xy 6.834823 -78.916965) (xy 6.712585 -78.936728) (xy 6.589332 -78.948618) (xy 6.46557 -78.952587)
			(xy 6.341808 -78.948618) (xy 6.218555 -78.936728) (xy 6.096317 -78.916965) (xy 5.975596 -78.889411)
			(xy 5.856889 -78.85418) (xy 5.740682 -78.811415) (xy 5.627455 -78.761292) (xy 5.517671 -78.704018)
			(xy 5.411783 -78.639828) (xy 5.310225 -78.568985) (xy 5.213414 -78.491782) (xy 5.121749 -78.408534)
			(xy 5.035606 -78.319584) (xy 4.955339 -78.225297) (xy 4.881277 -78.126062) (xy 4.813726 -78.022285)
			(xy 4.752963 -77.914394) (xy 4.699237 -77.802831) (xy 4.652769 -77.688055) (xy 4.613751 -77.570538)
			(xy 4.582342 -77.450762) (xy 4.558672 -77.32922) (xy 4.542837 -77.206412) (xy 4.534904 -77.082841)
			(xy 0.509016 -77.082841) (xy 0.509016 -79.261331) (xy 109.258352 -79.261331) (xy 109.258352 -79.171169)
			(xy 109.266434 -79.081369) (xy 109.282533 -78.992656) (xy 109.306519 -78.905743) (xy 109.3382 -78.82133)
			(xy 109.37732 -78.740096) (xy 109.423564 -78.662697) (xy 109.476561 -78.589754) (xy 109.535882 -78.521855)
			(xy 109.601051 -78.459547) (xy 109.671542 -78.403332) (xy 109.74679 -78.353662) (xy 109.826186 -78.310937)
			(xy 109.909093 -78.275501) (xy 109.994842 -78.247639) (xy 110.082744 -78.227576) (xy 110.17209 -78.215473)
			(xy 110.262162 -78.211428) (xy 110.352234 -78.215473) (xy 110.44158 -78.227576) (xy 110.529482 -78.247639)
			(xy 110.615231 -78.275501) (xy 110.698138 -78.310937) (xy 110.777534 -78.353662) (xy 110.852782 -78.403332)
			(xy 110.923273 -78.459547) (xy 110.988442 -78.521855) (xy 111.047763 -78.589754) (xy 111.10076 -78.662697)
			(xy 111.147004 -78.740096) (xy 111.186124 -78.82133) (xy 111.217805 -78.905743) (xy 111.241791 -78.992656)
			(xy 111.25789 -79.081369) (xy 111.265972 -79.171169) (xy 111.266478 -79.21625) (xy 111.265972 -79.261331)
			(xy 111.25789 -79.351131) (xy 111.241791 -79.439844) (xy 111.217805 -79.526757) (xy 111.186124 -79.61117)
			(xy 111.147004 -79.692404) (xy 111.10076 -79.769803) (xy 111.047763 -79.842746) (xy 110.988442 -79.910645)
			(xy 110.923273 -79.972953) (xy 110.852782 -80.029168) (xy 110.777534 -80.078838) (xy 110.698138 -80.121563)
			(xy 110.615231 -80.156999) (xy 110.529482 -80.184861) (xy 110.44158 -80.204924) (xy 110.352234 -80.217027)
			(xy 110.262162 -80.221072) (xy 110.17209 -80.217027) (xy 110.082744 -80.204924) (xy 109.994842 -80.184861)
			(xy 109.909093 -80.156999) (xy 109.826186 -80.121563) (xy 109.74679 -80.078838) (xy 109.671542 -80.029168)
			(xy 109.601051 -79.972953) (xy 109.535882 -79.910645) (xy 109.476561 -79.842746) (xy 109.423564 -79.769803)
			(xy 109.37732 -79.692404) (xy 109.3382 -79.61117) (xy 109.306519 -79.526757) (xy 109.282533 -79.439844)
			(xy 109.266434 -79.351131) (xy 109.258352 -79.261331) (xy 0.509016 -79.261331) (xy 0.509016 -90.697241)
			(xy 4.534904 -90.697241) (xy 4.534904 -90.573415) (xy 4.542837 -90.449844) (xy 4.558672 -90.327036)
			(xy 4.582342 -90.205494) (xy 4.613751 -90.085718) (xy 4.652769 -89.968201) (xy 4.699237 -89.853425)
			(xy 4.752963 -89.741862) (xy 4.813726 -89.633971) (xy 4.881277 -89.530194) (xy 4.955339 -89.430959)
			(xy 5.035606 -89.336672) (xy 5.121749 -89.247722) (xy 5.213414 -89.164474) (xy 5.310225 -89.087271)
			(xy 5.411783 -89.016428) (xy 5.517671 -88.952238) (xy 5.627455 -88.894964) (xy 5.740682 -88.844841)
			(xy 5.856889 -88.802076) (xy 5.975596 -88.766845) (xy 6.096317 -88.739291) (xy 6.218555 -88.719528)
			(xy 6.341808 -88.707638) (xy 6.46557 -88.70367) (xy 6.589332 -88.707638) (xy 6.712585 -88.719528)
			(xy 6.834823 -88.739291) (xy 6.955544 -88.766845) (xy 7.074251 -88.802076) (xy 7.190458 -88.844841)
			(xy 7.231461 -88.862992) (xy 23.993081 -88.862992) (xy 23.993081 -88.736856) (xy 24.001001 -88.610968)
			(xy 24.016811 -88.485826) (xy 24.040446 -88.361923) (xy 24.071815 -88.23975) (xy 24.110793 -88.119787)
			(xy 24.157227 -88.002508) (xy 24.210934 -87.888376) (xy 24.271701 -87.777841) (xy 24.339288 -87.671341)
			(xy 24.413429 -87.569294) (xy 24.493832 -87.472104) (xy 24.580178 -87.380154) (xy 24.672128 -87.293808)
			(xy 24.769318 -87.213405) (xy 24.871365 -87.139264) (xy 24.977865 -87.071677) (xy 25.0884 -87.01091)
			(xy 25.202532 -86.957203) (xy 25.319811 -86.910769) (xy 25.439774 -86.871791) (xy 25.561947 -86.840422)
			(xy 25.68585 -86.816787) (xy 25.810992 -86.800977) (xy 25.93688 -86.793057) (xy 26.063016 -86.793057)
			(xy 26.188904 -86.800977) (xy 26.314046 -86.816787) (xy 26.437949 -86.840422) (xy 26.560122 -86.871791)
			(xy 26.680085 -86.910769) (xy 26.797364 -86.957203) (xy 26.911496 -87.01091) (xy 27.022031 -87.071677)
			(xy 27.128531 -87.139264) (xy 27.230578 -87.213405) (xy 27.327768 -87.293808) (xy 27.419718 -87.380154)
			(xy 27.506064 -87.472104) (xy 27.586467 -87.569294) (xy 27.660608 -87.671341) (xy 27.728195 -87.777841)
			(xy 27.788962 -87.888376) (xy 27.842669 -88.002508) (xy 27.889103 -88.119787) (xy 27.928081 -88.23975)
			(xy 27.95945 -88.361923) (xy 27.983085 -88.485826) (xy 27.998895 -88.610968) (xy 28.006815 -88.736856)
			(xy 28.00731 -88.799924) (xy 28.006815 -88.862992) (xy 87.993207 -88.862992) (xy 87.993207 -88.736856)
			(xy 88.001127 -88.610968) (xy 88.016937 -88.485826) (xy 88.040572 -88.361923) (xy 88.071941 -88.23975)
			(xy 88.110919 -88.119787) (xy 88.157353 -88.002508) (xy 88.21106 -87.888376) (xy 88.271827 -87.777841)
			(xy 88.339414 -87.671341) (xy 88.413555 -87.569294) (xy 88.493958 -87.472104) (xy 88.580304 -87.380154)
			(xy 88.672254 -87.293808) (xy 88.769444 -87.213405) (xy 88.871491 -87.139264) (xy 88.977991 -87.071677)
			(xy 89.088526 -87.01091) (xy 89.202658 -86.957203) (xy 89.319937 -86.910769) (xy 89.4399 -86.871791)
			(xy 89.562073 -86.840422) (xy 89.685976 -86.816787) (xy 89.811118 -86.800977) (xy 89.937006 -86.793057)
			(xy 90.063142 -86.793057) (xy 90.18903 -86.800977) (xy 90.314172 -86.816787) (xy 90.438075 -86.840422)
			(xy 90.560248 -86.871791) (xy 90.680211 -86.910769) (xy 90.79749 -86.957203) (xy 90.911622 -87.01091)
			(xy 91.022157 -87.071677) (xy 91.128657 -87.139264) (xy 91.230704 -87.213405) (xy 91.327894 -87.293808)
			(xy 91.419844 -87.380154) (xy 91.50619 -87.472104) (xy 91.586593 -87.569294) (xy 91.660734 -87.671341)
			(xy 91.728321 -87.777841) (xy 91.789088 -87.888376) (xy 91.842795 -88.002508) (xy 91.889229 -88.119787)
			(xy 91.928207 -88.23975) (xy 91.959576 -88.361923) (xy 91.983211 -88.485826) (xy 91.999021 -88.610968)
			(xy 92.006941 -88.736856) (xy 92.007436 -88.799924) (xy 92.006941 -88.862992) (xy 91.999021 -88.98888)
			(xy 91.983211 -89.114022) (xy 91.959576 -89.237925) (xy 91.928207 -89.360098) (xy 91.889229 -89.480061)
			(xy 91.842795 -89.59734) (xy 91.789088 -89.711472) (xy 91.728321 -89.822007) (xy 91.660734 -89.928507)
			(xy 91.586593 -90.030554) (xy 91.50619 -90.127744) (xy 91.419844 -90.219694) (xy 91.327894 -90.30604)
			(xy 91.230704 -90.386443) (xy 91.128657 -90.460584) (xy 91.022157 -90.528171) (xy 90.911622 -90.588938)
			(xy 90.79749 -90.642645) (xy 90.680211 -90.689079) (xy 90.560248 -90.728057) (xy 90.438075 -90.759426)
			(xy 90.314172 -90.783061) (xy 90.18903 -90.798871) (xy 90.063142 -90.806791) (xy 89.937006 -90.806791)
			(xy 89.811118 -90.798871) (xy 89.685976 -90.783061) (xy 89.562073 -90.759426) (xy 89.4399 -90.728057)
			(xy 89.319937 -90.689079) (xy 89.202658 -90.642645) (xy 89.088526 -90.588938) (xy 88.977991 -90.528171)
			(xy 88.871491 -90.460584) (xy 88.769444 -90.386443) (xy 88.672254 -90.30604) (xy 88.580304 -90.219694)
			(xy 88.493958 -90.127744) (xy 88.413555 -90.030554) (xy 88.339414 -89.928507) (xy 88.271827 -89.822007)
			(xy 88.21106 -89.711472) (xy 88.157353 -89.59734) (xy 88.110919 -89.480061) (xy 88.071941 -89.360098)
			(xy 88.040572 -89.237925) (xy 88.016937 -89.114022) (xy 88.001127 -88.98888) (xy 87.993207 -88.862992)
			(xy 28.006815 -88.862992) (xy 27.998895 -88.98888) (xy 27.983085 -89.114022) (xy 27.95945 -89.237925)
			(xy 27.928081 -89.360098) (xy 27.889103 -89.480061) (xy 27.842669 -89.59734) (xy 27.788962 -89.711472)
			(xy 27.728195 -89.822007) (xy 27.660608 -89.928507) (xy 27.586467 -90.030554) (xy 27.506064 -90.127744)
			(xy 27.419718 -90.219694) (xy 27.327768 -90.30604) (xy 27.230578 -90.386443) (xy 27.128531 -90.460584)
			(xy 27.022031 -90.528171) (xy 26.911496 -90.588938) (xy 26.797364 -90.642645) (xy 26.680085 -90.689079)
			(xy 26.560122 -90.728057) (xy 26.437949 -90.759426) (xy 26.314046 -90.783061) (xy 26.188904 -90.798871)
			(xy 26.063016 -90.806791) (xy 25.93688 -90.806791) (xy 25.810992 -90.798871) (xy 25.68585 -90.783061)
			(xy 25.561947 -90.759426) (xy 25.439774 -90.728057) (xy 25.319811 -90.689079) (xy 25.202532 -90.642645)
			(xy 25.0884 -90.588938) (xy 24.977865 -90.528171) (xy 24.871365 -90.460584) (xy 24.769318 -90.386443)
			(xy 24.672128 -90.30604) (xy 24.580178 -90.219694) (xy 24.493832 -90.127744) (xy 24.413429 -90.030554)
			(xy 24.339288 -89.928507) (xy 24.271701 -89.822007) (xy 24.210934 -89.711472) (xy 24.157227 -89.59734)
			(xy 24.110793 -89.480061) (xy 24.071815 -89.360098) (xy 24.040446 -89.237925) (xy 24.016811 -89.114022)
			(xy 24.001001 -88.98888) (xy 23.993081 -88.862992) (xy 7.231461 -88.862992) (xy 7.303685 -88.894964)
			(xy 7.413469 -88.952238) (xy 7.519357 -89.016428) (xy 7.620915 -89.087271) (xy 7.717726 -89.164474)
			(xy 7.809391 -89.247722) (xy 7.895534 -89.336672) (xy 7.975801 -89.430959) (xy 8.049863 -89.530194)
			(xy 8.117414 -89.633971) (xy 8.178177 -89.741862) (xy 8.231903 -89.853425) (xy 8.278371 -89.968201)
			(xy 8.317389 -90.085718) (xy 8.348798 -90.205494) (xy 8.372468 -90.327036) (xy 8.388303 -90.449844)
			(xy 8.396236 -90.573415) (xy 8.396732 -90.635328) (xy 8.396236 -90.697241) (xy 8.388303 -90.820812)
			(xy 8.372468 -90.94362) (xy 8.348798 -91.065162) (xy 8.317389 -91.184938) (xy 8.278371 -91.302455)
			(xy 8.231903 -91.417231) (xy 8.178177 -91.528794) (xy 8.117414 -91.636685) (xy 8.049863 -91.740462)
			(xy 7.975801 -91.839697) (xy 7.895534 -91.933984) (xy 7.809391 -92.022934) (xy 7.717726 -92.106182)
			(xy 7.620915 -92.183385) (xy 7.519357 -92.254228) (xy 7.413469 -92.318418) (xy 7.303685 -92.375692)
			(xy 7.190458 -92.425815) (xy 7.074251 -92.46858) (xy 6.955544 -92.503811) (xy 6.834823 -92.531365)
			(xy 6.712585 -92.551128) (xy 6.589332 -92.563018) (xy 6.46557 -92.566987) (xy 6.341808 -92.563018)
			(xy 6.218555 -92.551128) (xy 6.096317 -92.531365) (xy 5.975596 -92.503811) (xy 5.856889 -92.46858)
			(xy 5.740682 -92.425815) (xy 5.627455 -92.375692) (xy 5.517671 -92.318418) (xy 5.411783 -92.254228)
			(xy 5.310225 -92.183385) (xy 5.213414 -92.106182) (xy 5.121749 -92.022934) (xy 5.035606 -91.933984)
			(xy 4.955339 -91.839697) (xy 4.881277 -91.740462) (xy 4.813726 -91.636685) (xy 4.752963 -91.528794)
			(xy 4.699237 -91.417231) (xy 4.652769 -91.302455) (xy 4.613751 -91.184938) (xy 4.582342 -91.065162)
			(xy 4.558672 -90.94362) (xy 4.542837 -90.820812) (xy 4.534904 -90.697241) (xy 0.509016 -90.697241)
			(xy 0.509016 -95.79991) (xy 102.486719 -95.79991) (xy 102.490744 -95.657718) (xy 102.502807 -95.515982)
			(xy 102.52287 -95.375156) (xy 102.550868 -95.23569) (xy 102.586712 -95.098031) (xy 102.630286 -94.962621)
			(xy 102.681451 -94.829893) (xy 102.740044 -94.700272) (xy 102.805875 -94.574174) (xy 102.878736 -94.452002)
			(xy 102.958391 -94.334148) (xy 103.044587 -94.220989) (xy 103.137046 -94.112887) (xy 103.235474 -94.01019)
			(xy 103.339553 -93.913226) (xy 103.448952 -93.822306) (xy 103.56332 -93.73772) (xy 103.682289 -93.65974)
			(xy 103.80548 -93.588616) (xy 103.932497 -93.524575) (xy 104.062934 -93.467823) (xy 104.196373 -93.418541)
			(xy 104.332386 -93.376887) (xy 104.470538 -93.342995) (xy 104.610387 -93.316974) (xy 104.751483 -93.298906)
			(xy 104.893375 -93.288849) (xy 105.03561 -93.286836) (xy 105.17773 -93.292873) (xy 105.319281 -93.306941)
			(xy 105.45981 -93.328995) (xy 105.598865 -93.358964) (xy 105.736003 -93.396752) (xy 105.870783 -93.442238)
			(xy 106.002774 -93.495276) (xy 106.131553 -93.555697) (xy 106.256707 -93.623306) (xy 106.377835 -93.697888)
			(xy 106.494551 -93.779204) (xy 106.606479 -93.866992) (xy 106.713261 -93.960972) (xy 106.814555 -94.060842)
			(xy 106.910036 -94.166284) (xy 106.9994 -94.276958) (xy 107.082358 -94.392511) (xy 107.158647 -94.512572)
			(xy 107.228021 -94.636757) (xy 107.290258 -94.764668) (xy 107.345159 -94.895895) (xy 107.392547 -95.030018)
			(xy 107.432272 -95.166607) (xy 107.464205 -95.305225) (xy 107.488246 -95.445427) (xy 107.504315 -95.586765)
			(xy 107.512363 -95.728786) (xy 107.512866 -95.79991) (xy 107.512363 -95.871034) (xy 107.504315 -96.013055)
			(xy 107.488246 -96.154393) (xy 107.464205 -96.294595) (xy 107.432272 -96.433213) (xy 107.392547 -96.569802)
			(xy 107.345159 -96.703925) (xy 107.290258 -96.835152) (xy 107.228021 -96.963063) (xy 107.158647 -97.087248)
			(xy 107.082358 -97.207309) (xy 106.9994 -97.322862) (xy 106.910036 -97.433536) (xy 106.814555 -97.538978)
			(xy 106.713261 -97.638848) (xy 106.606479 -97.732828) (xy 106.494551 -97.820616) (xy 106.377835 -97.901932)
			(xy 106.256707 -97.976514) (xy 106.131553 -98.044123) (xy 106.002774 -98.104544) (xy 105.870783 -98.157582)
			(xy 105.736003 -98.203068) (xy 105.598865 -98.240856) (xy 105.45981 -98.270825) (xy 105.319281 -98.292879)
			(xy 105.17773 -98.306947) (xy 105.03561 -98.312984) (xy 104.893375 -98.310971) (xy 104.751483 -98.300914)
			(xy 104.610387 -98.282846) (xy 104.470538 -98.256825) (xy 104.332386 -98.222933) (xy 104.196373 -98.181279)
			(xy 104.062934 -98.131997) (xy 103.932497 -98.075245) (xy 103.80548 -98.011204) (xy 103.682289 -97.94008)
			(xy 103.56332 -97.8621) (xy 103.448952 -97.777514) (xy 103.339553 -97.686594) (xy 103.235474 -97.58963)
			(xy 103.137046 -97.486933) (xy 103.044587 -97.378831) (xy 102.958391 -97.265672) (xy 102.878736 -97.147818)
			(xy 102.805875 -97.025646) (xy 102.740044 -96.899548) (xy 102.681451 -96.769927) (xy 102.630286 -96.637199)
			(xy 102.586712 -96.501789) (xy 102.550868 -96.36413) (xy 102.52287 -96.224664) (xy 102.502807 -96.083838)
			(xy 102.490744 -95.942102) (xy 102.486719 -95.79991) (xy 0.509016 -95.79991) (xy 0.509016 -165.386004)
			(xy 0.210312 -165.684708) (xy -2.507742 -165.684708) (xy -2.507742 -160.585658) (xy -2.507996 -160.585404)
			(xy -2.507996 -0.635) (xy -2.50849 -0.618345) (xy -2.517111 -0.586171) (xy -2.533766 -0.557324) (xy -2.55732 -0.53377)
			(xy -2.586167 -0.517115) (xy -2.618341 -0.508494) (xy -2.634996 -0.508) (xy -16.237966 -0.508) (xy -16.293773 -0.508522)
			(xy -16.405075 -0.516863) (xy -16.515442 -0.533498) (xy -16.624258 -0.558335) (xy -16.730913 -0.591234)
			(xy -16.834812 -0.632011) (xy -16.935372 -0.680438) (xy -17.032033 -0.736246) (xy -17.124253 -0.79912)
			(xy -17.211516 -0.86871) (xy -17.293335 -0.944627) (xy -17.369252 -1.026446) (xy -17.438842 -1.113709)
			(xy -17.501716 -1.205929) (xy -17.557524 -1.30259) (xy -17.605951 -1.40315) (xy -17.646728 -1.507049)
			(xy -17.679627 -1.613704) (xy -17.704464 -1.72252) (xy -17.721099 -1.832887) (xy -17.72944 -1.944189)
			(xy -17.729962 -1.999996) (xy -17.729962 -31.846463) (xy -12.286746 -31.846463) (xy -12.286746 -31.761741)
			(xy -12.278693 -31.677404) (xy -12.262659 -31.594214) (xy -12.238791 -31.512924) (xy -12.207303 -31.434272)
			(xy -12.168481 -31.358969) (xy -12.122678 -31.287697) (xy -12.070307 -31.221101) (xy -12.011842 -31.159786)
			(xy -11.947814 -31.104305) (xy -11.878802 -31.055162) (xy -11.805432 -31.012802) (xy -11.728367 -30.977607)
			(xy -11.648305 -30.949898) (xy -11.565972 -30.929924) (xy -11.482113 -30.917867) (xy -11.397488 -30.913836)
			(xy -11.312863 -30.917867) (xy -11.229004 -30.929924) (xy -11.146671 -30.949898) (xy -11.066609 -30.977607)
			(xy -10.989544 -31.012802) (xy -10.916174 -31.055162) (xy -10.847162 -31.104305) (xy -10.783134 -31.159786)
			(xy -10.724669 -31.221101) (xy -10.672298 -31.287697) (xy -10.626495 -31.358969) (xy -10.587673 -31.434272)
			(xy -10.556185 -31.512924) (xy -10.532317 -31.594214) (xy -10.516283 -31.677404) (xy -10.50823 -31.761741)
			(xy -10.507726 -31.804102) (xy -10.50823 -31.846463) (xy -7.714746 -31.846463) (xy -7.714746 -31.761741)
			(xy -7.706693 -31.677404) (xy -7.690659 -31.594214) (xy -7.666791 -31.512924) (xy -7.635303 -31.434272)
			(xy -7.596481 -31.358969) (xy -7.550678 -31.287697) (xy -7.498307 -31.221101) (xy -7.439842 -31.159786)
			(xy -7.375814 -31.104305) (xy -7.306802 -31.055162) (xy -7.233432 -31.012802) (xy -7.156367 -30.977607)
			(xy -7.076305 -30.949898) (xy -6.993972 -30.929924) (xy -6.910113 -30.917867) (xy -6.825488 -30.913836)
			(xy -6.740863 -30.917867) (xy -6.657004 -30.929924) (xy -6.574671 -30.949898) (xy -6.494609 -30.977607)
			(xy -6.417544 -31.012802) (xy -6.344174 -31.055162) (xy -6.275162 -31.104305) (xy -6.211134 -31.159786)
			(xy -6.152669 -31.221101) (xy -6.100298 -31.287697) (xy -6.054495 -31.358969) (xy -6.015673 -31.434272)
			(xy -5.984185 -31.512924) (xy -5.960317 -31.594214) (xy -5.944283 -31.677404) (xy -5.93623 -31.761741)
			(xy -5.935726 -31.804102) (xy -5.93623 -31.846463) (xy -5.944283 -31.9308) (xy -5.960317 -32.01399)
			(xy -5.984185 -32.09528) (xy -6.015673 -32.173932) (xy -6.054495 -32.249235) (xy -6.100298 -32.320507)
			(xy -6.152669 -32.387103) (xy -6.211134 -32.448418) (xy -6.275162 -32.503899) (xy -6.344174 -32.553042)
			(xy -6.417544 -32.595402) (xy -6.494609 -32.630597) (xy -6.574671 -32.658306) (xy -6.657004 -32.67828)
			(xy -6.740863 -32.690337) (xy -6.825488 -32.694369) (xy -6.910113 -32.690337) (xy -6.993972 -32.67828)
			(xy -7.076305 -32.658306) (xy -7.156367 -32.630597) (xy -7.233432 -32.595402) (xy -7.306802 -32.553042)
			(xy -7.375814 -32.503899) (xy -7.439842 -32.448418) (xy -7.498307 -32.387103) (xy -7.550678 -32.320507)
			(xy -7.596481 -32.249235) (xy -7.635303 -32.173932) (xy -7.666791 -32.09528) (xy -7.690659 -32.01399)
			(xy -7.706693 -31.9308) (xy -7.714746 -31.846463) (xy -10.50823 -31.846463) (xy -10.516283 -31.9308)
			(xy -10.532317 -32.01399) (xy -10.556185 -32.09528) (xy -10.587673 -32.173932) (xy -10.626495 -32.249235)
			(xy -10.672298 -32.320507) (xy -10.724669 -32.387103) (xy -10.783134 -32.448418) (xy -10.847162 -32.503899)
			(xy -10.916174 -32.553042) (xy -10.989544 -32.595402) (xy -11.066609 -32.630597) (xy -11.146671 -32.658306)
			(xy -11.229004 -32.67828) (xy -11.312863 -32.690337) (xy -11.397488 -32.694369) (xy -11.482113 -32.690337)
			(xy -11.565972 -32.67828) (xy -11.648305 -32.658306) (xy -11.728367 -32.630597) (xy -11.805432 -32.595402)
			(xy -11.878802 -32.553042) (xy -11.947814 -32.503899) (xy -12.011842 -32.448418) (xy -12.070307 -32.387103)
			(xy -12.122678 -32.320507) (xy -12.168481 -32.249235) (xy -12.207303 -32.173932) (xy -12.238791 -32.09528)
			(xy -12.262659 -32.01399) (xy -12.278693 -31.9308) (xy -12.286746 -31.846463) (xy -17.729962 -31.846463)
			(xy -17.729962 -35.910463) (xy -12.286746 -35.910463) (xy -12.286746 -35.825741) (xy -12.278693 -35.741404)
			(xy -12.262659 -35.658214) (xy -12.238791 -35.576924) (xy -12.207303 -35.498272) (xy -12.168481 -35.422969)
			(xy -12.122678 -35.351697) (xy -12.070307 -35.285101) (xy -12.011842 -35.223786) (xy -11.947814 -35.168305)
			(xy -11.878802 -35.119162) (xy -11.805432 -35.076802) (xy -11.728367 -35.041607) (xy -11.648305 -35.013898)
			(xy -11.565972 -34.993924) (xy -11.482113 -34.981867) (xy -11.397488 -34.977836) (xy -11.312863 -34.981867)
			(xy -11.229004 -34.993924) (xy -11.146671 -35.013898) (xy -11.066609 -35.041607) (xy -10.989544 -35.076802)
			(xy -10.916174 -35.119162) (xy -10.847162 -35.168305) (xy -10.783134 -35.223786) (xy -10.724669 -35.285101)
			(xy -10.672298 -35.351697) (xy -10.626495 -35.422969) (xy -10.587673 -35.498272) (xy -10.556185 -35.576924)
			(xy -10.532317 -35.658214) (xy -10.516283 -35.741404) (xy -10.50823 -35.825741) (xy -10.507726 -35.868102)
			(xy -10.50823 -35.910463) (xy -7.714746 -35.910463) (xy -7.714746 -35.825741) (xy -7.706693 -35.741404)
			(xy -7.690659 -35.658214) (xy -7.666791 -35.576924) (xy -7.635303 -35.498272) (xy -7.596481 -35.422969)
			(xy -7.550678 -35.351697) (xy -7.498307 -35.285101) (xy -7.439842 -35.223786) (xy -7.375814 -35.168305)
			(xy -7.306802 -35.119162) (xy -7.233432 -35.076802) (xy -7.156367 -35.041607) (xy -7.076305 -35.013898)
			(xy -6.993972 -34.993924) (xy -6.910113 -34.981867) (xy -6.825488 -34.977836) (xy -6.740863 -34.981867)
			(xy -6.657004 -34.993924) (xy -6.574671 -35.013898) (xy -6.494609 -35.041607) (xy -6.417544 -35.076802)
			(xy -6.344174 -35.119162) (xy -6.275162 -35.168305) (xy -6.211134 -35.223786) (xy -6.152669 -35.285101)
			(xy -6.100298 -35.351697) (xy -6.054495 -35.422969) (xy -6.015673 -35.498272) (xy -5.984185 -35.576924)
			(xy -5.960317 -35.658214) (xy -5.944283 -35.741404) (xy -5.93623 -35.825741) (xy -5.935726 -35.868102)
			(xy -5.93623 -35.910463) (xy -5.944283 -35.9948) (xy -5.960317 -36.07799) (xy -5.984185 -36.15928)
			(xy -6.015673 -36.237932) (xy -6.054495 -36.313235) (xy -6.100298 -36.384507) (xy -6.152669 -36.451103)
			(xy -6.211134 -36.512418) (xy -6.275162 -36.567899) (xy -6.344174 -36.617042) (xy -6.417544 -36.659402)
			(xy -6.494609 -36.694597) (xy -6.574671 -36.722306) (xy -6.657004 -36.74228) (xy -6.740863 -36.754337)
			(xy -6.825488 -36.758369) (xy -6.910113 -36.754337) (xy -6.993972 -36.74228) (xy -7.076305 -36.722306)
			(xy -7.156367 -36.694597) (xy -7.233432 -36.659402) (xy -7.306802 -36.617042) (xy -7.375814 -36.567899)
			(xy -7.439842 -36.512418) (xy -7.498307 -36.451103) (xy -7.550678 -36.384507) (xy -7.596481 -36.313235)
			(xy -7.635303 -36.237932) (xy -7.666791 -36.15928) (xy -7.690659 -36.07799) (xy -7.706693 -35.9948)
			(xy -7.714746 -35.910463) (xy -10.50823 -35.910463) (xy -10.516283 -35.9948) (xy -10.532317 -36.07799)
			(xy -10.556185 -36.15928) (xy -10.587673 -36.237932) (xy -10.626495 -36.313235) (xy -10.672298 -36.384507)
			(xy -10.724669 -36.451103) (xy -10.783134 -36.512418) (xy -10.847162 -36.567899) (xy -10.916174 -36.617042)
			(xy -10.989544 -36.659402) (xy -11.066609 -36.694597) (xy -11.146671 -36.722306) (xy -11.229004 -36.74228)
			(xy -11.312863 -36.754337) (xy -11.397488 -36.758369) (xy -11.482113 -36.754337) (xy -11.565972 -36.74228)
			(xy -11.648305 -36.722306) (xy -11.728367 -36.694597) (xy -11.805432 -36.659402) (xy -11.878802 -36.617042)
			(xy -11.947814 -36.567899) (xy -12.011842 -36.512418) (xy -12.070307 -36.451103) (xy -12.122678 -36.384507)
			(xy -12.168481 -36.313235) (xy -12.207303 -36.237932) (xy -12.238791 -36.15928) (xy -12.262659 -36.07799)
			(xy -12.278693 -35.9948) (xy -12.286746 -35.910463) (xy -17.729962 -35.910463) (xy -17.729962 -59.105743)
			(xy -12.286746 -59.105743) (xy -12.286746 -59.021021) (xy -12.278693 -58.936684) (xy -12.262659 -58.853494)
			(xy -12.238791 -58.772204) (xy -12.207303 -58.693552) (xy -12.168481 -58.618249) (xy -12.122678 -58.546977)
			(xy -12.070307 -58.480381) (xy -12.011842 -58.419066) (xy -11.947814 -58.363585) (xy -11.878802 -58.314442)
			(xy -11.805432 -58.272082) (xy -11.728367 -58.236887) (xy -11.648305 -58.209178) (xy -11.565972 -58.189204)
			(xy -11.482113 -58.177147) (xy -11.397488 -58.173116) (xy -11.312863 -58.177147) (xy -11.229004 -58.189204)
			(xy -11.146671 -58.209178) (xy -11.066609 -58.236887) (xy -10.989544 -58.272082) (xy -10.916174 -58.314442)
			(xy -10.847162 -58.363585) (xy -10.783134 -58.419066) (xy -10.724669 -58.480381) (xy -10.672298 -58.546977)
			(xy -10.626495 -58.618249) (xy -10.587673 -58.693552) (xy -10.556185 -58.772204) (xy -10.532317 -58.853494)
			(xy -10.516283 -58.936684) (xy -10.50823 -59.021021) (xy -10.507726 -59.063382) (xy -10.50823 -59.105743)
			(xy -7.714746 -59.105743) (xy -7.714746 -59.021021) (xy -7.706693 -58.936684) (xy -7.690659 -58.853494)
			(xy -7.666791 -58.772204) (xy -7.635303 -58.693552) (xy -7.596481 -58.618249) (xy -7.550678 -58.546977)
			(xy -7.498307 -58.480381) (xy -7.439842 -58.419066) (xy -7.375814 -58.363585) (xy -7.306802 -58.314442)
			(xy -7.233432 -58.272082) (xy -7.156367 -58.236887) (xy -7.076305 -58.209178) (xy -6.993972 -58.189204)
			(xy -6.910113 -58.177147) (xy -6.825488 -58.173116) (xy -6.740863 -58.177147) (xy -6.657004 -58.189204)
			(xy -6.574671 -58.209178) (xy -6.494609 -58.236887) (xy -6.417544 -58.272082) (xy -6.344174 -58.314442)
			(xy -6.275162 -58.363585) (xy -6.211134 -58.419066) (xy -6.152669 -58.480381) (xy -6.100298 -58.546977)
			(xy -6.054495 -58.618249) (xy -6.015673 -58.693552) (xy -5.984185 -58.772204) (xy -5.960317 -58.853494)
			(xy -5.944283 -58.936684) (xy -5.93623 -59.021021) (xy -5.935726 -59.063382) (xy -5.93623 -59.105743)
			(xy -5.944283 -59.19008) (xy -5.960317 -59.27327) (xy -5.984185 -59.35456) (xy -6.015673 -59.433212)
			(xy -6.054495 -59.508515) (xy -6.100298 -59.579787) (xy -6.152669 -59.646383) (xy -6.211134 -59.707698)
			(xy -6.275162 -59.763179) (xy -6.344174 -59.812322) (xy -6.417544 -59.854682) (xy -6.494609 -59.889877)
			(xy -6.574671 -59.917586) (xy -6.657004 -59.93756) (xy -6.740863 -59.949617) (xy -6.825488 -59.953649)
			(xy -6.910113 -59.949617) (xy -6.993972 -59.93756) (xy -7.076305 -59.917586) (xy -7.156367 -59.889877)
			(xy -7.233432 -59.854682) (xy -7.306802 -59.812322) (xy -7.375814 -59.763179) (xy -7.439842 -59.707698)
			(xy -7.498307 -59.646383) (xy -7.550678 -59.579787) (xy -7.596481 -59.508515) (xy -7.635303 -59.433212)
			(xy -7.666791 -59.35456) (xy -7.690659 -59.27327) (xy -7.706693 -59.19008) (xy -7.714746 -59.105743)
			(xy -10.50823 -59.105743) (xy -10.516283 -59.19008) (xy -10.532317 -59.27327) (xy -10.556185 -59.35456)
			(xy -10.587673 -59.433212) (xy -10.626495 -59.508515) (xy -10.672298 -59.579787) (xy -10.724669 -59.646383)
			(xy -10.783134 -59.707698) (xy -10.847162 -59.763179) (xy -10.916174 -59.812322) (xy -10.989544 -59.854682)
			(xy -11.066609 -59.889877) (xy -11.146671 -59.917586) (xy -11.229004 -59.93756) (xy -11.312863 -59.949617)
			(xy -11.397488 -59.953649) (xy -11.482113 -59.949617) (xy -11.565972 -59.93756) (xy -11.648305 -59.917586)
			(xy -11.728367 -59.889877) (xy -11.805432 -59.854682) (xy -11.878802 -59.812322) (xy -11.947814 -59.763179)
			(xy -12.011842 -59.707698) (xy -12.070307 -59.646383) (xy -12.122678 -59.579787) (xy -12.168481 -59.508515)
			(xy -12.207303 -59.433212) (xy -12.238791 -59.35456) (xy -12.262659 -59.27327) (xy -12.278693 -59.19008)
			(xy -12.286746 -59.105743) (xy -17.729962 -59.105743) (xy -17.729962 -63.169743) (xy -12.286746 -63.169743)
			(xy -12.286746 -63.085021) (xy -12.278693 -63.000684) (xy -12.262659 -62.917494) (xy -12.238791 -62.836204)
			(xy -12.207303 -62.757552) (xy -12.168481 -62.682249) (xy -12.122678 -62.610977) (xy -12.070307 -62.544381)
			(xy -12.011842 -62.483066) (xy -11.947814 -62.427585) (xy -11.878802 -62.378442) (xy -11.805432 -62.336082)
			(xy -11.728367 -62.300887) (xy -11.648305 -62.273178) (xy -11.565972 -62.253204) (xy -11.482113 -62.241147)
			(xy -11.397488 -62.237116) (xy -11.312863 -62.241147) (xy -11.229004 -62.253204) (xy -11.146671 -62.273178)
			(xy -11.066609 -62.300887) (xy -10.989544 -62.336082) (xy -10.916174 -62.378442) (xy -10.847162 -62.427585)
			(xy -10.783134 -62.483066) (xy -10.724669 -62.544381) (xy -10.672298 -62.610977) (xy -10.626495 -62.682249)
			(xy -10.587673 -62.757552) (xy -10.556185 -62.836204) (xy -10.532317 -62.917494) (xy -10.516283 -63.000684)
			(xy -10.50823 -63.085021) (xy -10.507726 -63.127382) (xy -10.50823 -63.169743) (xy -7.714746 -63.169743)
			(xy -7.714746 -63.085021) (xy -7.706693 -63.000684) (xy -7.690659 -62.917494) (xy -7.666791 -62.836204)
			(xy -7.635303 -62.757552) (xy -7.596481 -62.682249) (xy -7.550678 -62.610977) (xy -7.498307 -62.544381)
			(xy -7.439842 -62.483066) (xy -7.375814 -62.427585) (xy -7.306802 -62.378442) (xy -7.233432 -62.336082)
			(xy -7.156367 -62.300887) (xy -7.076305 -62.273178) (xy -6.993972 -62.253204) (xy -6.910113 -62.241147)
			(xy -6.825488 -62.237116) (xy -6.740863 -62.241147) (xy -6.657004 -62.253204) (xy -6.574671 -62.273178)
			(xy -6.494609 -62.300887) (xy -6.417544 -62.336082) (xy -6.344174 -62.378442) (xy -6.275162 -62.427585)
			(xy -6.211134 -62.483066) (xy -6.152669 -62.544381) (xy -6.100298 -62.610977) (xy -6.054495 -62.682249)
			(xy -6.015673 -62.757552) (xy -5.984185 -62.836204) (xy -5.960317 -62.917494) (xy -5.944283 -63.000684)
			(xy -5.93623 -63.085021) (xy -5.935726 -63.127382) (xy -5.93623 -63.169743) (xy -5.944283 -63.25408)
			(xy -5.960317 -63.33727) (xy -5.984185 -63.41856) (xy -6.015673 -63.497212) (xy -6.054495 -63.572515)
			(xy -6.100298 -63.643787) (xy -6.152669 -63.710383) (xy -6.211134 -63.771698) (xy -6.275162 -63.827179)
			(xy -6.344174 -63.876322) (xy -6.417544 -63.918682) (xy -6.494609 -63.953877) (xy -6.574671 -63.981586)
			(xy -6.657004 -64.00156) (xy -6.740863 -64.013617) (xy -6.825488 -64.017649) (xy -6.910113 -64.013617)
			(xy -6.993972 -64.00156) (xy -7.076305 -63.981586) (xy -7.156367 -63.953877) (xy -7.233432 -63.918682)
			(xy -7.306802 -63.876322) (xy -7.375814 -63.827179) (xy -7.439842 -63.771698) (xy -7.498307 -63.710383)
			(xy -7.550678 -63.643787) (xy -7.596481 -63.572515) (xy -7.635303 -63.497212) (xy -7.666791 -63.41856)
			(xy -7.690659 -63.33727) (xy -7.706693 -63.25408) (xy -7.714746 -63.169743) (xy -10.50823 -63.169743)
			(xy -10.516283 -63.25408) (xy -10.532317 -63.33727) (xy -10.556185 -63.41856) (xy -10.587673 -63.497212)
			(xy -10.626495 -63.572515) (xy -10.672298 -63.643787) (xy -10.724669 -63.710383) (xy -10.783134 -63.771698)
			(xy -10.847162 -63.827179) (xy -10.916174 -63.876322) (xy -10.989544 -63.918682) (xy -11.066609 -63.953877)
			(xy -11.146671 -63.981586) (xy -11.229004 -64.00156) (xy -11.312863 -64.013617) (xy -11.397488 -64.017649)
			(xy -11.482113 -64.013617) (xy -11.565972 -64.00156) (xy -11.648305 -63.981586) (xy -11.728367 -63.953877)
			(xy -11.805432 -63.918682) (xy -11.878802 -63.876322) (xy -11.947814 -63.827179) (xy -12.011842 -63.771698)
			(xy -12.070307 -63.710383) (xy -12.122678 -63.643787) (xy -12.168481 -63.572515) (xy -12.207303 -63.497212)
			(xy -12.238791 -63.41856) (xy -12.262659 -63.33727) (xy -12.278693 -63.25408) (xy -12.286746 -63.169743)
			(xy -17.729962 -63.169743) (xy -17.729962 -187.619583) (xy -12.286746 -187.619583) (xy -12.286746 -187.534861)
			(xy -12.278693 -187.450524) (xy -12.262659 -187.367334) (xy -12.238791 -187.286044) (xy -12.207303 -187.207392)
			(xy -12.168481 -187.132089) (xy -12.122678 -187.060817) (xy -12.070307 -186.994221) (xy -12.011842 -186.932906)
			(xy -11.947814 -186.877425) (xy -11.878802 -186.828282) (xy -11.805432 -186.785922) (xy -11.728367 -186.750727)
			(xy -11.648305 -186.723018) (xy -11.565972 -186.703044) (xy -11.482113 -186.690987) (xy -11.397488 -186.686956)
			(xy -11.312863 -186.690987) (xy -11.229004 -186.703044) (xy -11.146671 -186.723018) (xy -11.066609 -186.750727)
			(xy -10.989544 -186.785922) (xy -10.916174 -186.828282) (xy -10.847162 -186.877425) (xy -10.783134 -186.932906)
			(xy -10.724669 -186.994221) (xy -10.672298 -187.060817) (xy -10.626495 -187.132089) (xy -10.587673 -187.207392)
			(xy -10.556185 -187.286044) (xy -10.532317 -187.367334) (xy -10.516283 -187.450524) (xy -10.50823 -187.534861)
			(xy -10.507726 -187.577222) (xy -10.50823 -187.619583) (xy -7.714746 -187.619583) (xy -7.714746 -187.534861)
			(xy -7.706693 -187.450524) (xy -7.690659 -187.367334) (xy -7.666791 -187.286044) (xy -7.635303 -187.207392)
			(xy -7.596481 -187.132089) (xy -7.550678 -187.060817) (xy -7.498307 -186.994221) (xy -7.439842 -186.932906)
			(xy -7.375814 -186.877425) (xy -7.306802 -186.828282) (xy -7.233432 -186.785922) (xy -7.156367 -186.750727)
			(xy -7.076305 -186.723018) (xy -6.993972 -186.703044) (xy -6.910113 -186.690987) (xy -6.825488 -186.686956)
			(xy -6.740863 -186.690987) (xy -6.657004 -186.703044) (xy -6.574671 -186.723018) (xy -6.494609 -186.750727)
			(xy -6.417544 -186.785922) (xy -6.344174 -186.828282) (xy -6.275162 -186.877425) (xy -6.211134 -186.932906)
			(xy -6.152669 -186.994221) (xy -6.100298 -187.060817) (xy -6.054495 -187.132089) (xy -6.015673 -187.207392)
			(xy -5.984185 -187.286044) (xy -5.960317 -187.367334) (xy -5.944283 -187.450524) (xy -5.93623 -187.534861)
			(xy -5.935726 -187.577222) (xy -5.93623 -187.619583) (xy -5.944283 -187.70392) (xy -5.960317 -187.78711)
			(xy -5.984185 -187.8684) (xy -6.015673 -187.947052) (xy -6.054495 -188.022355) (xy -6.100298 -188.093627)
			(xy -6.152669 -188.160223) (xy -6.211134 -188.221538) (xy -6.275162 -188.277019) (xy -6.344174 -188.326162)
			(xy -6.417544 -188.368522) (xy -6.494609 -188.403717) (xy -6.574671 -188.431426) (xy -6.657004 -188.4514)
			(xy -6.740863 -188.463457) (xy -6.825488 -188.467489) (xy -6.910113 -188.463457) (xy -6.993972 -188.4514)
			(xy -7.076305 -188.431426) (xy -7.156367 -188.403717) (xy -7.233432 -188.368522) (xy -7.306802 -188.326162)
			(xy -7.375814 -188.277019) (xy -7.439842 -188.221538) (xy -7.498307 -188.160223) (xy -7.550678 -188.093627)
			(xy -7.596481 -188.022355) (xy -7.635303 -187.947052) (xy -7.666791 -187.8684) (xy -7.690659 -187.78711)
			(xy -7.706693 -187.70392) (xy -7.714746 -187.619583) (xy -10.50823 -187.619583) (xy -10.516283 -187.70392)
			(xy -10.532317 -187.78711) (xy -10.556185 -187.8684) (xy -10.587673 -187.947052) (xy -10.626495 -188.022355)
			(xy -10.672298 -188.093627) (xy -10.724669 -188.160223) (xy -10.783134 -188.221538) (xy -10.847162 -188.277019)
			(xy -10.916174 -188.326162) (xy -10.989544 -188.368522) (xy -11.066609 -188.403717) (xy -11.146671 -188.431426)
			(xy -11.229004 -188.4514) (xy -11.312863 -188.463457) (xy -11.397488 -188.467489) (xy -11.482113 -188.463457)
			(xy -11.565972 -188.4514) (xy -11.648305 -188.431426) (xy -11.728367 -188.403717) (xy -11.805432 -188.368522)
			(xy -11.878802 -188.326162) (xy -11.947814 -188.277019) (xy -12.011842 -188.221538) (xy -12.070307 -188.160223)
			(xy -12.122678 -188.093627) (xy -12.168481 -188.022355) (xy -12.207303 -187.947052) (xy -12.238791 -187.8684)
			(xy -12.262659 -187.78711) (xy -12.278693 -187.70392) (xy -12.286746 -187.619583) (xy -17.729962 -187.619583)
			(xy -17.729962 -191.683583) (xy -12.286746 -191.683583) (xy -12.286746 -191.598861) (xy -12.278693 -191.514524)
			(xy -12.262659 -191.431334) (xy -12.238791 -191.350044) (xy -12.207303 -191.271392) (xy -12.168481 -191.196089)
			(xy -12.122678 -191.124817) (xy -12.070307 -191.058221) (xy -12.011842 -190.996906) (xy -11.947814 -190.941425)
			(xy -11.878802 -190.892282) (xy -11.805432 -190.849922) (xy -11.728367 -190.814727) (xy -11.648305 -190.787018)
			(xy -11.565972 -190.767044) (xy -11.482113 -190.754987) (xy -11.397488 -190.750956) (xy -11.312863 -190.754987)
			(xy -11.229004 -190.767044) (xy -11.146671 -190.787018) (xy -11.066609 -190.814727) (xy -10.989544 -190.849922)
			(xy -10.916174 -190.892282) (xy -10.847162 -190.941425) (xy -10.783134 -190.996906) (xy -10.724669 -191.058221)
			(xy -10.672298 -191.124817) (xy -10.626495 -191.196089) (xy -10.587673 -191.271392) (xy -10.556185 -191.350044)
			(xy -10.532317 -191.431334) (xy -10.516283 -191.514524) (xy -10.50823 -191.598861) (xy -10.507726 -191.641222)
			(xy -10.50823 -191.683583) (xy -7.714746 -191.683583) (xy -7.714746 -191.598861) (xy -7.706693 -191.514524)
			(xy -7.690659 -191.431334) (xy -7.666791 -191.350044) (xy -7.635303 -191.271392) (xy -7.596481 -191.196089)
			(xy -7.550678 -191.124817) (xy -7.498307 -191.058221) (xy -7.439842 -190.996906) (xy -7.375814 -190.941425)
			(xy -7.306802 -190.892282) (xy -7.233432 -190.849922) (xy -7.156367 -190.814727) (xy -7.076305 -190.787018)
			(xy -6.993972 -190.767044) (xy -6.910113 -190.754987) (xy -6.825488 -190.750956) (xy -6.740863 -190.754987)
			(xy -6.657004 -190.767044) (xy -6.574671 -190.787018) (xy -6.494609 -190.814727) (xy -6.417544 -190.849922)
			(xy -6.344174 -190.892282) (xy -6.275162 -190.941425) (xy -6.211134 -190.996906) (xy -6.152669 -191.058221)
			(xy -6.100298 -191.124817) (xy -6.054495 -191.196089) (xy -6.015673 -191.271392) (xy -5.984185 -191.350044)
			(xy -5.960317 -191.431334) (xy -5.944283 -191.514524) (xy -5.93623 -191.598861) (xy -5.935726 -191.641222)
			(xy -5.93623 -191.683583) (xy -5.944283 -191.76792) (xy -5.960317 -191.85111) (xy -5.984185 -191.9324)
			(xy -6.015673 -192.011052) (xy -6.054495 -192.086355) (xy -6.100298 -192.157627) (xy -6.152669 -192.224223)
			(xy -6.211134 -192.285538) (xy -6.275162 -192.341019) (xy -6.344174 -192.390162) (xy -6.417544 -192.432522)
			(xy -6.494609 -192.467717) (xy -6.574671 -192.495426) (xy -6.657004 -192.5154) (xy -6.740863 -192.527457)
			(xy -6.825488 -192.531489) (xy -6.910113 -192.527457) (xy -6.993972 -192.5154) (xy -7.076305 -192.495426)
			(xy -7.156367 -192.467717) (xy -7.233432 -192.432522) (xy -7.306802 -192.390162) (xy -7.375814 -192.341019)
			(xy -7.439842 -192.285538) (xy -7.498307 -192.224223) (xy -7.550678 -192.157627) (xy -7.596481 -192.086355)
			(xy -7.635303 -192.011052) (xy -7.666791 -191.9324) (xy -7.690659 -191.85111) (xy -7.706693 -191.76792)
			(xy -7.714746 -191.683583) (xy -10.50823 -191.683583) (xy -10.516283 -191.76792) (xy -10.532317 -191.85111)
			(xy -10.556185 -191.9324) (xy -10.587673 -192.011052) (xy -10.626495 -192.086355) (xy -10.672298 -192.157627)
			(xy -10.724669 -192.224223) (xy -10.783134 -192.285538) (xy -10.847162 -192.341019) (xy -10.916174 -192.390162)
			(xy -10.989544 -192.432522) (xy -11.066609 -192.467717) (xy -11.146671 -192.495426) (xy -11.229004 -192.5154)
			(xy -11.312863 -192.527457) (xy -11.397488 -192.531489) (xy -11.482113 -192.527457) (xy -11.565972 -192.5154)
			(xy -11.648305 -192.495426) (xy -11.728367 -192.467717) (xy -11.805432 -192.432522) (xy -11.878802 -192.390162)
			(xy -11.947814 -192.341019) (xy -12.011842 -192.285538) (xy -12.070307 -192.224223) (xy -12.122678 -192.157627)
			(xy -12.168481 -192.086355) (xy -12.207303 -192.011052) (xy -12.238791 -191.9324) (xy -12.262659 -191.85111)
			(xy -12.278693 -191.76792) (xy -12.286746 -191.683583) (xy -17.729962 -191.683583) (xy -17.729962 -206.70012)
			(xy -17.72944 -206.755927) (xy -17.721099 -206.867229) (xy -17.704464 -206.977596) (xy -17.679627 -207.086412)
			(xy -17.646728 -207.193067) (xy -17.605951 -207.296966) (xy -17.557524 -207.397526) (xy -17.501716 -207.494187)
			(xy -17.438842 -207.586407) (xy -17.369252 -207.67367) (xy -17.293335 -207.755489) (xy -17.211516 -207.831406)
			(xy -17.124253 -207.900996) (xy -17.032033 -207.96387) (xy -16.935372 -208.019678) (xy -16.834812 -208.068105)
			(xy -16.730913 -208.108882) (xy -16.624258 -208.141781) (xy -16.515442 -208.166618) (xy -16.405075 -208.183253)
			(xy -16.293773 -208.191594) (xy -16.237966 -208.192116)
		)
		(stroke
			(width 0)
			(type solid)
		)
		(fill yes)
		(layer "In1.Cu")
		(net "GND")
	)
	(gr_arc
		(start 1.500124 -70.79996)
		(mid 0.439376 -71.239336)
		(end 0 -72.300084)
		(stroke
			(width 1.016)
			(type default)
		)
		(layer "In1.Cu")
	)
	(gr_line
		(start 1.500124 -70.79996)
		(end 6.500114 -70.79996)
		(stroke
			(width 1.016)
			(type default)
		)
		(layer "In1.Cu")
	)
	(gr_line
		(start 1.999996 -170.699938)
		(end 10.359898 -170.699938)
		(stroke
			(width 1.016)
			(type default)
		)
		(layer "In1.Cu")
	)
	(gr_arc
		(start 1.999996 0)
		(mid 0.585785 -0.585785)
		(end 0 -1.999996)
		(stroke
			(width 1.016)
			(type default)
		)
		(layer "In1.Cu")
	)
	(gr_line
		(start 1.999996 0)
		(end 198.000112 0)
		(stroke
			(width 1.016)
			(type default)
		)
		(layer "In1.Cu")
	)
	(gr_arc
		(start 6.500114 -70.79996)
		(mid 7.560682 -70.360658)
		(end 7.999984 -69.30009)
		(stroke
			(width 1.016)
			(type default)
		)
		(layer "In1.Cu")
	)
	(gr_line
		(start 6.500114 -30.80004)
		(end 1.500124 -30.80004)
		(stroke
			(width 1.016)
			(type default)
		)
		(layer "In1.Cu")
	)
	(gr_line
		(start 7.999984 -69.30009)
		(end 7.999984 -32.29991)
		(stroke
			(width 1.016)
			(type default)
		)
		(layer "In1.Cu")
	)
	(gr_arc
		(start 7.999984 -32.29991)
		(mid 7.560682 -31.239342)
		(end 6.500114 -30.80004)
		(stroke
			(width 1.016)
			(type default)
		)
		(layer "In1.Cu")
	)
	(gr_line
		(start 12.359894 -208.197196)
		(end 12.497054 -208.334356)
		(stroke
			(width 1.016)
			(type default)
		)
		(layer "In1.Cu")
	)
	(gr_arc
		(start 12.359894 -172.699934)
		(mid 11.774121 -171.285702)
		(end 10.359898 -170.699938)
		(stroke
			(width 1.016)
			(type default)
		)
		(layer "In1.Cu")
	)
	(gr_line
		(start 12.359894 -172.699934)
		(end 12.359894 -208.197196)
		(stroke
			(width 1.016)
			(type default)
		)
		(layer "In1.Cu")
	)
	(gr_line
		(start 12.418568 -203.257404)
		(end 187.31738 -203.257404)
		(stroke
			(width 0.508)
			(type default)
		)
		(layer "In1.Cu")
	)
	(gr_line
		(start 12.497054 -208.334356)
		(end 12.864084 -208.699608)
		(stroke
			(width 1.016)
			(type default)
		)
		(layer "In1.Cu")
	)
	(gr_line
		(start 12.581636 -204.561948)
		(end 12.774168 -204.75448)
		(stroke
			(width 1.016)
			(type default)
		)
		(layer "In1.Cu")
	)
	(gr_line
		(start 12.581636 -203.77277)
		(end 12.581636 -204.561948)
		(stroke
			(width 1.016)
			(type default)
		)
		(layer "In1.Cu")
	)
	(gr_line
		(start 12.61999 -203.811124)
		(end 12.581636 -203.77277)
		(stroke
			(width 1.016)
			(type default)
		)
		(layer "In1.Cu")
	)
	(gr_line
		(start 12.620244 -207.314292)
		(end 12.697206 -207.391254)
		(stroke
			(width 1.016)
			(type default)
		)
		(layer "In1.Cu")
	)
	(gr_line
		(start 12.620244 -206.582772)
		(end 12.620244 -207.314292)
		(stroke
			(width 1.016)
			(type default)
		)
		(layer "In1.Cu")
	)
	(gr_line
		(start 12.697206 -207.391254)
		(end 13.274294 -206.814166)
		(stroke
			(width 1.016)
			(type default)
		)
		(layer "In1.Cu")
	)
	(gr_line
		(start 12.697206 -207.391254)
		(end 187.081414 -207.391254)
		(stroke
			(width 1.016)
			(type default)
		)
		(layer "In1.Cu")
	)
	(gr_line
		(start 12.71651 -206.159608)
		(end 187.3123 -206.159608)
		(stroke
			(width 1.016)
			(type default)
		)
		(layer "In1.Cu")
	)
	(gr_line
		(start 12.71651 -205.35138)
		(end 12.71651 -206.159608)
		(stroke
			(width 1.016)
			(type default)
		)
		(layer "In1.Cu")
	)
	(gr_line
		(start 12.774168 -204.75448)
		(end 187.004198 -204.75448)
		(stroke
			(width 1.016)
			(type default)
		)
		(layer "In1.Cu")
	)
	(gr_line
		(start 12.774422 -205.293468)
		(end 12.71651 -205.35138)
		(stroke
			(width 1.016)
			(type default)
		)
		(layer "In1.Cu")
	)
	(gr_line
		(start 12.851638 -206.814166)
		(end 12.620244 -206.582772)
		(stroke
			(width 1.016)
			(type default)
		)
		(layer "In1.Cu")
	)
	(gr_line
		(start 13.005054 -205.5241)
		(end 12.774422 -205.293468)
		(stroke
			(width 1.016)
			(type default)
		)
		(layer "In1.Cu")
	)
	(gr_line
		(start 13.274294 -206.814166)
		(end 187.119768 -206.814166)
		(stroke
			(width 1.016)
			(type default)
		)
		(layer "In1.Cu")
	)
	(gr_line
		(start 13.54328 -208.237328)
		(end 12.697206 -207.391254)
		(stroke
			(width 1.016)
			(type default)
		)
		(layer "In1.Cu")
	)
	(gr_line
		(start 56.30418 -63.52032)
		(end 56.30418 -58.9026)
		(stroke
			(width 0.254)
			(type default)
		)
		(layer "In1.Cu")
	)
	(gr_line
		(start 56.30418 -58.9026)
		(end 56.67248 -58.5343)
		(stroke
			(width 0.254)
			(type default)
		)
		(layer "In1.Cu")
	)
	(gr_line
		(start 56.67248 -58.5343)
		(end 56.67248 -57.99836)
		(stroke
			(width 0.254)
			(type default)
		)
		(layer "In1.Cu")
	)
	(gr_line
		(start 56.67248 -57.99836)
		(end 56.67248 -51.752754)
		(stroke
			(width 0.254)
			(type default)
		)
		(layer "In1.Cu")
	)
	(gr_line
		(start 56.67248 -51.752754)
		(end 58.077608 -50.347626)
		(stroke
			(width 0.254)
			(type default)
		)
		(layer "In1.Cu")
	)
	(gr_line
		(start 57.240678 -64.456818)
		(end 56.30418 -63.52032)
		(stroke
			(width 0.254)
			(type default)
		)
		(layer "In1.Cu")
	)
	(gr_line
		(start 58.077608 -50.347626)
		(end 58.077608 -39.438326)
		(stroke
			(width 0.254)
			(type default)
		)
		(layer "In1.Cu")
	)
	(gr_line
		(start 58.077608 -39.438326)
		(end 63.40348 -34.112454)
		(stroke
			(width 0.254)
			(type default)
		)
		(layer "In1.Cu")
	)
	(gr_line
		(start 59.752738 -64.456818)
		(end 57.240678 -64.456818)
		(stroke
			(width 0.254)
			(type default)
		)
		(layer "In1.Cu")
	)
	(gr_line
		(start 60.977272 -68.125086)
		(end 61.11367 -67.885056)
		(stroke
			(width 0.254)
			(type default)
		)
		(layer "In1.Cu")
	)
	(gr_line
		(start 60.991242 -68.383912)
		(end 60.977272 -68.125086)
		(stroke
			(width 0.254)
			(type default)
		)
		(layer "In1.Cu")
	)
	(gr_line
		(start 61.019436 -67.348608)
		(end 61.179456 -67.137026)
		(stroke
			(width 0.254)
			(type default)
		)
		(layer "In1.Cu")
	)
	(gr_line
		(start 61.047884 -67.503802)
		(end 61.019436 -67.348608)
		(stroke
			(width 0.254)
			(type default)
		)
		(layer "In1.Cu")
	)
	(gr_line
		(start 61.052456 -66.736976)
		(end 61.052456 -66.44513)
		(stroke
			(width 0.254)
			(type default)
		)
		(layer "In1.Cu")
	)
	(gr_line
		(start 61.052456 -66.44513)
		(end 61.111384 -66.386202)
		(stroke
			(width 0.254)
			(type default)
		)
		(layer "In1.Cu")
	)
	(gr_line
		(start 61.111384 -66.386202)
		(end 61.111384 -65.815464)
		(stroke
			(width 0.254)
			(type default)
		)
		(layer "In1.Cu")
	)
	(gr_line
		(start 61.111384 -65.815464)
		(end 59.752738 -64.456818)
		(stroke
			(width 0.254)
			(type default)
		)
		(layer "In1.Cu")
	)
	(gr_line
		(start 61.11367 -67.885056)
		(end 61.174884 -67.67322)
		(stroke
			(width 0.254)
			(type default)
		)
		(layer "In1.Cu")
	)
	(gr_line
		(start 61.174884 -67.67322)
		(end 61.047884 -67.503802)
		(stroke
			(width 0.254)
			(type default)
		)
		(layer "In1.Cu")
	)
	(gr_line
		(start 61.179456 -67.137026)
		(end 61.221874 -67.094608)
		(stroke
			(width 0.254)
			(type default)
		)
		(layer "In1.Cu")
	)
	(gr_line
		(start 61.221874 -67.094608)
		(end 61.221874 -66.906394)
		(stroke
			(width 0.254)
			(type default)
		)
		(layer "In1.Cu")
	)
	(gr_line
		(start 61.221874 -66.906394)
		(end 61.052456 -66.736976)
		(stroke
			(width 0.254)
			(type default)
		)
		(layer "In1.Cu")
	)
	(gr_line
		(start 61.270388 -68.661788)
		(end 60.991242 -68.383912)
		(stroke
			(width 0.254)
			(type default)
		)
		(layer "In1.Cu")
	)
	(gr_line
		(start 63.40348 -34.112454)
		(end 63.40348 -30.3403)
		(stroke
			(width 0.254)
			(type default)
		)
		(layer "In1.Cu")
	)
	(gr_line
		(start 63.40348 -30.3403)
		(end 64.038226 -29.705554)
		(stroke
			(width 0.254)
			(type default)
		)
		(layer "In1.Cu")
	)
	(gr_line
		(start 64.038226 -29.705554)
		(end 66.926968 -29.705554)
		(stroke
			(width 0.254)
			(type default)
		)
		(layer "In1.Cu")
	)
	(gr_line
		(start 64.34074 -68.661788)
		(end 61.270388 -68.661788)
		(stroke
			(width 0.254)
			(type default)
		)
		(layer "In1.Cu")
	)
	(gr_line
		(start 64.61506 -68.387468)
		(end 64.34074 -68.661788)
		(stroke
			(width 0.254)
			(type default)
		)
		(layer "In1.Cu")
	)
	(gr_line
		(start 64.61506 -64.53632)
		(end 64.61506 -68.387468)
		(stroke
			(width 0.254)
			(type default)
		)
		(layer "In1.Cu")
	)
	(gr_line
		(start 64.978788 -64.172592)
		(end 64.61506 -64.53632)
		(stroke
			(width 0.254)
			(type default)
		)
		(layer "In1.Cu")
	)
	(gr_line
		(start 65.85331 -64.172592)
		(end 64.978788 -64.172592)
		(stroke
			(width 0.254)
			(type default)
		)
		(layer "In1.Cu")
	)
	(gr_line
		(start 66.84391 -63.181992)
		(end 65.85331 -64.172592)
		(stroke
			(width 0.254)
			(type default)
		)
		(layer "In1.Cu")
	)
	(gr_line
		(start 66.84391 -62.224666)
		(end 66.84391 -63.181992)
		(stroke
			(width 0.254)
			(type default)
		)
		(layer "In1.Cu")
	)
	(gr_line
		(start 66.926968 -29.705554)
		(end 67.39636 -29.236162)
		(stroke
			(width 0.254)
			(type default)
		)
		(layer "In1.Cu")
	)
	(gr_line
		(start 67.383914 -29.223716)
		(end 67.39636 -29.236162)
		(stroke
			(width 0.254)
			(type default)
		)
		(layer "In1.Cu")
	)
	(gr_line
		(start 67.383914 -27.113992)
		(end 67.383914 -29.223716)
		(stroke
			(width 0.254)
			(type default)
		)
		(layer "In1.Cu")
	)
	(gr_line
		(start 67.383914 -27.113992)
		(end 67.383914 -25.796748)
		(stroke
			(width 0.254)
			(type default)
		)
		(layer "In1.Cu")
	)
	(gr_line
		(start 67.383914 -25.796748)
		(end 67.85356 -25.327102)
		(stroke
			(width 0.254)
			(type default)
		)
		(layer "In1.Cu")
	)
	(gr_line
		(start 67.39636 -29.236162)
		(end 67.39636 -27.126438)
		(stroke
			(width 0.254)
			(type default)
		)
		(layer "In1.Cu")
	)
	(gr_line
		(start 67.39636 -27.126438)
		(end 67.383914 -27.113992)
		(stroke
			(width 0.254)
			(type default)
		)
		(layer "In1.Cu")
	)
	(gr_line
		(start 67.551046 -20.55368)
		(end 67.551046 -19.097498)
		(stroke
			(width 0.254)
			(type default)
		)
		(layer "In1.Cu")
	)
	(gr_line
		(start 67.551046 -19.097498)
		(end 68.264024 -18.38452)
		(stroke
			(width 0.254)
			(type default)
		)
		(layer "In1.Cu")
	)
	(gr_line
		(start 67.85356 -25.327102)
		(end 67.85356 -20.856194)
		(stroke
			(width 0.254)
			(type default)
		)
		(layer "In1.Cu")
	)
	(gr_line
		(start 67.85356 -20.856194)
		(end 67.551046 -20.55368)
		(stroke
			(width 0.254)
			(type default)
		)
		(layer "In1.Cu")
	)
	(gr_line
		(start 68.13296 -60.935616)
		(end 66.84391 -62.224666)
		(stroke
			(width 0.254)
			(type default)
		)
		(layer "In1.Cu")
	)
	(gr_line
		(start 68.13296 -59.611006)
		(end 68.13296 -60.935616)
		(stroke
			(width 0.254)
			(type default)
		)
		(layer "In1.Cu")
	)
	(gr_line
		(start 68.264024 -18.38452)
		(end 81.392014 -18.38452)
		(stroke
			(width 0.254)
			(type default)
		)
		(layer "In1.Cu")
	)
	(gr_line
		(start 68.45427 -59.289696)
		(end 68.13296 -59.611006)
		(stroke
			(width 0.254)
			(type default)
		)
		(layer "In1.Cu")
	)
	(gr_line
		(start 72.151748 -59.289696)
		(end 68.45427 -59.289696)
		(stroke
			(width 0.254)
			(type default)
		)
		(layer "In1.Cu")
	)
	(gr_line
		(start 75.879706 -55.561738)
		(end 72.151748 -59.289696)
		(stroke
			(width 0.254)
			(type default)
		)
		(layer "In1.Cu")
	)
	(gr_line
		(start 76.76515 -55.561738)
		(end 75.879706 -55.561738)
		(stroke
			(width 0.254)
			(type default)
		)
		(layer "In1.Cu")
	)
	(gr_line
		(start 81.392014 -18.38452)
		(end 81.586832 -18.579338)
		(stroke
			(width 0.254)
			(type default)
		)
		(layer "In1.Cu")
	)
	(gr_line
		(start 81.586832 -23.396194)
		(end 81.587086 -23.396194)
		(stroke
			(width 0.254)
			(type default)
		)
		(layer "In1.Cu")
	)
	(gr_line
		(start 81.586832 -18.579338)
		(end 81.586832 -23.396194)
		(stroke
			(width 0.254)
			(type default)
		)
		(layer "In1.Cu")
	)
	(gr_line
		(start 81.587086 -23.396194)
		(end 82.582004 -24.391112)
		(stroke
			(width 0.254)
			(type default)
		)
		(layer "In1.Cu")
	)
	(gr_line
		(start 82.183986 -29.163772)
		(end 82.546444 -29.52623)
		(stroke
			(width 0.254)
			(type default)
		)
		(layer "In1.Cu")
	)
	(gr_line
		(start 82.183986 -27.058366)
		(end 82.183986 -29.163772)
		(stroke
			(width 0.254)
			(type default)
		)
		(layer "In1.Cu")
	)
	(gr_line
		(start 82.546444 -29.52623)
		(end 82.733134 -29.52623)
		(stroke
			(width 0.254)
			(type default)
		)
		(layer "In1.Cu")
	)
	(gr_line
		(start 82.57032 -26.672032)
		(end 82.183986 -27.058366)
		(stroke
			(width 0.254)
			(type default)
		)
		(layer "In1.Cu")
	)
	(gr_line
		(start 82.582004 -26.660348)
		(end 82.57032 -26.672032)
		(stroke
			(width 0.254)
			(type default)
		)
		(layer "In1.Cu")
	)
	(gr_line
		(start 82.582004 -24.391112)
		(end 82.582004 -26.660348)
		(stroke
			(width 0.254)
			(type default)
		)
		(layer "In1.Cu")
	)
	(gr_line
		(start 82.733134 -29.52623)
		(end 82.98815 -29.52623)
		(stroke
			(width 0.254)
			(type default)
		)
		(layer "In1.Cu")
	)
	(gr_line
		(start 82.98815 -29.52623)
		(end 84.59978 -31.13786)
		(stroke
			(width 0.254)
			(type default)
		)
		(layer "In1.Cu")
	)
	(gr_line
		(start 83.064604 -208.699608)
		(end 12.864084 -208.699608)
		(stroke
			(width 1.016)
			(type default)
		)
		(layer "In1.Cu")
	)
	(gr_line
		(start 83.064604 -208.699608)
		(end 83.54441 -208.222342)
		(stroke
			(width 1.016)
			(type default)
		)
		(layer "In1.Cu")
	)
	(gr_line
		(start 83.54441 -208.222342)
		(end 83.559904 -208.206848)
		(stroke
			(width 1.016)
			(type default)
		)
		(layer "In1.Cu")
	)
	(gr_line
		(start 83.559904 -208.206848)
		(end 83.559904 -201.250042)
		(stroke
			(width 1.016)
			(type default)
		)
		(layer "In1.Cu")
	)
	(gr_line
		(start 84.491322 -205.408784)
		(end 84.491322 -201.000868)
		(stroke
			(width 1.016)
			(type default)
		)
		(layer "In1.Cu")
	)
	(gr_line
		(start 84.491322 -201.000868)
		(end 84.626196 -201.135742)
		(stroke
			(width 1.016)
			(type default)
		)
		(layer "In1.Cu")
	)
	(gr_line
		(start 84.59978 -47.727108)
		(end 76.76515 -55.561738)
		(stroke
			(width 0.254)
			(type default)
		)
		(layer "In1.Cu")
	)
	(gr_line
		(start 84.59978 -31.13786)
		(end 84.59978 -47.727108)
		(stroke
			(width 0.254)
			(type default)
		)
		(layer "In1.Cu")
	)
	(gr_line
		(start 84.626196 -206.332582)
		(end 85.049868 -206.756254)
		(stroke
			(width 1.016)
			(type default)
		)
		(layer "In1.Cu")
	)
	(gr_line
		(start 84.626196 -201.135742)
		(end 84.626196 -206.332582)
		(stroke
			(width 1.016)
			(type default)
		)
		(layer "In1.Cu")
	)
	(gr_line
		(start 85.049868 -206.756254)
		(end 98.619564 -206.756254)
		(stroke
			(width 1.016)
			(type default)
		)
		(layer "In1.Cu")
	)
	(gr_line
		(start 85.460078 -208.196942)
		(end 85.464904 -208.201768)
		(stroke
			(width 1.016)
			(type default)
		)
		(layer "In1.Cu")
	)
	(gr_arc
		(start 85.460078 -201.250042)
		(mid 84.509991 -200.299828)
		(end 83.559904 -201.250042)
		(stroke
			(width 1.016)
			(type default)
		)
		(layer "In1.Cu")
	)
	(gr_line
		(start 85.460078 -201.250042)
		(end 85.460078 -208.196942)
		(stroke
			(width 1.016)
			(type default)
		)
		(layer "In1.Cu")
	)
	(gr_line
		(start 85.464904 -208.201768)
		(end 85.965284 -208.699608)
		(stroke
			(width 1.016)
			(type default)
		)
		(layer "In1.Cu")
	)
	(gr_line
		(start 85.742272 -206.659734)
		(end 84.491322 -205.408784)
		(stroke
			(width 1.016)
			(type default)
		)
		(layer "In1.Cu")
	)
	(gr_line
		(start 96.165924 -208.699608)
		(end 85.965284 -208.699608)
		(stroke
			(width 1.016)
			(type default)
		)
		(layer "In1.Cu")
	)
	(gr_line
		(start 96.165924 -208.699608)
		(end 96.659954 -208.205578)
		(stroke
			(width 1.016)
			(type default)
		)
		(layer "In1.Cu")
	)
	(gr_line
		(start 96.659954 -208.205578)
		(end 96.659954 -188.250068)
		(stroke
			(width 1.016)
			(type default)
		)
		(layer "In1.Cu")
	)
	(gr_line
		(start 97.387664 -203.946252)
		(end 97.387664 -187.277756)
		(stroke
			(width 1.016)
			(type default)
		)
		(layer "In1.Cu")
	)
	(gr_line
		(start 97.387664 -187.277756)
		(end 98.908362 -185.757058)
		(stroke
			(width 1.016)
			(type default)
		)
		(layer "In1.Cu")
	)
	(gr_line
		(start 97.79127 -203.310744)
		(end 101.409754 -203.310744)
		(stroke
			(width 1.27)
			(type default)
		)
		(layer "In1.Cu")
	)
	(gr_line
		(start 97.983802 -203.118212)
		(end 97.79127 -203.310744)
		(stroke
			(width 1.27)
			(type default)
		)
		(layer "In1.Cu")
	)
	(gr_line
		(start 97.983802 -187.681616)
		(end 97.983802 -203.118212)
		(stroke
			(width 1.27)
			(type default)
		)
		(layer "In1.Cu")
	)
	(gr_line
		(start 98.40722 -202.733148)
		(end 98.869246 -203.195174)
		(stroke
			(width 1.27)
			(type default)
		)
		(layer "In1.Cu")
	)
	(gr_line
		(start 98.40722 -188.412882)
		(end 98.40722 -202.733148)
		(stroke
			(width 1.27)
			(type default)
		)
		(layer "In1.Cu")
	)
	(gr_line
		(start 98.619564 -206.756254)
		(end 98.619564 -205.178152)
		(stroke
			(width 1.016)
			(type default)
		)
		(layer "In1.Cu")
	)
	(gr_line
		(start 98.619564 -205.178152)
		(end 97.387664 -203.946252)
		(stroke
			(width 1.016)
			(type default)
		)
		(layer "In1.Cu")
	)
	(gr_line
		(start 98.869246 -203.195174)
		(end 100.562918 -201.501502)
		(stroke
			(width 1.27)
			(type default)
		)
		(layer "In1.Cu")
	)
	(gr_line
		(start 98.908362 -185.757058)
		(end 100.794566 -185.757058)
		(stroke
			(width 1.016)
			(type default)
		)
		(layer "In1.Cu")
	)
	(gr_line
		(start 99.061778 -186.60364)
		(end 97.983802 -187.681616)
		(stroke
			(width 1.27)
			(type default)
		)
		(layer "In1.Cu")
	)
	(gr_line
		(start 99.331272 -202.232768)
		(end 100.408994 -201.155046)
		(stroke
			(width 1.27)
			(type default)
		)
		(layer "In1.Cu")
	)
	(gr_line
		(start 99.331272 -189.105794)
		(end 99.331272 -202.232768)
		(stroke
			(width 1.27)
			(type default)
		)
		(layer "In1.Cu")
	)
	(gr_line
		(start 99.562158 -187.257944)
		(end 98.40722 -188.412882)
		(stroke
			(width 1.27)
			(type default)
		)
		(layer "In1.Cu")
	)
	(gr_line
		(start 99.985576 -188.45149)
		(end 99.331272 -189.105794)
		(stroke
			(width 1.27)
			(type default)
		)
		(layer "In1.Cu")
	)
	(gr_line
		(start 100.332032 -187.257944)
		(end 99.562158 -187.257944)
		(stroke
			(width 1.27)
			(type default)
		)
		(layer "In1.Cu")
	)
	(gr_line
		(start 100.408994 -202.92568)
		(end 100.87102 -202.463654)
		(stroke
			(width 1.27)
			(type default)
		)
		(layer "In1.Cu")
	)
	(gr_line
		(start 100.408994 -201.655172)
		(end 100.408994 -202.92568)
		(stroke
			(width 1.27)
			(type default)
		)
		(layer "In1.Cu")
	)
	(gr_line
		(start 100.408994 -201.155046)
		(end 100.408994 -188.95187)
		(stroke
			(width 1.27)
			(type default)
		)
		(layer "In1.Cu")
	)
	(gr_line
		(start 100.562918 -201.501502)
		(end 100.562918 -201.501248)
		(stroke
			(width 1.27)
			(type default)
		)
		(layer "In1.Cu")
	)
	(gr_line
		(start 100.562918 -201.501248)
		(end 100.408994 -201.655172)
		(stroke
			(width 1.27)
			(type default)
		)
		(layer "In1.Cu")
	)
	(gr_line
		(start 100.601526 -188.45149)
		(end 99.985576 -188.45149)
		(stroke
			(width 1.27)
			(type default)
		)
		(layer "In1.Cu")
	)
	(gr_line
		(start 100.794566 -185.757058)
		(end 102.853236 -187.815728)
		(stroke
			(width 1.016)
			(type default)
		)
		(layer "In1.Cu")
	)
	(gr_line
		(start 100.87102 -202.463654)
		(end 100.87102 -188.720984)
		(stroke
			(width 1.27)
			(type default)
		)
		(layer "In1.Cu")
	)
	(gr_line
		(start 100.87102 -188.720984)
		(end 100.601526 -188.45149)
		(stroke
			(width 1.27)
			(type default)
		)
		(layer "In1.Cu")
	)
	(gr_line
		(start 100.947982 -186.60364)
		(end 99.061778 -186.60364)
		(stroke
			(width 1.27)
			(type default)
		)
		(layer "In1.Cu")
	)
	(gr_line
		(start 101.409754 -203.310744)
		(end 101.640894 -203.079604)
		(stroke
			(width 1.27)
			(type default)
		)
		(layer "In1.Cu")
	)
	(gr_line
		(start 101.640894 -203.079604)
		(end 101.640894 -188.566806)
		(stroke
			(width 1.27)
			(type default)
		)
		(layer "In1.Cu")
	)
	(gr_line
		(start 101.640894 -188.566806)
		(end 100.332032 -187.257944)
		(stroke
			(width 1.27)
			(type default)
		)
		(layer "In1.Cu")
	)
	(gr_line
		(start 102.064312 -203.233528)
		(end 102.064312 -187.71997)
		(stroke
			(width 1.27)
			(type default)
		)
		(layer "In1.Cu")
	)
	(gr_line
		(start 102.064312 -187.71997)
		(end 100.947982 -186.60364)
		(stroke
			(width 1.27)
			(type default)
		)
		(layer "In1.Cu")
	)
	(gr_line
		(start 102.333806 -203.503022)
		(end 102.064312 -203.233528)
		(stroke
			(width 1.27)
			(type default)
		)
		(layer "In1.Cu")
	)
	(gr_line
		(start 102.853236 -202.983592)
		(end 102.333806 -203.503022)
		(stroke
			(width 1.016)
			(type default)
		)
		(layer "In1.Cu")
	)
	(gr_line
		(start 102.853236 -187.815728)
		(end 102.853236 -202.983592)
		(stroke
			(width 1.016)
			(type default)
		)
		(layer "In1.Cu")
	)
	(gr_line
		(start 103.359966 -208.19745)
		(end 103.364284 -208.201768)
		(stroke
			(width 1.016)
			(type default)
		)
		(layer "In1.Cu")
	)
	(gr_arc
		(start 103.359966 -188.250068)
		(mid 100.00996 -184.900062)
		(end 96.659954 -188.250068)
		(stroke
			(width 1.016)
			(type default)
		)
		(layer "In1.Cu")
	)
	(gr_line
		(start 103.359966 -188.250068)
		(end 103.359966 -208.19745)
		(stroke
			(width 1.016)
			(type default)
		)
		(layer "In1.Cu")
	)
	(gr_line
		(start 103.364284 -208.201768)
		(end 103.864664 -208.699608)
		(stroke
			(width 1.016)
			(type default)
		)
		(layer "In1.Cu")
	)
	(gr_line
		(start 148.989034 -66.04889)
		(end 148.99259 -66.052446)
		(stroke
			(width 0.127)
			(type default)
		)
		(layer "In1.Cu")
	)
	(gr_line
		(start 148.989034 -65.515998)
		(end 148.989034 -66.04889)
		(stroke
			(width 0.127)
			(type default)
		)
		(layer "In1.Cu")
	)
	(gr_line
		(start 148.99259 -66.052446)
		(end 149.006052 -66.038984)
		(stroke
			(width 0.127)
			(type default)
		)
		(layer "In1.Cu")
	)
	(gr_line
		(start 148.99259 -66.052446)
		(end 150.13686 -66.052446)
		(stroke
			(width 0.127)
			(type default)
		)
		(layer "In1.Cu")
	)
	(gr_line
		(start 149.002496 -66.008758)
		(end 149.022816 -65.988438)
		(stroke
			(width 0.127)
			(type default)
		)
		(layer "In1.Cu")
	)
	(gr_line
		(start 149.002496 -65.566798)
		(end 149.002496 -66.008758)
		(stroke
			(width 0.127)
			(type default)
		)
		(layer "In1.Cu")
	)
	(gr_line
		(start 149.00275 -64.830706)
		(end 149.006306 -64.834262)
		(stroke
			(width 0.127)
			(type default)
		)
		(layer "In1.Cu")
	)
	(gr_line
		(start 149.00275 -64.297814)
		(end 149.00275 -64.830706)
		(stroke
			(width 0.127)
			(type default)
		)
		(layer "In1.Cu")
	)
	(gr_line
		(start 149.006052 -66.038984)
		(end 149.006052 -65.563242)
		(stroke
			(width 0.127)
			(type default)
		)
		(layer "In1.Cu")
	)
	(gr_line
		(start 149.006052 -65.563242)
		(end 149.002496 -65.566798)
		(stroke
			(width 0.127)
			(type default)
		)
		(layer "In1.Cu")
	)
	(gr_line
		(start 149.006306 -64.834262)
		(end 149.019768 -64.8208)
		(stroke
			(width 0.127)
			(type default)
		)
		(layer "In1.Cu")
	)
	(gr_line
		(start 149.006306 -64.834262)
		(end 150.150576 -64.834262)
		(stroke
			(width 0.127)
			(type default)
		)
		(layer "In1.Cu")
	)
	(gr_line
		(start 149.016212 -64.790574)
		(end 149.036532 -64.770254)
		(stroke
			(width 0.127)
			(type default)
		)
		(layer "In1.Cu")
	)
	(gr_line
		(start 149.016212 -64.348614)
		(end 149.016212 -64.790574)
		(stroke
			(width 0.127)
			(type default)
		)
		(layer "In1.Cu")
	)
	(gr_line
		(start 149.019514 -65.485518)
		(end 148.989034 -65.515998)
		(stroke
			(width 0.127)
			(type default)
		)
		(layer "In1.Cu")
	)
	(gr_line
		(start 149.019768 -64.8208)
		(end 149.019768 -64.345058)
		(stroke
			(width 0.127)
			(type default)
		)
		(layer "In1.Cu")
	)
	(gr_line
		(start 149.019768 -64.345058)
		(end 149.016212 -64.348614)
		(stroke
			(width 0.127)
			(type default)
		)
		(layer "In1.Cu")
	)
	(gr_line
		(start 149.022816 -65.988438)
		(end 149.022816 -65.563242)
		(stroke
			(width 0.127)
			(type default)
		)
		(layer "In1.Cu")
	)
	(gr_line
		(start 149.022816 -65.563242)
		(end 149.039834 -65.58026)
		(stroke
			(width 0.127)
			(type default)
		)
		(layer "In1.Cu")
	)
	(gr_line
		(start 149.026118 -65.880488)
		(end 149.036278 -65.890648)
		(stroke
			(width 0.127)
			(type default)
		)
		(layer "In1.Cu")
	)
	(gr_line
		(start 149.026118 -65.850008)
		(end 149.03958 -65.86347)
		(stroke
			(width 0.127)
			(type default)
		)
		(layer "In1.Cu")
	)
	(gr_line
		(start 149.03323 -64.267334)
		(end 149.00275 -64.297814)
		(stroke
			(width 0.127)
			(type default)
		)
		(layer "In1.Cu")
	)
	(gr_line
		(start 149.036278 -65.890648)
		(end 150.08606 -65.890648)
		(stroke
			(width 0.127)
			(type default)
		)
		(layer "In1.Cu")
	)
	(gr_line
		(start 149.036532 -64.770254)
		(end 149.036532 -64.345058)
		(stroke
			(width 0.127)
			(type default)
		)
		(layer "In1.Cu")
	)
	(gr_line
		(start 149.036532 -64.345058)
		(end 149.05355 -64.362076)
		(stroke
			(width 0.127)
			(type default)
		)
		(layer "In1.Cu")
	)
	(gr_line
		(start 149.03958 -65.86347)
		(end 150.109682 -65.86347)
		(stroke
			(width 0.127)
			(type default)
		)
		(layer "In1.Cu")
	)
	(gr_line
		(start 149.039834 -66.028824)
		(end 149.04974 -66.018918)
		(stroke
			(width 0.127)
			(type default)
		)
		(layer "In1.Cu")
	)
	(gr_line
		(start 149.039834 -65.58026)
		(end 149.039834 -66.028824)
		(stroke
			(width 0.127)
			(type default)
		)
		(layer "In1.Cu")
	)
	(gr_line
		(start 149.039834 -64.662304)
		(end 149.049994 -64.672464)
		(stroke
			(width 0.127)
			(type default)
		)
		(layer "In1.Cu")
	)
	(gr_line
		(start 149.039834 -64.631824)
		(end 149.053296 -64.645286)
		(stroke
			(width 0.127)
			(type default)
		)
		(layer "In1.Cu")
	)
	(gr_line
		(start 149.046438 -65.934336)
		(end 149.114002 -66.0019)
		(stroke
			(width 0.127)
			(type default)
		)
		(layer "In1.Cu")
	)
	(gr_line
		(start 149.04974 -66.018918)
		(end 149.04974 -65.54978)
		(stroke
			(width 0.127)
			(type default)
		)
		(layer "In1.Cu")
	)
	(gr_line
		(start 149.04974 -65.54978)
		(end 149.07006 -65.5701)
		(stroke
			(width 0.127)
			(type default)
		)
		(layer "In1.Cu")
	)
	(gr_line
		(start 149.049994 -64.672464)
		(end 150.099776 -64.672464)
		(stroke
			(width 0.127)
			(type default)
		)
		(layer "In1.Cu")
	)
	(gr_line
		(start 149.053296 -64.645286)
		(end 150.123398 -64.645286)
		(stroke
			(width 0.127)
			(type default)
		)
		(layer "In1.Cu")
	)
	(gr_line
		(start 149.05355 -64.81064)
		(end 149.063456 -64.800734)
		(stroke
			(width 0.127)
			(type default)
		)
		(layer "In1.Cu")
	)
	(gr_line
		(start 149.05355 -64.362076)
		(end 149.05355 -64.81064)
		(stroke
			(width 0.127)
			(type default)
		)
		(layer "In1.Cu")
	)
	(gr_line
		(start 149.0599 -65.931034)
		(end 150.04542 -65.931034)
		(stroke
			(width 0.127)
			(type default)
		)
		(layer "In1.Cu")
	)
	(gr_line
		(start 149.0599 -65.728596)
		(end 149.120606 -65.789302)
		(stroke
			(width 0.127)
			(type default)
		)
		(layer "In1.Cu")
	)
	(gr_line
		(start 149.060154 -64.716152)
		(end 149.127718 -64.783716)
		(stroke
			(width 0.127)
			(type default)
		)
		(layer "In1.Cu")
	)
	(gr_line
		(start 149.063456 -64.800734)
		(end 149.063456 -64.331596)
		(stroke
			(width 0.127)
			(type default)
		)
		(layer "In1.Cu")
	)
	(gr_line
		(start 149.063456 -64.331596)
		(end 149.083776 -64.351916)
		(stroke
			(width 0.127)
			(type default)
		)
		(layer "In1.Cu")
	)
	(gr_line
		(start 149.066758 -65.610486)
		(end 149.07006 -65.613788)
		(stroke
			(width 0.127)
			(type default)
		)
		(layer "In1.Cu")
	)
	(gr_line
		(start 149.07006 -66.018664)
		(end 149.083522 -66.005202)
		(stroke
			(width 0.127)
			(type default)
		)
		(layer "In1.Cu")
	)
	(gr_line
		(start 149.07006 -65.613788)
		(end 150.072344 -65.613788)
		(stroke
			(width 0.127)
			(type default)
		)
		(layer "In1.Cu")
	)
	(gr_line
		(start 149.07006 -65.5701)
		(end 149.07006 -66.018664)
		(stroke
			(width 0.127)
			(type default)
		)
		(layer "In1.Cu")
	)
	(gr_line
		(start 149.073362 -65.650872)
		(end 149.120606 -65.698116)
		(stroke
			(width 0.127)
			(type default)
		)
		(layer "In1.Cu")
	)
	(gr_line
		(start 149.073616 -64.71285)
		(end 150.059136 -64.71285)
		(stroke
			(width 0.127)
			(type default)
		)
		(layer "In1.Cu")
	)
	(gr_line
		(start 149.073616 -64.510412)
		(end 149.134322 -64.571118)
		(stroke
			(width 0.127)
			(type default)
		)
		(layer "In1.Cu")
	)
	(gr_line
		(start 149.076918 -65.823084)
		(end 149.124162 -65.870328)
		(stroke
			(width 0.127)
			(type default)
		)
		(layer "In1.Cu")
	)
	(gr_line
		(start 149.08022 -65.951354)
		(end 149.0599 -65.931034)
		(stroke
			(width 0.127)
			(type default)
		)
		(layer "In1.Cu")
	)
	(gr_line
		(start 149.08022 -65.947798)
		(end 149.093682 -65.934336)
		(stroke
			(width 0.127)
			(type default)
		)
		(layer "In1.Cu")
	)
	(gr_line
		(start 149.080474 -64.392302)
		(end 149.083776 -64.395604)
		(stroke
			(width 0.127)
			(type default)
		)
		(layer "In1.Cu")
	)
	(gr_line
		(start 149.083522 -66.005202)
		(end 149.083522 -65.546224)
		(stroke
			(width 0.127)
			(type default)
		)
		(layer "In1.Cu")
	)
	(gr_line
		(start 149.083522 -65.546224)
		(end 149.10054 -65.563242)
		(stroke
			(width 0.127)
			(type default)
		)
		(layer "In1.Cu")
	)
	(gr_line
		(start 149.083776 -64.80048)
		(end 149.097238 -64.787018)
		(stroke
			(width 0.127)
			(type default)
		)
		(layer "In1.Cu")
	)
	(gr_line
		(start 149.083776 -64.395604)
		(end 150.08606 -64.395604)
		(stroke
			(width 0.127)
			(type default)
		)
		(layer "In1.Cu")
	)
	(gr_line
		(start 149.083776 -64.351916)
		(end 149.083776 -64.80048)
		(stroke
			(width 0.127)
			(type default)
		)
		(layer "In1.Cu")
	)
	(gr_line
		(start 149.087078 -65.954656)
		(end 149.08022 -65.947798)
		(stroke
			(width 0.127)
			(type default)
		)
		(layer "In1.Cu")
	)
	(gr_line
		(start 149.087078 -64.432688)
		(end 149.134322 -64.479932)
		(stroke
			(width 0.127)
			(type default)
		)
		(layer "In1.Cu")
	)
	(gr_line
		(start 149.090634 -64.6049)
		(end 149.137878 -64.652144)
		(stroke
			(width 0.127)
			(type default)
		)
		(layer "In1.Cu")
	)
	(gr_line
		(start 149.093682 -65.934336)
		(end 150.062438 -65.934336)
		(stroke
			(width 0.127)
			(type default)
		)
		(layer "In1.Cu")
	)
	(gr_line
		(start 149.093936 -64.73317)
		(end 149.073616 -64.71285)
		(stroke
			(width 0.127)
			(type default)
		)
		(layer "In1.Cu")
	)
	(gr_line
		(start 149.093936 -64.729614)
		(end 149.107398 -64.716152)
		(stroke
			(width 0.127)
			(type default)
		)
		(layer "In1.Cu")
	)
	(gr_line
		(start 149.097238 -64.787018)
		(end 149.097238 -64.32804)
		(stroke
			(width 0.127)
			(type default)
		)
		(layer "In1.Cu")
	)
	(gr_line
		(start 149.097238 -64.32804)
		(end 149.114256 -64.345058)
		(stroke
			(width 0.127)
			(type default)
		)
		(layer "In1.Cu")
	)
	(gr_line
		(start 149.10054 -66.025522)
		(end 149.1107 -66.015362)
		(stroke
			(width 0.127)
			(type default)
		)
		(layer "In1.Cu")
	)
	(gr_line
		(start 149.10054 -65.563242)
		(end 149.10054 -66.025522)
		(stroke
			(width 0.127)
			(type default)
		)
		(layer "In1.Cu")
	)
	(gr_line
		(start 149.100794 -64.736472)
		(end 149.093936 -64.729614)
		(stroke
			(width 0.127)
			(type default)
		)
		(layer "In1.Cu")
	)
	(gr_line
		(start 149.107398 -64.716152)
		(end 150.076154 -64.716152)
		(stroke
			(width 0.127)
			(type default)
		)
		(layer "In1.Cu")
	)
	(gr_line
		(start 149.1107 -66.015362)
		(end 149.1107 -65.54978)
		(stroke
			(width 0.127)
			(type default)
		)
		(layer "In1.Cu")
	)
	(gr_line
		(start 149.1107 -65.54978)
		(end 149.130766 -65.569846)
		(stroke
			(width 0.127)
			(type default)
		)
		(layer "In1.Cu")
	)
	(gr_line
		(start 149.114002 -66.0019)
		(end 150.03526 -66.0019)
		(stroke
			(width 0.127)
			(type default)
		)
		(layer "In1.Cu")
	)
	(gr_line
		(start 149.114256 -64.807338)
		(end 149.124416 -64.797178)
		(stroke
			(width 0.127)
			(type default)
		)
		(layer "In1.Cu")
	)
	(gr_line
		(start 149.114256 -64.345058)
		(end 149.114256 -64.807338)
		(stroke
			(width 0.127)
			(type default)
		)
		(layer "In1.Cu")
	)
	(gr_line
		(start 149.120606 -65.789302)
		(end 150.082504 -65.789302)
		(stroke
			(width 0.127)
			(type default)
		)
		(layer "In1.Cu")
	)
	(gr_line
		(start 149.120606 -65.698116)
		(end 150.116286 -65.698116)
		(stroke
			(width 0.127)
			(type default)
		)
		(layer "In1.Cu")
	)
	(gr_line
		(start 149.124162 -65.870328)
		(end 150.042118 -65.870328)
		(stroke
			(width 0.127)
			(type default)
		)
		(layer "In1.Cu")
	)
	(gr_line
		(start 149.124416 -64.797178)
		(end 149.124416 -64.331596)
		(stroke
			(width 0.127)
			(type default)
		)
		(layer "In1.Cu")
	)
	(gr_line
		(start 149.124416 -64.331596)
		(end 149.144482 -64.351662)
		(stroke
			(width 0.127)
			(type default)
		)
		(layer "In1.Cu")
	)
	(gr_line
		(start 149.127718 -64.783716)
		(end 150.048976 -64.783716)
		(stroke
			(width 0.127)
			(type default)
		)
		(layer "In1.Cu")
	)
	(gr_line
		(start 149.130766 -66.018664)
		(end 149.147784 -66.001646)
		(stroke
			(width 0.127)
			(type default)
		)
		(layer "In1.Cu")
	)
	(gr_line
		(start 149.130766 -65.569846)
		(end 149.130766 -66.018664)
		(stroke
			(width 0.127)
			(type default)
		)
		(layer "In1.Cu")
	)
	(gr_line
		(start 149.134322 -64.571118)
		(end 150.09622 -64.571118)
		(stroke
			(width 0.127)
			(type default)
		)
		(layer "In1.Cu")
	)
	(gr_line
		(start 149.134322 -64.479932)
		(end 150.130002 -64.479932)
		(stroke
			(width 0.127)
			(type default)
		)
		(layer "In1.Cu")
	)
	(gr_line
		(start 149.137878 -64.652144)
		(end 150.055834 -64.652144)
		(stroke
			(width 0.127)
			(type default)
		)
		(layer "In1.Cu")
	)
	(gr_line
		(start 149.144482 -64.80048)
		(end 149.1615 -64.783462)
		(stroke
			(width 0.127)
			(type default)
		)
		(layer "In1.Cu")
	)
	(gr_line
		(start 149.144482 -64.351662)
		(end 149.144482 -64.80048)
		(stroke
			(width 0.127)
			(type default)
		)
		(layer "In1.Cu")
	)
	(gr_line
		(start 149.147784 -66.001646)
		(end 149.147784 -65.52946)
		(stroke
			(width 0.127)
			(type default)
		)
		(layer "In1.Cu")
	)
	(gr_line
		(start 149.147784 -65.52946)
		(end 149.066758 -65.610486)
		(stroke
			(width 0.127)
			(type default)
		)
		(layer "In1.Cu")
	)
	(gr_line
		(start 149.147784 -65.52946)
		(end 149.174708 -65.556384)
		(stroke
			(width 0.127)
			(type default)
		)
		(layer "In1.Cu")
	)
	(gr_line
		(start 149.1615 -64.783462)
		(end 149.1615 -64.311276)
		(stroke
			(width 0.127)
			(type default)
		)
		(layer "In1.Cu")
	)
	(gr_line
		(start 149.1615 -64.311276)
		(end 149.080474 -64.392302)
		(stroke
			(width 0.127)
			(type default)
		)
		(layer "In1.Cu")
	)
	(gr_line
		(start 149.1615 -64.311276)
		(end 149.188424 -64.3382)
		(stroke
			(width 0.127)
			(type default)
		)
		(layer "In1.Cu")
	)
	(gr_line
		(start 149.174708 -65.998598)
		(end 149.211792 -65.961514)
		(stroke
			(width 0.127)
			(type default)
		)
		(layer "In1.Cu")
	)
	(gr_line
		(start 149.174708 -65.556384)
		(end 149.174708 -65.998598)
		(stroke
			(width 0.127)
			(type default)
		)
		(layer "In1.Cu")
	)
	(gr_line
		(start 149.188424 -64.780414)
		(end 149.225508 -64.74333)
		(stroke
			(width 0.127)
			(type default)
		)
		(layer "In1.Cu")
	)
	(gr_line
		(start 149.188424 -64.3382)
		(end 149.188424 -64.780414)
		(stroke
			(width 0.127)
			(type default)
		)
		(layer "In1.Cu")
	)
	(gr_line
		(start 149.211792 -65.961514)
		(end 149.211792 -65.569846)
		(stroke
			(width 0.127)
			(type default)
		)
		(layer "In1.Cu")
	)
	(gr_line
		(start 149.211792 -65.569846)
		(end 149.245574 -65.603628)
		(stroke
			(width 0.127)
			(type default)
		)
		(layer "In1.Cu")
	)
	(gr_line
		(start 149.225508 -64.74333)
		(end 149.225508 -64.351662)
		(stroke
			(width 0.127)
			(type default)
		)
		(layer "In1.Cu")
	)
	(gr_line
		(start 149.225508 -64.351662)
		(end 149.25929 -64.385444)
		(stroke
			(width 0.127)
			(type default)
		)
		(layer "In1.Cu")
	)
	(gr_line
		(start 149.245574 -66.008758)
		(end 149.262592 -65.99174)
		(stroke
			(width 0.127)
			(type default)
		)
		(layer "In1.Cu")
	)
	(gr_line
		(start 149.245574 -65.603628)
		(end 149.245574 -66.008758)
		(stroke
			(width 0.127)
			(type default)
		)
		(layer "In1.Cu")
	)
	(gr_line
		(start 149.25929 -64.790574)
		(end 149.276308 -64.773556)
		(stroke
			(width 0.127)
			(type default)
		)
		(layer "In1.Cu")
	)
	(gr_line
		(start 149.25929 -64.385444)
		(end 149.25929 -64.790574)
		(stroke
			(width 0.127)
			(type default)
		)
		(layer "In1.Cu")
	)
	(gr_line
		(start 149.262592 -65.99174)
		(end 149.262592 -65.532762)
		(stroke
			(width 0.127)
			(type default)
		)
		(layer "In1.Cu")
	)
	(gr_line
		(start 149.262592 -65.532762)
		(end 149.286214 -65.556384)
		(stroke
			(width 0.127)
			(type default)
		)
		(layer "In1.Cu")
	)
	(gr_line
		(start 149.276308 -64.773556)
		(end 149.276308 -64.314578)
		(stroke
			(width 0.127)
			(type default)
		)
		(layer "In1.Cu")
	)
	(gr_line
		(start 149.276308 -64.314578)
		(end 149.29993 -64.3382)
		(stroke
			(width 0.127)
			(type default)
		)
		(layer "In1.Cu")
	)
	(gr_line
		(start 149.286214 -66.015362)
		(end 149.313138 -65.988438)
		(stroke
			(width 0.127)
			(type default)
		)
		(layer "In1.Cu")
	)
	(gr_line
		(start 149.286214 -65.556384)
		(end 149.286214 -66.015362)
		(stroke
			(width 0.127)
			(type default)
		)
		(layer "In1.Cu")
	)
	(gr_line
		(start 149.29993 -64.797178)
		(end 149.326854 -64.770254)
		(stroke
			(width 0.127)
			(type default)
		)
		(layer "In1.Cu")
	)
	(gr_line
		(start 149.29993 -64.3382)
		(end 149.29993 -64.797178)
		(stroke
			(width 0.127)
			(type default)
		)
		(layer "In1.Cu")
	)
	(gr_line
		(start 149.313138 -65.988438)
		(end 149.313138 -65.54978)
		(stroke
			(width 0.127)
			(type default)
		)
		(layer "In1.Cu")
	)
	(gr_line
		(start 149.313138 -65.54978)
		(end 149.350222 -65.586864)
		(stroke
			(width 0.127)
			(type default)
		)
		(layer "In1.Cu")
	)
	(gr_line
		(start 149.326854 -64.770254)
		(end 149.326854 -64.331596)
		(stroke
			(width 0.127)
			(type default)
		)
		(layer "In1.Cu")
	)
	(gr_line
		(start 149.326854 -64.331596)
		(end 149.363938 -64.36868)
		(stroke
			(width 0.127)
			(type default)
		)
		(layer "In1.Cu")
	)
	(gr_line
		(start 149.350222 -66.025522)
		(end 149.370542 -66.005202)
		(stroke
			(width 0.127)
			(type default)
		)
		(layer "In1.Cu")
	)
	(gr_line
		(start 149.350222 -65.586864)
		(end 149.350222 -66.025522)
		(stroke
			(width 0.127)
			(type default)
		)
		(layer "In1.Cu")
	)
	(gr_line
		(start 149.363938 -64.807338)
		(end 149.384258 -64.787018)
		(stroke
			(width 0.127)
			(type default)
		)
		(layer "In1.Cu")
	)
	(gr_line
		(start 149.363938 -64.36868)
		(end 149.363938 -64.807338)
		(stroke
			(width 0.127)
			(type default)
		)
		(layer "In1.Cu")
	)
	(gr_line
		(start 149.370542 -66.005202)
		(end 149.370542 -65.50914)
		(stroke
			(width 0.127)
			(type default)
		)
		(layer "In1.Cu")
	)
	(gr_line
		(start 149.370542 -65.50914)
		(end 149.431248 -65.569846)
		(stroke
			(width 0.127)
			(type default)
		)
		(layer "In1.Cu")
	)
	(gr_line
		(start 149.384258 -64.787018)
		(end 149.384258 -64.290956)
		(stroke
			(width 0.127)
			(type default)
		)
		(layer "In1.Cu")
	)
	(gr_line
		(start 149.384258 -64.290956)
		(end 149.444964 -64.351662)
		(stroke
			(width 0.127)
			(type default)
		)
		(layer "In1.Cu")
	)
	(gr_line
		(start 149.431248 -66.0019)
		(end 149.471634 -65.961514)
		(stroke
			(width 0.127)
			(type default)
		)
		(layer "In1.Cu")
	)
	(gr_line
		(start 149.431248 -65.569846)
		(end 149.431248 -66.0019)
		(stroke
			(width 0.127)
			(type default)
		)
		(layer "In1.Cu")
	)
	(gr_line
		(start 149.444964 -64.783716)
		(end 149.48535 -64.74333)
		(stroke
			(width 0.127)
			(type default)
		)
		(layer "In1.Cu")
	)
	(gr_line
		(start 149.444964 -64.351662)
		(end 149.444964 -64.783716)
		(stroke
			(width 0.127)
			(type default)
		)
		(layer "In1.Cu")
	)
	(gr_line
		(start 149.471634 -65.961514)
		(end 149.471634 -65.536064)
		(stroke
			(width 0.127)
			(type default)
		)
		(layer "In1.Cu")
	)
	(gr_line
		(start 149.471634 -65.536064)
		(end 149.495256 -65.559686)
		(stroke
			(width 0.127)
			(type default)
		)
		(layer "In1.Cu")
	)
	(gr_line
		(start 149.48535 -64.74333)
		(end 149.48535 -64.31788)
		(stroke
			(width 0.127)
			(type default)
		)
		(layer "In1.Cu")
	)
	(gr_line
		(start 149.48535 -64.31788)
		(end 149.508972 -64.341502)
		(stroke
			(width 0.127)
			(type default)
		)
		(layer "In1.Cu")
	)
	(gr_line
		(start 149.495256 -66.02222)
		(end 149.539198 -65.978278)
		(stroke
			(width 0.127)
			(type default)
		)
		(layer "In1.Cu")
	)
	(gr_line
		(start 149.495256 -65.559686)
		(end 149.495256 -66.02222)
		(stroke
			(width 0.127)
			(type default)
		)
		(layer "In1.Cu")
	)
	(gr_line
		(start 149.508972 -64.804036)
		(end 149.552914 -64.760094)
		(stroke
			(width 0.127)
			(type default)
		)
		(layer "In1.Cu")
	)
	(gr_line
		(start 149.508972 -64.341502)
		(end 149.508972 -64.804036)
		(stroke
			(width 0.127)
			(type default)
		)
		(layer "In1.Cu")
	)
	(gr_line
		(start 149.539198 -65.978278)
		(end 149.539198 -65.542922)
		(stroke
			(width 0.127)
			(type default)
		)
		(layer "In1.Cu")
	)
	(gr_line
		(start 149.539198 -65.542922)
		(end 149.569678 -65.573402)
		(stroke
			(width 0.127)
			(type default)
		)
		(layer "In1.Cu")
	)
	(gr_line
		(start 149.552914 -64.760094)
		(end 149.552914 -64.324738)
		(stroke
			(width 0.127)
			(type default)
		)
		(layer "In1.Cu")
	)
	(gr_line
		(start 149.552914 -64.324738)
		(end 149.583394 -64.355218)
		(stroke
			(width 0.127)
			(type default)
		)
		(layer "In1.Cu")
	)
	(gr_line
		(start 149.569678 -65.998598)
		(end 149.589744 -65.978532)
		(stroke
			(width 0.127)
			(type default)
		)
		(layer "In1.Cu")
	)
	(gr_line
		(start 149.569678 -65.573402)
		(end 149.569678 -65.998598)
		(stroke
			(width 0.127)
			(type default)
		)
		(layer "In1.Cu")
	)
	(gr_line
		(start 149.583394 -64.780414)
		(end 149.60346 -64.760348)
		(stroke
			(width 0.127)
			(type default)
		)
		(layer "In1.Cu")
	)
	(gr_line
		(start 149.583394 -64.355218)
		(end 149.583394 -64.780414)
		(stroke
			(width 0.127)
			(type default)
		)
		(layer "In1.Cu")
	)
	(gr_line
		(start 149.589744 -65.978532)
		(end 149.589744 -65.563242)
		(stroke
			(width 0.127)
			(type default)
		)
		(layer "In1.Cu")
	)
	(gr_line
		(start 149.589744 -65.563242)
		(end 149.630384 -65.603882)
		(stroke
			(width 0.127)
			(type default)
		)
		(layer "In1.Cu")
	)
	(gr_line
		(start 149.60346 -64.760348)
		(end 149.60346 -64.345058)
		(stroke
			(width 0.127)
			(type default)
		)
		(layer "In1.Cu")
	)
	(gr_line
		(start 149.60346 -64.345058)
		(end 149.6441 -64.385698)
		(stroke
			(width 0.127)
			(type default)
		)
		(layer "In1.Cu")
	)
	(gr_line
		(start 149.630384 -66.0019)
		(end 149.640544 -65.99174)
		(stroke
			(width 0.127)
			(type default)
		)
		(layer "In1.Cu")
	)
	(gr_line
		(start 149.630384 -65.603882)
		(end 149.630384 -66.0019)
		(stroke
			(width 0.127)
			(type default)
		)
		(layer "In1.Cu")
	)
	(gr_line
		(start 149.640544 -65.99174)
		(end 149.640544 -65.536064)
		(stroke
			(width 0.127)
			(type default)
		)
		(layer "In1.Cu")
	)
	(gr_line
		(start 149.640544 -65.536064)
		(end 149.69109 -65.58661)
		(stroke
			(width 0.127)
			(type default)
		)
		(layer "In1.Cu")
	)
	(gr_line
		(start 149.6441 -64.783716)
		(end 149.65426 -64.773556)
		(stroke
			(width 0.127)
			(type default)
		)
		(layer "In1.Cu")
	)
	(gr_line
		(start 149.6441 -64.385698)
		(end 149.6441 -64.783716)
		(stroke
			(width 0.127)
			(type default)
		)
		(layer "In1.Cu")
	)
	(gr_line
		(start 149.65426 -64.773556)
		(end 149.65426 -64.31788)
		(stroke
			(width 0.127)
			(type default)
		)
		(layer "In1.Cu")
	)
	(gr_line
		(start 149.65426 -64.31788)
		(end 149.704806 -64.368426)
		(stroke
			(width 0.127)
			(type default)
		)
		(layer "In1.Cu")
	)
	(gr_line
		(start 149.69109 -66.015362)
		(end 149.694392 -66.01206)
		(stroke
			(width 0.127)
			(type default)
		)
		(layer "In1.Cu")
	)
	(gr_line
		(start 149.69109 -65.58661)
		(end 149.69109 -66.015362)
		(stroke
			(width 0.127)
			(type default)
		)
		(layer "In1.Cu")
	)
	(gr_line
		(start 149.694392 -66.01206)
		(end 149.694392 -65.54978)
		(stroke
			(width 0.127)
			(type default)
		)
		(layer "In1.Cu")
	)
	(gr_line
		(start 149.694392 -65.54978)
		(end 149.728174 -65.583562)
		(stroke
			(width 0.127)
			(type default)
		)
		(layer "In1.Cu")
	)
	(gr_line
		(start 149.704806 -64.797178)
		(end 149.708108 -64.793876)
		(stroke
			(width 0.127)
			(type default)
		)
		(layer "In1.Cu")
	)
	(gr_line
		(start 149.704806 -64.368426)
		(end 149.704806 -64.797178)
		(stroke
			(width 0.127)
			(type default)
		)
		(layer "In1.Cu")
	)
	(gr_line
		(start 149.708108 -64.793876)
		(end 149.708108 -64.331596)
		(stroke
			(width 0.127)
			(type default)
		)
		(layer "In1.Cu")
	)
	(gr_line
		(start 149.708108 -64.331596)
		(end 149.74189 -64.365378)
		(stroke
			(width 0.127)
			(type default)
		)
		(layer "In1.Cu")
	)
	(gr_line
		(start 149.728174 -65.99174)
		(end 149.751796 -65.968118)
		(stroke
			(width 0.127)
			(type default)
		)
		(layer "In1.Cu")
	)
	(gr_line
		(start 149.728174 -65.583562)
		(end 149.728174 -65.99174)
		(stroke
			(width 0.127)
			(type default)
		)
		(layer "In1.Cu")
	)
	(gr_line
		(start 149.74189 -64.773556)
		(end 149.765512 -64.749934)
		(stroke
			(width 0.127)
			(type default)
		)
		(layer "In1.Cu")
	)
	(gr_line
		(start 149.74189 -64.365378)
		(end 149.74189 -64.773556)
		(stroke
			(width 0.127)
			(type default)
		)
		(layer "In1.Cu")
	)
	(gr_line
		(start 149.751796 -65.968118)
		(end 149.751796 -65.553082)
		(stroke
			(width 0.127)
			(type default)
		)
		(layer "In1.Cu")
	)
	(gr_line
		(start 149.751796 -65.553082)
		(end 149.78888 -65.590166)
		(stroke
			(width 0.127)
			(type default)
		)
		(layer "In1.Cu")
	)
	(gr_line
		(start 149.765512 -64.749934)
		(end 149.765512 -64.334898)
		(stroke
			(width 0.127)
			(type default)
		)
		(layer "In1.Cu")
	)
	(gr_line
		(start 149.765512 -64.334898)
		(end 149.802596 -64.371982)
		(stroke
			(width 0.127)
			(type default)
		)
		(layer "In1.Cu")
	)
	(gr_line
		(start 149.78888 -66.0019)
		(end 149.802342 -65.988438)
		(stroke
			(width 0.127)
			(type default)
		)
		(layer "In1.Cu")
	)
	(gr_line
		(start 149.78888 -65.590166)
		(end 149.78888 -66.0019)
		(stroke
			(width 0.127)
			(type default)
		)
		(layer "In1.Cu")
	)
	(gr_line
		(start 149.802342 -65.988438)
		(end 149.802342 -65.556384)
		(stroke
			(width 0.127)
			(type default)
		)
		(layer "In1.Cu")
	)
	(gr_line
		(start 149.802342 -65.556384)
		(end 149.846284 -65.600326)
		(stroke
			(width 0.127)
			(type default)
		)
		(layer "In1.Cu")
	)
	(gr_line
		(start 149.802596 -64.783716)
		(end 149.816058 -64.770254)
		(stroke
			(width 0.127)
			(type default)
		)
		(layer "In1.Cu")
	)
	(gr_line
		(start 149.802596 -64.371982)
		(end 149.802596 -64.783716)
		(stroke
			(width 0.127)
			(type default)
		)
		(layer "In1.Cu")
	)
	(gr_line
		(start 149.816058 -64.770254)
		(end 149.816058 -64.3382)
		(stroke
			(width 0.127)
			(type default)
		)
		(layer "In1.Cu")
	)
	(gr_line
		(start 149.816058 -64.3382)
		(end 149.86 -64.382142)
		(stroke
			(width 0.127)
			(type default)
		)
		(layer "In1.Cu")
	)
	(gr_line
		(start 149.846284 -65.995042)
		(end 149.856444 -65.984882)
		(stroke
			(width 0.127)
			(type default)
		)
		(layer "In1.Cu")
	)
	(gr_line
		(start 149.846284 -65.600326)
		(end 149.846284 -65.995042)
		(stroke
			(width 0.127)
			(type default)
		)
		(layer "In1.Cu")
	)
	(gr_line
		(start 149.856444 -65.984882)
		(end 149.856444 -65.553082)
		(stroke
			(width 0.127)
			(type default)
		)
		(layer "In1.Cu")
	)
	(gr_line
		(start 149.856444 -65.553082)
		(end 149.880066 -65.576704)
		(stroke
			(width 0.127)
			(type default)
		)
		(layer "In1.Cu")
	)
	(gr_line
		(start 149.86 -64.776858)
		(end 149.87016 -64.766698)
		(stroke
			(width 0.127)
			(type default)
		)
		(layer "In1.Cu")
	)
	(gr_line
		(start 149.86 -64.382142)
		(end 149.86 -64.776858)
		(stroke
			(width 0.127)
			(type default)
		)
		(layer "In1.Cu")
	)
	(gr_line
		(start 149.87016 -64.766698)
		(end 149.87016 -64.334898)
		(stroke
			(width 0.127)
			(type default)
		)
		(layer "In1.Cu")
	)
	(gr_line
		(start 149.87016 -64.334898)
		(end 149.893782 -64.35852)
		(stroke
			(width 0.127)
			(type default)
		)
		(layer "In1.Cu")
	)
	(gr_line
		(start 149.880066 -65.998598)
		(end 149.893528 -65.985136)
		(stroke
			(width 0.127)
			(type default)
		)
		(layer "In1.Cu")
	)
	(gr_line
		(start 149.880066 -65.576704)
		(end 149.880066 -65.998598)
		(stroke
			(width 0.127)
			(type default)
		)
		(layer "In1.Cu")
	)
	(gr_line
		(start 149.893528 -65.985136)
		(end 149.893528 -65.559686)
		(stroke
			(width 0.127)
			(type default)
		)
		(layer "In1.Cu")
	)
	(gr_line
		(start 149.893528 -65.559686)
		(end 149.930612 -65.59677)
		(stroke
			(width 0.127)
			(type default)
		)
		(layer "In1.Cu")
	)
	(gr_line
		(start 149.893782 -64.780414)
		(end 149.907244 -64.766952)
		(stroke
			(width 0.127)
			(type default)
		)
		(layer "In1.Cu")
	)
	(gr_line
		(start 149.893782 -64.35852)
		(end 149.893782 -64.780414)
		(stroke
			(width 0.127)
			(type default)
		)
		(layer "In1.Cu")
	)
	(gr_line
		(start 149.907244 -64.766952)
		(end 149.907244 -64.341502)
		(stroke
			(width 0.127)
			(type default)
		)
		(layer "In1.Cu")
	)
	(gr_line
		(start 149.907244 -64.341502)
		(end 149.944328 -64.378586)
		(stroke
			(width 0.127)
			(type default)
		)
		(layer "In1.Cu")
	)
	(gr_line
		(start 149.930612 -65.985136)
		(end 149.954234 -66.008758)
		(stroke
			(width 0.127)
			(type default)
		)
		(layer "In1.Cu")
	)
	(gr_line
		(start 149.930612 -65.59677)
		(end 149.930612 -65.985136)
		(stroke
			(width 0.127)
			(type default)
		)
		(layer "In1.Cu")
	)
	(gr_line
		(start 149.944328 -64.766952)
		(end 149.96795 -64.790574)
		(stroke
			(width 0.127)
			(type default)
		)
		(layer "In1.Cu")
	)
	(gr_line
		(start 149.944328 -64.378586)
		(end 149.944328 -64.766952)
		(stroke
			(width 0.127)
			(type default)
		)
		(layer "In1.Cu")
	)
	(gr_line
		(start 149.954234 -66.008758)
		(end 150.069042 -66.008758)
		(stroke
			(width 0.127)
			(type default)
		)
		(layer "In1.Cu")
	)
	(gr_line
		(start 149.96795 -64.790574)
		(end 150.082758 -64.790574)
		(stroke
			(width 0.127)
			(type default)
		)
		(layer "In1.Cu")
	)
	(gr_line
		(start 149.97811 -65.934336)
		(end 149.046438 -65.934336)
		(stroke
			(width 0.127)
			(type default)
		)
		(layer "In1.Cu")
	)
	(gr_line
		(start 149.991826 -64.716152)
		(end 149.060154 -64.716152)
		(stroke
			(width 0.127)
			(type default)
		)
		(layer "In1.Cu")
	)
	(gr_line
		(start 149.994874 -65.948052)
		(end 149.994874 -65.52946)
		(stroke
			(width 0.127)
			(type default)
		)
		(layer "In1.Cu")
	)
	(gr_line
		(start 149.994874 -65.52946)
		(end 149.147784 -65.52946)
		(stroke
			(width 0.127)
			(type default)
		)
		(layer "In1.Cu")
	)
	(gr_line
		(start 149.998176 -65.951354)
		(end 149.08022 -65.951354)
		(stroke
			(width 0.127)
			(type default)
		)
		(layer "In1.Cu")
	)
	(gr_line
		(start 149.998176 -65.586864)
		(end 149.998176 -65.951354)
		(stroke
			(width 0.127)
			(type default)
		)
		(layer "In1.Cu")
	)
	(gr_line
		(start 150.001478 -65.954656)
		(end 149.994874 -65.948052)
		(stroke
			(width 0.127)
			(type default)
		)
		(layer "In1.Cu")
	)
	(gr_line
		(start 150.001478 -65.597024)
		(end 150.001478 -65.954656)
		(stroke
			(width 0.127)
			(type default)
		)
		(layer "In1.Cu")
	)
	(gr_line
		(start 150.00859 -65.880488)
		(end 149.026118 -65.880488)
		(stroke
			(width 0.127)
			(type default)
		)
		(layer "In1.Cu")
	)
	(gr_line
		(start 150.00859 -64.729868)
		(end 150.00859 -64.311276)
		(stroke
			(width 0.127)
			(type default)
		)
		(layer "In1.Cu")
	)
	(gr_line
		(start 150.00859 -64.311276)
		(end 149.1615 -64.311276)
		(stroke
			(width 0.127)
			(type default)
		)
		(layer "In1.Cu")
	)
	(gr_line
		(start 150.011892 -64.73317)
		(end 149.093936 -64.73317)
		(stroke
			(width 0.127)
			(type default)
		)
		(layer "In1.Cu")
	)
	(gr_line
		(start 150.011892 -64.36868)
		(end 150.011892 -64.73317)
		(stroke
			(width 0.127)
			(type default)
		)
		(layer "In1.Cu")
	)
	(gr_line
		(start 150.015194 -64.736472)
		(end 150.00859 -64.729868)
		(stroke
			(width 0.127)
			(type default)
		)
		(layer "In1.Cu")
	)
	(gr_line
		(start 150.015194 -64.37884)
		(end 150.015194 -64.736472)
		(stroke
			(width 0.127)
			(type default)
		)
		(layer "In1.Cu")
	)
	(gr_line
		(start 150.021798 -65.563242)
		(end 149.998176 -65.586864)
		(stroke
			(width 0.127)
			(type default)
		)
		(layer "In1.Cu")
	)
	(gr_line
		(start 150.022306 -64.662304)
		(end 149.039834 -64.662304)
		(stroke
			(width 0.127)
			(type default)
		)
		(layer "In1.Cu")
	)
	(gr_line
		(start 150.03526 -66.0019)
		(end 150.03526 -65.576704)
		(stroke
			(width 0.127)
			(type default)
		)
		(layer "In1.Cu")
	)
	(gr_line
		(start 150.03526 -65.97142)
		(end 150.03526 -65.563242)
		(stroke
			(width 0.127)
			(type default)
		)
		(layer "In1.Cu")
	)
	(gr_line
		(start 150.03526 -65.650872)
		(end 149.073362 -65.650872)
		(stroke
			(width 0.127)
			(type default)
		)
		(layer "In1.Cu")
	)
	(gr_line
		(start 150.03526 -65.576704)
		(end 150.021798 -65.563242)
		(stroke
			(width 0.127)
			(type default)
		)
		(layer "In1.Cu")
	)
	(gr_line
		(start 150.03526 -65.563242)
		(end 150.001478 -65.597024)
		(stroke
			(width 0.127)
			(type default)
		)
		(layer "In1.Cu")
	)
	(gr_line
		(start 150.035514 -64.345058)
		(end 150.011892 -64.36868)
		(stroke
			(width 0.127)
			(type default)
		)
		(layer "In1.Cu")
	)
	(gr_line
		(start 150.042118 -65.870328)
		(end 149.97811 -65.934336)
		(stroke
			(width 0.127)
			(type default)
		)
		(layer "In1.Cu")
	)
	(gr_line
		(start 150.04542 -65.931034)
		(end 150.069042 -65.954656)
		(stroke
			(width 0.127)
			(type default)
		)
		(layer "In1.Cu")
	)
	(gr_line
		(start 150.04542 -65.850008)
		(end 149.026118 -65.850008)
		(stroke
			(width 0.127)
			(type default)
		)
		(layer "In1.Cu")
	)
	(gr_line
		(start 150.048722 -65.823084)
		(end 149.076918 -65.823084)
		(stroke
			(width 0.127)
			(type default)
		)
		(layer "In1.Cu")
	)
	(gr_line
		(start 150.048976 -64.783716)
		(end 150.048976 -64.35852)
		(stroke
			(width 0.127)
			(type default)
		)
		(layer "In1.Cu")
	)
	(gr_line
		(start 150.048976 -64.753236)
		(end 150.048976 -64.345058)
		(stroke
			(width 0.127)
			(type default)
		)
		(layer "In1.Cu")
	)
	(gr_line
		(start 150.048976 -64.432688)
		(end 149.087078 -64.432688)
		(stroke
			(width 0.127)
			(type default)
		)
		(layer "In1.Cu")
	)
	(gr_line
		(start 150.048976 -64.35852)
		(end 150.035514 -64.345058)
		(stroke
			(width 0.127)
			(type default)
		)
		(layer "In1.Cu")
	)
	(gr_line
		(start 150.048976 -64.345058)
		(end 150.015194 -64.37884)
		(stroke
			(width 0.127)
			(type default)
		)
		(layer "In1.Cu")
	)
	(gr_line
		(start 150.052278 -65.988438)
		(end 150.03526 -65.97142)
		(stroke
			(width 0.127)
			(type default)
		)
		(layer "In1.Cu")
	)
	(gr_line
		(start 150.052278 -65.532762)
		(end 150.052278 -65.988438)
		(stroke
			(width 0.127)
			(type default)
		)
		(layer "In1.Cu")
	)
	(gr_line
		(start 150.055834 -64.652144)
		(end 149.991826 -64.716152)
		(stroke
			(width 0.127)
			(type default)
		)
		(layer "In1.Cu")
	)
	(gr_line
		(start 150.059136 -64.71285)
		(end 150.082758 -64.736472)
		(stroke
			(width 0.127)
			(type default)
		)
		(layer "In1.Cu")
	)
	(gr_line
		(start 150.059136 -64.631824)
		(end 149.039834 -64.631824)
		(stroke
			(width 0.127)
			(type default)
		)
		(layer "In1.Cu")
	)
	(gr_line
		(start 150.062438 -65.934336)
		(end 150.00859 -65.880488)
		(stroke
			(width 0.127)
			(type default)
		)
		(layer "In1.Cu")
	)
	(gr_line
		(start 150.062438 -64.6049)
		(end 149.090634 -64.6049)
		(stroke
			(width 0.127)
			(type default)
		)
		(layer "In1.Cu")
	)
	(gr_line
		(start 150.065994 -64.770254)
		(end 150.048976 -64.753236)
		(stroke
			(width 0.127)
			(type default)
		)
		(layer "In1.Cu")
	)
	(gr_line
		(start 150.065994 -64.314578)
		(end 150.065994 -64.770254)
		(stroke
			(width 0.127)
			(type default)
		)
		(layer "In1.Cu")
	)
	(gr_line
		(start 150.069042 -66.008758)
		(end 150.089362 -65.988438)
		(stroke
			(width 0.127)
			(type default)
		)
		(layer "In1.Cu")
	)
	(gr_line
		(start 150.069042 -65.954656)
		(end 149.087078 -65.954656)
		(stroke
			(width 0.127)
			(type default)
		)
		(layer "In1.Cu")
	)
	(gr_line
		(start 150.069042 -65.515998)
		(end 150.052278 -65.532762)
		(stroke
			(width 0.127)
			(type default)
		)
		(layer "In1.Cu")
	)
	(gr_line
		(start 150.072344 -65.613788)
		(end 150.03526 -65.650872)
		(stroke
			(width 0.127)
			(type default)
		)
		(layer "In1.Cu")
	)
	(gr_line
		(start 150.0759 -65.829688)
		(end 149.063456 -65.829688)
		(stroke
			(width 0.127)
			(type default)
		)
		(layer "In1.Cu")
	)
	(gr_line
		(start 150.076154 -64.716152)
		(end 150.022306 -64.662304)
		(stroke
			(width 0.127)
			(type default)
		)
		(layer "In1.Cu")
	)
	(gr_line
		(start 150.082504 -65.789302)
		(end 150.048722 -65.823084)
		(stroke
			(width 0.127)
			(type default)
		)
		(layer "In1.Cu")
	)
	(gr_line
		(start 150.082758 -64.790574)
		(end 150.103078 -64.770254)
		(stroke
			(width 0.127)
			(type default)
		)
		(layer "In1.Cu")
	)
	(gr_line
		(start 150.082758 -64.736472)
		(end 149.100794 -64.736472)
		(stroke
			(width 0.127)
			(type default)
		)
		(layer "In1.Cu")
	)
	(gr_line
		(start 150.082758 -64.297814)
		(end 150.065994 -64.314578)
		(stroke
			(width 0.127)
			(type default)
		)
		(layer "In1.Cu")
	)
	(gr_line
		(start 150.085806 -65.728596)
		(end 149.0599 -65.728596)
		(stroke
			(width 0.127)
			(type default)
		)
		(layer "In1.Cu")
	)
	(gr_line
		(start 150.08606 -65.890648)
		(end 150.04542 -65.850008)
		(stroke
			(width 0.127)
			(type default)
		)
		(layer "In1.Cu")
	)
	(gr_line
		(start 150.08606 -64.395604)
		(end 150.048976 -64.432688)
		(stroke
			(width 0.127)
			(type default)
		)
		(layer "In1.Cu")
	)
	(gr_line
		(start 150.089362 -65.988438)
		(end 150.089362 -65.536318)
		(stroke
			(width 0.127)
			(type default)
		)
		(layer "In1.Cu")
	)
	(gr_line
		(start 150.089362 -65.536318)
		(end 150.069042 -65.515998)
		(stroke
			(width 0.127)
			(type default)
		)
		(layer "In1.Cu")
	)
	(gr_line
		(start 150.089616 -64.611504)
		(end 149.077172 -64.611504)
		(stroke
			(width 0.127)
			(type default)
		)
		(layer "In1.Cu")
	)
	(gr_line
		(start 150.09622 -64.571118)
		(end 150.062438 -64.6049)
		(stroke
			(width 0.127)
			(type default)
		)
		(layer "In1.Cu")
	)
	(gr_line
		(start 150.099522 -64.510412)
		(end 149.073616 -64.510412)
		(stroke
			(width 0.127)
			(type default)
		)
		(layer "In1.Cu")
	)
	(gr_line
		(start 150.099776 -64.672464)
		(end 150.059136 -64.631824)
		(stroke
			(width 0.127)
			(type default)
		)
		(layer "In1.Cu")
	)
	(gr_line
		(start 150.103078 -64.770254)
		(end 150.103078 -64.318134)
		(stroke
			(width 0.127)
			(type default)
		)
		(layer "In1.Cu")
	)
	(gr_line
		(start 150.103078 -64.318134)
		(end 150.082758 -64.297814)
		(stroke
			(width 0.127)
			(type default)
		)
		(layer "In1.Cu")
	)
	(gr_line
		(start 150.109682 -65.86347)
		(end 150.0759 -65.829688)
		(stroke
			(width 0.127)
			(type default)
		)
		(layer "In1.Cu")
	)
	(gr_line
		(start 150.116286 -65.698116)
		(end 150.085806 -65.728596)
		(stroke
			(width 0.127)
			(type default)
		)
		(layer "In1.Cu")
	)
	(gr_line
		(start 150.123398 -64.645286)
		(end 150.089616 -64.611504)
		(stroke
			(width 0.127)
			(type default)
		)
		(layer "In1.Cu")
	)
	(gr_line
		(start 150.126446 -65.485518)
		(end 149.019514 -65.485518)
		(stroke
			(width 0.127)
			(type default)
		)
		(layer "In1.Cu")
	)
	(gr_line
		(start 150.130002 -64.479932)
		(end 150.099522 -64.510412)
		(stroke
			(width 0.127)
			(type default)
		)
		(layer "In1.Cu")
	)
	(gr_line
		(start 150.13686 -66.052446)
		(end 150.156926 -66.03238)
		(stroke
			(width 0.127)
			(type default)
		)
		(layer "In1.Cu")
	)
	(gr_line
		(start 150.140162 -64.267334)
		(end 149.03323 -64.267334)
		(stroke
			(width 0.127)
			(type default)
		)
		(layer "In1.Cu")
	)
	(gr_line
		(start 150.150576 -64.834262)
		(end 150.170642 -64.814196)
		(stroke
			(width 0.127)
			(type default)
		)
		(layer "In1.Cu")
	)
	(gr_line
		(start 150.156926 -66.03238)
		(end 150.156926 -65.515998)
		(stroke
			(width 0.127)
			(type default)
		)
		(layer "In1.Cu")
	)
	(gr_line
		(start 150.156926 -65.515998)
		(end 150.126446 -65.485518)
		(stroke
			(width 0.127)
			(type default)
		)
		(layer "In1.Cu")
	)
	(gr_line
		(start 150.170642 -64.814196)
		(end 150.170642 -64.297814)
		(stroke
			(width 0.127)
			(type default)
		)
		(layer "In1.Cu")
	)
	(gr_line
		(start 150.170642 -64.297814)
		(end 150.140162 -64.267334)
		(stroke
			(width 0.127)
			(type default)
		)
		(layer "In1.Cu")
	)
	(gr_line
		(start 155.372308 -49.275238)
		(end 155.372308 -50.97526)
		(stroke
			(width 1.7018)
			(type default)
		)
		(layer "In1.Cu")
	)
	(gr_line
		(start 155.372308 -45.465238)
		(end 155.372308 -47.16526)
		(stroke
			(width 1.7018)
			(type default)
		)
		(layer "In1.Cu")
	)
	(gr_line
		(start 158.6992 -45.708062)
		(end 158.6992 -46.978062)
		(stroke
			(width 0.8128)
			(type default)
		)
		(layer "In1.Cu")
	)
	(gr_line
		(start 161.280348 -49.560734)
		(end 161.280348 -50.830734)
		(stroke
			(width 0.8128)
			(type default)
		)
		(layer "In1.Cu")
	)
	(gr_line
		(start 173.70425 -206.659734)
		(end 85.742272 -206.659734)
		(stroke
			(width 1.016)
			(type default)
		)
		(layer "In1.Cu")
	)
	(gr_line
		(start 174.065184 -208.699608)
		(end 103.864664 -208.699608)
		(stroke
			(width 1.016)
			(type default)
		)
		(layer "In1.Cu")
	)
	(gr_line
		(start 174.342552 -208.423764)
		(end 174.065184 -208.699608)
		(stroke
			(width 1.016)
			(type default)
		)
		(layer "In1.Cu")
	)
	(gr_line
		(start 174.559976 -208.20634)
		(end 174.342552 -208.423764)
		(stroke
			(width 1.016)
			(type default)
		)
		(layer "In1.Cu")
	)
	(gr_line
		(start 174.559976 -201.250042)
		(end 174.559976 -208.20634)
		(stroke
			(width 1.016)
			(type default)
		)
		(layer "In1.Cu")
	)
	(gr_line
		(start 175.494442 -204.869542)
		(end 173.70425 -206.659734)
		(stroke
			(width 1.016)
			(type default)
		)
		(layer "In1.Cu")
	)
	(gr_line
		(start 175.494442 -201.039476)
		(end 175.494442 -204.869542)
		(stroke
			(width 1.016)
			(type default)
		)
		(layer "In1.Cu")
	)
	(gr_line
		(start 175.53305 -205.543658)
		(end 175.53305 -201.000868)
		(stroke
			(width 1.016)
			(type default)
		)
		(layer "In1.Cu")
	)
	(gr_line
		(start 175.53305 -201.000868)
		(end 175.494442 -201.039476)
		(stroke
			(width 1.016)
			(type default)
		)
		(layer "In1.Cu")
	)
	(gr_line
		(start 175.879252 -205.88986)
		(end 175.53305 -205.543658)
		(stroke
			(width 1.016)
			(type default)
		)
		(layer "In1.Cu")
	)
	(gr_line
		(start 176.459896 -208.19618)
		(end 176.459896 -201.250042)
		(stroke
			(width 1.016)
			(type default)
		)
		(layer "In1.Cu")
	)
	(gr_arc
		(start 176.459896 -201.250042)
		(mid 175.509936 -200.300082)
		(end 174.559976 -201.250042)
		(stroke
			(width 1.016)
			(type default)
		)
		(layer "In1.Cu")
	)
	(gr_line
		(start 176.465484 -208.201768)
		(end 176.459896 -208.19618)
		(stroke
			(width 1.016)
			(type default)
		)
		(layer "In1.Cu")
	)
	(gr_line
		(start 176.965864 -208.699608)
		(end 176.465484 -208.201768)
		(stroke
			(width 1.016)
			(type default)
		)
		(layer "In1.Cu")
	)
	(gr_line
		(start 186.195462 -205.88986)
		(end 175.879252 -205.88986)
		(stroke
			(width 1.016)
			(type default)
		)
		(layer "In1.Cu")
	)
	(gr_line
		(start 187.004198 -204.75448)
		(end 187.524136 -204.234542)
		(stroke
			(width 1.016)
			(type default)
		)
		(layer "In1.Cu")
	)
	(gr_line
		(start 187.081414 -207.391254)
		(end 187.350908 -207.12176)
		(stroke
			(width 1.016)
			(type default)
		)
		(layer "In1.Cu")
	)
	(gr_line
		(start 187.119768 -206.814166)
		(end 12.851638 -206.814166)
		(stroke
			(width 1.016)
			(type default)
		)
		(layer "In1.Cu")
	)
	(gr_line
		(start 187.119768 -206.814166)
		(end 186.195462 -205.88986)
		(stroke
			(width 1.016)
			(type default)
		)
		(layer "In1.Cu")
	)
	(gr_line
		(start 187.163964 -208.699608)
		(end 176.965864 -208.699608)
		(stroke
			(width 1.016)
			(type default)
		)
		(layer "In1.Cu")
	)
	(gr_line
		(start 187.178188 -203.811124)
		(end 12.61999 -203.811124)
		(stroke
			(width 1.016)
			(type default)
		)
		(layer "In1.Cu")
	)
	(gr_line
		(start 187.196984 -205.5241)
		(end 13.005054 -205.5241)
		(stroke
			(width 1.016)
			(type default)
		)
		(layer "In1.Cu")
	)
	(gr_line
		(start 187.3123 -206.159608)
		(end 187.389262 -206.082646)
		(stroke
			(width 1.016)
			(type default)
		)
		(layer "In1.Cu")
	)
	(gr_line
		(start 187.31738 -203.257404)
		(end 187.524644 -203.464668)
		(stroke
			(width 0.508)
			(type default)
		)
		(layer "In1.Cu")
	)
	(gr_line
		(start 187.350908 -208.512664)
		(end 187.163964 -208.699608)
		(stroke
			(width 1.016)
			(type default)
		)
		(layer "In1.Cu")
	)
	(gr_line
		(start 187.350908 -207.12176)
		(end 187.350908 -208.512664)
		(stroke
			(width 1.016)
			(type default)
		)
		(layer "In1.Cu")
	)
	(gr_line
		(start 187.389262 -206.544672)
		(end 187.119768 -206.814166)
		(stroke
			(width 1.016)
			(type default)
		)
		(layer "In1.Cu")
	)
	(gr_line
		(start 187.389262 -206.082646)
		(end 187.389262 -206.544672)
		(stroke
			(width 1.016)
			(type default)
		)
		(layer "In1.Cu")
	)
	(gr_line
		(start 187.524136 -205.196948)
		(end 187.196984 -205.5241)
		(stroke
			(width 1.016)
			(type default)
		)
		(layer "In1.Cu")
	)
	(gr_line
		(start 187.524136 -204.234542)
		(end 187.524136 -205.196948)
		(stroke
			(width 1.016)
			(type default)
		)
		(layer "In1.Cu")
	)
	(gr_line
		(start 187.524644 -203.464668)
		(end 187.178188 -203.811124)
		(stroke
			(width 1.016)
			(type default)
		)
		(layer "In1.Cu")
	)
	(gr_line
		(start 187.62853 -208.237328)
		(end 13.54328 -208.237328)
		(stroke
			(width 1.016)
			(type default)
		)
		(layer "In1.Cu")
	)
	(gr_line
		(start 187.62853 -208.237328)
		(end 187.163964 -208.699608)
		(stroke
			(width 1.016)
			(type default)
		)
		(layer "In1.Cu")
	)
	(gr_line
		(start 187.660026 -208.205832)
		(end 187.62853 -208.237328)
		(stroke
			(width 1.016)
			(type default)
		)
		(layer "In1.Cu")
	)
	(gr_line
		(start 187.660026 -172.699934)
		(end 187.660026 -208.205832)
		(stroke
			(width 1.016)
			(type default)
		)
		(layer "In1.Cu")
	)
	(gr_arc
		(start 189.660022 -170.699938)
		(mid 188.245811 -171.285723)
		(end 187.660026 -172.699934)
		(stroke
			(width 1.016)
			(type default)
		)
		(layer "In1.Cu")
	)
	(gr_arc
		(start 196.699886 -72.650096)
		(mid 197.139352 -73.71068)
		(end 198.20001 -74.149966)
		(stroke
			(width 1.016)
			(type default)
		)
		(layer "In1.Cu")
	)
	(gr_line
		(start 196.699886 -33.64992)
		(end 196.699886 -72.650096)
		(stroke
			(width 1.016)
			(type default)
		)
		(layer "In1.Cu")
	)
	(gr_line
		(start 198.000112 -170.699938)
		(end 189.660022 -170.699938)
		(stroke
			(width 1.016)
			(type default)
		)
		(layer "In1.Cu")
	)
	(gr_arc
		(start 198.000112 -170.699938)
		(mid 199.41433 -170.114151)
		(end 200.000108 -168.699942)
		(stroke
			(width 1.016)
			(type default)
		)
		(layer "In1.Cu")
	)
	(gr_line
		(start 198.20001 -74.149966)
		(end 198.499984 -74.149966)
		(stroke
			(width 1.016)
			(type default)
		)
		(layer "In1.Cu")
	)
	(gr_arc
		(start 198.20001 -32.15005)
		(mid 197.139352 -32.589336)
		(end 196.699886 -33.64992)
		(stroke
			(width 1.016)
			(type default)
		)
		(layer "In1.Cu")
	)
	(gr_line
		(start 198.499984 -32.15005)
		(end 198.20001 -32.15005)
		(stroke
			(width 1.016)
			(type default)
		)
		(layer "In1.Cu")
	)
	(gr_arc
		(start 198.499984 -32.15005)
		(mid 199.560751 -31.710681)
		(end 200.000108 -30.649926)
		(stroke
			(width 1.016)
			(type default)
		)
		(layer "In1.Cu")
	)
	(gr_arc
		(start 200.000108 -75.65009)
		(mid 199.560727 -74.589354)
		(end 198.499984 -74.149966)
		(stroke
			(width 1.016)
			(type default)
		)
		(layer "In1.Cu")
	)
	(gr_line
		(start 200.000108 -75.65009)
		(end 200.000108 -168.699942)
		(stroke
			(width 1.016)
			(type default)
		)
		(layer "In1.Cu")
	)
	(gr_arc
		(start 200.000108 -1.999996)
		(mid 199.414322 -0.585784)
		(end 198.000112 0)
		(stroke
			(width 1.016)
			(type default)
		)
		(layer "In1.Cu")
	)
	(gr_line
		(start 200.000108 -1.999996)
		(end 200.000108 -30.649926)
		(stroke
			(width 1.016)
			(type default)
		)
		(layer "In1.Cu")
	)
	(gr_poly
		(pts
			(xy 165.3159 -140.901674) (xy 158.83636 -140.901674) (xy 158.83636 -143.152114) (xy 165.3159 -143.152114)
		)
		(stroke
			(width 0)
			(type solid)
		)
		(fill yes)
		(layer "In2.Cu")
		(net "GND")
	)
	(gr_poly
		(pts
			(xy 85.51926 -86.813644) (xy 85.51926 -82.564224) (xy 85.45068 -82.495644) (xy 83.48472 -82.495644)
			(xy 83.37804 -82.602324) (xy 83.37804 -86.760304) (xy 83.5279 -86.910164) (xy 85.42274 -86.910164)
		)
		(stroke
			(width 0)
			(type solid)
		)
		(fill yes)
		(layer "In2.Cu")
		(net "GND")
	)
	(gr_poly
		(pts
			(xy 126.17196 -123.236736) (xy 126.17196 -122.502168) (xy 125.98654 -122.316748) (xy 124.7394 -122.316748)
			(xy 124.6886 -122.367548) (xy 124.6886 -123.193048) (xy 124.79274 -123.297188) (xy 126.111508 -123.297188)
		)
		(stroke
			(width 0)
			(type solid)
		)
		(fill yes)
		(layer "In2.Cu")
		(net "P1V05_NODE1")
	)
	(gr_poly
		(pts
			(xy 163.717478 -155.73248) (xy 163.717478 -150.539196) (xy 163.633404 -150.455122) (xy 158.345886 -150.455122)
			(xy 158.293308 -150.5077) (xy 158.293308 -155.77439) (xy 158.345886 -155.826968) (xy 163.62299 -155.826968)
		)
		(stroke
			(width 0)
			(type solid)
		)
		(fill yes)
		(layer "In2.Cu")
		(net "GND")
	)
	(gr_poly
		(pts
			(xy 192.51422 -80.314038) (xy 192.51422 -78.634082) (xy 192.37325 -78.493112) (xy 189.38494 -78.493112)
			(xy 189.23254 -78.645512) (xy 189.23254 -80.076802) (xy 189.55512 -80.399382) (xy 192.428876 -80.399382)
		)
		(stroke
			(width 0)
			(type solid)
		)
		(fill yes)
		(layer "In2.Cu")
		(net "P5V_STB_NODE1")
	)
	(gr_poly
		(pts
			(xy 38.835076 -104.281732) (xy 38.835076 -103.92537) (xy 38.835076 -101.67874) (xy 37.5158 -100.359464)
			(xy 33.392872 -100.359464) (xy 33.01746 -100.734876) (xy 33.01746 -103.32466) (xy 33.01746 -104.41432)
			(xy 33.11017 -104.50703) (xy 38.609778 -104.50703)
		)
		(stroke
			(width 0)
			(type solid)
		)
		(fill yes)
		(layer "In2.Cu")
		(net "P1V5_SUS_NODE1")
	)
	(gr_poly
		(pts
			(xy 37.014912 -113.723166) (xy 37.014912 -109.762036) (xy 37.014912 -109.049058) (xy 36.78936 -108.823506)
			(xy 36.076382 -108.823506) (xy 32.548068 -108.823506) (xy 32.360362 -109.011212) (xy 32.360362 -114.62258)
			(xy 32.549592 -114.81181) (xy 33.336484 -114.81181) (xy 35.926268 -114.81181)
		)
		(stroke
			(width 0)
			(type solid)
		)
		(fill yes)
		(layer "In2.Cu")
		(net "P1V5_SUS_NODE1")
	)
	(gr_poly
		(pts
			(xy 141.021308 -160.994852) (xy 142.233396 -160.994852) (xy 142.253716 -160.974532) (xy 142.253716 -158.190438)
			(xy 142.226538 -158.16326) (xy 138.788394 -158.16326) (xy 138.66114 -158.290514)
			(arc
				(start 138.66114 -160.919414)
				(mid 138.698337 -161.009217)
				(end 138.78814 -161.046414)
			)
			(xy 140.969746 -161.046414)
		)
		(stroke
			(width 0)
			(type solid)
		)
		(fill yes)
		(layer "In2.Cu")
		(net "GND")
	)
	(gr_poly
		(pts
			(arc
				(start 32.662114 -21.769324)
				(mid 32.91332 -21.674982)
				(end 33.164526 -21.769324)
			)
			(xy 33.200594 -21.80082) (xy 33.830514 -21.80082) (xy 33.87852 -21.752814) (xy 33.87852 -20.193254)
			(xy 33.559496 -19.87423) (xy 31.338774 -19.87423) (xy 31.14548 -20.067524) (xy 31.14548 -21.58492)
			(xy 31.36138 -21.80082) (xy 32.626046 -21.80082)
		)
		(stroke
			(width 0)
			(type solid)
		)
		(fill yes)
		(layer "In2.Cu")
		(net "P5V_NODE1")
	)
	(gr_poly
		(pts
			(arc
				(start 117.990874 -46.184058)
				(mid 118.080677 -46.146861)
				(end 118.117874 -46.057058)
			)
			(arc
				(start 118.117874 -38.955218)
				(mid 118.080677 -38.865415)
				(end 117.990874 -38.828218)
			)
			(arc
				(start 112.910874 -38.828218)
				(mid 112.821071 -38.865415)
				(end 112.783874 -38.955218)
			)
			(xy 112.783874 -46.057058) (xy 112.910874 -46.184058)
		)
		(stroke
			(width 0)
			(type solid)
		)
		(fill yes)
		(layer "In2.Cu")
		(net "GND")
	)
	(gr_poly
		(pts
			(xy 170.301666 -103.927148) (xy 170.301666 -97.951544) (xy 170.249596 -97.899474) (xy 169.66946 -97.899474)
			(arc
				(start 169.644314 -97.910904)
				(mid 169.349031 -97.992328)
				(end 169.043096 -97.977198)
			)
			(arc
				(start 169.043096 -97.977198)
				(mid 168.737294 -97.992292)
				(end 168.442132 -97.910904)
			)
			(xy 168.416986 -97.899474) (xy 164.336476 -97.899474) (xy 164.169852 -98.066098) (xy 164.169852 -103.91648)
			(xy 164.273992 -104.02062) (xy 170.208194 -104.02062)
		)
		(stroke
			(width 0)
			(type solid)
		)
		(fill yes)
		(layer "In2.Cu")
		(net "GND")
	)
	(gr_poly
		(pts
			(xy 67.426586 -163.6776)
			(arc
				(start 70.709536 -163.6776)
				(mid 70.799339 -163.640403)
				(end 70.836536 -163.5506)
			)
			(xy 70.836536 -161.3535) (xy 71.447406 -160.74263) (xy 71.447406 -150.823676) (xy 70.892162 -150.268432)
			(xy 65.39611 -150.268432) (xy 65.02273 -150.641812) (xy 65.02273 -159.422338) (xy 65.438782 -159.83839)
			(xy 66.077084 -159.83839) (xy 66.55943 -160.320736)
			(arc
				(start 66.55943 -163.584382)
				(mid 66.596627 -163.674185)
				(end 66.68643 -163.711382)
			)
			(xy 67.392804 -163.711382)
		)
		(stroke
			(width 0)
			(type solid)
		)
		(fill yes)
		(layer "In2.Cu")
		(net "P5V_STB_NODE1")
	)
	(gr_poly
		(pts
			(arc
				(start 76.672948 -119.60479)
				(mid 76.367132 -119.60479)
				(end 76.672948 -119.60479)
			)
		)
		(stroke
			(width 0)
			(type solid)
		)
		(fill yes)
		(layer "In2.Cu")
		(net "GND")
	)
	(gr_poly
		(pts
			(arc
				(start 77.935328 -121.193306)
				(mid 77.629512 -121.193306)
				(end 77.935328 -121.193306)
			)
		)
		(stroke
			(width 0)
			(type solid)
		)
		(fill yes)
		(layer "In2.Cu")
		(net "GND")
	)
	(gr_poly
		(pts
			(arc
				(start 37.64534 -63.254382)
				(mid 37.32022 -63.254382)
				(end 37.64534 -63.254382)
			)
		)
		(stroke
			(width 0)
			(type solid)
		)
		(fill yes)
		(layer "In2.Cu")
		(net "GND")
	)
	(gr_poly
		(pts
			(arc
				(start 104.062276 -122.703336)
				(mid 103.737156 -122.703336)
				(end 104.062276 -122.703336)
			)
		)
		(stroke
			(width 0)
			(type solid)
		)
		(fill yes)
		(layer "In2.Cu")
		(net "GND")
	)
	(gr_poly
		(pts
			(arc
				(start 104.8766 -122.651774)
				(mid 104.55148 -122.651774)
				(end 104.8766 -122.651774)
			)
		)
		(stroke
			(width 0)
			(type solid)
		)
		(fill yes)
		(layer "In2.Cu")
		(net "GND")
	)
	(gr_poly
		(pts
			(arc
				(start 111.385858 -119.652542)
				(mid 111.060738 -119.652542)
				(end 111.385858 -119.652542)
			)
		)
		(stroke
			(width 0)
			(type solid)
		)
		(fill yes)
		(layer "In2.Cu")
		(net "GND")
	)
	(gr_poly
		(pts
			(arc
				(start 135.70712 -120.358408)
				(mid 135.796923 -120.321211)
				(end 135.83412 -120.231408)
			)
			(arc
				(start 135.83412 -114.775742)
				(mid 135.796923 -114.685939)
				(end 135.70712 -114.648742)
			)
			(xy 131.435348 -114.648742) (xy 130.268472 -114.648742) (xy 130.05943 -114.857784) (xy 130.05943 -115.183412)
			(xy 130.05943 -115.183666)
			(arc
				(start 130.05943 -120.231408)
				(mid 130.096627 -120.321211)
				(end 130.18643 -120.358408)
			)
		)
		(stroke
			(width 0)
			(type solid)
		)
		(fill yes)
		(layer "In2.Cu")
		(net "GND")
	)
	(gr_poly
		(pts
			(arc
				(start 161.10458 -102.541578)
				(mid 160.77946 -102.541578)
				(end 161.10458 -102.541578)
			)
		)
		(stroke
			(width 0)
			(type solid)
		)
		(fill yes)
		(layer "In2.Cu")
		(net "GND")
	)
	(gr_poly
		(pts
			(arc
				(start 153.983944 -152.694386)
				(mid 153.630376 -152.694386)
				(end 153.983944 -152.694386)
			)
		)
		(stroke
			(width 0)
			(type solid)
		)
		(fill yes)
		(layer "In2.Cu")
		(net "GND")
	)
	(gr_poly
		(pts
			(arc
				(start 46.79442 -167.674544)
				(mid 46.884223 -167.637347)
				(end 46.92142 -167.547544)
			)
			(arc
				(start 46.92142 -164.394896)
				(mid 46.884223 -164.305093)
				(end 46.79442 -164.267896)
			)
			(arc
				(start 40.31234 -164.267896)
				(mid 40.222537 -164.305093)
				(end 40.18534 -164.394896)
			)
			(arc
				(start 40.18534 -167.547544)
				(mid 40.222537 -167.637347)
				(end 40.31234 -167.674544)
			)
		)
		(stroke
			(width 0)
			(type solid)
		)
		(fill yes)
		(layer "In2.Cu")
		(net "GND")
	)
	(gr_poly
		(pts
			(arc
				(start 147.30222 -79.664814)
				(mid 146.915124 -79.664814)
				(end 147.30222 -79.664814)
			)
		)
		(stroke
			(width 0)
			(type solid)
		)
		(fill yes)
		(layer "In2.Cu")
		(net "GND")
	)
	(gr_poly
		(pts
			(arc
				(start 148.49221 -79.700882)
				(mid 148.105114 -79.700882)
				(end 148.49221 -79.700882)
			)
		)
		(stroke
			(width 0)
			(type solid)
		)
		(fill yes)
		(layer "In2.Cu")
		(net "GND")
	)
	(gr_poly
		(pts
			(arc
				(start 129.249678 -109.84611)
				(mid 129.409444 -109.811047)
				(end 129.56921 -109.84611)
			)
			(xy 129.59461 -109.857794)
			(arc
				(start 131.572 -109.857794)
				(mid 131.661803 -109.820597)
				(end 131.699 -109.730794)
			)
			(arc
				(start 131.699 -106.71048)
				(mid 131.661803 -106.620677)
				(end 131.572 -106.58348)
			)
			(arc
				(start 126.814072 -106.58348)
				(mid 126.724269 -106.620677)
				(end 126.687072 -106.71048)
			)
			(arc
				(start 126.687072 -109.730794)
				(mid 126.724269 -109.820597)
				(end 126.814072 -109.857794)
			)
			(xy 129.224278 -109.857794)
		)
		(stroke
			(width 0)
			(type solid)
		)
		(fill yes)
		(layer "In2.Cu")
		(net "GND")
	)
	(gr_poly
		(pts
			(arc
				(start 169.470578 -92.547186)
				(mid 169.533189 -92.53068)
				(end 169.579544 -92.485464)
			)
			(arc
				(start 169.579544 -92.485464)
				(mid 169.90695 -92.299794)
				(end 170.234356 -92.485464)
			)
			(xy 170.251628 -92.514166) (xy 170.30954 -92.547186)
			(arc
				(start 172.11802 -92.547186)
				(mid 172.207823 -92.509989)
				(end 172.24502 -92.420186)
			)
			(arc
				(start 172.24502 -90.177366)
				(mid 172.207823 -90.087563)
				(end 172.11802 -90.050366)
			)
			(arc
				(start 166.6113 -90.050366)
				(mid 166.521497 -90.087563)
				(end 166.4843 -90.177366)
			)
			(arc
				(start 166.4843 -92.420186)
				(mid 166.521497 -92.509989)
				(end 166.6113 -92.547186)
			)
		)
		(stroke
			(width 0)
			(type solid)
		)
		(fill yes)
		(layer "In2.Cu")
		(net "GND")
	)
	(gr_poly
		(pts
			(xy 63.754508 -14.898624) (xy 65.736216 -14.898624) (xy 65.84188 -14.793214) (xy 65.84188 -14.229588)
			(xy 65.8368 -14.224508) (xy 65.8368 -13.406628) (xy 65.450212 -13.02004) (xy 65.176908 -13.02004)
			(xy 65.163446 -13.006832) (xy 63.745872 -13.006832) (xy 63.683642 -13.046202) (xy 63.667894 -13.079984)
			(xy 63.656038 -13.104314) (xy 63.626477 -13.149651) (xy 63.590804 -13.190353) (xy 63.549734 -13.225602)
			(xy 63.504094 -13.254691) (xy 63.454799 -13.277035) (xy 63.40284 -13.292185) (xy 63.349261 -13.299837)
			(xy 63.295139 -13.299837) (xy 63.24156 -13.292185) (xy 63.189601 -13.277035) (xy 63.140306 -13.254691)
			(xy 63.094666 -13.225602) (xy 63.053596 -13.190353) (xy 63.017923 -13.149651) (xy 62.988362 -13.104314)
			(xy 62.976506 -13.079984) (xy 62.970042 -13.067065) (xy 62.952238 -13.044323) (xy 62.929768 -13.026177)
			(xy 62.903787 -13.013561) (xy 62.875632 -13.007122) (xy 62.86119 -13.006832) (xy 62.770258 -13.006832)
			(xy 62.755792 -13.007226) (xy 62.727605 -13.013754) (xy 62.701613 -13.026463) (xy 62.679153 -13.044701)
			(xy 62.661379 -13.067531) (xy 62.654942 -13.080492) (xy 62.643112 -13.104909) (xy 62.613574 -13.150418)
			(xy 62.577885 -13.191284) (xy 62.536767 -13.226681) (xy 62.491049 -13.255895) (xy 62.441653 -13.278338)
			(xy 62.389576 -13.293556) (xy 62.335868 -13.301243) (xy 62.281612 -13.301243) (xy 62.227904 -13.293556)
			(xy 62.175827 -13.278338) (xy 62.126431 -13.255895) (xy 62.080713 -13.226681) (xy 62.039595 -13.191284)
			(xy 62.003906 -13.150418) (xy 61.974368 -13.104909) (xy 61.962538 -13.080492) (xy 61.956119 -13.067504)
			(xy 61.938373 -13.044613) (xy 61.915918 -13.026317) (xy 61.889915 -13.013558) (xy 61.861704 -13.006996)
			(xy 61.847222 -13.006578) (xy 61.727334 -13.006578) (xy 61.662564 -13.051028) (xy 61.64834 -13.087858)
			(xy 61.638383 -13.112262) (xy 61.612715 -13.158297) (xy 61.580951 -13.200358) (xy 61.543697 -13.237643)
			(xy 61.501663 -13.269442) (xy 61.455649 -13.295148) (xy 61.406534 -13.314272) (xy 61.355253 -13.32645)
			(xy 61.329062 -13.329412) (xy 61.28385 -13.33373) (xy 61.19368 -13.4239) (xy 61.19368 -13.648944)
			(xy 64.004442 -13.648944) (xy 64.008513 -13.593322) (xy 64.020639 -13.538885) (xy 64.040562 -13.486794)
			(xy 64.067858 -13.438159) (xy 64.101944 -13.394016) (xy 64.142093 -13.355307) (xy 64.187451 -13.322856)
			(xy 64.237051 -13.297355) (xy 64.289835 -13.279348) (xy 64.344678 -13.269218) (xy 64.400412 -13.267181)
			(xy 64.455849 -13.273281) (xy 64.509806 -13.287387) (xy 64.561135 -13.309199) (xy 64.608741 -13.338253)
			(xy 64.651609 -13.373928) (xy 64.688826 -13.415465) (xy 64.719599 -13.461978) (xy 64.743271 -13.512475)
			(xy 64.759339 -13.565882) (xy 64.767459 -13.621058) (xy 64.767968 -13.648944) (xy 64.767459 -13.67683)
			(xy 64.759339 -13.732006) (xy 64.743271 -13.785413) (xy 64.719599 -13.83591) (xy 64.688826 -13.882423)
			(xy 64.651609 -13.92396) (xy 64.608741 -13.959635) (xy 64.561135 -13.988689) (xy 64.509806 -14.010501)
			(xy 64.455849 -14.024607) (xy 64.400412 -14.030707) (xy 64.344678 -14.02867) (xy 64.289835 -14.01854)
			(xy 64.237051 -14.000533) (xy 64.187451 -13.975032) (xy 64.142093 -13.942581) (xy 64.101944 -13.903872)
			(xy 64.067858 -13.859729) (xy 64.040562 -13.811094) (xy 64.020639 -13.759003) (xy 64.008513 -13.704566)
			(xy 64.004442 -13.648944) (xy 61.19368 -13.648944) (xy 61.19368 -14.623542) (xy 61.4807 -14.910562)
			(xy 63.74257 -14.910562)
		)
		(stroke
			(width 0)
			(type solid)
		)
		(fill yes)
		(layer "In2.Cu")
		(net "P5V_NODE1")
	)
	(gr_poly
		(pts
			(xy 75.652376 -108.653072) (xy 75.652376 -106.232452) (xy 73.1139 -103.693976) (xy 69.172074 -103.693976)
			(xy 67.92087 -103.422958) (xy 66.726054 -103.422958) (xy 66.040508 -102.737412) (xy 65.538604 -102.737412)
			(xy 64.703706 -101.902514) (xy 62.1665 -101.902514) (xy 62.149846 -101.903009) (xy 62.117673 -101.91163)
			(xy 62.088828 -101.928285) (xy 62.065277 -101.951839) (xy 62.048625 -101.980686) (xy 62.040007 -102.01286)
			(xy 62.0395 -102.029514) (xy 62.0395 -104.382062) (xy 62.03999 -104.39872) (xy 62.048605 -104.430903)
			(xy 62.065257 -104.459758) (xy 62.088811 -104.48332) (xy 62.117662 -104.499981) (xy 62.149842 -104.508605)
			(xy 62.1665 -104.509062) (xy 63.316104 -104.509062) (xy 64.506348 -105.699306) (xy 64.518282 -105.710493)
			(xy 64.546547 -105.726935) (xy 64.578064 -105.735647) (xy 64.610761 -105.736058) (xy 64.626744 -105.73258)
			(xy 64.653178 -105.726531) (xy 64.70713 -105.72109) (xy 64.761309 -105.723341) (xy 64.814625 -105.733236)
			(xy 64.866003 -105.750578) (xy 64.914409 -105.775017) (xy 64.95887 -105.806061) (xy 64.998489 -105.843084)
			(xy 65.015872 -105.863898) (xy 65.031054 -105.88193) (xy 65.066875 -105.912563) (xy 65.107727 -105.936072)
			(xy 65.15221 -105.951652) (xy 65.198803 -105.958768) (xy 65.245909 -105.957178) (xy 65.291916 -105.946936)
			(xy 65.335248 -105.928392) (xy 65.374421 -105.902182) (xy 65.408095 -105.869202) (xy 65.422018 -105.850182)
			(xy 65.438239 -105.827834) (xy 65.476073 -105.787614) (xy 65.51931 -105.753267) (xy 65.567047 -105.725513)
			(xy 65.618287 -105.70493) (xy 65.671959 -105.691948) (xy 65.726941 -105.68684) (xy 65.782085 -105.689711)
			(xy 65.83624 -105.700502) (xy 65.888273 -105.718987) (xy 65.937098 -105.74478) (xy 65.981694 -105.777342)
			(xy 66.021131 -105.815994) (xy 66.054583 -105.859926) (xy 66.081353 -105.908222) (xy 66.100881 -105.959873)
			(xy 66.112759 -106.0138) (xy 66.116739 -106.068875) (xy 66.112737 -106.123949) (xy 66.108523 -106.143044)
			(xy 66.368674 -106.143044) (xy 66.372745 -106.087422) (xy 66.384871 -106.032985) (xy 66.404794 -105.980894)
			(xy 66.43209 -105.932259) (xy 66.466176 -105.888116) (xy 66.506325 -105.849407) (xy 66.551683 -105.816956)
			(xy 66.601283 -105.791455) (xy 66.654067 -105.773448) (xy 66.70891 -105.763318) (xy 66.764644 -105.761281)
			(xy 66.820081 -105.767381) (xy 66.874038 -105.781487) (xy 66.925367 -105.803299) (xy 66.972973 -105.832353)
			(xy 67.015841 -105.868028) (xy 67.053058 -105.909565) (xy 67.083831 -105.956078) (xy 67.107503 -106.006575)
			(xy 67.123571 -106.059982) (xy 67.131691 -106.115158) (xy 67.1322 -106.143044) (xy 67.131691 -106.17093)
			(xy 67.123571 -106.226106) (xy 67.107503 -106.279513) (xy 67.083831 -106.33001) (xy 67.053058 -106.376523)
			(xy 67.015841 -106.41806) (xy 66.972973 -106.453735) (xy 66.925367 -106.482789) (xy 66.874038 -106.504601)
			(xy 66.820081 -106.518707) (xy 66.764644 -106.524807) (xy 66.70891 -106.52277) (xy 66.654067 -106.51264)
			(xy 66.601283 -106.494633) (xy 66.551683 -106.469132) (xy 66.506325 -106.436681) (xy 66.466176 -106.397972)
			(xy 66.43209 -106.353829) (xy 66.404794 -106.305194) (xy 66.384871 -106.253103) (xy 66.372745 -106.198666)
			(xy 66.368674 -106.143044) (xy 66.108523 -106.143044) (xy 66.100838 -106.177871) (xy 66.08129 -106.229514)
			(xy 66.054501 -106.2778) (xy 66.021031 -106.321719) (xy 65.98158 -106.360355) (xy 65.93697 -106.392899)
			(xy 65.888135 -106.418673) (xy 65.836095 -106.437138) (xy 65.809114 -106.443018) (xy 65.786755 -106.447937)
			(xy 65.744166 -106.464718) (xy 65.705271 -106.488856) (xy 65.671328 -106.519569) (xy 65.643434 -106.555866)
			(xy 65.622492 -106.596571) (xy 65.609179 -106.640368) (xy 65.603926 -106.685842) (xy 65.606902 -106.731521)
			(xy 65.618011 -106.775929) (xy 65.636894 -106.817629) (xy 65.66294 -106.855273) (xy 65.678812 -106.87177)
			(xy 66.159634 -107.352592) (xy 67.06311 -107.352592) (xy 67.067181 -107.29697) (xy 67.079307 -107.242533)
			(xy 67.09923 -107.190442) (xy 67.126526 -107.141807) (xy 67.160612 -107.097664) (xy 67.200761 -107.058955)
			(xy 67.246119 -107.026504) (xy 67.295719 -107.001003) (xy 67.348503 -106.982996) (xy 67.403346 -106.972866)
			(xy 67.45908 -106.970829) (xy 67.514517 -106.976929) (xy 67.568474 -106.991035) (xy 67.619803 -107.012847)
			(xy 67.667409 -107.041901) (xy 67.710277 -107.077576) (xy 67.747494 -107.119113) (xy 67.778267 -107.165626)
			(xy 67.801939 -107.216123) (xy 67.818007 -107.26953) (xy 67.826127 -107.324706) (xy 67.826636 -107.352592)
			(xy 67.826127 -107.380478) (xy 67.818007 -107.435654) (xy 67.801939 -107.489061) (xy 67.778267 -107.539558)
			(xy 67.747494 -107.586071) (xy 67.710277 -107.627608) (xy 67.667409 -107.663283) (xy 67.619803 -107.692337)
			(xy 67.568474 -107.714149) (xy 67.514517 -107.728255) (xy 67.45908 -107.734355) (xy 67.403346 -107.732318)
			(xy 67.348503 -107.722188) (xy 67.295719 -107.704181) (xy 67.246119 -107.67868) (xy 67.200761 -107.646229)
			(xy 67.160612 -107.60752) (xy 67.126526 -107.563377) (xy 67.09923 -107.514742) (xy 67.079307 -107.462651)
			(xy 67.067181 -107.408214) (xy 67.06311 -107.352592) (xy 66.159634 -107.352592) (xy 67.584066 -108.777024)
			(xy 75.52817 -108.777024)
		)
		(stroke
			(width 0)
			(type solid)
		)
		(fill yes)
		(layer "In2.Cu")
		(net "P1V8_STB_NODE1")
	)
	(gr_poly
		(pts
			(xy 91.538806 -176.381156) (xy 91.556586 -176.354232) (xy 91.571268 -176.332508) (xy 91.605647 -176.29292)
			(xy 91.645124 -176.258413) (xy 91.688953 -176.229636) (xy 91.736311 -176.207132) (xy 91.786304 -176.191325)
			(xy 91.83799 -176.182513) (xy 91.86418 -176.181258) (xy 91.886316 -176.180091) (xy 91.929709 -176.171056)
			(xy 91.970879 -176.154634) (xy 92.008577 -176.131323) (xy 92.041663 -176.101828) (xy 92.069134 -176.067044)
			(xy 92.090157 -176.028024) (xy 92.104097 -175.985949) (xy 92.107766 -175.964088) (xy 92.112296 -175.936564)
			(xy 92.128349 -175.883144) (xy 92.15201 -175.832632) (xy 92.182774 -175.786103) (xy 92.219987 -175.74455)
			(xy 92.262853 -175.70886) (xy 92.31046 -175.679792) (xy 92.361793 -175.657967) (xy 92.415757 -175.64385)
			(xy 92.471201 -175.637742) (xy 92.526944 -175.639773) (xy 92.581796 -175.6499) (xy 92.63459 -175.667906)
			(xy 92.684198 -175.693409) (xy 92.729563 -175.725864) (xy 92.769719 -175.76458) (xy 92.803809 -175.80873)
			(xy 92.831106 -175.857374) (xy 92.851028 -175.909475) (xy 92.86315 -175.963922) (xy 92.867215 -176.019553)
			(xy 92.863135 -176.075183) (xy 92.857574 -176.102518) (xy 92.853106 -176.124839) (xy 92.851253 -176.170317)
			(xy 92.857529 -176.215398) (xy 92.871733 -176.258641) (xy 92.893412 -176.298663) (xy 92.921871 -176.334184)
			(xy 92.956201 -176.364069) (xy 92.995305 -176.387362) (xy 93.037933 -176.403319) (xy 93.08272 -176.411429)
			(xy 93.105478 -176.41189) (xy 93.646498 -176.41189) (xy 94.09684 -175.961548) (xy 94.09684 -174.407576)
			(xy 93.902276 -174.213012) (xy 93.885347 -174.196842) (xy 93.846743 -174.17037) (xy 93.803942 -174.15142)
			(xy 93.758393 -174.140633) (xy 93.711639 -174.138376) (xy 93.665263 -174.144723) (xy 93.620835 -174.159462)
			(xy 93.57986 -174.182091) (xy 93.561408 -174.196502) (xy 93.540281 -174.213235) (xy 93.494222 -174.241218)
			(xy 93.444685 -174.262444) (xy 93.392654 -174.276491) (xy 93.339165 -174.28308) (xy 93.285281 -174.282079)
			(xy 93.232073 -174.273509) (xy 93.1806 -174.257541) (xy 93.131885 -174.234491) (xy 93.086896 -174.204817)
			(xy 93.046528 -174.169111) (xy 93.011584 -174.128082) (xy 92.996766 -174.10557) (xy 92.987487 -174.091839)
			(xy 92.963202 -174.069307) (xy 92.933931 -174.053795) (xy 92.901651 -174.046352) (xy 92.868543 -174.04748)
			(xy 92.836844 -174.057104) (xy 92.822522 -174.065438) (xy 92.79359 -174.08264) (xy 92.731119 -174.10768)
			(xy 92.698316 -174.115222) (xy 92.679806 -174.119686) (xy 92.64647 -174.13805) (xy 92.632784 -174.15129)
			(xy 92.618369 -174.138926) (xy 92.584143 -174.122516) (xy 92.565474 -174.119032) (xy 92.537809 -174.114451)
			(xy 92.484124 -174.098255) (xy 92.45854 -174.086774) (xy 92.443846 -174.080455) (xy 92.412423 -174.074535)
			(xy 92.380515 -174.076614) (xy 92.350126 -174.086561) (xy 92.323164 -174.103751) (xy 92.301323 -174.127104)
			(xy 92.293186 -174.140876) (xy 92.279134 -174.165579) (xy 92.244845 -174.2109) (xy 92.204211 -174.250633)
			(xy 92.158133 -174.283897) (xy 92.107629 -174.309957) (xy 92.053818 -174.328236) (xy 91.997891 -174.338329)
			(xy 91.941085 -174.340013) (xy 91.884658 -174.333251) (xy 91.829859 -174.318192) (xy 91.7779 -174.295169)
			(xy 91.729932 -174.264693) (xy 91.687016 -174.227437) (xy 91.650103 -174.184227) (xy 91.620009 -174.136018)
			(xy 91.5974 -174.083878) (xy 91.589606 -174.056548) (xy 91.584829 -174.040575) (xy 91.568188 -174.011697)
			(xy 91.544636 -173.988114) (xy 91.51578 -173.971435) (xy 91.483589 -173.962797) (xy 91.466924 -173.962314)
			(xy 89.28608 -173.962314) (xy 88.98382 -174.264574) (xy 88.98382 -175.073405) (xy 91.476181 -175.073405)
			(xy 91.478782 -175.018395) (xy 91.489266 -174.964332) (xy 91.507413 -174.912337) (xy 91.532848 -174.863491)
			(xy 91.565041 -174.81881) (xy 91.603324 -174.779222) (xy 91.646901 -174.745549) (xy 91.694866 -174.718491)
			(xy 91.746223 -174.698611) (xy 91.799905 -174.686321) (xy 91.854796 -174.681877) (xy 91.909756 -174.685371)
			(xy 91.963643 -174.696731) (xy 91.989656 -174.705772) (xy 92.011837 -174.713382) (xy 92.058061 -174.721255)
			(xy 92.104944 -174.720515) (xy 92.150895 -174.711186) (xy 92.194355 -174.693585) (xy 92.233849 -174.66831)
			(xy 92.268035 -174.636218) (xy 92.295754 -174.5984) (xy 92.306394 -174.577502) (xy 92.319491 -174.551363)
			(xy 92.35251 -174.503116) (xy 92.392509 -174.460477) (xy 92.43855 -174.424446) (xy 92.489554 -174.395868)
			(xy 92.544323 -174.375414) (xy 92.57284 -174.368968) (xy 92.591315 -174.36441) (xy 92.62463 -174.346063)
			(xy 92.638372 -174.3329) (xy 92.652805 -174.345238) (xy 92.687023 -174.361646) (xy 92.705682 -174.365158)
			(xy 92.733105 -174.369629) (xy 92.786329 -174.385584) (xy 92.836675 -174.409091) (xy 92.883079 -174.439651)
			(xy 92.92456 -174.47662) (xy 92.96024 -174.519214) (xy 92.989364 -174.566533) (xy 93.011317 -174.617576)
			(xy 93.025633 -174.671263) (xy 93.032011 -174.72646) (xy 93.030316 -174.781997) (xy 93.020582 -174.836702)
			(xy 93.003017 -174.889416) (xy 92.977991 -174.939024) (xy 92.946034 -174.984479) (xy 92.907822 -175.024817)
			(xy 92.864164 -175.059186) (xy 92.815981 -175.086858) (xy 92.764295 -175.107249) (xy 92.710197 -175.119928)
			(xy 92.654832 -175.124626) (xy 92.599372 -175.121243) (xy 92.544989 -175.109851) (xy 92.518738 -175.100742)
			(xy 92.496561 -175.093118) (xy 92.450336 -175.085245) (xy 92.403451 -175.085987) (xy 92.357498 -175.095317)
			(xy 92.314037 -175.11292) (xy 92.274543 -175.138197) (xy 92.240357 -175.170291) (xy 92.212639 -175.208113)
			(xy 92.202 -175.229012) (xy 92.189686 -175.253645) (xy 92.158961 -175.299347) (xy 92.121983 -175.340157)
			(xy 92.079523 -175.375227) (xy 92.032461 -175.403828) (xy 91.981776 -175.425365) (xy 91.928521 -175.439391)
			(xy 91.873803 -175.445614) (xy 91.818759 -175.443906) (xy 91.764532 -175.434302) (xy 91.71225 -175.417001)
			(xy 91.662998 -175.392362) (xy 91.6178 -175.360899) (xy 91.577595 -175.323264) (xy 91.54322 -175.280239)
			(xy 91.515387 -175.23272) (xy 91.494675 -175.181692) (xy 91.481516 -175.128217) (xy 91.476181 -175.073405)
			(xy 88.98382 -175.073405) (xy 88.98382 -176.08677) (xy 89.30894 -176.41189) (xy 91.482418 -176.41189)
		)
		(stroke
			(width 0)
			(type solid)
		)
		(fill yes)
		(layer "In2.Cu")
		(net "P3V3_NODE1")
	)
	(gr_poly
		(pts
			(xy 10.9093 -91.824302) (xy 10.9093 -90.543126) (xy 13.25626 -88.196166) (xy 13.25626 -80.161638)
			(xy 12.605512 -79.51089) (xy 3.53822 -79.51089) (xy 2.1463 -80.90281) (xy 2.1463 -81.774992) (xy 10.396718 -81.774992)
			(xy 10.396718 -81.68112) (xy 10.404679 -81.587586) (xy 10.420543 -81.495064) (xy 10.444197 -81.404221)
			(xy 10.475469 -81.315712) (xy 10.514135 -81.230173) (xy 10.559916 -81.148221) (xy 10.612482 -81.070447)
			(xy 10.671455 -80.997412) (xy 10.736408 -80.92964) (xy 10.806875 -80.867621) (xy 10.882348 -80.811802)
			(xy 10.962283 -80.762584) (xy 11.046104 -80.720322) (xy 11.133207 -80.685322) (xy 11.222964 -80.657834)
			(xy 11.314729 -80.638057) (xy 11.407841 -80.626134) (xy 11.501628 -80.62215) (xy 11.595415 -80.626134)
			(xy 11.688527 -80.638057) (xy 11.780292 -80.657834) (xy 11.870049 -80.685322) (xy 11.957152 -80.720322)
			(xy 12.040973 -80.762584) (xy 12.120908 -80.811802) (xy 12.196381 -80.867621) (xy 12.266848 -80.92964)
			(xy 12.331801 -80.997412) (xy 12.390774 -81.070447) (xy 12.44334 -81.148221) (xy 12.489121 -81.230173)
			(xy 12.527787 -81.315712) (xy 12.559059 -81.404221) (xy 12.582713 -81.495064) (xy 12.598577 -81.587586)
			(xy 12.606538 -81.68112) (xy 12.607036 -81.728056) (xy 12.606538 -81.774992) (xy 12.598577 -81.868526)
			(xy 12.582713 -81.961048) (xy 12.559059 -82.051891) (xy 12.527787 -82.1404) (xy 12.489121 -82.225939)
			(xy 12.44334 -82.307891) (xy 12.390774 -82.385665) (xy 12.331801 -82.4587) (xy 12.266848 -82.526472)
			(xy 12.196381 -82.588491) (xy 12.120908 -82.64431) (xy 12.040973 -82.693528) (xy 11.957152 -82.73579)
			(xy 11.870049 -82.77079) (xy 11.780292 -82.798278) (xy 11.688527 -82.818055) (xy 11.595415 -82.829978)
			(xy 11.501628 -82.833963) (xy 11.407841 -82.829978) (xy 11.314729 -82.818055) (xy 11.222964 -82.798278)
			(xy 11.133207 -82.77079) (xy 11.046104 -82.73579) (xy 10.962283 -82.693528) (xy 10.882348 -82.64431)
			(xy 10.806875 -82.588491) (xy 10.736408 -82.526472) (xy 10.671455 -82.4587) (xy 10.612482 -82.385665)
			(xy 10.559916 -82.307891) (xy 10.514135 -82.225939) (xy 10.475469 -82.1404) (xy 10.444197 -82.051891)
			(xy 10.420543 -81.961048) (xy 10.404679 -81.868526) (xy 10.396718 -81.774992) (xy 2.1463 -81.774992)
			(xy 2.1463 -85.975136) (xy 10.396718 -85.975136) (xy 10.396718 -85.881264) (xy 10.404679 -85.78773)
			(xy 10.420543 -85.695208) (xy 10.444197 -85.604365) (xy 10.475469 -85.515856) (xy 10.514135 -85.430317)
			(xy 10.559916 -85.348365) (xy 10.612482 -85.270591) (xy 10.671455 -85.197556) (xy 10.736408 -85.129784)
			(xy 10.806875 -85.067765) (xy 10.882348 -85.011946) (xy 10.962283 -84.962728) (xy 11.046104 -84.920466)
			(xy 11.133207 -84.885466) (xy 11.222964 -84.857978) (xy 11.314729 -84.838201) (xy 11.407841 -84.826278)
			(xy 11.501628 -84.822294) (xy 11.595415 -84.826278) (xy 11.688527 -84.838201) (xy 11.780292 -84.857978)
			(xy 11.870049 -84.885466) (xy 11.957152 -84.920466) (xy 12.040973 -84.962728) (xy 12.120908 -85.011946)
			(xy 12.196381 -85.067765) (xy 12.266848 -85.129784) (xy 12.331801 -85.197556) (xy 12.390774 -85.270591)
			(xy 12.44334 -85.348365) (xy 12.489121 -85.430317) (xy 12.527787 -85.515856) (xy 12.559059 -85.604365)
			(xy 12.582713 -85.695208) (xy 12.598577 -85.78773) (xy 12.606538 -85.881264) (xy 12.607036 -85.9282)
			(xy 12.606538 -85.975136) (xy 12.598577 -86.06867) (xy 12.582713 -86.161192) (xy 12.559059 -86.252035)
			(xy 12.527787 -86.340544) (xy 12.489121 -86.426083) (xy 12.44334 -86.508035) (xy 12.390774 -86.585809)
			(xy 12.331801 -86.658844) (xy 12.266848 -86.726616) (xy 12.196381 -86.788635) (xy 12.120908 -86.844454)
			(xy 12.040973 -86.893672) (xy 11.957152 -86.935934) (xy 11.870049 -86.970934) (xy 11.780292 -86.998422)
			(xy 11.688527 -87.018199) (xy 11.595415 -87.030122) (xy 11.501628 -87.034107) (xy 11.407841 -87.030122)
			(xy 11.314729 -87.018199) (xy 11.222964 -86.998422) (xy 11.133207 -86.970934) (xy 11.046104 -86.935934)
			(xy 10.962283 -86.893672) (xy 10.882348 -86.844454) (xy 10.806875 -86.788635) (xy 10.736408 -86.726616)
			(xy 10.671455 -86.658844) (xy 10.612482 -86.585809) (xy 10.559916 -86.508035) (xy 10.514135 -86.426083)
			(xy 10.475469 -86.340544) (xy 10.444197 -86.252035) (xy 10.420543 -86.161192) (xy 10.404679 -86.06867)
			(xy 10.396718 -85.975136) (xy 2.1463 -85.975136) (xy 2.1463 -90.697241) (xy 4.534904 -90.697241)
			(xy 4.534904 -90.573415) (xy 4.542837 -90.449844) (xy 4.558672 -90.327036) (xy 4.582342 -90.205494)
			(xy 4.613751 -90.085718) (xy 4.652769 -89.968201) (xy 4.699237 -89.853425) (xy 4.752963 -89.741862)
			(xy 4.813726 -89.633971) (xy 4.881277 -89.530194) (xy 4.955339 -89.430959) (xy 5.035606 -89.336672)
			(xy 5.121749 -89.247722) (xy 5.213414 -89.164474) (xy 5.310225 -89.087271) (xy 5.411783 -89.016428)
			(xy 5.517671 -88.952238) (xy 5.627455 -88.894964) (xy 5.740682 -88.844841) (xy 5.856889 -88.802076)
			(xy 5.975596 -88.766845) (xy 6.096317 -88.739291) (xy 6.218555 -88.719528) (xy 6.341808 -88.707638)
			(xy 6.46557 -88.70367) (xy 6.589332 -88.707638) (xy 6.712585 -88.719528) (xy 6.834823 -88.739291)
			(xy 6.955544 -88.766845) (xy 7.074251 -88.802076) (xy 7.190458 -88.844841) (xy 7.303685 -88.894964)
			(xy 7.413469 -88.952238) (xy 7.519357 -89.016428) (xy 7.620915 -89.087271) (xy 7.717726 -89.164474)
			(xy 7.809391 -89.247722) (xy 7.895534 -89.336672) (xy 7.975801 -89.430959) (xy 8.049863 -89.530194)
			(xy 8.117414 -89.633971) (xy 8.178177 -89.741862) (xy 8.231903 -89.853425) (xy 8.278371 -89.968201)
			(xy 8.317389 -90.085718) (xy 8.348798 -90.205494) (xy 8.372468 -90.327036) (xy 8.388303 -90.449844)
			(xy 8.396236 -90.573415) (xy 8.396732 -90.635328) (xy 8.396236 -90.697241) (xy 8.388303 -90.820812)
			(xy 8.372468 -90.94362) (xy 8.348798 -91.065162) (xy 8.317389 -91.184938) (xy 8.278371 -91.302455)
			(xy 8.231903 -91.417231) (xy 8.178177 -91.528794) (xy 8.117414 -91.636685) (xy 8.049863 -91.740462)
			(xy 7.975801 -91.839697) (xy 7.895534 -91.933984) (xy 7.809391 -92.022934) (xy 7.717726 -92.106182)
			(xy 7.620915 -92.183385) (xy 7.519357 -92.254228) (xy 7.413469 -92.318418) (xy 7.303685 -92.375692)
			(xy 7.190458 -92.425815) (xy 7.074251 -92.46858) (xy 6.955544 -92.503811) (xy 6.834823 -92.531365)
			(xy 6.712585 -92.551128) (xy 6.589332 -92.563018) (xy 6.46557 -92.566987) (xy 6.341808 -92.563018)
			(xy 6.218555 -92.551128) (xy 6.096317 -92.531365) (xy 5.975596 -92.503811) (xy 5.856889 -92.46858)
			(xy 5.740682 -92.425815) (xy 5.627455 -92.375692) (xy 5.517671 -92.318418) (xy 5.411783 -92.254228)
			(xy 5.310225 -92.183385) (xy 5.213414 -92.106182) (xy 5.121749 -92.022934) (xy 5.035606 -91.933984)
			(xy 4.955339 -91.839697) (xy 4.881277 -91.740462) (xy 4.813726 -91.636685) (xy 4.752963 -91.528794)
			(xy 4.699237 -91.417231) (xy 4.652769 -91.302455) (xy 4.613751 -91.184938) (xy 4.582342 -91.065162)
			(xy 4.558672 -90.94362) (xy 4.542837 -90.820812) (xy 4.534904 -90.697241) (xy 2.1463 -90.697241)
			(xy 2.1463 -95.601282) (xy 2.75082 -96.205802) (xy 6.5278 -96.205802)
		)
		(stroke
			(width 0)
			(type solid)
		)
		(fill yes)
		(layer "In2.Cu")
		(net "P12V_DBG")
	)
	(gr_poly
		(pts
			(xy 184.75198 -60.791598) (xy 184.75198 -57.383172) (xy 184.722674 -57.327673) (xy 184.670561 -57.213484)
			(xy 184.626078 -57.096113) (xy 184.589417 -56.976068) (xy 184.560736 -56.853871) (xy 184.540161 -56.730051)
			(xy 184.52778 -56.605145) (xy 184.523647 -56.479695) (xy 184.527781 -56.354245) (xy 184.540162 -56.229339)
			(xy 184.560738 -56.105519) (xy 184.589419 -55.983321) (xy 184.626082 -55.863277) (xy 184.670566 -55.745906)
			(xy 184.722678 -55.631717) (xy 184.75198 -55.576216) (xy 184.75198 -51.130708) (xy 183.94172 -50.320448)
			(xy 182.596536 -50.320448) (xy 182.581897 -50.320863) (xy 182.553391 -50.327542) (xy 182.527152 -50.340533)
			(xy 182.50456 -50.359156) (xy 182.486799 -50.382432) (xy 182.480458 -50.395632) (xy 182.455205 -50.451115)
			(xy 182.398569 -50.559075) (xy 182.335145 -50.663194) (xy 182.265195 -50.763044) (xy 182.189003 -50.858218)
			(xy 182.106882 -50.948325) (xy 182.019168 -51.032998) (xy 181.92622 -51.111889) (xy 181.828419 -51.184677)
			(xy 181.726163 -51.251062) (xy 181.619872 -51.310773) (xy 181.509981 -51.363567) (xy 181.39694 -51.409226)
			(xy 181.28121 -51.447565) (xy 181.163266 -51.478426) (xy 181.04359 -51.501683) (xy 180.922673 -51.51724)
			(xy 180.801007 -51.525035) (xy 180.679093 -51.525035) (xy 180.557427 -51.51724) (xy 180.43651 -51.501683)
			(xy 180.316834 -51.478426) (xy 180.19889 -51.447565) (xy 180.08316 -51.409226) (xy 179.970119 -51.363567)
			(xy 179.860228 -51.310773) (xy 179.753937 -51.251062) (xy 179.651681 -51.184677) (xy 179.55388 -51.111889)
			(xy 179.460932 -51.032998) (xy 179.373218 -50.948325) (xy 179.291097 -50.858218) (xy 179.214905 -50.763044)
			(xy 179.144955 -50.663194) (xy 179.081531 -50.559075) (xy 179.024895 -50.451115) (xy 178.999642 -50.395632)
			(xy 178.993304 -50.382425) (xy 178.97558 -50.35911) (xy 178.952991 -50.340469) (xy 178.926736 -50.327492)
			(xy 178.898209 -50.320866) (xy 178.883564 -50.320448) (xy 171.983654 -50.320448) (xy 171.74464 -50.559462)
			(xy 171.74464 -53.881528) (xy 177.84648 -53.881528) (xy 177.850551 -53.825906) (xy 177.862677 -53.771469)
			(xy 177.8826 -53.719378) (xy 177.909896 -53.670743) (xy 177.943982 -53.6266) (xy 177.984131 -53.587891)
			(xy 178.029489 -53.55544) (xy 178.079089 -53.529939) (xy 178.131873 -53.511932) (xy 178.186716 -53.501802)
			(xy 178.24245 -53.499765) (xy 178.297887 -53.505865) (xy 178.351844 -53.519971) (xy 178.403173 -53.541783)
			(xy 178.450779 -53.570837) (xy 178.493647 -53.606512) (xy 178.530864 -53.648049) (xy 178.561637 -53.694562)
			(xy 178.585309 -53.745059) (xy 178.601377 -53.798466) (xy 178.609497 -53.853642) (xy 178.610006 -53.881528)
			(xy 178.609497 -53.909414) (xy 178.601377 -53.96459) (xy 178.585309 -54.017997) (xy 178.561637 -54.068494)
			(xy 178.530864 -54.115007) (xy 178.493647 -54.156544) (xy 178.450779 -54.192219) (xy 178.403173 -54.221273)
			(xy 178.351844 -54.243085) (xy 178.297887 -54.257191) (xy 178.24245 -54.263291) (xy 178.186716 -54.261254)
			(xy 178.131873 -54.251124) (xy 178.079089 -54.233117) (xy 178.029489 -54.207616) (xy 177.984131 -54.175165)
			(xy 177.943982 -54.136456) (xy 177.909896 -54.092313) (xy 177.8826 -54.043678) (xy 177.862677 -53.991587)
			(xy 177.850551 -53.93715) (xy 177.84648 -53.881528) (xy 171.74464 -53.881528) (xy 171.74464 -55.084472)
			(xy 177.65852 -55.084472) (xy 177.662591 -55.02885) (xy 177.674717 -54.974413) (xy 177.69464 -54.922322)
			(xy 177.721936 -54.873687) (xy 177.756022 -54.829544) (xy 177.796171 -54.790835) (xy 177.841529 -54.758384)
			(xy 177.891129 -54.732883) (xy 177.943913 -54.714876) (xy 177.998756 -54.704746) (xy 178.05449 -54.702709)
			(xy 178.109927 -54.708809) (xy 178.163884 -54.722915) (xy 178.215213 -54.744727) (xy 178.262819 -54.773781)
			(xy 178.305687 -54.809456) (xy 178.342904 -54.850993) (xy 178.373677 -54.897506) (xy 178.397349 -54.948003)
			(xy 178.413417 -55.00141) (xy 178.421537 -55.056586) (xy 178.422046 -55.084472) (xy 178.421537 -55.112358)
			(xy 178.413417 -55.167534) (xy 178.397349 -55.220941) (xy 178.373677 -55.271438) (xy 178.342904 -55.317951)
			(xy 178.305687 -55.359488) (xy 178.262819 -55.395163) (xy 178.215213 -55.424217) (xy 178.163884 -55.446029)
			(xy 178.109927 -55.460135) (xy 178.05449 -55.466235) (xy 177.998756 -55.464198) (xy 177.943913 -55.454068)
			(xy 177.891129 -55.436061) (xy 177.841529 -55.41056) (xy 177.796171 -55.378109) (xy 177.756022 -55.3394)
			(xy 177.721936 -55.295257) (xy 177.69464 -55.246622) (xy 177.674717 -55.194531) (xy 177.662591 -55.140094)
			(xy 177.65852 -55.084472) (xy 171.74464 -55.084472) (xy 171.74464 -56.227472) (xy 177.670458 -56.227472)
			(xy 177.674529 -56.17185) (xy 177.686655 -56.117413) (xy 177.706578 -56.065322) (xy 177.733874 -56.016687)
			(xy 177.76796 -55.972544) (xy 177.808109 -55.933835) (xy 177.853467 -55.901384) (xy 177.903067 -55.875883)
			(xy 177.955851 -55.857876) (xy 178.010694 -55.847746) (xy 178.066428 -55.845709) (xy 178.121865 -55.851809)
			(xy 178.175822 -55.865915) (xy 178.227151 -55.887727) (xy 178.274757 -55.916781) (xy 178.317625 -55.952456)
			(xy 178.354842 -55.993993) (xy 178.385615 -56.040506) (xy 178.409287 -56.091003) (xy 178.425355 -56.14441)
			(xy 178.433475 -56.199586) (xy 178.433984 -56.227472) (xy 178.433475 -56.255358) (xy 178.425355 -56.310534)
			(xy 178.409287 -56.363941) (xy 178.385615 -56.414438) (xy 178.354842 -56.460951) (xy 178.338048 -56.479694)
			(xy 178.834042 -56.479694) (xy 178.838039 -56.356318) (xy 178.850014 -56.23346) (xy 178.869917 -56.111635)
			(xy 178.897663 -55.991354) (xy 178.933137 -55.87312) (xy 178.97619 -55.757431) (xy 179.026641 -55.644772)
			(xy 179.084278 -55.535614) (xy 179.148861 -55.430416) (xy 179.220118 -55.329619) (xy 179.297749 -55.233646)
			(xy 179.381431 -55.142899) (xy 179.47081 -55.05776) (xy 179.565514 -54.978584) (xy 179.665143 -54.905705)
			(xy 179.769282 -54.839427) (xy 179.877492 -54.780029) (xy 179.98932 -54.727761) (xy 180.104296 -54.68284)
			(xy 180.22194 -54.645456) (xy 180.341756 -54.615766) (xy 180.463243 -54.593893) (xy 180.585891 -54.57993)
			(xy 180.709186 -54.573936) (xy 180.83261 -54.575935) (xy 180.955646 -54.585919) (xy 181.077777 -54.603846)
			(xy 181.198492 -54.629641) (xy 181.317285 -54.663196) (xy 181.433656 -54.704369) (xy 181.547118 -54.752989)
			(xy 181.657194 -54.808852) (xy 181.763424 -54.871723) (xy 181.865362 -54.941338) (xy 181.962579 -55.017405)
			(xy 182.054669 -55.099606) (xy 182.141245 -55.187595) (xy 182.221944 -55.281004) (xy 182.296427 -55.379441)
			(xy 182.364382 -55.482492) (xy 182.425524 -55.589726) (xy 182.479597 -55.700693) (xy 182.526373 -55.814927)
			(xy 182.565657 -55.93195) (xy 182.597284 -56.05127) (xy 182.621121 -56.172387) (xy 182.637068 -56.294792)
			(xy 182.645058 -56.417974) (xy 182.645558 -56.479694) (xy 182.645058 -56.541414) (xy 182.637068 -56.664596)
			(xy 182.621121 -56.787001) (xy 182.597284 -56.908118) (xy 182.565657 -57.027438) (xy 182.526373 -57.144461)
			(xy 182.479597 -57.258695) (xy 182.425524 -57.369662) (xy 182.364382 -57.476896) (xy 182.296427 -57.579947)
			(xy 182.221944 -57.678384) (xy 182.141245 -57.771793) (xy 182.054669 -57.859782) (xy 181.962579 -57.941983)
			(xy 181.865362 -58.01805) (xy 181.763424 -58.087665) (xy 181.657194 -58.150536) (xy 181.547118 -58.206399)
			(xy 181.433656 -58.255019) (xy 181.317285 -58.296192) (xy 181.198492 -58.329747) (xy 181.077777 -58.355542)
			(xy 180.955646 -58.373469) (xy 180.83261 -58.383453) (xy 180.709186 -58.385452) (xy 180.585891 -58.379458)
			(xy 180.463243 -58.365495) (xy 180.341756 -58.343622) (xy 180.22194 -58.313932) (xy 180.104296 -58.276548)
			(xy 179.98932 -58.231627) (xy 179.877492 -58.179359) (xy 179.769282 -58.119961) (xy 179.665143 -58.053683)
			(xy 179.565514 -57.980804) (xy 179.47081 -57.901628) (xy 179.381431 -57.816489) (xy 179.297749 -57.725742)
			(xy 179.220118 -57.629769) (xy 179.148861 -57.528972) (xy 179.084278 -57.423774) (xy 179.026641 -57.314616)
			(xy 178.97619 -57.201957) (xy 178.933137 -57.086268) (xy 178.897663 -56.968034) (xy 178.869917 -56.847753)
			(xy 178.850014 -56.725928) (xy 178.838039 -56.60307) (xy 178.834042 -56.479694) (xy 178.338048 -56.479694)
			(xy 178.317625 -56.502488) (xy 178.274757 -56.538163) (xy 178.227151 -56.567217) (xy 178.175822 -56.589029)
			(xy 178.121865 -56.603135) (xy 178.066428 -56.609235) (xy 178.010694 -56.607198) (xy 177.955851 -56.597068)
			(xy 177.903067 -56.579061) (xy 177.853467 -56.55356) (xy 177.808109 -56.521109) (xy 177.76796 -56.4824)
			(xy 177.733874 -56.438257) (xy 177.706578 -56.389622) (xy 177.686655 -56.337531) (xy 177.674529 -56.283094)
			(xy 177.670458 -56.227472) (xy 171.74464 -56.227472) (xy 171.74464 -60.570364) (xy 172.301154 -61.126878)
			(xy 184.4167 -61.126878)
		)
		(stroke
			(width 0)
			(type solid)
		)
		(fill yes)
		(layer "In2.Cu")
		(net "USBPWR_P1")
	)
	(gr_poly
		(pts
			(xy 135.247888 -123.680474) (xy 135.275419 -123.669873) (xy 135.332835 -123.656326) (xy 135.391652 -123.651774)
			(xy 135.450469 -123.656326) (xy 135.507885 -123.669873) (xy 135.535416 -123.680474) (xy 135.55853 -123.689872)
			(xy 136.494774 -123.689872) (xy 136.517888 -123.680474) (xy 136.545419 -123.669873) (xy 136.602835 -123.656326)
			(xy 136.661652 -123.651774) (xy 136.720469 -123.656326) (xy 136.777885 -123.669873) (xy 136.805416 -123.680474)
			(xy 136.82853 -123.689872) (xy 140.564362 -123.689872) (xy 141.14526 -123.108974) (xy 141.14526 -118.963186)
			(xy 140.962634 -118.78056) (xy 137.238994 -118.78056) (xy 137.015728 -119.003826) (xy 137.015728 -119.677942)
			(xy 137.016211 -119.70049) (xy 137.024164 -119.744878) (xy 137.039829 -119.787165) (xy 137.062715 -119.826021)
			(xy 137.092102 -119.860226) (xy 137.127067 -119.888704) (xy 137.166512 -119.910561) (xy 137.209195 -119.925109)
			(xy 137.253778 -119.931892) (xy 137.298857 -119.930697) (xy 137.321036 -119.926608) (xy 137.348022 -119.921523)
			(xy 137.402837 -119.918242) (xy 137.457556 -119.922852) (xy 137.511049 -119.935259) (xy 137.562211 -119.955206)
			(xy 137.609986 -119.98228) (xy 137.653386 -120.015924) (xy 137.672826 -120.03532) (xy 137.691173 -120.054992)
			(xy 137.722722 -120.098561) (xy 137.747836 -120.146131) (xy 137.766017 -120.196758) (xy 137.776905 -120.249436)
			(xy 137.780282 -120.303122) (xy 137.776084 -120.35675) (xy 137.764391 -120.409256) (xy 137.745437 -120.459599)
			(xy 137.719598 -120.506778) (xy 137.687386 -120.549859) (xy 137.64944 -120.587987) (xy 137.606514 -120.620405)
			(xy 137.559459 -120.64647) (xy 137.509208 -120.665665) (xy 137.483088 -120.672098) (xy 137.455919 -120.677806)
			(xy 137.400579 -120.682217) (xy 137.345184 -120.678554) (xy 137.290907 -120.666895) (xy 137.238895 -120.647486)
			(xy 137.190247 -120.620739) (xy 137.145994 -120.587218) (xy 137.107072 -120.547633) (xy 137.074302 -120.502821)
			(xy 137.048379 -120.45373) (xy 137.038588 -120.42775) (xy 137.029872 -120.406491) (xy 137.005925 -120.367284)
			(xy 136.97532 -120.333022) (xy 136.939053 -120.30482) (xy 136.898306 -120.283598) (xy 136.854409 -120.270047)
			(xy 136.80879 -120.264609) (xy 136.762937 -120.267461) (xy 136.718344 -120.278511) (xy 136.676464 -120.297398)
			(xy 136.638662 -120.323507) (xy 136.622028 -120.339358) (xy 136.345676 -120.61571) (xy 136.334234 -120.627817)
			(xy 136.317543 -120.656633) (xy 136.308881 -120.688789) (xy 136.308838 -120.72209) (xy 136.317419 -120.754267)
			(xy 136.334037 -120.783126) (xy 136.345422 -120.795288) (xy 136.365868 -120.816594) (xy 136.400599 -120.864349)
			(xy 136.427557 -120.916886) (xy 136.446096 -120.972949) (xy 136.455773 -121.0312) (xy 136.456359 -121.090246)
			(xy 136.447838 -121.148677) (xy 136.439656 -121.17705) (xy 136.430765 -121.20407) (xy 136.406102 -121.255326)
			(xy 136.374104 -121.302353) (xy 136.335478 -121.344108) (xy 136.291081 -121.379665) (xy 136.241897 -121.408238)
			(xy 136.189017 -121.429192) (xy 136.133611 -121.442063) (xy 136.076909 -121.446565) (xy 136.020167 -121.4426)
			(xy 135.964642 -121.430254) (xy 135.911565 -121.409802) (xy 135.862113 -121.381697) (xy 135.839454 -121.364502)
			(xy 135.815963 -121.345297) (xy 135.77479 -121.300731) (xy 135.741186 -121.250213) (xy 135.715997 -121.195015)
			(xy 135.699858 -121.136527) (xy 135.695944 -121.106438) (xy 135.691118 -121.062242) (xy 135.566658 -120.937782)
			(xy 130.32105 -120.937782) (xy 129.89941 -120.516142) (xy 129.89941 -120.485916) (xy 129.875788 -120.452642)
			(xy 129.859131 -120.428272) (xy 129.832735 -120.375477) (xy 129.814784 -120.319246) (xy 129.805708 -120.260921)
			(xy 129.805176 -120.231408) (xy 129.805176 -118.066312) (xy 129.453386 -117.714522) (xy 128.33731 -117.714522)
			(xy 128.102614 -117.949218) (xy 128.093216 -117.970046) (xy 128.085326 -117.98675) (xy 128.066754 -118.018686)
			(xy 128.056132 -118.0338) (xy 128.043178 -118.050564) (xy 128.014984 -118.085616) (xy 128.014984 -122.099832)
			(xy 130.771644 -122.099832) (xy 130.775715 -122.04421) (xy 130.787841 -121.989773) (xy 130.807764 -121.937682)
			(xy 130.83506 -121.889047) (xy 130.869146 -121.844904) (xy 130.909295 -121.806195) (xy 130.954653 -121.773744)
			(xy 131.004253 -121.748243) (xy 131.057037 -121.730236) (xy 131.11188 -121.720106) (xy 131.167614 -121.718069)
			(xy 131.223051 -121.724169) (xy 131.277008 -121.738275) (xy 131.328337 -121.760087) (xy 131.375943 -121.789141)
			(xy 131.418811 -121.824816) (xy 131.456028 -121.866353) (xy 131.486801 -121.912866) (xy 131.503043 -121.947513)
			(xy 133.121806 -121.947513) (xy 133.128607 -121.893055) (xy 133.14314 -121.840133) (xy 133.165107 -121.789841)
			(xy 133.194054 -121.743214) (xy 133.229383 -121.701217) (xy 133.270365 -121.664715) (xy 133.316154 -121.634463)
			(xy 133.365806 -121.611083) (xy 133.418296 -121.59506) (xy 133.47254 -121.586723) (xy 133.527419 -121.586245)
			(xy 133.5818 -121.593635) (xy 133.634561 -121.608741) (xy 133.684613 -121.631251) (xy 133.730922 -121.660701)
			(xy 133.772535 -121.696483) (xy 133.80859 -121.737858) (xy 133.838345 -121.783973) (xy 133.861185 -121.833875)
			(xy 133.876639 -121.886535) (xy 133.884388 -121.940867) (xy 133.884272 -121.995747) (xy 133.876293 -122.050045)
			(xy 133.860616 -122.102639) (xy 133.837565 -122.152444) (xy 133.807615 -122.198432) (xy 133.771384 -122.239655)
			(xy 133.750812 -122.25782) (xy 133.734213 -122.272566) (xy 133.705983 -122.306833) (xy 133.684135 -122.345483)
			(xy 133.669331 -122.387339) (xy 133.662021 -122.431131) (xy 133.662429 -122.475527) (xy 133.670541 -122.519177)
			(xy 133.686111 -122.560755) (xy 133.708666 -122.598997) (xy 133.73752 -122.63274) (xy 133.754368 -122.647202)
			(xy 133.775295 -122.664969) (xy 133.812261 -122.705556) (xy 133.843029 -122.751021) (xy 133.866965 -122.800426)
			(xy 133.883575 -122.852751) (xy 133.892515 -122.906916) (xy 133.893216 -122.94235) (xy 138.642342 -122.94235)
			(xy 138.646413 -122.886728) (xy 138.658539 -122.832291) (xy 138.678462 -122.7802) (xy 138.705758 -122.731565)
			(xy 138.739844 -122.687422) (xy 138.779993 -122.648713) (xy 138.825351 -122.616262) (xy 138.874951 -122.590761)
			(xy 138.927735 -122.572754) (xy 138.982578 -122.562624) (xy 139.038312 -122.560587) (xy 139.093749 -122.566687)
			(xy 139.147706 -122.580793) (xy 139.199035 -122.602605) (xy 139.246641 -122.631659) (xy 139.289509 -122.667334)
			(xy 139.326726 -122.708871) (xy 139.357499 -122.755384) (xy 139.381171 -122.805881) (xy 139.397239 -122.859288)
			(xy 139.405359 -122.914464) (xy 139.405868 -122.94235) (xy 139.405359 -122.970236) (xy 139.397239 -123.025412)
			(xy 139.381171 -123.078819) (xy 139.357499 -123.129316) (xy 139.326726 -123.175829) (xy 139.289509 -123.217366)
			(xy 139.246641 -123.253041) (xy 139.199035 -123.282095) (xy 139.147706 -123.303907) (xy 139.093749 -123.318013)
			(xy 139.038312 -123.324113) (xy 138.982578 -123.322076) (xy 138.927735 -123.311946) (xy 138.874951 -123.293939)
			(xy 138.825351 -123.268438) (xy 138.779993 -123.235987) (xy 138.739844 -123.197278) (xy 138.705758 -123.153135)
			(xy 138.678462 -123.1045) (xy 138.658539 -123.052409) (xy 138.646413 -122.997972) (xy 138.642342 -122.94235)
			(xy 133.893216 -122.94235) (xy 133.893601 -122.961803) (xy 133.88681 -123.016279) (xy 133.872284 -123.06922)
			(xy 133.850322 -123.119534) (xy 133.821376 -123.16618) (xy 133.786045 -123.208198) (xy 133.745057 -123.244719)
			(xy 133.69926 -123.27499) (xy 133.649597 -123.298386) (xy 133.597094 -123.314424) (xy 133.542835 -123.322773)
			(xy 133.487939 -123.323261) (xy 133.43354 -123.315878) (xy 133.380761 -123.300775) (xy 133.33069 -123.278266)
			(xy 133.284361 -123.248813) (xy 133.242731 -123.213026) (xy 133.206659 -123.171643) (xy 133.176889 -123.125518)
			(xy 133.154036 -123.075603) (xy 133.138571 -123.022929) (xy 133.130813 -122.968582) (xy 133.130924 -122.913684)
			(xy 133.1389 -122.859369) (xy 133.154576 -122.806757) (xy 133.17763 -122.756935) (xy 133.207586 -122.71093)
			(xy 133.243824 -122.669692) (xy 133.264402 -122.65152) (xy 133.280967 -122.636735) (xy 133.309206 -122.602478)
			(xy 133.331063 -122.563835) (xy 133.345875 -122.521983) (xy 133.353191 -122.478194) (xy 133.352788 -122.4338)
			(xy 133.344678 -122.390151) (xy 133.329108 -122.348574) (xy 133.306552 -122.310335) (xy 133.277696 -122.276596)
			(xy 133.260846 -122.262138) (xy 133.24 -122.244286) (xy 133.203056 -122.203701) (xy 133.172309 -122.158242)
			(xy 133.148394 -122.108846) (xy 133.131803 -122.056533) (xy 133.122879 -122.002383) (xy 133.121806 -121.947513)
			(xy 131.503043 -121.947513) (xy 131.510473 -121.963363) (xy 131.526541 -122.01677) (xy 131.534661 -122.071946)
			(xy 131.53517 -122.099832) (xy 131.534661 -122.127718) (xy 131.526541 -122.182894) (xy 131.510473 -122.236301)
			(xy 131.486801 -122.286798) (xy 131.456028 -122.333311) (xy 131.418811 -122.374848) (xy 131.375943 -122.410523)
			(xy 131.328337 -122.439577) (xy 131.277008 -122.461389) (xy 131.223051 -122.475495) (xy 131.167614 -122.481595)
			(xy 131.11188 -122.479558) (xy 131.057037 -122.469428) (xy 131.004253 -122.451421) (xy 130.954653 -122.42592)
			(xy 130.909295 -122.393469) (xy 130.869146 -122.35476) (xy 130.83506 -122.310617) (xy 130.807764 -122.261982)
			(xy 130.787841 -122.209891) (xy 130.775715 -122.155454) (xy 130.771644 -122.099832) (xy 128.014984 -122.099832)
			(xy 128.014984 -123.169172) (xy 128.535684 -123.689872) (xy 135.224774 -123.689872)
		)
		(stroke
			(width 0)
			(type solid)
		)
		(fill yes)
		(layer "In2.Cu")
		(net "P1V5_CLK_NODE1")
	)
	(gr_poly
		(pts
			(xy 194.4624 -38.599618) (xy 194.4624 -30.862524) (xy 193.69532 -30.095444) (xy 175.720502 -30.095444)
			(xy 175.69806 -30.095896) (xy 175.653866 -30.103729) (xy 175.611735 -30.119205) (xy 175.572979 -30.141842)
			(xy 175.538803 -30.170936) (xy 175.510269 -30.205582) (xy 175.488267 -30.244702) (xy 175.47348 -30.287079)
			(xy 175.466369 -30.331395) (xy 175.467154 -30.376271) (xy 175.475811 -30.420311) (xy 175.48352 -30.441392)
			(xy 175.494104 -30.467259) (xy 175.508441 -30.521278) (xy 175.514744 -30.57681) (xy 175.512878 -30.632667)
			(xy 175.502882 -30.687655) (xy 175.48497 -30.740596) (xy 175.459527 -30.790357) (xy 175.427096 -30.835874)
			(xy 175.388371 -30.876172) (xy 175.344181 -30.910389) (xy 175.295471 -30.937793) (xy 175.243285 -30.957797)
			(xy 175.188739 -30.969973) (xy 175.133 -30.974061) (xy 175.077261 -30.969973) (xy 175.022715 -30.957797)
			(xy 174.970529 -30.937793) (xy 174.921819 -30.910389) (xy 174.877629 -30.876172) (xy 174.838904 -30.835874)
			(xy 174.806473 -30.790357) (xy 174.78103 -30.740596) (xy 174.763118 -30.687655) (xy 174.753122 -30.632667)
			(xy 174.751256 -30.57681) (xy 174.757559 -30.521278) (xy 174.771896 -30.467259) (xy 174.78248 -30.441392)
			(xy 174.790162 -30.420301) (xy 174.798814 -30.376261) (xy 174.799597 -30.331385) (xy 174.792486 -30.28707)
			(xy 174.777702 -30.244692) (xy 174.755704 -30.20557) (xy 174.727176 -30.170921) (xy 174.693006 -30.14182)
			(xy 174.654256 -30.119174) (xy 174.61213 -30.103686) (xy 174.56794 -30.095838) (xy 174.545498 -30.095444)
			(xy 174.128176 -30.095444) (xy 171.82592 -32.3977) (xy 171.82592 -35.59556) (xy 175.169574 -35.59556)
			(xy 175.173645 -35.539938) (xy 175.185771 -35.485501) (xy 175.205694 -35.43341) (xy 175.23299 -35.384775)
			(xy 175.267076 -35.340632) (xy 175.307225 -35.301923) (xy 175.352583 -35.269472) (xy 175.402183 -35.243971)
			(xy 175.454967 -35.225964) (xy 175.50981 -35.215834) (xy 175.565544 -35.213797) (xy 175.620981 -35.219897)
			(xy 175.674938 -35.234003) (xy 175.726267 -35.255815) (xy 175.773873 -35.284869) (xy 175.816741 -35.320544)
			(xy 175.853958 -35.362081) (xy 175.884731 -35.408594) (xy 175.908403 -35.459091) (xy 175.924471 -35.512498)
			(xy 175.932591 -35.567674) (xy 175.9331 -35.59556) (xy 175.932591 -35.623446) (xy 175.924471 -35.678622)
			(xy 175.908403 -35.732029) (xy 175.884731 -35.782526) (xy 175.853958 -35.829039) (xy 175.816741 -35.870576)
			(xy 175.773873 -35.906251) (xy 175.726267 -35.935305) (xy 175.674938 -35.957117) (xy 175.620981 -35.971223)
			(xy 175.565544 -35.977323) (xy 175.50981 -35.975286) (xy 175.454967 -35.965156) (xy 175.402183 -35.947149)
			(xy 175.352583 -35.921648) (xy 175.307225 -35.889197) (xy 175.267076 -35.850488) (xy 175.23299 -35.806345)
			(xy 175.205694 -35.75771) (xy 175.185771 -35.705619) (xy 175.173645 -35.651182) (xy 175.169574 -35.59556)
			(xy 171.82592 -35.59556) (xy 171.82592 -36.46297) (xy 178.834042 -36.46297) (xy 178.838039 -36.339594)
			(xy 178.850014 -36.216736) (xy 178.869917 -36.094911) (xy 178.897663 -35.97463) (xy 178.933137 -35.856396)
			(xy 178.97619 -35.740707) (xy 179.026641 -35.628048) (xy 179.084278 -35.51889) (xy 179.148861 -35.413692)
			(xy 179.220118 -35.312895) (xy 179.297749 -35.216922) (xy 179.381431 -35.126175) (xy 179.47081 -35.041036)
			(xy 179.565514 -34.96186) (xy 179.665143 -34.888981) (xy 179.769282 -34.822703) (xy 179.877492 -34.763305)
			(xy 179.98932 -34.711037) (xy 180.104296 -34.666116) (xy 180.22194 -34.628732) (xy 180.341756 -34.599042)
			(xy 180.463243 -34.577169) (xy 180.585891 -34.563206) (xy 180.709186 -34.557212) (xy 180.83261 -34.559211)
			(xy 180.955646 -34.569195) (xy 181.077777 -34.587122) (xy 181.198492 -34.612917) (xy 181.317285 -34.646472)
			(xy 181.433656 -34.687645) (xy 181.547118 -34.736265) (xy 181.657194 -34.792128) (xy 181.763424 -34.854999)
			(xy 181.865362 -34.924614) (xy 181.962579 -35.000681) (xy 182.054669 -35.082882) (xy 182.141245 -35.170871)
			(xy 182.221944 -35.26428) (xy 182.296427 -35.362717) (xy 182.364382 -35.465768) (xy 182.425524 -35.573002)
			(xy 182.479597 -35.683969) (xy 182.526373 -35.798203) (xy 182.565657 -35.915226) (xy 182.597284 -36.034546)
			(xy 182.621121 -36.155663) (xy 182.637068 -36.278068) (xy 182.645058 -36.40125) (xy 182.645558 -36.46297)
			(xy 184.523642 -36.46297) (xy 184.527639 -36.339594) (xy 184.539614 -36.216736) (xy 184.559517 -36.094911)
			(xy 184.587263 -35.97463) (xy 184.622737 -35.856396) (xy 184.66579 -35.740707) (xy 184.716241 -35.628048)
			(xy 184.773878 -35.51889) (xy 184.838461 -35.413692) (xy 184.909718 -35.312895) (xy 184.987349 -35.216922)
			(xy 185.071031 -35.126175) (xy 185.16041 -35.041036) (xy 185.255114 -34.96186) (xy 185.354743 -34.888981)
			(xy 185.458882 -34.822703) (xy 185.567092 -34.763305) (xy 185.67892 -34.711037) (xy 185.793896 -34.666116)
			(xy 185.91154 -34.628732) (xy 186.031356 -34.599042) (xy 186.152843 -34.577169) (xy 186.275491 -34.563206)
			(xy 186.398786 -34.557212) (xy 186.52221 -34.559211) (xy 186.645246 -34.569195) (xy 186.767377 -34.587122)
			(xy 186.888092 -34.612917) (xy 187.006885 -34.646472) (xy 187.123256 -34.687645) (xy 187.236718 -34.736265)
			(xy 187.346794 -34.792128) (xy 187.453024 -34.854999) (xy 187.554962 -34.924614) (xy 187.652179 -35.000681)
			(xy 187.744269 -35.082882) (xy 187.830845 -35.170871) (xy 187.911544 -35.26428) (xy 187.986027 -35.362717)
			(xy 188.053982 -35.465768) (xy 188.115124 -35.573002) (xy 188.169197 -35.683969) (xy 188.215973 -35.798203)
			(xy 188.255257 -35.915226) (xy 188.286884 -36.034546) (xy 188.310721 -36.155663) (xy 188.326668 -36.278068)
			(xy 188.334658 -36.40125) (xy 188.335158 -36.46297) (xy 188.334658 -36.52469) (xy 188.326668 -36.647872)
			(xy 188.310721 -36.770277) (xy 188.286884 -36.891394) (xy 188.255257 -37.010714) (xy 188.215973 -37.127737)
			(xy 188.169197 -37.241971) (xy 188.115124 -37.352938) (xy 188.053982 -37.460172) (xy 187.986027 -37.563223)
			(xy 187.911544 -37.66166) (xy 187.830845 -37.755069) (xy 187.744269 -37.843058) (xy 187.652179 -37.925259)
			(xy 187.554962 -38.001326) (xy 187.453024 -38.070941) (xy 187.346794 -38.133812) (xy 187.236718 -38.189675)
			(xy 187.123256 -38.238295) (xy 187.006885 -38.279468) (xy 186.888092 -38.313023) (xy 186.767377 -38.338818)
			(xy 186.645246 -38.356745) (xy 186.52221 -38.366729) (xy 186.398786 -38.368728) (xy 186.275491 -38.362734)
			(xy 186.152843 -38.348771) (xy 186.031356 -38.326898) (xy 185.91154 -38.297208) (xy 185.793896 -38.259824)
			(xy 185.67892 -38.214903) (xy 185.567092 -38.162635) (xy 185.458882 -38.103237) (xy 185.354743 -38.036959)
			(xy 185.255114 -37.96408) (xy 185.16041 -37.884904) (xy 185.071031 -37.799765) (xy 184.987349 -37.709018)
			(xy 184.909718 -37.613045) (xy 184.838461 -37.512248) (xy 184.773878 -37.40705) (xy 184.716241 -37.297892)
			(xy 184.66579 -37.185233) (xy 184.622737 -37.069544) (xy 184.587263 -36.95131) (xy 184.559517 -36.831029)
			(xy 184.539614 -36.709204) (xy 184.527639 -36.586346) (xy 184.523642 -36.46297) (xy 182.645558 -36.46297)
			(xy 182.645058 -36.52469) (xy 182.637068 -36.647872) (xy 182.621121 -36.770277) (xy 182.597284 -36.891394)
			(xy 182.565657 -37.010714) (xy 182.526373 -37.127737) (xy 182.479597 -37.241971) (xy 182.425524 -37.352938)
			(xy 182.364382 -37.460172) (xy 182.296427 -37.563223) (xy 182.221944 -37.66166) (xy 182.141245 -37.755069)
			(xy 182.054669 -37.843058) (xy 181.962579 -37.925259) (xy 181.865362 -38.001326) (xy 181.763424 -38.070941)
			(xy 181.657194 -38.133812) (xy 181.547118 -38.189675) (xy 181.433656 -38.238295) (xy 181.317285 -38.279468)
			(xy 181.198492 -38.313023) (xy 181.077777 -38.338818) (xy 180.955646 -38.356745) (xy 180.83261 -38.366729)
			(xy 180.709186 -38.368728) (xy 180.585891 -38.362734) (xy 180.463243 -38.348771) (xy 180.341756 -38.326898)
			(xy 180.22194 -38.297208) (xy 180.104296 -38.259824) (xy 179.98932 -38.214903) (xy 179.877492 -38.162635)
			(xy 179.769282 -38.103237) (xy 179.665143 -38.036959) (xy 179.565514 -37.96408) (xy 179.47081 -37.884904)
			(xy 179.381431 -37.799765) (xy 179.297749 -37.709018) (xy 179.220118 -37.613045) (xy 179.148861 -37.512248)
			(xy 179.084278 -37.40705) (xy 179.026641 -37.297892) (xy 178.97619 -37.185233) (xy 178.933137 -37.069544)
			(xy 178.897663 -36.95131) (xy 178.869917 -36.831029) (xy 178.850014 -36.709204) (xy 178.838039 -36.586346)
			(xy 178.834042 -36.46297) (xy 171.82592 -36.46297) (xy 171.82592 -36.848034) (xy 175.211738 -36.848034)
			(xy 175.215809 -36.792412) (xy 175.227935 -36.737975) (xy 175.247858 -36.685884) (xy 175.275154 -36.637249)
			(xy 175.30924 -36.593106) (xy 175.349389 -36.554397) (xy 175.394747 -36.521946) (xy 175.444347 -36.496445)
			(xy 175.497131 -36.478438) (xy 175.551974 -36.468308) (xy 175.607708 -36.466271) (xy 175.663145 -36.472371)
			(xy 175.717102 -36.486477) (xy 175.768431 -36.508289) (xy 175.816037 -36.537343) (xy 175.858905 -36.573018)
			(xy 175.896122 -36.614555) (xy 175.926895 -36.661068) (xy 175.950567 -36.711565) (xy 175.966635 -36.764972)
			(xy 175.974755 -36.820148) (xy 175.975264 -36.848034) (xy 175.974755 -36.87592) (xy 175.966635 -36.931096)
			(xy 175.950567 -36.984503) (xy 175.926895 -37.035) (xy 175.896122 -37.081513) (xy 175.858905 -37.12305)
			(xy 175.816037 -37.158725) (xy 175.768431 -37.187779) (xy 175.717102 -37.209591) (xy 175.663145 -37.223697)
			(xy 175.607708 -37.229797) (xy 175.551974 -37.22776) (xy 175.497131 -37.21763) (xy 175.444347 -37.199623)
			(xy 175.394747 -37.174122) (xy 175.349389 -37.141671) (xy 175.30924 -37.102962) (xy 175.275154 -37.058819)
			(xy 175.247858 -37.010184) (xy 175.227935 -36.958093) (xy 175.215809 -36.903656) (xy 175.211738 -36.848034)
			(xy 171.82592 -36.848034) (xy 171.82592 -37.991034) (xy 175.203102 -37.991034) (xy 175.207173 -37.935412)
			(xy 175.219299 -37.880975) (xy 175.239222 -37.828884) (xy 175.266518 -37.780249) (xy 175.300604 -37.736106)
			(xy 175.340753 -37.697397) (xy 175.386111 -37.664946) (xy 175.435711 -37.639445) (xy 175.488495 -37.621438)
			(xy 175.543338 -37.611308) (xy 175.599072 -37.609271) (xy 175.654509 -37.615371) (xy 175.708466 -37.629477)
			(xy 175.759795 -37.651289) (xy 175.807401 -37.680343) (xy 175.850269 -37.716018) (xy 175.887486 -37.757555)
			(xy 175.918259 -37.804068) (xy 175.941931 -37.854565) (xy 175.957999 -37.907972) (xy 175.966119 -37.963148)
			(xy 175.966628 -37.991034) (xy 175.966119 -38.01892) (xy 175.957999 -38.074096) (xy 175.941931 -38.127503)
			(xy 175.918259 -38.178) (xy 175.887486 -38.224513) (xy 175.850269 -38.26605) (xy 175.807401 -38.301725)
			(xy 175.759795 -38.330779) (xy 175.708466 -38.352591) (xy 175.654509 -38.366697) (xy 175.599072 -38.372797)
			(xy 175.543338 -38.37076) (xy 175.488495 -38.36063) (xy 175.435711 -38.342623) (xy 175.386111 -38.317122)
			(xy 175.340753 -38.284671) (xy 175.300604 -38.245962) (xy 175.266518 -38.201819) (xy 175.239222 -38.153184)
			(xy 175.219299 -38.101093) (xy 175.207173 -38.046656) (xy 175.203102 -37.991034) (xy 171.82592 -37.991034)
			(xy 171.82592 -38.91788) (xy 173.42612 -40.51808) (xy 192.543938 -40.51808)
		)
		(stroke
			(width 0)
			(type solid)
		)
		(fill yes)
		(layer "In2.Cu")
		(net "USBPWR_P0")
	)
	(gr_poly
		(pts
			(xy 73.29424 -175.883824) (xy 73.309694 -175.867699) (xy 73.335258 -175.83108) (xy 73.35403 -175.790558)
			(xy 73.365434 -175.74738) (xy 73.369119 -175.702873) (xy 73.36497 -175.658407) (xy 73.353117 -175.615349)
			(xy 73.333923 -175.575025) (xy 73.307979 -175.538675) (xy 73.276082 -175.507417) (xy 73.239215 -175.482212)
			(xy 73.219056 -175.472598) (xy 73.194313 -175.460961) (xy 73.148154 -175.431652) (xy 73.106651 -175.396054)
			(xy 73.070654 -175.354896) (xy 73.040902 -175.309021) (xy 73.018003 -175.259369) (xy 73.002426 -175.206957)
			(xy 72.99449 -175.152858) (xy 72.994358 -175.09818) (xy 73.002033 -175.044043) (xy 73.017357 -174.991556)
			(xy 73.040017 -174.941794) (xy 73.069547 -174.895777) (xy 73.105345 -174.854446) (xy 73.146676 -174.818648)
			(xy 73.192693 -174.789117) (xy 73.242455 -174.766457) (xy 73.294942 -174.751133) (xy 73.349079 -174.743458)
			(xy 73.403757 -174.74359) (xy 73.457856 -174.751525) (xy 73.510268 -174.767102) (xy 73.55992 -174.790001)
			(xy 73.605795 -174.819754) (xy 73.646953 -174.85575) (xy 73.682551 -174.897253) (xy 73.71186 -174.943412)
			(xy 73.7235 -174.968154) (xy 73.733099 -174.988326) (xy 73.758281 -175.025219) (xy 73.789528 -175.057138)
			(xy 73.825877 -175.083101) (xy 73.866205 -175.102306) (xy 73.909271 -175.114161) (xy 73.953747 -175.118302)
			(xy 73.998262 -175.1146) (xy 74.041443 -175.103169) (xy 74.081959 -175.084362) (xy 74.118561 -175.058758)
			(xy 74.134726 -175.043338) (xy 75.25512 -173.922944) (xy 75.955398 -173.922944) (xy 77.178408 -172.699934)
			(xy 77.319632 -172.699934) (xy 77.379068 -172.640752) (xy 78.13675 -172.640752) (xy 78.34376 -172.433488)
			(xy 78.34376 -170.478196) (xy 78.343265 -170.461543) (xy 78.334642 -170.429374) (xy 78.317986 -170.400533)
			(xy 78.294432 -170.376987) (xy 78.265585 -170.360341) (xy 78.233413 -170.351729) (xy 78.21676 -170.351196)
			(xy 77.624178 -170.351196) (xy 77.173836 -170.801284) (xy 76.180696 -170.801284) (xy 76.158404 -170.801749)
			(xy 76.114505 -170.809529) (xy 76.072636 -170.824849) (xy 76.034083 -170.84724) (xy 76.000029 -170.876015)
			(xy 75.971517 -170.91029) (xy 75.949424 -170.949014) (xy 75.934426 -170.991) (xy 75.926985 -171.034958)
			(xy 75.927327 -171.07954) (xy 75.935444 -171.123378) (xy 75.951085 -171.165128) (xy 75.962002 -171.18457)
			(xy 75.975816 -171.208866) (xy 75.996963 -171.2606) (xy 76.010336 -171.314866) (xy 76.015648 -171.370503)
			(xy 76.012786 -171.426318) (xy 76.001811 -171.48112) (xy 75.982959 -171.533733) (xy 75.956631 -171.583033)
			(xy 75.923393 -171.627964) (xy 75.883954 -171.667565) (xy 75.83916 -171.700988) (xy 75.789969 -171.727518)
			(xy 75.737434 -171.746588) (xy 75.682678 -171.757788) (xy 75.626875 -171.760879) (xy 75.571217 -171.755796)
			(xy 75.516897 -171.742647) (xy 75.465076 -171.721713) (xy 75.416864 -171.693442) (xy 75.373293 -171.65844)
			(xy 75.335294 -171.617456) (xy 75.303682 -171.571366) (xy 75.279133 -171.521157) (xy 75.270106 -171.494704)
			(xy 75.263116 -171.474163) (xy 75.243143 -171.435648) (xy 75.216916 -171.401087) (xy 75.185199 -171.371484)
			(xy 75.148912 -171.347701) (xy 75.109113 -171.330429) (xy 75.066957 -171.320171) (xy 75.023671 -171.317225)
			(xy 74.980514 -171.321676) (xy 74.938741 -171.333395) (xy 74.899567 -171.352042) (xy 74.86413 -171.377074)
			(xy 74.848466 -171.392088) (xy 74.706734 -171.53382) (xy 74.695278 -171.545929) (xy 74.678572 -171.574763)
			(xy 74.669923 -171.606944) (xy 74.669925 -171.640268) (xy 74.678577 -171.672449) (xy 74.695286 -171.701281)
			(xy 74.706734 -171.713398) (xy 74.706988 -171.713652) (xy 74.707242 -171.713906) (xy 74.726386 -171.733462)
			(xy 74.759443 -171.777074) (xy 74.785929 -171.824963) (xy 74.805298 -171.876146) (xy 74.817155 -171.929571)
			(xy 74.821255 -171.984142) (xy 74.817514 -172.038739) (xy 74.80601 -172.092242) (xy 74.786978 -172.14355)
			(xy 74.760808 -172.191613) (xy 74.728039 -172.235442) (xy 74.689343 -172.274139) (xy 74.645513 -172.306908)
			(xy 74.597451 -172.333077) (xy 74.546142 -172.35211) (xy 74.49264 -172.363614) (xy 74.438043 -172.367355)
			(xy 74.383472 -172.363255) (xy 74.330046 -172.351399) (xy 74.278864 -172.332029) (xy 74.230975 -172.305544)
			(xy 74.187362 -172.272486) (xy 74.167746 -172.253402) (xy 74.167492 -172.253148) (xy 74.167238 -172.252894)
			(xy 74.155077 -172.241521) (xy 74.126242 -172.224899) (xy 74.09409 -172.216296) (xy 74.060808 -172.216296)
			(xy 74.028656 -172.224899) (xy 73.999821 -172.241521) (xy 73.98766 -172.252894) (xy 73.968864 -172.27169)
			(xy 73.946765 -172.275956) (xy 73.904433 -172.291233) (xy 73.865456 -172.313731) (xy 73.831055 -172.342747)
			(xy 73.802306 -172.377372) (xy 73.78011 -172.416522) (xy 73.765161 -172.458971) (xy 73.757928 -172.503389)
			(xy 73.758637 -172.548388) (xy 73.767265 -172.592557) (xy 73.783543 -172.634514) (xy 73.794874 -172.65396)
			(xy 73.808896 -172.677971) (xy 73.830598 -172.729164) (xy 73.844639 -172.782964) (xy 73.850724 -172.838232)
			(xy 73.848723 -172.893799) (xy 73.838678 -172.948486) (xy 73.820802 -173.001137) (xy 73.795474 -173.050635)
			(xy 73.76323 -173.095934) (xy 73.724753 -173.136073) (xy 73.680858 -173.170202) (xy 73.632474 -173.197599)
			(xy 73.580625 -173.217683) (xy 73.526411 -173.23003) (xy 73.470979 -173.234378) (xy 73.415503 -173.230634)
			(xy 73.361157 -173.218878) (xy 73.309094 -173.199359) (xy 73.260414 -173.17249) (xy 73.21615 -173.13884)
			(xy 73.177238 -173.099122) (xy 73.144503 -173.054177) (xy 73.118638 -173.004957) (xy 73.10019 -172.952504)
			(xy 73.089551 -172.897929) (xy 73.086945 -172.842388) (xy 73.092428 -172.787057) (xy 73.105884 -172.733107)
			(xy 73.127027 -172.681682) (xy 73.15541 -172.633869) (xy 73.190433 -172.590683) (xy 73.231352 -172.553037)
			(xy 73.277302 -172.521728) (xy 73.302114 -172.50918) (xy 73.335134 -172.493178) (xy 73.373742 -172.431456)
			(xy 73.373742 -172.39488) (xy 73.373197 -172.378231) (xy 73.364576 -172.346069) (xy 73.347928 -172.317233)
			(xy 73.324385 -172.293686) (xy 73.295551 -172.277032) (xy 73.263391 -172.268406) (xy 73.246742 -172.26788)
			(xy 73.052178 -172.26788) (xy 71.977906 -173.3423) (xy 74.032362 -173.3423) (xy 74.036433 -173.286678)
			(xy 74.048559 -173.232241) (xy 74.068482 -173.18015) (xy 74.095778 -173.131515) (xy 74.129864 -173.087372)
			(xy 74.170013 -173.048663) (xy 74.215371 -173.016212) (xy 74.264971 -172.990711) (xy 74.317755 -172.972704)
			(xy 74.372598 -172.962574) (xy 74.428332 -172.960537) (xy 74.483769 -172.966637) (xy 74.537726 -172.980743)
			(xy 74.589055 -173.002555) (xy 74.636661 -173.031609) (xy 74.679529 -173.067284) (xy 74.716746 -173.108821)
			(xy 74.747519 -173.155334) (xy 74.771191 -173.205831) (xy 74.787259 -173.259238) (xy 74.795379 -173.314414)
			(xy 74.795888 -173.3423) (xy 74.795379 -173.370186) (xy 74.787259 -173.425362) (xy 74.771191 -173.478769)
			(xy 74.747519 -173.529266) (xy 74.716746 -173.575779) (xy 74.679529 -173.617316) (xy 74.636661 -173.652991)
			(xy 74.589055 -173.682045) (xy 74.537726 -173.703857) (xy 74.483769 -173.717963) (xy 74.428332 -173.724063)
			(xy 74.372598 -173.722026) (xy 74.317755 -173.711896) (xy 74.264971 -173.693889) (xy 74.215371 -173.668388)
			(xy 74.170013 -173.635937) (xy 74.129864 -173.597228) (xy 74.095778 -173.553085) (xy 74.068482 -173.50445)
			(xy 74.048559 -173.452359) (xy 74.036433 -173.397922) (xy 74.032362 -173.3423) (xy 71.977906 -173.3423)
			(xy 71.209408 -174.110904) (xy 71.209408 -174.576486) (xy 71.208906 -174.608447) (xy 71.200895 -174.671865)
			(xy 71.184998 -174.733779) (xy 71.161466 -174.793212) (xy 71.130672 -174.849227) (xy 71.093099 -174.900942)
			(xy 71.049342 -174.947539) (xy 71.000089 -174.988284) (xy 70.946118 -175.022535) (xy 70.888279 -175.049752)
			(xy 70.827486 -175.069505) (xy 70.764696 -175.081483) (xy 70.7009 -175.085497) (xy 70.637104 -175.081483)
			(xy 70.574314 -175.069505) (xy 70.513521 -175.049752) (xy 70.455682 -175.022535) (xy 70.401711 -174.988284)
			(xy 70.352458 -174.947539) (xy 70.308701 -174.900942) (xy 70.271128 -174.849227) (xy 70.240334 -174.793212)
			(xy 70.216802 -174.733779) (xy 70.200905 -174.671865) (xy 70.192894 -174.608447) (xy 70.192392 -174.576486)
			(xy 70.192392 -174.001176) (xy 70.191846 -173.98453) (xy 70.183224 -173.952374) (xy 70.166574 -173.923545)
			(xy 70.14303 -173.900007) (xy 70.114196 -173.883364) (xy 70.082038 -173.87475) (xy 70.065392 -173.874176)
			(xy 69.599556 -173.874176) (xy 68.66636 -174.807626) (xy 68.66636 -175.087026) (xy 68.711572 -175.152304)
			(xy 68.74891 -175.166274) (xy 68.775037 -175.176557) (xy 68.824194 -175.203689) (xy 68.868844 -175.237733)
			(xy 68.908021 -175.277954) (xy 68.940881 -175.323482) (xy 68.966713 -175.373334) (xy 68.984958 -175.426435)
			(xy 68.995225 -175.481636) (xy 68.997289 -175.537746) (xy 68.991107 -175.593552) (xy 68.976813 -175.64785)
			(xy 68.954714 -175.699466) (xy 68.92529 -175.747286) (xy 68.889174 -175.790276) (xy 68.847146 -175.827509)
			(xy 68.800116 -175.85818) (xy 68.774818 -175.870362) (xy 68.761828 -175.876779) (xy 68.738933 -175.894524)
			(xy 68.720632 -175.916977) (xy 68.707871 -175.942982) (xy 68.701307 -175.971195) (xy 68.700904 -175.985678)
			(xy 68.700904 -176.713642) (xy 70.096632 -176.713642) (xy 70.100703 -176.65802) (xy 70.112829 -176.603583)
			(xy 70.132752 -176.551492) (xy 70.160048 -176.502857) (xy 70.194134 -176.458714) (xy 70.234283 -176.420005)
			(xy 70.279641 -176.387554) (xy 70.329241 -176.362053) (xy 70.382025 -176.344046) (xy 70.436868 -176.333916)
			(xy 70.492602 -176.331879) (xy 70.548039 -176.337979) (xy 70.601996 -176.352085) (xy 70.653325 -176.373897)
			(xy 70.700931 -176.402951) (xy 70.743799 -176.438626) (xy 70.781016 -176.480163) (xy 70.811789 -176.526676)
			(xy 70.835461 -176.577173) (xy 70.851529 -176.63058) (xy 70.859649 -176.685756) (xy 70.860158 -176.713642)
			(xy 70.859649 -176.741528) (xy 70.851529 -176.796704) (xy 70.835461 -176.850111) (xy 70.811789 -176.900608)
			(xy 70.781016 -176.947121) (xy 70.743799 -176.988658) (xy 70.700931 -177.024333) (xy 70.653325 -177.053387)
			(xy 70.601996 -177.075199) (xy 70.548039 -177.089305) (xy 70.492602 -177.095405) (xy 70.436868 -177.093368)
			(xy 70.382025 -177.083238) (xy 70.329241 -177.065231) (xy 70.279641 -177.03973) (xy 70.234283 -177.007279)
			(xy 70.194134 -176.96857) (xy 70.160048 -176.924427) (xy 70.132752 -176.875792) (xy 70.112829 -176.823701)
			(xy 70.100703 -176.769264) (xy 70.096632 -176.713642) (xy 68.700904 -176.713642) (xy 68.700904 -177.142394)
			(xy 69.023484 -177.464974) (xy 69.035599 -177.476358) (xy 69.064348 -177.493027) (xy 69.096427 -177.501703)
			(xy 69.129658 -177.501797) (xy 69.161786 -177.493303) (xy 69.190628 -177.476797) (xy 69.202808 -177.465482)
			(xy 69.222094 -177.446974) (xy 69.264918 -177.414984) (xy 69.31179 -177.389288) (xy 69.36179 -177.370387)
			(xy 69.413939 -177.358653) (xy 69.467215 -177.354314) (xy 69.520576 -177.357456) (xy 69.572975 -177.368018)
			(xy 69.623387 -177.385792) (xy 69.670823 -177.41043) (xy 69.714354 -177.441451) (xy 69.753128 -177.478245)
			(xy 69.786385 -177.520092) (xy 69.813474 -177.566173) (xy 69.824092 -177.590704) (xy 69.830202 -177.6044)
			(xy 69.847806 -177.628672) (xy 69.870591 -177.648162) (xy 69.897297 -177.661792) (xy 69.926448 -177.668808)
			(xy 69.94144 -177.66919) (xy 71.508874 -177.66919)
		)
		(stroke
			(width 0)
			(type solid)
		)
		(fill yes)
		(layer "In2.Cu")
		(net "P5V_NODE1")
	)
	(gr_poly
		(pts
			(xy 177.287428 -151.597106) (xy 181.24678 -151.597106) (xy 182.24246 -150.601426) (xy 182.24246 -146.240754)
			(xy 182.241911 -146.224112) (xy 182.233285 -146.191964) (xy 182.216632 -146.163143) (xy 182.193088 -146.139615)
			(xy 182.164257 -146.122982) (xy 182.132103 -146.114378) (xy 182.11546 -146.113754) (xy 176.28997 -146.113754)
			(xy 175.998378 -146.405346) (xy 175.989234 -146.42338) (xy 175.975107 -146.449916) (xy 175.939792 -146.498564)
			(xy 175.897286 -146.541073) (xy 175.848642 -146.576391) (xy 175.822102 -146.590512) (xy 175.804068 -146.599656)
			(xy 175.71212 -146.691604) (xy 175.700678 -146.703721) (xy 175.683997 -146.73256) (xy 175.67536 -146.764737)
			(xy 175.675359 -146.798053) (xy 175.683993 -146.830231) (xy 175.700672 -146.859071) (xy 175.71212 -146.871182)
			(xy 175.734218 -146.893026) (xy 175.763936 -146.902424) (xy 175.7904 -146.91127) (xy 175.84061 -146.93561)
			(xy 175.886739 -146.967004) (xy 175.927803 -147.004782) (xy 175.962926 -147.048139) (xy 175.991359 -147.09615)
			(xy 176.012496 -147.14779) (xy 176.025884 -147.201959) (xy 176.03124 -147.2575) (xy 176.028448 -147.313228)
			(xy 176.017569 -147.367956) (xy 175.998833 -147.420515) (xy 175.972642 -147.469784) (xy 175.939553 -147.514713)
			(xy 175.900272 -147.554343) (xy 175.878236 -147.57146) (xy 175.859739 -147.586016) (xy 175.82798 -147.62075)
			(xy 175.80316 -147.660738) (xy 175.786126 -147.704612) (xy 175.777462 -147.750871) (xy 175.777462 -147.797936)
			(xy 175.786128 -147.844195) (xy 175.803163 -147.888069) (xy 175.827985 -147.928055) (xy 175.859744 -147.962789)
			(xy 175.878236 -147.977352) (xy 175.899698 -147.994076) (xy 175.938117 -148.032602) (xy 175.970674 -148.076196)
			(xy 175.996707 -148.123973) (xy 176.015688 -148.174963) (xy 176.027233 -148.228133) (xy 176.031108 -148.282404)
			(xy 176.027232 -148.336674) (xy 176.015686 -148.389844) (xy 175.996704 -148.440834) (xy 175.97067 -148.48861)
			(xy 175.938113 -148.532203) (xy 175.899692 -148.570728) (xy 175.878236 -148.58746) (xy 175.859739 -148.602016)
			(xy 175.82798 -148.63675) (xy 175.80316 -148.676738) (xy 175.786126 -148.720612) (xy 175.777462 -148.766871)
			(xy 175.777462 -148.813936) (xy 175.786128 -148.860195) (xy 175.803163 -148.904069) (xy 175.827985 -148.944055)
			(xy 175.859744 -148.978789) (xy 175.878236 -148.993352) (xy 175.900357 -149.010585) (xy 175.939782 -149.05046)
			(xy 175.972946 -149.095677) (xy 175.999133 -149.145261) (xy 176.01778 -149.198144) (xy 176.028486 -149.253187)
			(xy 176.031018 -149.309204) (xy 176.025324 -149.364989) (xy 176.011526 -149.419339) (xy 175.98992 -149.471084)
			(xy 175.960973 -149.519109) (xy 175.925307 -149.56238) (xy 175.883692 -149.599963) (xy 175.837023 -149.63105)
			(xy 175.786307 -149.654971) (xy 175.732636 -149.671211) (xy 175.677165 -149.679419) (xy 175.621091 -149.679419)
			(xy 175.56562 -149.671211) (xy 175.511949 -149.654971) (xy 175.461233 -149.63105) (xy 175.414564 -149.599963)
			(xy 175.372949 -149.56238) (xy 175.337283 -149.519109) (xy 175.308336 -149.471084) (xy 175.28673 -149.419339)
			(xy 175.272932 -149.364989) (xy 175.267238 -149.309204) (xy 175.26977 -149.253187) (xy 175.280476 -149.198144)
			(xy 175.299123 -149.145261) (xy 175.32531 -149.095677) (xy 175.358474 -149.05046) (xy 175.397899 -149.010585)
			(xy 175.42002 -148.993352) (xy 175.438521 -148.978798) (xy 175.470287 -148.944065) (xy 175.495114 -148.904077)
			(xy 175.512153 -148.860201) (xy 175.520821 -148.813938) (xy 175.520821 -148.766869) (xy 175.512155 -148.720606)
			(xy 175.495117 -148.67673) (xy 175.470291 -148.636741) (xy 175.438526 -148.602007) (xy 175.42002 -148.58746)
			(xy 175.398555 -148.570737) (xy 175.360129 -148.532213) (xy 175.327566 -148.48862) (xy 175.301527 -148.440843)
			(xy 175.282541 -148.38985) (xy 175.270993 -148.336678) (xy 175.267117 -148.282404) (xy 175.270992 -148.22813)
			(xy 175.282539 -148.174957) (xy 175.301524 -148.123964) (xy 175.327562 -148.076186) (xy 175.360124 -148.032592)
			(xy 175.39855 -147.994068) (xy 175.42002 -147.977352) (xy 175.438521 -147.962798) (xy 175.470287 -147.928065)
			(xy 175.495114 -147.888077) (xy 175.512153 -147.844201) (xy 175.520821 -147.797938) (xy 175.520821 -147.750869)
			(xy 175.512155 -147.704606) (xy 175.495117 -147.66073) (xy 175.470291 -147.620741) (xy 175.438526 -147.586007)
			(xy 175.42002 -147.57146) (xy 175.396553 -147.553124) (xy 175.355088 -147.510381) (xy 175.33747 -147.48637)
			(xy 175.324315 -147.468563) (xy 175.292907 -147.437369) (xy 175.256568 -147.41209) (xy 175.216397 -147.393493)
			(xy 175.17361 -147.38214) (xy 175.129504 -147.378375) (xy 175.085412 -147.382312) (xy 175.04267 -147.393832)
			(xy 175.002572 -147.412586) (xy 174.966332 -147.438006) (xy 174.950374 -147.45335) (xy 172.343572 -150.060152)
			(xy 176.300382 -150.060152) (xy 176.304453 -150.00453) (xy 176.316579 -149.950093) (xy 176.336502 -149.898002)
			(xy 176.363798 -149.849367) (xy 176.397884 -149.805224) (xy 176.438033 -149.766515) (xy 176.483391 -149.734064)
			(xy 176.532991 -149.708563) (xy 176.585775 -149.690556) (xy 176.640618 -149.680426) (xy 176.696352 -149.678389)
			(xy 176.751789 -149.684489) (xy 176.805746 -149.698595) (xy 176.857075 -149.720407) (xy 176.904681 -149.749461)
			(xy 176.947549 -149.785136) (xy 176.984766 -149.826673) (xy 177.015539 -149.873186) (xy 177.039211 -149.923683)
			(xy 177.055279 -149.97709) (xy 177.063399 -150.032266) (xy 177.063908 -150.060152) (xy 177.063399 -150.088038)
			(xy 177.055279 -150.143214) (xy 177.039211 -150.196621) (xy 177.015539 -150.247118) (xy 176.984766 -150.293631)
			(xy 176.947549 -150.335168) (xy 176.904681 -150.370843) (xy 176.857075 -150.399897) (xy 176.805746 -150.421709)
			(xy 176.751789 -150.435815) (xy 176.696352 -150.441915) (xy 176.640618 -150.439878) (xy 176.585775 -150.429748)
			(xy 176.532991 -150.411741) (xy 176.483391 -150.38624) (xy 176.438033 -150.353789) (xy 176.397884 -150.31508)
			(xy 176.363798 -150.270937) (xy 176.336502 -150.222302) (xy 176.316579 -150.170211) (xy 176.304453 -150.115774)
			(xy 176.300382 -150.060152) (xy 172.343572 -150.060152) (xy 171.75607 -150.647654) (xy 180.653942 -150.647654)
			(xy 180.658013 -150.592032) (xy 180.670139 -150.537595) (xy 180.690062 -150.485504) (xy 180.717358 -150.436869)
			(xy 180.751444 -150.392726) (xy 180.791593 -150.354017) (xy 180.836951 -150.321566) (xy 180.886551 -150.296065)
			(xy 180.939335 -150.278058) (xy 180.994178 -150.267928) (xy 181.049912 -150.265891) (xy 181.105349 -150.271991)
			(xy 181.159306 -150.286097) (xy 181.210635 -150.307909) (xy 181.258241 -150.336963) (xy 181.301109 -150.372638)
			(xy 181.338326 -150.414175) (xy 181.369099 -150.460688) (xy 181.392771 -150.511185) (xy 181.408839 -150.564592)
			(xy 181.416959 -150.619768) (xy 181.417468 -150.647654) (xy 181.416959 -150.67554) (xy 181.408839 -150.730716)
			(xy 181.392771 -150.784123) (xy 181.369099 -150.83462) (xy 181.338326 -150.881133) (xy 181.301109 -150.92267)
			(xy 181.258241 -150.958345) (xy 181.210635 -150.987399) (xy 181.159306 -151.009211) (xy 181.105349 -151.023317)
			(xy 181.049912 -151.029417) (xy 180.994178 -151.02738) (xy 180.939335 -151.01725) (xy 180.886551 -150.999243)
			(xy 180.836951 -150.973742) (xy 180.791593 -150.941291) (xy 180.751444 -150.902582) (xy 180.717358 -150.858439)
			(xy 180.690062 -150.809804) (xy 180.670139 -150.757713) (xy 180.658013 -150.703276) (xy 180.653942 -150.647654)
			(xy 171.75607 -150.647654) (xy 167.753792 -154.649932) (xy 167.743155 -154.661163) (xy 167.727159 -154.687629)
			(xy 167.71799 -154.717164) (xy 167.716185 -154.748036) (xy 167.721851 -154.778437) (xy 167.727884 -154.79268)
			(xy 167.738739 -154.817655) (xy 167.754054 -154.869911) (xy 167.76178 -154.923815) (xy 167.76176 -154.97827)
			(xy 167.753993 -155.032168) (xy 167.738639 -155.084413) (xy 167.716009 -155.133943) (xy 167.686564 -155.17975)
			(xy 167.650903 -155.220903) (xy 167.60975 -155.256565) (xy 167.563942 -155.28601) (xy 167.514412 -155.30864)
			(xy 167.462167 -155.323994) (xy 167.408269 -155.33176) (xy 167.353814 -155.33178) (xy 167.29991 -155.324054)
			(xy 167.247654 -155.308739) (xy 167.222678 -155.297886) (xy 167.208432 -155.291848) (xy 167.17803 -155.286138)
			(xy 167.147149 -155.287927) (xy 167.11761 -155.297111) (xy 167.091158 -155.313147) (xy 167.07993 -155.323794)
			(xy 167.030146 -155.373578) (xy 167.00373 -155.39974) (xy 166.98908 -155.46578) (xy 170.036742 -155.46578)
			(xy 170.040813 -155.410158) (xy 170.052939 -155.355721) (xy 170.072862 -155.30363) (xy 170.100158 -155.254995)
			(xy 170.134244 -155.210852) (xy 170.174393 -155.172143) (xy 170.219751 -155.139692) (xy 170.269351 -155.114191)
			(xy 170.322135 -155.096184) (xy 170.376978 -155.086054) (xy 170.432712 -155.084017) (xy 170.488149 -155.090117)
			(xy 170.542106 -155.104223) (xy 170.593435 -155.126035) (xy 170.641041 -155.155089) (xy 170.683909 -155.190764)
			(xy 170.721126 -155.232301) (xy 170.751899 -155.278814) (xy 170.775571 -155.329311) (xy 170.791639 -155.382718)
			(xy 170.799759 -155.437894) (xy 170.800268 -155.46578) (xy 170.799759 -155.493666) (xy 170.791639 -155.548842)
			(xy 170.775571 -155.602249) (xy 170.751899 -155.652746) (xy 170.721126 -155.699259) (xy 170.683909 -155.740796)
			(xy 170.641041 -155.776471) (xy 170.593435 -155.805525) (xy 170.542106 -155.827337) (xy 170.488149 -155.841443)
			(xy 170.432712 -155.847543) (xy 170.376978 -155.845506) (xy 170.322135 -155.835376) (xy 170.269351 -155.817369)
			(xy 170.219751 -155.791868) (xy 170.174393 -155.759417) (xy 170.134244 -155.720708) (xy 170.100158 -155.676565)
			(xy 170.072862 -155.62793) (xy 170.052939 -155.575839) (xy 170.040813 -155.521402) (xy 170.036742 -155.46578)
			(xy 166.98908 -155.46578) (xy 166.987728 -155.471876) (xy 167.000428 -155.506674) (xy 167.009249 -155.532326)
			(xy 167.020378 -155.585415) (xy 167.023871 -155.639546) (xy 167.019657 -155.693626) (xy 167.007821 -155.746562)
			(xy 166.988602 -155.797287) (xy 166.962388 -155.844776) (xy 166.929709 -155.888071) (xy 166.910766 -155.907486)
			(xy 166.894002 -155.923996) (xy 166.851838 -156.017722) (xy 166.881556 -156.098494) (xy 166.883663 -156.101228)
			(xy 168.495019 -156.101228) (xy 168.497892 -156.046571) (xy 168.508545 -155.992885) (xy 168.526761 -155.941272)
			(xy 168.552164 -155.892792) (xy 168.584234 -155.848439) (xy 168.622313 -155.809124) (xy 168.665619 -155.775654)
			(xy 168.713263 -155.748715) (xy 168.764267 -155.72886) (xy 168.817586 -155.716497) (xy 168.872123 -155.71188)
			(xy 168.926761 -155.715104) (xy 168.980378 -155.726101) (xy 169.031872 -155.744647) (xy 169.080189 -155.770361)
			(xy 169.124335 -155.802716) (xy 169.163405 -155.841046) (xy 169.196597 -155.884566) (xy 169.223229 -155.932382)
			(xy 169.242756 -155.983513) (xy 169.254776 -156.036909) (xy 169.259043 -156.091475) (xy 169.257726 -156.118814)
			(xy 169.256775 -156.14083) (xy 169.261523 -156.184635) (xy 169.273754 -156.226965) (xy 169.293099 -156.266552)
			(xy 169.318981 -156.302211) (xy 169.350624 -156.332873) (xy 169.38708 -156.35762) (xy 169.427256 -156.37571)
			(xy 169.46995 -156.386602) (xy 169.513883 -156.38997) (xy 169.535856 -156.388308) (xy 169.563145 -156.386191)
			(xy 169.617817 -156.388716) (xy 169.671568 -156.399028) (xy 169.723293 -156.416914) (xy 169.771932 -156.442008)
			(xy 169.816486 -156.473795) (xy 169.856041 -156.511622) (xy 169.889784 -156.554713) (xy 169.917024 -156.602184)
			(xy 169.937201 -156.65306) (xy 169.949901 -156.706296) (xy 169.954864 -156.760802) (xy 169.951987 -156.815457)
			(xy 169.94133 -156.86914) (xy 169.923111 -156.920749) (xy 169.897704 -156.969226) (xy 169.865632 -157.013574)
			(xy 169.827551 -157.052885) (xy 169.784244 -157.08635) (xy 169.736599 -157.113284) (xy 169.685595 -157.133134)
			(xy 169.632277 -157.145491) (xy 169.577741 -157.150103) (xy 169.523106 -157.146874) (xy 169.469492 -157.135872)
			(xy 169.418001 -157.117322) (xy 169.369689 -157.091604) (xy 169.325548 -157.059247) (xy 169.286483 -157.020914)
			(xy 169.253297 -156.977392) (xy 169.22667 -156.929575) (xy 169.207149 -156.878444) (xy 169.195135 -156.825048)
			(xy 169.190874 -156.770484) (xy 169.192194 -156.743146) (xy 169.193162 -156.721131) (xy 169.188408 -156.677327)
			(xy 169.176173 -156.634998) (xy 169.156824 -156.595412) (xy 169.13094 -156.559755) (xy 169.099296 -156.529094)
			(xy 169.06284 -156.504347) (xy 169.022663 -156.486256) (xy 168.97997 -156.475363) (xy 168.936037 -156.471992)
			(xy 168.914064 -156.473652) (xy 168.88678 -156.475826) (xy 168.832105 -156.473304) (xy 168.778352 -156.462995)
			(xy 168.726623 -156.445112) (xy 168.677981 -156.42002) (xy 168.633423 -156.388235) (xy 168.593865 -156.35041)
			(xy 168.560117 -156.307319) (xy 168.532873 -156.259849) (xy 168.512691 -156.208973) (xy 168.499986 -156.155735)
			(xy 168.495019 -156.101228) (xy 166.883663 -156.101228) (xy 166.893494 -156.113988) (xy 166.910139 -156.136331)
			(xy 166.937459 -156.184889) (xy 166.957423 -156.236904) (xy 166.969608 -156.29127) (xy 166.973755 -156.34683)
			(xy 166.969774 -156.402403) (xy 166.957751 -156.456805) (xy 166.937942 -156.508879) (xy 166.910768 -156.557518)
			(xy 166.876806 -156.601685) (xy 166.836781 -156.640443) (xy 166.791543 -156.672965) (xy 166.742055 -156.69856)
			(xy 166.689371 -156.716683) (xy 166.63461 -156.726949) (xy 166.578938 -156.729139) (xy 166.52354 -156.723206)
			(xy 166.469594 -156.709278) (xy 166.418248 -156.687649) (xy 166.370596 -156.658781) (xy 166.327649 -156.623288)
			(xy 166.290324 -156.581925) (xy 166.274496 -156.558996) (xy 166.261627 -156.540579) (xy 166.230507 -156.508176)
			(xy 166.194177 -156.481746) (xy 166.153769 -156.46211) (xy 166.110539 -156.449881) (xy 166.065833 -156.445439)
			(xy 166.021042 -156.448921) (xy 165.977559 -156.46022) (xy 165.936739 -156.478983) (xy 165.89985 -156.504628)
			(xy 165.88359 -156.520134) (xy 165.608 -156.795724) (xy 165.608 -157.793182) (xy 167.2463 -159.431482)
			(xy 169.453052 -159.431482)
		)
		(stroke
			(width 0)
			(type solid)
		)
		(fill yes)
		(layer "In2.Cu")
		(net "LAN2_CTRL_P1V9")
	)
	(gr_poly
		(pts
			(xy 31.152338 -165.295834) (xy 31.152338 -145.95348) (xy 31.151823 -145.930835) (xy 31.143758 -145.886268)
			(xy 31.127922 -145.843836) (xy 31.104818 -145.804882) (xy 31.075176 -145.770639) (xy 31.039934 -145.742191)
			(xy 31.000209 -145.720438) (xy 30.957258 -145.70607) (xy 30.91244 -145.699541) (xy 30.867175 -145.701058)
			(xy 30.822895 -145.710573) (xy 30.781002 -145.727785) (xy 30.761686 -145.739612) (xy 30.73848 -145.753865)
			(xy 30.688888 -145.776364) (xy 30.636601 -145.791586) (xy 30.582682 -145.799222) (xy 30.528224 -145.799115)
			(xy 30.474335 -145.791268) (xy 30.422108 -145.775841) (xy 30.372604 -145.753147) (xy 30.326829 -145.723647)
			(xy 30.285712 -145.68794) (xy 30.250088 -145.64675) (xy 30.220681 -145.600916) (xy 30.198087 -145.551366)
			(xy 30.182766 -145.499108) (xy 30.175029 -145.445203) (xy 30.175033 -145.390745) (xy 30.182777 -145.336841)
			(xy 30.198105 -145.284585) (xy 30.220706 -145.235039) (xy 30.250119 -145.189208) (xy 30.285749 -145.148024)
			(xy 30.326871 -145.112322) (xy 30.37265 -145.082828) (xy 30.422156 -145.06014) (xy 30.474385 -145.044721)
			(xy 30.528276 -145.036881) (xy 30.582733 -145.036782) (xy 30.636652 -145.044425) (xy 30.688937 -145.059654)
			(xy 30.738526 -145.08216) (xy 30.761686 -145.096484) (xy 30.781037 -145.108244) (xy 30.822917 -145.125451)
			(xy 30.867184 -145.134963) (xy 30.912435 -145.136479) (xy 30.95724 -145.129953) (xy 31.000178 -145.115589)
			(xy 31.039891 -145.093843) (xy 31.075122 -145.065403) (xy 31.104755 -145.03117) (xy 31.127852 -144.992227)
			(xy 31.143682 -144.949808) (xy 31.151744 -144.905254) (xy 31.152338 -144.882616) (xy 31.152338 -133.82879)
			(xy 30.405578 -133.08203) (xy 21.881592 -133.08203) (xy 21.335238 -133.628384) (xy 21.335238 -135.387234)
			(xy 28.212714 -135.387234) (xy 28.213598 -135.331216) (xy 28.222665 -135.27593) (xy 28.239722 -135.222564)
			(xy 28.264401 -135.172267) (xy 28.296172 -135.126121) (xy 28.334351 -135.085119) (xy 28.378117 -135.050142)
			(xy 28.426528 -135.021943) (xy 28.478543 -135.001129) (xy 28.533044 -134.988146) (xy 28.588857 -134.983276)
			(xy 28.644782 -134.986621) (xy 28.699617 -134.998111) (xy 28.75218 -135.017498) (xy 28.801343 -135.044366)
			(xy 28.846047 -135.078135) (xy 28.885331 -135.11808) (xy 28.91835 -135.163342) (xy 28.944392 -135.212946)
			(xy 28.962899 -135.265826) (xy 28.973472 -135.320845) (xy 28.975884 -135.376818) (xy 28.970082 -135.432542)
			(xy 28.956192 -135.486818) (xy 28.934512 -135.538479) (xy 28.905509 -135.586413) (xy 28.869807 -135.629589)
			(xy 28.84932 -135.6487) (xy 28.833586 -135.663549) (xy 28.80684 -135.697549) (xy 28.786235 -135.735586)
			(xy 28.772368 -135.776561) (xy 28.765637 -135.819293) (xy 28.766237 -135.862548) (xy 28.774151 -135.905077)
			(xy 28.789151 -135.945652) (xy 28.810803 -135.983102) (xy 28.838482 -136.016346) (xy 28.854654 -136.030716)
			(xy 28.875659 -136.049256) (xy 28.912528 -136.091442) (xy 28.94283 -136.138567) (xy 28.965913 -136.189617)
			(xy 28.98128 -136.243495) (xy 28.988601 -136.299041) (xy 28.987719 -136.35506) (xy 28.978651 -136.410348)
			(xy 28.961595 -136.463715) (xy 28.936915 -136.514013) (xy 28.905144 -136.56016) (xy 28.866965 -136.601164)
			(xy 28.823198 -136.636141) (xy 28.774786 -136.664341) (xy 28.72277 -136.685156) (xy 28.668269 -136.698139)
			(xy 28.612455 -136.70301) (xy 28.556528 -136.699665) (xy 28.501693 -136.688175) (xy 28.449128 -136.668787)
			(xy 28.399964 -136.64192) (xy 28.355259 -136.60815) (xy 28.315974 -136.568204) (xy 28.282955 -136.522941)
			(xy 28.256912 -136.473336) (xy 28.238405 -136.420454) (xy 28.227832 -136.365435) (xy 28.22542 -136.30946)
			(xy 28.231222 -136.253735) (xy 28.245113 -136.199458) (xy 28.266793 -136.147797) (xy 28.295797 -136.099862)
			(xy 28.331501 -136.056686) (xy 28.351988 -136.037574) (xy 28.367748 -136.022751) (xy 28.394493 -135.988747)
			(xy 28.415096 -135.950706) (xy 28.428961 -135.909726) (xy 28.43569 -135.866991) (xy 28.435086 -135.823733)
			(xy 28.427169 -135.781202) (xy 28.412166 -135.740625) (xy 28.39051 -135.703173) (xy 28.362827 -135.669928)
			(xy 28.346654 -135.655558) (xy 28.325651 -135.637016) (xy 28.288783 -135.59483) (xy 28.258483 -135.547706)
			(xy 28.235401 -135.496656) (xy 28.220035 -135.442779) (xy 28.212714 -135.387234) (xy 21.335238 -135.387234)
			(xy 21.335238 -137.476693) (xy 28.552559 -137.476693) (xy 28.552828 -137.420842) (xy 28.561239 -137.365628)
			(xy 28.577613 -137.312231) (xy 28.601599 -137.261792) (xy 28.632685 -137.215391) (xy 28.670206 -137.17402)
			(xy 28.713359 -137.138563) (xy 28.761222 -137.109779) (xy 28.812771 -137.088283) (xy 28.866904 -137.074535)
			(xy 28.922463 -137.068829) (xy 28.978261 -137.071287) (xy 29.033103 -137.081856) (xy 29.085817 -137.10031)
			(xy 29.135277 -137.126255) (xy 29.180424 -137.159136) (xy 29.220292 -137.19825) (xy 29.25403 -137.24276)
			(xy 29.280916 -137.291714) (xy 29.300375 -137.344066) (xy 29.31199 -137.398697) (xy 29.315514 -137.454437)
			(xy 29.310871 -137.510095) (xy 29.29816 -137.564481) (xy 29.277654 -137.616432) (xy 29.24979 -137.664836)
			(xy 29.23286 -137.68705) (xy 29.219406 -137.704694) (xy 29.198338 -137.743743) (xy 29.184373 -137.785857)
			(xy 29.177934 -137.829757) (xy 29.179217 -137.874108) (xy 29.188183 -137.917562) (xy 29.20456 -137.958799)
			(xy 29.227851 -137.996564) (xy 29.242258 -138.01344) (xy 29.260459 -138.034622) (xy 29.291094 -138.081319)
			(xy 29.31459 -138.131984) (xy 29.330446 -138.185534) (xy 29.338323 -138.240824) (xy 29.338052 -138.296672)
			(xy 29.329639 -138.351883) (xy 29.313264 -138.405276) (xy 29.289277 -138.455711) (xy 29.258191 -138.502108)
			(xy 29.220671 -138.543476) (xy 29.177519 -138.578929) (xy 29.129658 -138.60771) (xy 29.078111 -138.629203)
			(xy 29.023981 -138.642948) (xy 28.968425 -138.648652) (xy 28.912631 -138.646193) (xy 28.857792 -138.635623)
			(xy 28.805081 -138.617168) (xy 28.755625 -138.591223) (xy 28.710481 -138.558343) (xy 28.670616 -138.519231)
			(xy 28.636881 -138.474723) (xy 28.609998 -138.42577) (xy 28.590541 -138.373421) (xy 28.578928 -138.318794)
			(xy 28.575405 -138.263057) (xy 28.580049 -138.207402) (xy 28.59276 -138.153019) (xy 28.613266 -138.101072)
			(xy 28.641129 -138.05267) (xy 28.658058 -138.030458) (xy 28.67151 -138.012812) (xy 28.692585 -137.973765)
			(xy 28.706557 -137.931651) (xy 28.712999 -137.88775) (xy 28.711716 -137.843398) (xy 28.702748 -137.799942)
			(xy 28.686367 -137.758706) (xy 28.663071 -137.720942) (xy 28.64866 -137.704068) (xy 28.630436 -137.682903)
			(xy 28.599798 -137.636205) (xy 28.576298 -137.585539) (xy 28.560439 -137.531986) (xy 28.552559 -137.476693)
			(xy 21.335238 -137.476693) (xy 21.335238 -142.487904) (xy 21.539962 -142.692628) (xy 21.591778 -142.693136)
			(xy 21.618633 -142.693896) (xy 21.671737 -142.702029) (xy 21.723174 -142.717532) (xy 21.771928 -142.740098)
			(xy 21.817033 -142.769282) (xy 21.857599 -142.804504) (xy 21.892821 -142.84507) (xy 21.922003 -142.890176)
			(xy 21.944569 -142.93893) (xy 21.960072 -142.990367) (xy 21.968204 -143.043471) (xy 21.968968 -143.070326)
			(xy 21.969476 -143.122142) (xy 23.524464 -144.67713) (xy 23.524464 -155.42006) (xy 27.466542 -155.42006)
			(xy 27.470613 -155.364438) (xy 27.482739 -155.310001) (xy 27.502662 -155.25791) (xy 27.529958 -155.209275)
			(xy 27.564044 -155.165132) (xy 27.604193 -155.126423) (xy 27.649551 -155.093972) (xy 27.699151 -155.068471)
			(xy 27.751935 -155.050464) (xy 27.806778 -155.040334) (xy 27.862512 -155.038297) (xy 27.917949 -155.044397)
			(xy 27.971906 -155.058503) (xy 28.023235 -155.080315) (xy 28.070841 -155.109369) (xy 28.113709 -155.145044)
			(xy 28.150926 -155.186581) (xy 28.181699 -155.233094) (xy 28.205371 -155.283591) (xy 28.221439 -155.336998)
			(xy 28.229559 -155.392174) (xy 28.230068 -155.42006) (xy 28.229559 -155.447946) (xy 28.221439 -155.503122)
			(xy 28.205371 -155.556529) (xy 28.181699 -155.607026) (xy 28.150926 -155.653539) (xy 28.113709 -155.695076)
			(xy 28.070841 -155.730751) (xy 28.023235 -155.759805) (xy 27.971906 -155.781617) (xy 27.917949 -155.795723)
			(xy 27.862512 -155.801823) (xy 27.806778 -155.799786) (xy 27.751935 -155.789656) (xy 27.699151 -155.771649)
			(xy 27.649551 -155.746148) (xy 27.604193 -155.713697) (xy 27.564044 -155.674988) (xy 27.529958 -155.630845)
			(xy 27.502662 -155.58221) (xy 27.482739 -155.530119) (xy 27.470613 -155.475682) (xy 27.466542 -155.42006)
			(xy 23.524464 -155.42006) (xy 23.524464 -156.647896) (xy 27.430982 -156.647896) (xy 27.435053 -156.592274)
			(xy 27.447179 -156.537837) (xy 27.467102 -156.485746) (xy 27.494398 -156.437111) (xy 27.528484 -156.392968)
			(xy 27.568633 -156.354259) (xy 27.613991 -156.321808) (xy 27.663591 -156.296307) (xy 27.716375 -156.2783)
			(xy 27.771218 -156.26817) (xy 27.826952 -156.266133) (xy 27.882389 -156.272233) (xy 27.936346 -156.286339)
			(xy 27.987675 -156.308151) (xy 28.035281 -156.337205) (xy 28.078149 -156.37288) (xy 28.115366 -156.414417)
			(xy 28.146139 -156.46093) (xy 28.169811 -156.511427) (xy 28.185879 -156.564834) (xy 28.193999 -156.62001)
			(xy 28.194508 -156.647896) (xy 28.193999 -156.675782) (xy 28.185879 -156.730958) (xy 28.169811 -156.784365)
			(xy 28.146139 -156.834862) (xy 28.115366 -156.881375) (xy 28.078149 -156.922912) (xy 28.035281 -156.958587)
			(xy 27.987675 -156.987641) (xy 27.936346 -157.009453) (xy 27.882389 -157.023559) (xy 27.826952 -157.029659)
			(xy 27.771218 -157.027622) (xy 27.716375 -157.017492) (xy 27.663591 -156.999485) (xy 27.613991 -156.973984)
			(xy 27.568633 -156.941533) (xy 27.528484 -156.902824) (xy 27.494398 -156.858681) (xy 27.467102 -156.810046)
			(xy 27.447179 -156.757955) (xy 27.435053 -156.703518) (xy 27.430982 -156.647896) (xy 23.524464 -156.647896)
			(xy 23.524464 -157.84195) (xy 27.408122 -157.84195) (xy 27.412193 -157.786328) (xy 27.424319 -157.731891)
			(xy 27.444242 -157.6798) (xy 27.471538 -157.631165) (xy 27.505624 -157.587022) (xy 27.545773 -157.548313)
			(xy 27.591131 -157.515862) (xy 27.640731 -157.490361) (xy 27.693515 -157.472354) (xy 27.748358 -157.462224)
			(xy 27.804092 -157.460187) (xy 27.859529 -157.466287) (xy 27.913486 -157.480393) (xy 27.964815 -157.502205)
			(xy 28.012421 -157.531259) (xy 28.055289 -157.566934) (xy 28.092506 -157.608471) (xy 28.123279 -157.654984)
			(xy 28.146951 -157.705481) (xy 28.163019 -157.758888) (xy 28.171139 -157.814064) (xy 28.171648 -157.84195)
			(xy 28.171139 -157.869836) (xy 28.163019 -157.925012) (xy 28.146951 -157.978419) (xy 28.123279 -158.028916)
			(xy 28.092506 -158.075429) (xy 28.055289 -158.116966) (xy 28.012421 -158.152641) (xy 27.964815 -158.181695)
			(xy 27.913486 -158.203507) (xy 27.859529 -158.217613) (xy 27.804092 -158.223713) (xy 27.748358 -158.221676)
			(xy 27.693515 -158.211546) (xy 27.640731 -158.193539) (xy 27.591131 -158.168038) (xy 27.545773 -158.135587)
			(xy 27.505624 -158.096878) (xy 27.471538 -158.052735) (xy 27.444242 -158.0041) (xy 27.424319 -157.952009)
			(xy 27.412193 -157.897572) (xy 27.408122 -157.84195) (xy 23.524464 -157.84195) (xy 23.524464 -163.750498)
			(xy 27.370022 -163.750498) (xy 27.374093 -163.694876) (xy 27.386219 -163.640439) (xy 27.406142 -163.588348)
			(xy 27.433438 -163.539713) (xy 27.467524 -163.49557) (xy 27.507673 -163.456861) (xy 27.553031 -163.42441)
			(xy 27.602631 -163.398909) (xy 27.655415 -163.380902) (xy 27.710258 -163.370772) (xy 27.765992 -163.368735)
			(xy 27.821429 -163.374835) (xy 27.875386 -163.388941) (xy 27.926715 -163.410753) (xy 27.974321 -163.439807)
			(xy 28.017189 -163.475482) (xy 28.054406 -163.517019) (xy 28.085179 -163.563532) (xy 28.108851 -163.614029)
			(xy 28.124919 -163.667436) (xy 28.133039 -163.722612) (xy 28.133548 -163.750498) (xy 28.133039 -163.778384)
			(xy 28.124919 -163.83356) (xy 28.108851 -163.886967) (xy 28.085179 -163.937464) (xy 28.054406 -163.983977)
			(xy 28.017189 -164.025514) (xy 27.974321 -164.061189) (xy 27.926715 -164.090243) (xy 27.875386 -164.112055)
			(xy 27.821429 -164.126161) (xy 27.765992 -164.132261) (xy 27.710258 -164.130224) (xy 27.655415 -164.120094)
			(xy 27.602631 -164.102087) (xy 27.553031 -164.076586) (xy 27.507673 -164.044135) (xy 27.467524 -164.005426)
			(xy 27.433438 -163.961283) (xy 27.406142 -163.912648) (xy 27.386219 -163.860557) (xy 27.374093 -163.80612)
			(xy 27.370022 -163.750498) (xy 23.524464 -163.750498) (xy 23.524464 -164.342572) (xy 24.025098 -164.843206)
			(xy 27.370022 -164.843206) (xy 27.374093 -164.787584) (xy 27.386219 -164.733147) (xy 27.406142 -164.681056)
			(xy 27.433438 -164.632421) (xy 27.467524 -164.588278) (xy 27.507673 -164.549569) (xy 27.553031 -164.517118)
			(xy 27.602631 -164.491617) (xy 27.655415 -164.47361) (xy 27.710258 -164.46348) (xy 27.765992 -164.461443)
			(xy 27.821429 -164.467543) (xy 27.875386 -164.481649) (xy 27.926715 -164.503461) (xy 27.974321 -164.532515)
			(xy 28.017189 -164.56819) (xy 28.054406 -164.609727) (xy 28.085179 -164.65624) (xy 28.108851 -164.706737)
			(xy 28.124919 -164.760144) (xy 28.133039 -164.81532) (xy 28.133548 -164.843206) (xy 28.133039 -164.871092)
			(xy 28.124919 -164.926268) (xy 28.108851 -164.979675) (xy 28.085179 -165.030172) (xy 28.054406 -165.076685)
			(xy 28.017189 -165.118222) (xy 27.974321 -165.153897) (xy 27.926715 -165.182951) (xy 27.875386 -165.204763)
			(xy 27.821429 -165.218869) (xy 27.765992 -165.224969) (xy 27.710258 -165.222932) (xy 27.655415 -165.212802)
			(xy 27.602631 -165.194795) (xy 27.553031 -165.169294) (xy 27.507673 -165.136843) (xy 27.467524 -165.098134)
			(xy 27.433438 -165.053991) (xy 27.406142 -165.005356) (xy 27.386219 -164.953265) (xy 27.374093 -164.898828)
			(xy 27.370022 -164.843206) (xy 24.025098 -164.843206) (xy 24.86914 -165.687248) (xy 30.760924 -165.687248)
		)
		(stroke
			(width 0)
			(type solid)
		)
		(fill yes)
		(layer "In2.Cu")
		(net "P1V9_LAN1")
	)
	(gr_poly
		(pts
			(xy 71.77278 -13.366496) (xy 71.77278 -8.115046) (xy 71.59752 -7.939786) (xy 70.26402 -7.939786)
			(xy 70.247363 -7.940278) (xy 70.215183 -7.948896) (xy 70.186329 -7.965549) (xy 70.162769 -7.989102)
			(xy 70.146109 -8.017951) (xy 70.137483 -8.050129) (xy 70.13702 -8.066786) (xy 70.13702 -10.62482)
			(xy 69.54012 -11.22172) (xy 66.607182 -11.22172) (xy 65.00368 -9.618218) (xy 65.00368 -7.62) (xy 64.994028 -7.596632)
			(xy 64.983126 -7.568745) (xy 64.969164 -7.510522) (xy 64.964468 -7.450833) (xy 64.969154 -7.391144)
			(xy 64.983105 -7.332918) (xy 64.994028 -7.30504) (xy 65.00368 -7.281672) (xy 65.00368 -2.585974)
			(xy 64.215772 -1.798066) (xy 49.3522 -1.798066) (xy 49.33555 -1.798609) (xy 49.303384 -1.807226)
			(xy 49.274544 -1.823874) (xy 49.250995 -1.847417) (xy 49.234339 -1.876253) (xy 49.225714 -1.908416)
			(xy 49.2252 -1.925066) (xy 49.2252 -4.591304) (xy 49.48174 -4.847844) (xy 51.713384 -4.847844) (xy 52.283152 -5.417612)
			(xy 56.004533 -5.417612) (xy 56.004536 -5.361546) (xy 56.012746 -5.306084) (xy 56.028985 -5.252422)
			(xy 56.052905 -5.201714) (xy 56.083989 -5.155054) (xy 56.121569 -5.113446) (xy 56.164834 -5.077788)
			(xy 56.212852 -5.048846) (xy 56.26459 -5.027245) (xy 56.318933 -5.013449) (xy 56.374709 -5.007757)
			(xy 56.430718 -5.01029) (xy 56.485753 -5.020995) (xy 56.538628 -5.039639) (xy 56.588204 -5.065823)
			(xy 56.633414 -5.098981) (xy 56.673283 -5.1384) (xy 56.690514 -5.160518) (xy 56.70507 -5.179016)
			(xy 56.739804 -5.210777) (xy 56.779792 -5.235599) (xy 56.823666 -5.252635) (xy 56.869927 -5.2613)
			(xy 56.916993 -5.2613) (xy 56.963254 -5.252635) (xy 57.007128 -5.235599) (xy 57.047116 -5.210777)
			(xy 57.08185 -5.179016) (xy 57.096406 -5.160518) (xy 57.113129 -5.139054) (xy 57.151655 -5.100631)
			(xy 57.195248 -5.068072) (xy 57.243025 -5.042036) (xy 57.294016 -5.023052) (xy 57.347188 -5.011505)
			(xy 57.40146 -5.00763) (xy 57.455732 -5.011505) (xy 57.508904 -5.023052) (xy 57.559895 -5.042036)
			(xy 57.607672 -5.068072) (xy 57.651265 -5.100631) (xy 57.689791 -5.139054) (xy 57.706514 -5.160518)
			(xy 57.72107 -5.179016) (xy 57.755804 -5.210777) (xy 57.795792 -5.235599) (xy 57.839666 -5.252635)
			(xy 57.885927 -5.2613) (xy 57.932993 -5.2613) (xy 57.979254 -5.252635) (xy 58.023128 -5.235599) (xy 58.063116 -5.210777)
			(xy 58.09785 -5.179016) (xy 58.112406 -5.160518) (xy 58.129614 -5.138373) (xy 58.169491 -5.098937)
			(xy 58.214711 -5.065764) (xy 58.264299 -5.039567) (xy 58.317188 -5.020912) (xy 58.372239 -5.0102)
			(xy 58.428264 -5.007661) (xy 58.484058 -5.013351) (xy 58.538417 -5.027147) (xy 58.590172 -5.048751)
			(xy 58.638206 -5.077699) (xy 58.681486 -5.113367) (xy 58.719078 -5.154985) (xy 58.750173 -5.201659)
			(xy 58.774101 -5.252381) (xy 58.790346 -5.306059) (xy 58.798559 -5.361538) (xy 58.798562 -5.417612)
			(xy 61.084533 -5.417612) (xy 61.084536 -5.361546) (xy 61.092746 -5.306084) (xy 61.108985 -5.252422)
			(xy 61.132905 -5.201714) (xy 61.163989 -5.155054) (xy 61.201569 -5.113446) (xy 61.244834 -5.077788)
			(xy 61.292852 -5.048846) (xy 61.34459 -5.027245) (xy 61.398933 -5.013449) (xy 61.454709 -5.007757)
			(xy 61.510718 -5.01029) (xy 61.565753 -5.020995) (xy 61.618628 -5.039639) (xy 61.668204 -5.065823)
			(xy 61.713414 -5.098981) (xy 61.753283 -5.1384) (xy 61.770514 -5.160518) (xy 61.78507 -5.179016)
			(xy 61.819804 -5.210777) (xy 61.859792 -5.235599) (xy 61.903666 -5.252635) (xy 61.949927 -5.2613)
			(xy 61.996993 -5.2613) (xy 62.043254 -5.252635) (xy 62.087128 -5.235599) (xy 62.127116 -5.210777)
			(xy 62.16185 -5.179016) (xy 62.176406 -5.160518) (xy 62.193129 -5.139054) (xy 62.231655 -5.100631)
			(xy 62.275248 -5.068072) (xy 62.323025 -5.042036) (xy 62.374016 -5.023052) (xy 62.427188 -5.011505)
			(xy 62.48146 -5.00763) (xy 62.535732 -5.011505) (xy 62.588904 -5.023052) (xy 62.639895 -5.042036)
			(xy 62.687672 -5.068072) (xy 62.731265 -5.100631) (xy 62.769791 -5.139054) (xy 62.786514 -5.160518)
			(xy 62.80107 -5.179016) (xy 62.835804 -5.210777) (xy 62.875792 -5.235599) (xy 62.919666 -5.252635)
			(xy 62.965927 -5.2613) (xy 63.012993 -5.2613) (xy 63.059254 -5.252635) (xy 63.103128 -5.235599) (xy 63.143116 -5.210777)
			(xy 63.17785 -5.179016) (xy 63.192406 -5.160518) (xy 63.209614 -5.138373) (xy 63.249491 -5.098937)
			(xy 63.294711 -5.065764) (xy 63.344299 -5.039567) (xy 63.397188 -5.020912) (xy 63.452239 -5.0102)
			(xy 63.508264 -5.007661) (xy 63.564058 -5.013351) (xy 63.618417 -5.027147) (xy 63.670172 -5.048751)
			(xy 63.718206 -5.077699) (xy 63.761486 -5.113367) (xy 63.799078 -5.154985) (xy 63.830173 -5.201659)
			(xy 63.854101 -5.252381) (xy 63.870346 -5.306059) (xy 63.878559 -5.361538) (xy 63.878562 -5.417621)
			(xy 63.870355 -5.4731) (xy 63.854116 -5.52678) (xy 63.830194 -5.577505) (xy 63.799104 -5.624182)
			(xy 63.761516 -5.665804) (xy 63.71824 -5.701477) (xy 63.670209 -5.73043) (xy 63.618457 -5.75204)
			(xy 63.564099 -5.765842) (xy 63.508306 -5.771538) (xy 63.45228 -5.769005) (xy 63.397229 -5.758299)
			(xy 63.344337 -5.739649) (xy 63.294746 -5.713458) (xy 63.249523 -5.68029) (xy 63.209642 -5.640859)
			(xy 63.192406 -5.618734) (xy 63.17785 -5.600236) (xy 63.143116 -5.568475) (xy 63.103128 -5.543653)
			(xy 63.059254 -5.526617) (xy 63.012993 -5.517952) (xy 62.965927 -5.517952) (xy 62.919666 -5.526617)
			(xy 62.875792 -5.543653) (xy 62.835804 -5.568475) (xy 62.80107 -5.600236) (xy 62.786514 -5.618734)
			(xy 62.769791 -5.640198) (xy 62.731265 -5.678621) (xy 62.687672 -5.71118) (xy 62.639895 -5.737216)
			(xy 62.588904 -5.7562) (xy 62.535732 -5.767747) (xy 62.48146 -5.771622) (xy 62.427188 -5.767747)
			(xy 62.374016 -5.7562) (xy 62.323025 -5.737216) (xy 62.275248 -5.71118) (xy 62.231655 -5.678621)
			(xy 62.193129 -5.640198) (xy 62.176406 -5.618734) (xy 62.16185 -5.600236) (xy 62.127116 -5.568475)
			(xy 62.087128 -5.543653) (xy 62.043254 -5.526617) (xy 61.996993 -5.517952) (xy 61.949927 -5.517952)
			(xy 61.903666 -5.526617) (xy 61.859792 -5.543653) (xy 61.819804 -5.568475) (xy 61.78507 -5.600236)
			(xy 61.770514 -5.618734) (xy 61.753256 -5.640831) (xy 61.713382 -5.680246) (xy 61.668169 -5.713399)
			(xy 61.618589 -5.739577) (xy 61.565712 -5.758216) (xy 61.510676 -5.768915) (xy 61.454667 -5.771442)
			(xy 61.398892 -5.765743) (xy 61.344551 -5.751942) (xy 61.292815 -5.730335) (xy 61.2448 -5.701388)
			(xy 61.201539 -5.665725) (xy 61.163964 -5.624113) (xy 61.132884 -5.57745) (xy 61.10897 -5.526739)
			(xy 61.092737 -5.473075) (xy 61.084533 -5.417612) (xy 58.798562 -5.417612) (xy 58.798562 -5.417621)
			(xy 58.790355 -5.4731) (xy 58.774116 -5.52678) (xy 58.750194 -5.577505) (xy 58.719104 -5.624182)
			(xy 58.681516 -5.665804) (xy 58.63824 -5.701477) (xy 58.590209 -5.73043) (xy 58.538457 -5.75204)
			(xy 58.484099 -5.765842) (xy 58.428306 -5.771538) (xy 58.37228 -5.769005) (xy 58.317229 -5.758299)
			(xy 58.264337 -5.739649) (xy 58.214746 -5.713458) (xy 58.169523 -5.68029) (xy 58.129642 -5.640859)
			(xy 58.112406 -5.618734) (xy 58.09785 -5.600236) (xy 58.063116 -5.568475) (xy 58.023128 -5.543653)
			(xy 57.979254 -5.526617) (xy 57.932993 -5.517952) (xy 57.885927 -5.517952) (xy 57.839666 -5.526617)
			(xy 57.795792 -5.543653) (xy 57.755804 -5.568475) (xy 57.72107 -5.600236) (xy 57.706514 -5.618734)
			(xy 57.689791 -5.640198) (xy 57.651265 -5.678621) (xy 57.607672 -5.71118) (xy 57.559895 -5.737216)
			(xy 57.508904 -5.7562) (xy 57.455732 -5.767747) (xy 57.40146 -5.771622) (xy 57.347188 -5.767747)
			(xy 57.294016 -5.7562) (xy 57.243025 -5.737216) (xy 57.195248 -5.71118) (xy 57.151655 -5.678621)
			(xy 57.113129 -5.640198) (xy 57.096406 -5.618734) (xy 57.08185 -5.600236) (xy 57.047116 -5.568475)
			(xy 57.007128 -5.543653) (xy 56.963254 -5.526617) (xy 56.916993 -5.517952) (xy 56.869927 -5.517952)
			(xy 56.823666 -5.526617) (xy 56.779792 -5.543653) (xy 56.739804 -5.568475) (xy 56.70507 -5.600236)
			(xy 56.690514 -5.618734) (xy 56.673256 -5.640831) (xy 56.633382 -5.680246) (xy 56.588169 -5.713399)
			(xy 56.538589 -5.739577) (xy 56.485712 -5.758216) (xy 56.430676 -5.768915) (xy 56.374667 -5.771442)
			(xy 56.318892 -5.765743) (xy 56.264551 -5.751942) (xy 56.212815 -5.730335) (xy 56.1648 -5.701388)
			(xy 56.121539 -5.665725) (xy 56.083964 -5.624113) (xy 56.052884 -5.57745) (xy 56.02897 -5.526739)
			(xy 56.012737 -5.473075) (xy 56.004533 -5.417612) (xy 52.283152 -5.417612) (xy 52.398168 -5.532628)
			(xy 52.398168 -6.64845) (xy 52.86502 -7.115302) (xy 53.500274 -7.115302) (xy 53.529484 -7.144512)
			(xy 59.699144 -7.144512) (xy 60.59678 -8.042148) (xy 60.59678 -11.586021) (xy 61.160728 -11.586021)
			(xy 61.160729 -11.529954) (xy 61.168938 -11.474491) (xy 61.185177 -11.420827) (xy 61.209096 -11.370118)
			(xy 61.24018 -11.323457) (xy 61.277759 -11.281848) (xy 61.321024 -11.246187) (xy 61.369043 -11.217244)
			(xy 61.420781 -11.195642) (xy 61.475124 -11.181845) (xy 61.530901 -11.176151) (xy 61.586911 -11.178683)
			(xy 61.641946 -11.189387) (xy 61.694823 -11.208031) (xy 61.744401 -11.234214) (xy 61.789612 -11.267372)
			(xy 61.829483 -11.30679) (xy 61.846714 -11.328908) (xy 61.86127 -11.347406) (xy 61.896004 -11.379167)
			(xy 61.935992 -11.403989) (xy 61.979866 -11.421025) (xy 62.026127 -11.42969) (xy 62.073193 -11.42969)
			(xy 62.119454 -11.421025) (xy 62.163328 -11.403989) (xy 62.203316 -11.379167) (xy 62.23805 -11.347406)
			(xy 62.252606 -11.328908) (xy 62.269329 -11.307444) (xy 62.307855 -11.269021) (xy 62.351448 -11.236462)
			(xy 62.399225 -11.210426) (xy 62.450216 -11.191442) (xy 62.503388 -11.179895) (xy 62.55766 -11.17602)
			(xy 62.611932 -11.179895) (xy 62.665104 -11.191442) (xy 62.716095 -11.210426) (xy 62.763872 -11.236462)
			(xy 62.807465 -11.269021) (xy 62.845991 -11.307444) (xy 62.862714 -11.328908) (xy 62.87727 -11.347406)
			(xy 62.912004 -11.379167) (xy 62.951992 -11.403989) (xy 62.995866 -11.421025) (xy 63.042127 -11.42969)
			(xy 63.089193 -11.42969) (xy 63.135454 -11.421025) (xy 63.179328 -11.403989) (xy 63.219316 -11.379167)
			(xy 63.25405 -11.347406) (xy 63.268606 -11.328908) (xy 63.285824 -11.306771) (xy 63.325701 -11.267337)
			(xy 63.370921 -11.234165) (xy 63.420509 -11.20797) (xy 63.473398 -11.189316) (xy 63.528447 -11.178605)
			(xy 63.584472 -11.176067) (xy 63.640264 -11.181758) (xy 63.694623 -11.195555) (xy 63.746376 -11.21716)
			(xy 63.794409 -11.246109) (xy 63.837687 -11.281777) (xy 63.875278 -11.323395) (xy 63.906372 -11.370069)
			(xy 63.930298 -11.420791) (xy 63.946542 -11.474469) (xy 63.954753 -11.529946) (xy 63.954755 -11.586028)
			(xy 63.946548 -11.641506) (xy 63.930307 -11.695186) (xy 63.906384 -11.745909) (xy 63.875294 -11.792584)
			(xy 63.837706 -11.834206) (xy 63.79443 -11.869876) (xy 63.746399 -11.898828) (xy 63.694647 -11.920437)
			(xy 63.64029 -11.934237) (xy 63.584498 -11.939932) (xy 63.528473 -11.937398) (xy 63.473422 -11.926691)
			(xy 63.420532 -11.908041) (xy 63.370942 -11.881849) (xy 63.32572 -11.84868) (xy 63.285841 -11.809249)
			(xy 63.268606 -11.787124) (xy 63.25405 -11.768626) (xy 63.219316 -11.736865) (xy 63.179328 -11.712043)
			(xy 63.135454 -11.695007) (xy 63.089193 -11.686342) (xy 63.042127 -11.686342) (xy 62.995866 -11.695007)
			(xy 62.951992 -11.712043) (xy 62.912004 -11.736865) (xy 62.87727 -11.768626) (xy 62.862714 -11.787124)
			(xy 62.845991 -11.808588) (xy 62.807465 -11.847011) (xy 62.763872 -11.87957) (xy 62.716095 -11.905606)
			(xy 62.665104 -11.92459) (xy 62.611932 -11.936137) (xy 62.55766 -11.940012) (xy 62.503388 -11.936137)
			(xy 62.450216 -11.92459) (xy 62.399225 -11.905606) (xy 62.351448 -11.87957) (xy 62.307855 -11.847011)
			(xy 62.269329 -11.808588) (xy 62.252606 -11.787124) (xy 62.23805 -11.768626) (xy 62.203316 -11.736865)
			(xy 62.163328 -11.712043) (xy 62.119454 -11.695007) (xy 62.073193 -11.686342) (xy 62.026127 -11.686342)
			(xy 61.979866 -11.695007) (xy 61.935992 -11.712043) (xy 61.896004 -11.736865) (xy 61.86127 -11.768626)
			(xy 61.846714 -11.787124) (xy 61.829466 -11.809229) (xy 61.789592 -11.848645) (xy 61.744379 -11.8818)
			(xy 61.694799 -11.90798) (xy 61.641922 -11.92662) (xy 61.586885 -11.93732) (xy 61.530875 -11.939848)
			(xy 61.475098 -11.934151) (xy 61.420756 -11.92035) (xy 61.36902 -11.898744) (xy 61.321003 -11.869798)
			(xy 61.27774 -11.834135) (xy 61.240164 -11.792523) (xy 61.209083 -11.74586) (xy 61.185168 -11.695149)
			(xy 61.168933 -11.641484) (xy 61.160728 -11.586021) (xy 60.59678 -11.586021) (xy 60.59678 -12.74191)
			(xy 60.60313 -12.752324) (xy 60.92952 -12.752324) (xy 60.980828 -12.728194) (xy 60.998862 -12.70635)
			(xy 61.017077 -12.68512) (xy 61.05866 -12.647705) (xy 61.105261 -12.616763) (xy 61.15588 -12.592957)
			(xy 61.209433 -12.576797) (xy 61.264771 -12.568629) (xy 61.320709 -12.568629) (xy 61.376047 -12.576797)
			(xy 61.4296 -12.592957) (xy 61.480219 -12.616763) (xy 61.52682 -12.647705) (xy 61.568403 -12.68512)
			(xy 61.586618 -12.70635) (xy 61.604652 -12.728194) (xy 61.65596 -12.752324) (xy 61.925454 -12.752324)
			(xy 61.980064 -12.72413) (xy 61.997844 -12.698984) (xy 62.014458 -12.676481) (xy 62.053193 -12.636131)
			(xy 62.097405 -12.601868) (xy 62.146144 -12.574426) (xy 62.198368 -12.554393) (xy 62.252956 -12.5422)
			(xy 62.30874 -12.538106) (xy 62.364524 -12.5422) (xy 62.419112 -12.554393) (xy 62.471336 -12.574426)
			(xy 62.520075 -12.601868) (xy 62.564287 -12.636131) (xy 62.603022 -12.676481) (xy 62.619636 -12.698984)
			(xy 62.637416 -12.72413) (xy 62.692026 -12.752324) (xy 62.937898 -12.752324) (xy 62.992762 -12.723876)
			(xy 63.010796 -12.69873) (xy 63.027391 -12.676122) (xy 63.066128 -12.63557) (xy 63.110385 -12.601126)
			(xy 63.159209 -12.573535) (xy 63.211547 -12.553391) (xy 63.266271 -12.541128) (xy 63.3222 -12.537011)
			(xy 63.378129 -12.541128) (xy 63.432853 -12.553391) (xy 63.485191 -12.573535) (xy 63.534015 -12.601126)
			(xy 63.578272 -12.63557) (xy 63.617009 -12.676122) (xy 63.633604 -12.69873) (xy 63.651638 -12.723876)
			(xy 63.706502 -12.752324) (xy 65.268856 -12.752324) (xy 65.282318 -12.765786) (xy 65.671446 -12.765786)
			(xy 66.476372 -13.570712) (xy 71.568564 -13.570712)
		)
		(stroke
			(width 0)
			(type solid)
		)
		(fill yes)
		(layer "In2.Cu")
		(net "P12V_AUX")
	)
	(gr_poly
		(pts
			(xy 62.764924 -98.316288) (xy 62.78157 -98.315742) (xy 62.813725 -98.30712) (xy 62.842554 -98.290469)
			(xy 62.866092 -98.266925) (xy 62.882734 -98.238092) (xy 62.891347 -98.205934) (xy 62.891924 -98.189288)
			(xy 62.891924 -97.329752) (xy 62.89167 -97.329498) (xy 62.89167 -91.016836) (xy 62.891216 -90.995268)
			(xy 62.883936 -90.952752) (xy 62.869577 -90.912076) (xy 62.848554 -90.874411) (xy 62.821471 -90.840838)
			(xy 62.789105 -90.812323) (xy 62.752387 -90.789686) (xy 62.712373 -90.773576) (xy 62.670213 -90.764457)
			(xy 62.627118 -90.762591) (xy 62.605666 -90.764868) (xy 62.578619 -90.768294) (xy 62.524101 -90.768302)
			(xy 62.470136 -90.760551) (xy 62.417824 -90.745198) (xy 62.36823 -90.722556) (xy 62.322363 -90.693086)
			(xy 62.281157 -90.657388) (xy 62.245452 -90.616189) (xy 62.215974 -90.570327) (xy 62.193324 -90.520736)
			(xy 62.177963 -90.468427) (xy 62.170202 -90.414463) (xy 62.170202 -90.359945) (xy 62.177961 -90.305982)
			(xy 62.193321 -90.253672) (xy 62.21597 -90.204081) (xy 62.245447 -90.158218) (xy 62.281151 -90.117018)
			(xy 62.322356 -90.081319) (xy 62.368222 -90.051848) (xy 62.417816 -90.029205) (xy 62.470128 -90.013851)
			(xy 62.524092 -90.006099) (xy 62.57861 -90.006106) (xy 62.605666 -90.009472) (xy 62.627119 -90.011739)
			(xy 62.670215 -90.009873) (xy 62.712376 -90.000755) (xy 62.752391 -89.984646) (xy 62.78911 -89.96201)
			(xy 62.821479 -89.933497) (xy 62.848566 -89.899926) (xy 62.869593 -89.862262) (xy 62.883956 -89.821588)
			(xy 62.891243 -89.779072) (xy 62.89167 -89.757504) (xy 62.89167 -87.260176) (xy 62.891197 -87.237812)
			(xy 62.883362 -87.193775) (xy 62.867937 -87.15179) (xy 62.845401 -87.113155) (xy 62.816448 -87.079062)
			(xy 62.781973 -87.050564) (xy 62.743041 -87.028543) (xy 62.700855 -87.013678) (xy 62.656718 -87.006428)
			(xy 62.611994 -87.007018) (xy 62.568063 -87.015429) (xy 62.546992 -87.02294) (xy 62.521582 -87.032573)
			(xy 62.468766 -87.04536) (xy 62.41467 -87.050516) (xy 62.36039 -87.047936) (xy 62.307026 -87.037673)
			(xy 62.255662 -87.019935) (xy 62.23127 -87.007954) (xy 62.207406 -86.995167) (xy 62.163224 -86.963875)
			(xy 62.12391 -86.926653) (xy 62.09025 -86.884247) (xy 62.062923 -86.83751) (xy 62.042475 -86.78738)
			(xy 62.029318 -86.734863) (xy 62.023716 -86.681013) (xy 62.025781 -86.626912) (xy 62.035472 -86.573646)
			(xy 62.052594 -86.522285) (xy 62.076803 -86.473859) (xy 62.107615 -86.429341) (xy 62.144408 -86.389625)
			(xy 62.186446 -86.355508) (xy 62.232885 -86.327675) (xy 62.257686 -86.31682) (xy 62.278784 -86.307418)
			(xy 62.317442 -86.282146) (xy 62.350897 -86.250304) (xy 62.378048 -86.212941) (xy 62.398001 -86.171287)
			(xy 62.410099 -86.126714) (xy 62.413943 -86.080688) (xy 62.409408 -86.034726) (xy 62.396642 -85.990339)
			(xy 62.376066 -85.94899) (xy 62.362588 -85.930232) (xy 62.3449 -85.907804) (xy 62.315733 -85.858692)
			(xy 62.294214 -85.805781) (xy 62.280823 -85.750254) (xy 62.275861 -85.693351) (xy 62.279437 -85.636343)
			(xy 62.291472 -85.580506) (xy 62.311696 -85.527087) (xy 62.339659 -85.477281) (xy 62.374734 -85.432199)
			(xy 62.416138 -85.39285) (xy 62.462946 -85.360114) (xy 62.514111 -85.334722) (xy 62.56849 -85.317241)
			(xy 62.624867 -85.308063) (xy 62.653418 -85.30717) (xy 62.657228 -85.30717) (xy 62.673879 -85.306672)
			(xy 62.706044 -85.298046) (xy 62.734881 -85.281388) (xy 62.758424 -85.257835) (xy 62.775068 -85.22899)
			(xy 62.78368 -85.196821) (xy 62.784228 -85.18017) (xy 62.784228 -85.132418) (xy 62.783974 -85.084412)
			(xy 62.692788 -84.96427) (xy 62.658498 -84.951316) (xy 62.63746 -84.943022) (xy 62.597348 -84.922138)
			(xy 62.578488 -84.90966) (xy 62.556606 -84.894193) (xy 62.51699 -84.858112) (xy 62.482809 -84.816844)
			(xy 62.454737 -84.771201) (xy 62.433324 -84.722081) (xy 62.418992 -84.670448) (xy 62.412023 -84.617319)
			(xy 62.412553 -84.563737) (xy 62.420573 -84.510756) (xy 62.427866 -84.484972) (xy 62.438026 -84.45119)
			(xy 62.421008 -84.383626) (xy 62.307216 -84.269834) (xy 62.307216 -83.681316) (xy 62.410848 -83.577684)
			(xy 62.410848 -83.235038) (xy 62.410469 -83.220667) (xy 62.404024 -83.192657) (xy 62.391453 -83.16681)
			(xy 62.3734 -83.144445) (xy 62.350786 -83.126706) (xy 62.33795 -83.12023) (xy 62.333632 -83.118198)
			(xy 62.333124 -83.117944) (xy 62.304168 -83.104007) (xy 62.249709 -83.06989) (xy 62.199984 -83.029183)
			(xy 62.155784 -82.982534) (xy 62.117815 -82.930687) (xy 62.086682 -82.874469) (xy 62.062881 -82.814776)
			(xy 62.046792 -82.752559) (xy 62.038672 -82.688811) (xy 62.03823 -82.65668) (xy 62.038484 -82.65668)
			(xy 62.038484 -82.44332) (xy 61.90107 -82.305906) (xy 60.813442 -82.305906) (xy 60.7441 -82.375248)
			(xy 60.728227 -82.391803) (xy 60.702134 -82.429514) (xy 60.683236 -82.471298) (xy 60.672147 -82.515796)
			(xy 60.669229 -82.561562) (xy 60.674576 -82.607108) (xy 60.688013 -82.650954) (xy 60.709106 -82.691674)
			(xy 60.737166 -82.727945) (xy 60.771284 -82.758589) (xy 60.790582 -82.77098) (xy 60.813161 -82.785422)
			(xy 60.854412 -82.819642) (xy 60.890467 -82.8593) (xy 60.920617 -82.903614) (xy 60.944267 -82.951711)
			(xy 60.960952 -83.002645) (xy 60.970344 -83.055413) (xy 60.972258 -83.108977) (xy 60.966656 -83.162281)
			(xy 60.953648 -83.214276) (xy 60.93349 -83.263938) (xy 60.90658 -83.31029) (xy 60.873447 -83.35242)
			(xy 60.834743 -83.389497) (xy 60.791231 -83.420792) (xy 60.767722 -83.433666) (xy 60.743126 -83.446028)
			(xy 60.691209 -83.464329) (xy 60.637198 -83.474965) (xy 60.609734 -83.476846) (xy 60.593662 -83.478117)
			(xy 60.562899 -83.487732) (xy 60.535531 -83.504757) (xy 60.51331 -83.528103) (xy 60.497655 -83.556277)
			(xy 60.489568 -83.587477) (xy 60.489084 -83.603592) (xy 60.489084 -84.111846) (xy 60.489576 -84.127991)
			(xy 60.497701 -84.159242) (xy 60.513396 -84.187462) (xy 60.53566 -84.21085) (xy 60.563073 -84.227915)
			(xy 60.593887 -84.237568) (xy 60.609988 -84.238846) (xy 60.637976 -84.240722) (xy 60.692994 -84.251659)
			(xy 60.745817 -84.270533) (xy 60.795306 -84.296938) (xy 60.840397 -84.330306) (xy 60.880115 -84.369916)
			(xy 60.913605 -84.414915) (xy 60.940145 -84.464333) (xy 60.950094 -84.49056) (xy 60.962794 -84.525358)
			(xy 61.08065 -84.616544) (xy 61.122052 -84.61756) (xy 61.148986 -84.618742) (xy 61.202142 -84.627748)
			(xy 61.2535 -84.644146) (xy 61.302039 -84.66761) (xy 61.346791 -84.697673) (xy 61.386867 -84.733736)
			(xy 61.421467 -84.775081) (xy 61.449904 -84.820884) (xy 61.47161 -84.870234) (xy 61.486153 -84.922148)
			(xy 61.493245 -84.975592) (xy 61.492743 -85.029503) (xy 61.484658 -85.082806) (xy 61.46915 -85.13444)
			(xy 61.446529 -85.183377) (xy 61.417245 -85.228644) (xy 61.381881 -85.269337) (xy 61.361828 -85.287358)
			(xy 61.344461 -85.303143) (xy 61.315266 -85.339882) (xy 61.293312 -85.381355) (xy 61.279344 -85.426154)
			(xy 61.273837 -85.472756) (xy 61.276978 -85.519577) (xy 61.288661 -85.565025) (xy 61.308488 -85.607557)
			(xy 61.321696 -85.626956) (xy 61.338211 -85.650061) (xy 61.364947 -85.700166) (xy 61.383961 -85.75368)
			(xy 61.394834 -85.809421) (xy 61.397324 -85.866158) (xy 61.391378 -85.922637) (xy 61.377126 -85.977612)
			(xy 61.354883 -86.029866) (xy 61.325141 -86.078247) (xy 61.288556 -86.121685) (xy 61.245937 -86.159221)
			(xy 61.222382 -86.175088) (xy 61.197236 -86.191344) (xy 61.14415 -86.281006) (xy 61.137546 -86.333838)
			(xy 61.145166 -86.359238) (xy 61.15272 -86.386175) (xy 61.160771 -86.441536) (xy 61.160652 -86.497479)
			(xy 61.152367 -86.552806) (xy 61.136093 -86.606329) (xy 61.112178 -86.656904) (xy 61.081136 -86.703444)
			(xy 61.043631 -86.744954) (xy 61.000468 -86.780543) (xy 60.952571 -86.809449) (xy 60.900967 -86.831052)
			(xy 60.846762 -86.844889) (xy 60.791118 -86.850664) (xy 60.76315 -86.849966) (xy 60.74081 -86.84948)
			(xy 60.696523 -86.855401) (xy 60.653952 -86.868968) (xy 60.614405 -86.889763) (xy 60.579099 -86.917147)
			(xy 60.54912 -86.950278) (xy 60.52539 -86.988136) (xy 60.508638 -87.029558) (xy 60.49938 -87.073269)
			(xy 60.498228 -87.095584) (xy 60.498228 -87.427816) (xy 60.75375 -87.427816) (xy 60.757821 -87.372194)
			(xy 60.769947 -87.317757) (xy 60.78987 -87.265666) (xy 60.817166 -87.217031) (xy 60.851252 -87.172888)
			(xy 60.891401 -87.134179) (xy 60.936759 -87.101728) (xy 60.986359 -87.076227) (xy 61.039143 -87.05822)
			(xy 61.093986 -87.04809) (xy 61.14972 -87.046053) (xy 61.205157 -87.052153) (xy 61.259114 -87.066259)
			(xy 61.310443 -87.088071) (xy 61.358049 -87.117125) (xy 61.400917 -87.1528) (xy 61.438134 -87.194337)
			(xy 61.468907 -87.24085) (xy 61.492579 -87.291347) (xy 61.508647 -87.344754) (xy 61.516767 -87.39993)
			(xy 61.517276 -87.427816) (xy 61.516767 -87.455702) (xy 61.508647 -87.510878) (xy 61.492579 -87.564285)
			(xy 61.468907 -87.614782) (xy 61.438134 -87.661295) (xy 61.400917 -87.702832) (xy 61.358049 -87.738507)
			(xy 61.310443 -87.767561) (xy 61.259114 -87.789373) (xy 61.205157 -87.803479) (xy 61.14972 -87.809579)
			(xy 61.093986 -87.807542) (xy 61.039143 -87.797412) (xy 60.986359 -87.779405) (xy 60.936759 -87.753904)
			(xy 60.891401 -87.721453) (xy 60.851252 -87.682744) (xy 60.817166 -87.638601) (xy 60.78987 -87.589966)
			(xy 60.769947 -87.537875) (xy 60.757821 -87.483438) (xy 60.75375 -87.427816) (xy 60.498228 -87.427816)
			(xy 60.498228 -87.610442) (xy 60.483242 -87.625428) (xy 60.483242 -87.899494) (xy 59.240166 -89.14257)
			(xy 59.240166 -89.397586) (xy 59.362594 -89.522046) (xy 59.406282 -89.52738) (xy 59.433198 -89.531219)
			(xy 59.485648 -89.545532) (xy 59.535535 -89.567146) (xy 59.581849 -89.595622) (xy 59.623652 -89.630385)
			(xy 59.660097 -89.670729) (xy 59.690446 -89.715838) (xy 59.714084 -89.764799) (xy 59.730533 -89.816619)
			(xy 59.735466 -89.843356) (xy 59.739525 -89.870648) (xy 59.740665 -89.925812) (xy 59.733842 -89.980564)
			(xy 59.719197 -90.033761) (xy 59.697038 -90.084292) (xy 59.667826 -90.1311) (xy 59.650376 -90.152474)
			(xy 59.635811 -90.171288) (xy 59.613248 -90.213171) (xy 59.598875 -90.258521) (xy 59.593193 -90.305754)
			(xy 59.596401 -90.35322) (xy 59.608387 -90.399259) (xy 59.619131 -90.421968) (xy 60.091318 -90.421968)
			(xy 60.095389 -90.366346) (xy 60.107515 -90.311909) (xy 60.127438 -90.259818) (xy 60.154734 -90.211183)
			(xy 60.18882 -90.16704) (xy 60.228969 -90.128331) (xy 60.274327 -90.09588) (xy 60.323927 -90.070379)
			(xy 60.376711 -90.052372) (xy 60.431554 -90.042242) (xy 60.487288 -90.040205) (xy 60.542725 -90.046305)
			(xy 60.596682 -90.060411) (xy 60.648011 -90.082223) (xy 60.695617 -90.111277) (xy 60.738485 -90.146952)
			(xy 60.775702 -90.188489) (xy 60.806475 -90.235002) (xy 60.830147 -90.285499) (xy 60.846215 -90.338906)
			(xy 60.854335 -90.394082) (xy 60.854844 -90.421968) (xy 60.854335 -90.449854) (xy 60.846215 -90.50503)
			(xy 60.830147 -90.558437) (xy 60.806475 -90.608934) (xy 60.775702 -90.655447) (xy 60.738485 -90.696984)
			(xy 60.695617 -90.732659) (xy 60.648011 -90.761713) (xy 60.596682 -90.783525) (xy 60.542725 -90.797631)
			(xy 60.487288 -90.803731) (xy 60.431554 -90.801694) (xy 60.376711 -90.791564) (xy 60.323927 -90.773557)
			(xy 60.274327 -90.748056) (xy 60.228969 -90.715605) (xy 60.18882 -90.676896) (xy 60.154734 -90.632753)
			(xy 60.127438 -90.584118) (xy 60.107515 -90.532027) (xy 60.095389 -90.47759) (xy 60.091318 -90.421968)
			(xy 59.619131 -90.421968) (xy 59.628733 -90.442263) (xy 59.642248 -90.461846) (xy 59.659206 -90.484017)
			(xy 59.68714 -90.532342) (xy 59.707731 -90.584222) (xy 59.720541 -90.63855) (xy 59.725295 -90.694165)
			(xy 59.721892 -90.749878) (xy 59.710405 -90.804501) (xy 59.691079 -90.856866) (xy 59.664326 -90.905855)
			(xy 59.630719 -90.950421) (xy 59.590975 -90.989613) (xy 59.545943 -91.022593) (xy 59.496584 -91.048657)
			(xy 59.443954 -91.067248) (xy 59.389176 -91.07797) (xy 59.361324 -91.079828) (xy 59.345188 -91.081047)
			(xy 59.314283 -91.090608) (xy 59.286781 -91.107642) (xy 59.264453 -91.131052) (xy 59.248739 -91.159329)
			(xy 59.240651 -91.190652) (xy 59.240166 -91.206828) (xy 59.240166 -92.33789) (xy 61.745112 -92.33789)
			(xy 61.749183 -92.282268) (xy 61.761309 -92.227831) (xy 61.781232 -92.17574) (xy 61.808528 -92.127105)
			(xy 61.842614 -92.082962) (xy 61.882763 -92.044253) (xy 61.928121 -92.011802) (xy 61.977721 -91.986301)
			(xy 62.030505 -91.968294) (xy 62.085348 -91.958164) (xy 62.141082 -91.956127) (xy 62.196519 -91.962227)
			(xy 62.250476 -91.976333) (xy 62.301805 -91.998145) (xy 62.349411 -92.027199) (xy 62.392279 -92.062874)
			(xy 62.429496 -92.104411) (xy 62.460269 -92.150924) (xy 62.483941 -92.201421) (xy 62.500009 -92.254828)
			(xy 62.508129 -92.310004) (xy 62.508638 -92.33789) (xy 62.508129 -92.365776) (xy 62.500009 -92.420952)
			(xy 62.483941 -92.474359) (xy 62.460269 -92.524856) (xy 62.429496 -92.571369) (xy 62.392279 -92.612906)
			(xy 62.349411 -92.648581) (xy 62.301805 -92.677635) (xy 62.250476 -92.699447) (xy 62.196519 -92.713553)
			(xy 62.141082 -92.719653) (xy 62.085348 -92.717616) (xy 62.030505 -92.707486) (xy 61.977721 -92.689479)
			(xy 61.928121 -92.663978) (xy 61.882763 -92.631527) (xy 61.842614 -92.592818) (xy 61.808528 -92.548675)
			(xy 61.781232 -92.50004) (xy 61.761309 -92.447949) (xy 61.749183 -92.393512) (xy 61.745112 -92.33789)
			(xy 59.240166 -92.33789) (xy 59.240166 -92.750132) (xy 59.327796 -92.869004) (xy 59.360816 -92.882466)
			(xy 59.386761 -92.893613) (xy 59.43532 -92.922434) (xy 59.479103 -92.958094) (xy 59.517154 -92.999817)
			(xy 59.548642 -93.04669) (xy 59.57288 -93.097691) (xy 59.589339 -93.151707) (xy 59.59766 -93.207559)
			(xy 59.597661 -93.264026) (xy 59.589343 -93.319878) (xy 59.572885 -93.373894) (xy 59.548649 -93.424897)
			(xy 59.517163 -93.471771) (xy 59.479114 -93.513495) (xy 59.435333 -93.549158) (xy 59.386775 -93.57798)
			(xy 59.360816 -93.589094) (xy 59.327796 -93.602556) (xy 59.240166 -93.721428) (xy 59.240166 -93.874336)
			(xy 59.962794 -93.874336) (xy 59.966865 -93.818714) (xy 59.978991 -93.764277) (xy 59.998914 -93.712186)
			(xy 60.02621 -93.663551) (xy 60.060296 -93.619408) (xy 60.100445 -93.580699) (xy 60.145803 -93.548248)
			(xy 60.195403 -93.522747) (xy 60.248187 -93.50474) (xy 60.30303 -93.49461) (xy 60.358764 -93.492573)
			(xy 60.414201 -93.498673) (xy 60.468158 -93.512779) (xy 60.519487 -93.534591) (xy 60.567093 -93.563645)
			(xy 60.574172 -93.569536) (xy 61.359794 -93.569536) (xy 61.363865 -93.513914) (xy 61.375991 -93.459477)
			(xy 61.395914 -93.407386) (xy 61.42321 -93.358751) (xy 61.457296 -93.314608) (xy 61.497445 -93.275899)
			(xy 61.542803 -93.243448) (xy 61.592403 -93.217947) (xy 61.645187 -93.19994) (xy 61.70003 -93.18981)
			(xy 61.755764 -93.187773) (xy 61.811201 -93.193873) (xy 61.865158 -93.207979) (xy 61.916487 -93.229791)
			(xy 61.964093 -93.258845) (xy 62.006961 -93.29452) (xy 62.044178 -93.336057) (xy 62.074951 -93.38257)
			(xy 62.098623 -93.433067) (xy 62.114691 -93.486474) (xy 62.122811 -93.54165) (xy 62.12332 -93.569536)
			(xy 62.122811 -93.597422) (xy 62.114691 -93.652598) (xy 62.098623 -93.706005) (xy 62.074951 -93.756502)
			(xy 62.044178 -93.803015) (xy 62.006961 -93.844552) (xy 61.964093 -93.880227) (xy 61.916487 -93.909281)
			(xy 61.865158 -93.931093) (xy 61.811201 -93.945199) (xy 61.755764 -93.951299) (xy 61.70003 -93.949262)
			(xy 61.645187 -93.939132) (xy 61.592403 -93.921125) (xy 61.542803 -93.895624) (xy 61.497445 -93.863173)
			(xy 61.457296 -93.824464) (xy 61.42321 -93.780321) (xy 61.395914 -93.731686) (xy 61.375991 -93.679595)
			(xy 61.363865 -93.625158) (xy 61.359794 -93.569536) (xy 60.574172 -93.569536) (xy 60.609961 -93.59932)
			(xy 60.647178 -93.640857) (xy 60.677951 -93.68737) (xy 60.701623 -93.737867) (xy 60.717691 -93.791274)
			(xy 60.725811 -93.84645) (xy 60.72632 -93.874336) (xy 60.725811 -93.902222) (xy 60.717691 -93.957398)
			(xy 60.701623 -94.010805) (xy 60.677951 -94.061302) (xy 60.647178 -94.107815) (xy 60.609961 -94.149352)
			(xy 60.567093 -94.185027) (xy 60.519487 -94.214081) (xy 60.468158 -94.235893) (xy 60.414201 -94.249999)
			(xy 60.358764 -94.256099) (xy 60.30303 -94.254062) (xy 60.248187 -94.243932) (xy 60.195403 -94.225925)
			(xy 60.145803 -94.200424) (xy 60.100445 -94.167973) (xy 60.060296 -94.129264) (xy 60.02621 -94.085121)
			(xy 59.998914 -94.036486) (xy 59.978991 -93.984395) (xy 59.966865 -93.929958) (xy 59.962794 -93.874336)
			(xy 59.240166 -93.874336) (xy 59.240166 -97.895156) (xy 59.578748 -98.233484) (xy 59.590856 -98.244942)
			(xy 59.619691 -98.261652) (xy 59.651874 -98.270303) (xy 59.6852 -98.270303) (xy 59.717383 -98.261652)
			(xy 59.746218 -98.244942) (xy 59.758326 -98.233484) (xy 59.760866 -98.230944) (xy 59.763406 -98.22815)
			(xy 59.7789 -98.21164) (xy 59.790655 -98.199105) (xy 59.807605 -98.169228) (xy 59.815968 -98.135911)
			(xy 59.815137 -98.101571) (xy 59.805171 -98.068697) (xy 59.796426 -98.053906) (xy 59.782081 -98.030414)
			(xy 59.75956 -97.980191) (xy 59.744491 -97.927252) (xy 59.737185 -97.872697) (xy 59.737795 -97.817659)
			(xy 59.746308 -97.763279) (xy 59.762547 -97.710688) (xy 59.786175 -97.660975) (xy 59.816702 -97.615175)
			(xy 59.83478 -97.59442) (xy 59.851697 -97.576202) (xy 59.889452 -97.543857) (xy 59.931083 -97.516679)
			(xy 59.975885 -97.495128) (xy 59.999372 -97.486978) (xy 60.026289 -97.47866) (xy 60.081812 -97.469128)
			(xy 60.138134 -97.467867) (xy 60.194028 -97.474904) (xy 60.248279 -97.490087) (xy 60.299707 -97.513085)
			(xy 60.347192 -97.543397) (xy 60.389702 -97.580365) (xy 60.426312 -97.623184) (xy 60.456225 -97.670922)
			(xy 60.47879 -97.722541) (xy 60.493517 -97.776918) (xy 60.500085 -97.83287) (xy 60.498351 -97.889179)
			(xy 60.49391 -97.917) (xy 60.490451 -97.938956) (xy 60.49036 -97.983399) (xy 60.497999 -98.02718)
			(xy 60.513136 -98.068966) (xy 60.53531 -98.107483) (xy 60.563844 -98.141556) (xy 60.597869 -98.170147)
			(xy 60.636349 -98.192385) (xy 60.678109 -98.207592) (xy 60.721878 -98.215304) (xy 60.7441 -98.215704)
			(xy 61.252354 -98.215704) (xy 61.352684 -98.316288)
		)
		(stroke
			(width 0)
			(type solid)
		)
		(fill yes)
		(layer "In2.Cu")
		(net "P1V8_SUS_NODE1")
	)
	(gr_poly
		(pts
			(xy 155.800044 -159.388048) (xy 155.822819 -159.387537) (xy 155.867639 -159.379411) (xy 155.910293 -159.363428)
			(xy 155.949416 -159.340098) (xy 155.983754 -159.31017) (xy 156.01221 -159.274601) (xy 156.03387 -159.23453)
			(xy 156.048042 -159.191241) (xy 156.054273 -159.146118) (xy 156.052362 -159.100608) (xy 156.042371 -159.056167)
			(xy 156.033978 -159.034988) (xy 156.023572 -159.009127) (xy 156.009525 -158.955184) (xy 156.003478 -158.89977)
			(xy 156.005559 -158.844067) (xy 156.015725 -158.789259) (xy 156.033758 -158.736514) (xy 156.059274 -158.686955)
			(xy 156.091732 -158.641636) (xy 156.130438 -158.601524) (xy 156.17457 -158.567471) (xy 156.223188 -158.540202)
			(xy 156.275256 -158.5203) (xy 156.329666 -158.508186) (xy 156.38526 -158.504119) (xy 156.440854 -158.508186)
			(xy 156.495264 -158.5203) (xy 156.547332 -158.540202) (xy 156.59595 -158.567471) (xy 156.640082 -158.601524)
			(xy 156.678788 -158.641636) (xy 156.711246 -158.686955) (xy 156.736762 -158.736514) (xy 156.754795 -158.789259)
			(xy 156.764961 -158.844067) (xy 156.767042 -158.89977) (xy 156.760995 -158.955184) (xy 156.746948 -159.009127)
			(xy 156.736542 -159.034988) (xy 156.72812 -159.056162) (xy 156.718106 -159.100612) (xy 156.716178 -159.146136)
			(xy 156.722398 -159.191273) (xy 156.736567 -159.234579) (xy 156.758231 -159.274663) (xy 156.786695 -159.310243)
			(xy 156.821047 -159.340176) (xy 156.860186 -159.363505) (xy 156.902857 -159.379481) (xy 156.947694 -159.387592)
			(xy 156.970476 -159.388048) (xy 158.251144 -159.388048) (xy 158.281624 -159.369506) (xy 158.304198 -159.356199)
			(xy 158.352215 -159.33522) (xy 158.402652 -159.321011) (xy 158.45456 -159.313839) (xy 158.50696 -159.313839)
			(xy 158.558868 -159.321011) (xy 158.609305 -159.33522) (xy 158.657322 -159.356199) (xy 158.679896 -159.369506)
			(xy 158.710376 -159.388048) (xy 159.687006 -159.388048) (xy 159.722312 -159.359092) (xy 159.746912 -159.339713)
			(xy 159.801165 -159.308441) (xy 159.830262 -159.296862) (xy 159.851509 -159.28837) (xy 159.890776 -159.264888)
			(xy 159.925207 -159.234757) (xy 159.953689 -159.198951) (xy 159.975302 -159.158625) (xy 159.98935 -159.115082)
			(xy 159.995377 -159.069728) (xy 159.99319 -159.024028) (xy 159.982859 -158.979457) (xy 159.964717 -158.937454)
			(xy 159.952436 -158.918148) (xy 159.937397 -158.894655) (xy 159.913562 -158.844226) (xy 159.897322 -158.790864)
			(xy 159.889025 -158.735706) (xy 159.888847 -158.679927) (xy 159.896792 -158.624717) (xy 159.91269 -158.571252)
			(xy 159.936204 -158.520672) (xy 159.966831 -158.474054) (xy 160.003919 -158.432392) (xy 160.046677 -158.396574)
			(xy 160.094195 -158.367363) (xy 160.14546 -158.345381) (xy 160.199379 -158.331098) (xy 160.254803 -158.324817)
			(xy 160.310551 -158.326672) (xy 160.365434 -158.336625) (xy 160.418284 -158.354462) (xy 160.467974 -158.379804)
			(xy 160.513444 -158.41211) (xy 160.553726 -158.450692) (xy 160.587962 -158.494728) (xy 160.615421 -158.54328)
			(xy 160.635519 -158.595312) (xy 160.647827 -158.649716) (xy 160.652083 -158.705332) (xy 160.648197 -158.760975)
			(xy 160.63625 -158.815459) (xy 160.616498 -158.867623) (xy 160.589361 -158.916356) (xy 160.555419 -158.960618)
			(xy 160.515394 -158.999467) (xy 160.470139 -159.032075) (xy 160.420619 -159.057746) (xy 160.367888 -159.075933)
			(xy 160.313072 -159.08625) (xy 160.257338 -159.088476) (xy 160.22955 -159.086042) (xy 160.213836 -159.08488)
			(xy 160.182662 -159.089401) (xy 160.15355 -159.10143) (xy 160.128277 -159.120231) (xy 160.108387 -159.144657)
			(xy 160.095096 -159.173215) (xy 160.089215 -159.204161) (xy 160.091103 -159.235604) (xy 160.100646 -159.265624)
			(xy 160.11726 -159.292386) (xy 160.139931 -159.314255) (xy 160.15335 -159.322516) (xy 160.167278 -159.330669)
			(xy 160.193857 -159.34898) (xy 160.206436 -159.359092) (xy 160.241742 -159.388048) (xy 161.313114 -159.388048)
			(xy 161.386774 -159.317436) (xy 161.388806 -159.266382) (xy 161.390456 -159.238622) (xy 161.400791 -159.183982)
			(xy 161.418949 -159.131421) (xy 161.444543 -159.082052) (xy 161.477033 -159.036921) (xy 161.515729 -158.996984)
			(xy 161.559813 -158.963087) (xy 161.608349 -158.935948) (xy 161.660312 -158.916141) (xy 161.714598 -158.904087)
			(xy 161.77006 -158.90004) (xy 161.825522 -158.904087) (xy 161.879808 -158.916141) (xy 161.931771 -158.935948)
			(xy 161.980307 -158.963087) (xy 162.024391 -158.996984) (xy 162.063087 -159.036921) (xy 162.095577 -159.082052)
			(xy 162.121171 -159.131421) (xy 162.139329 -159.183982) (xy 162.149664 -159.238622) (xy 162.151314 -159.266382)
			(xy 162.152494 -159.282533) (xy 162.161982 -159.313486) (xy 162.178951 -159.341056) (xy 162.20231 -159.363471)
			(xy 162.230557 -159.379288) (xy 162.261874 -159.387492) (xy 162.27806 -159.388048) (xy 163.232846 -159.388048)
			(xy 163.248197 -159.38763) (xy 163.27801 -159.380295) (xy 163.305201 -159.366039) (xy 163.32819 -159.345689)
			(xy 163.34564 -159.320429) (xy 163.356539 -159.291727) (xy 163.35883 -159.276542) (xy 163.3628 -159.248525)
			(xy 163.377938 -159.194005) (xy 163.400962 -159.142317) (xy 163.431367 -159.094597) (xy 163.468487 -159.051891)
			(xy 163.511507 -159.015136) (xy 163.559484 -158.985137) (xy 163.611365 -158.962553) (xy 163.666012 -158.947879)
			(xy 163.722228 -158.941437) (xy 163.778778 -158.943368) (xy 163.834423 -158.95363) (xy 163.887943 -158.971997)
			(xy 163.938162 -158.998068) (xy 163.983981 -159.031269) (xy 164.024394 -159.070874) (xy 164.041836 -159.093154)
			(xy 164.055274 -159.110231) (xy 164.086961 -159.139962) (xy 164.123244 -159.163868) (xy 164.163065 -159.181254)
			(xy 164.205263 -159.191611) (xy 164.248609 -159.194638) (xy 164.291837 -159.190247) (xy 164.333688 -159.178565)
			(xy 164.372942 -159.159934) (xy 164.408454 -159.134896) (xy 164.424106 -159.119824) (xy 164.488114 -159.055816)
			(xy 164.494718 -158.961074) (xy 164.466016 -158.922974) (xy 164.44945 -158.90028) (xy 164.422456 -158.851003)
			(xy 164.402982 -158.7983) (xy 164.39145 -158.74331) (xy 164.388107 -158.687224) (xy 164.393027 -158.631254)
			(xy 164.406102 -158.576611) (xy 164.427052 -158.524477) (xy 164.455421 -158.475979) (xy 164.490597 -158.432166)
			(xy 164.531818 -158.393987) (xy 164.578194 -158.362267) (xy 164.62872 -158.337692) (xy 164.682305 -158.320794)
			(xy 164.737788 -158.311938) (xy 164.793971 -158.311315) (xy 164.82187 -158.314644) (xy 164.843418 -158.317139)
			(xy 164.886766 -158.315617) (xy 164.929226 -158.306756) (xy 164.969565 -158.290812) (xy 165.006609 -158.268249)
			(xy 165.039283 -158.239722) (xy 165.066637 -158.20606) (xy 165.087877 -158.168241) (xy 165.102385 -158.127364)
			(xy 165.10974 -158.084618) (xy 165.11016 -158.06293) (xy 165.11016 -156.93898) (xy 165.353492 -156.695648)
			(xy 165.353492 -156.690314) (xy 166.230554 -155.813506) (xy 166.240971 -155.802417) (xy 166.256736 -155.776404)
			(xy 166.265922 -155.747407) (xy 166.268011 -155.717061) (xy 166.26586 -155.702) (xy 166.261542 -155.674216)
			(xy 166.260153 -155.618007) (xy 166.267029 -155.562202) (xy 166.282019 -155.508011) (xy 166.304799 -155.456606)
			(xy 166.334876 -155.409101) (xy 166.371599 -155.366524) (xy 166.414173 -155.329797) (xy 166.461676 -155.299715)
			(xy 166.513079 -155.27693) (xy 166.567269 -155.261935) (xy 166.623072 -155.255055) (xy 166.679282 -155.256439)
			(xy 166.707058 -155.260802) (xy 166.722122 -155.262985) (xy 166.752484 -155.260957) (xy 166.781492 -155.251762)
			(xy 166.807478 -155.235929) (xy 166.818564 -155.225496) (xy 166.93388 -155.11018) (xy 166.93388 -153.468324)
			(xy 166.933382 -153.445632) (xy 166.925325 -153.40097) (xy 166.909464 -153.358449) (xy 166.886303 -153.319421)
			(xy 166.856577 -153.285128) (xy 166.821234 -153.256659) (xy 166.781395 -153.234921) (xy 166.73833 -153.220605)
			(xy 166.693406 -153.214165) (xy 166.648052 -153.215807) (xy 166.625778 -153.220166) (xy 166.599046 -153.225475)
			(xy 166.544685 -153.229345) (xy 166.490326 -153.225442) (xy 166.437075 -153.213843) (xy 166.386017 -153.194786)
			(xy 166.338189 -153.168658) (xy 166.294566 -153.13599) (xy 166.256035 -153.097448) (xy 166.223381 -153.053815)
			(xy 166.197267 -153.00598) (xy 166.178224 -152.954916) (xy 166.166642 -152.901662) (xy 166.162755 -152.847301)
			(xy 166.166642 -152.792941) (xy 166.178224 -152.739687) (xy 166.197265 -152.688623) (xy 166.223379 -152.640787)
			(xy 166.256034 -152.597154) (xy 166.294564 -152.558612) (xy 166.338187 -152.525944) (xy 166.386014 -152.499815)
			(xy 166.437073 -152.480757) (xy 166.490323 -152.469158) (xy 166.544682 -152.465255) (xy 166.599044 -152.469125)
			(xy 166.625778 -152.474422) (xy 166.648056 -152.478768) (xy 166.693412 -152.480408) (xy 166.738339 -152.473969)
			(xy 166.781408 -152.459654) (xy 166.82125 -152.437918) (xy 166.8566 -152.409453) (xy 166.886333 -152.375163)
			(xy 166.909504 -152.336138) (xy 166.925378 -152.293619) (xy 166.933448 -152.248957) (xy 166.93388 -152.226264)
			(xy 166.93388 -150.951438) (xy 166.933426 -150.92965) (xy 166.925983 -150.886714) (xy 166.911327 -150.845676)
			(xy 166.889886 -150.807739) (xy 166.86229 -150.774014) (xy 166.829345 -150.745491) (xy 166.792019 -150.723004)
			(xy 166.751404 -150.707212) (xy 166.708691 -150.698579) (xy 166.665132 -150.697357) (xy 166.622002 -150.703583)
			(xy 166.60114 -150.709884) (xy 166.574671 -150.717986) (xy 166.520113 -150.727343) (xy 166.464776 -150.728715)
			(xy 166.409822 -150.722075) (xy 166.356405 -150.707561) (xy 166.305646 -150.685478) (xy 166.258613 -150.65629)
			(xy 166.216293 -150.62061) (xy 166.179574 -150.579188) (xy 166.149228 -150.532894) (xy 166.125892 -150.482699)
			(xy 166.110057 -150.429658) (xy 166.102054 -150.374886) (xy 166.102053 -150.319532) (xy 166.110053 -150.264759)
			(xy 166.125886 -150.211717) (xy 166.149219 -150.161522) (xy 166.179563 -150.115226) (xy 166.21628 -150.073802)
			(xy 166.258599 -150.03812) (xy 166.305631 -150.00893) (xy 166.356388 -149.986845) (xy 166.409805 -149.972329)
			(xy 166.464759 -149.965685) (xy 166.520096 -149.967055) (xy 166.574654 -149.976409) (xy 166.60114 -149.98446)
			(xy 166.621998 -149.99079) (xy 166.665135 -149.997037) (xy 166.708705 -149.99583) (xy 166.75143 -149.987205)
			(xy 166.792056 -149.971416) (xy 166.829392 -149.948925) (xy 166.862341 -149.920392) (xy 166.889938 -149.886655)
			(xy 166.911373 -149.848703) (xy 166.926016 -149.807649) (xy 166.933439 -149.764699) (xy 166.93388 -149.742906)
			(xy 166.93388 -146.756374) (xy 165.4937 -145.316194) (xy 162.165284 -145.316194) (xy 162.151128 -145.316552)
			(xy 162.123506 -145.322756) (xy 162.097942 -145.334921) (xy 162.075705 -145.352442) (xy 162.066478 -145.363184)
			(xy 162.048264 -145.384858) (xy 162.006526 -145.423105) (xy 161.959592 -145.454762) (xy 161.908495 -145.479135)
			(xy 161.854356 -145.495687) (xy 161.798366 -145.504055) (xy 161.741754 -145.504055) (xy 161.685764 -145.495687)
			(xy 161.631625 -145.479135) (xy 161.580528 -145.454762) (xy 161.533594 -145.423105) (xy 161.491856 -145.384858)
			(xy 161.473642 -145.363184) (xy 161.455354 -145.340832) (xy 161.403792 -145.316194) (xy 159.352488 -145.316194)
			(xy 159.330123 -145.316666) (xy 159.286084 -145.324499) (xy 159.244097 -145.33992) (xy 159.205457 -145.362453)
			(xy 159.17136 -145.391403) (xy 159.142856 -145.425875) (xy 159.120828 -145.464805) (xy 159.105955 -145.506989)
			(xy 159.098696 -145.551126) (xy 159.098488 -145.573496) (xy 159.098322 -145.601934) (xy 159.090592 -145.658273)
			(xy 159.074586 -145.712842) (xy 159.050661 -145.764431) (xy 159.019345 -145.811899) (xy 158.981331 -145.854193)
			(xy 158.937462 -145.890379) (xy 158.888709 -145.919654) (xy 158.836152 -145.94137) (xy 158.780954 -145.955047)
			(xy 158.724337 -145.960381) (xy 158.667556 -145.957254) (xy 158.611868 -145.945736) (xy 158.558505 -145.926082)
			(xy 158.533338 -145.91284) (xy 158.496254 -145.892266) (xy 158.412688 -145.904204) (xy 157.7467 -146.570192)
			(xy 157.7467 -146.877278) (xy 158.897318 -146.877278) (xy 158.901389 -146.821656) (xy 158.913515 -146.767219)
			(xy 158.933438 -146.715128) (xy 158.960734 -146.666493) (xy 158.99482 -146.62235) (xy 159.034969 -146.583641)
			(xy 159.080327 -146.55119) (xy 159.129927 -146.525689) (xy 159.182711 -146.507682) (xy 159.237554 -146.497552)
			(xy 159.293288 -146.495515) (xy 159.348725 -146.501615) (xy 159.402682 -146.515721) (xy 159.43523 -146.529552)
			(xy 162.094924 -146.529552) (xy 162.098995 -146.47393) (xy 162.111121 -146.419493) (xy 162.131044 -146.367402)
			(xy 162.15834 -146.318767) (xy 162.192426 -146.274624) (xy 162.232575 -146.235915) (xy 162.277933 -146.203464)
			(xy 162.327533 -146.177963) (xy 162.380317 -146.159956) (xy 162.43516 -146.149826) (xy 162.490894 -146.147789)
			(xy 162.546331 -146.153889) (xy 162.600288 -146.167995) (xy 162.651617 -146.189807) (xy 162.699223 -146.218861)
			(xy 162.742091 -146.254536) (xy 162.779308 -146.296073) (xy 162.810081 -146.342586) (xy 162.820927 -146.365722)
			(xy 163.922962 -146.365722) (xy 163.927033 -146.3101) (xy 163.939159 -146.255663) (xy 163.959082 -146.203572)
			(xy 163.986378 -146.154937) (xy 164.020464 -146.110794) (xy 164.060613 -146.072085) (xy 164.105971 -146.039634)
			(xy 164.155571 -146.014133) (xy 164.208355 -145.996126) (xy 164.263198 -145.985996) (xy 164.318932 -145.983959)
			(xy 164.374369 -145.990059) (xy 164.428326 -146.004165) (xy 164.479655 -146.025977) (xy 164.527261 -146.055031)
			(xy 164.570129 -146.090706) (xy 164.607346 -146.132243) (xy 164.638119 -146.178756) (xy 164.661791 -146.229253)
			(xy 164.677859 -146.28266) (xy 164.685979 -146.337836) (xy 164.686488 -146.365722) (xy 164.685979 -146.393608)
			(xy 164.677859 -146.448784) (xy 164.661791 -146.502191) (xy 164.638119 -146.552688) (xy 164.607346 -146.599201)
			(xy 164.570129 -146.640738) (xy 164.527261 -146.676413) (xy 164.479655 -146.705467) (xy 164.428326 -146.727279)
			(xy 164.374369 -146.741385) (xy 164.318932 -146.747485) (xy 164.263198 -146.745448) (xy 164.208355 -146.735318)
			(xy 164.155571 -146.717311) (xy 164.105971 -146.69181) (xy 164.060613 -146.659359) (xy 164.020464 -146.62065)
			(xy 163.986378 -146.576507) (xy 163.959082 -146.527872) (xy 163.939159 -146.475781) (xy 163.927033 -146.421344)
			(xy 163.922962 -146.365722) (xy 162.820927 -146.365722) (xy 162.833753 -146.393083) (xy 162.849821 -146.44649)
			(xy 162.857941 -146.501666) (xy 162.85845 -146.529552) (xy 162.857941 -146.557438) (xy 162.849821 -146.612614)
			(xy 162.833753 -146.666021) (xy 162.810081 -146.716518) (xy 162.779308 -146.763031) (xy 162.742091 -146.804568)
			(xy 162.699223 -146.840243) (xy 162.651617 -146.869297) (xy 162.600288 -146.891109) (xy 162.546331 -146.905215)
			(xy 162.490894 -146.911315) (xy 162.43516 -146.909278) (xy 162.380317 -146.899148) (xy 162.327533 -146.881141)
			(xy 162.277933 -146.85564) (xy 162.232575 -146.823189) (xy 162.192426 -146.78448) (xy 162.15834 -146.740337)
			(xy 162.131044 -146.691702) (xy 162.111121 -146.639611) (xy 162.098995 -146.585174) (xy 162.094924 -146.529552)
			(xy 159.43523 -146.529552) (xy 159.454011 -146.537533) (xy 159.501617 -146.566587) (xy 159.544485 -146.602262)
			(xy 159.581702 -146.643799) (xy 159.612475 -146.690312) (xy 159.636147 -146.740809) (xy 159.652215 -146.794216)
			(xy 159.660335 -146.849392) (xy 159.660844 -146.877278) (xy 159.660335 -146.905164) (xy 159.652215 -146.96034)
			(xy 159.636147 -147.013747) (xy 159.618439 -147.051522) (xy 165.08298 -147.051522) (xy 165.087051 -146.9959)
			(xy 165.099177 -146.941463) (xy 165.1191 -146.889372) (xy 165.146396 -146.840737) (xy 165.180482 -146.796594)
			(xy 165.220631 -146.757885) (xy 165.265989 -146.725434) (xy 165.315589 -146.699933) (xy 165.368373 -146.681926)
			(xy 165.423216 -146.671796) (xy 165.47895 -146.669759) (xy 165.534387 -146.675859) (xy 165.588344 -146.689965)
			(xy 165.639673 -146.711777) (xy 165.687279 -146.740831) (xy 165.730147 -146.776506) (xy 165.767364 -146.818043)
			(xy 165.798137 -146.864556) (xy 165.821809 -146.915053) (xy 165.837877 -146.96846) (xy 165.845997 -147.023636)
			(xy 165.846506 -147.051522) (xy 165.845997 -147.079408) (xy 165.837877 -147.134584) (xy 165.821809 -147.187991)
			(xy 165.798137 -147.238488) (xy 165.767364 -147.285001) (xy 165.730147 -147.326538) (xy 165.687279 -147.362213)
			(xy 165.639673 -147.391267) (xy 165.588344 -147.413079) (xy 165.534387 -147.427185) (xy 165.47895 -147.433285)
			(xy 165.423216 -147.431248) (xy 165.368373 -147.421118) (xy 165.315589 -147.403111) (xy 165.265989 -147.37761)
			(xy 165.220631 -147.345159) (xy 165.180482 -147.30645) (xy 165.146396 -147.262307) (xy 165.1191 -147.213672)
			(xy 165.099177 -147.161581) (xy 165.087051 -147.107144) (xy 165.08298 -147.051522) (xy 159.618439 -147.051522)
			(xy 159.612475 -147.064244) (xy 159.581702 -147.110757) (xy 159.544485 -147.152294) (xy 159.501617 -147.187969)
			(xy 159.454011 -147.217023) (xy 159.402682 -147.238835) (xy 159.348725 -147.252941) (xy 159.293288 -147.259041)
			(xy 159.237554 -147.257004) (xy 159.182711 -147.246874) (xy 159.129927 -147.228867) (xy 159.080327 -147.203366)
			(xy 159.034969 -147.170915) (xy 158.99482 -147.132206) (xy 158.960734 -147.088063) (xy 158.933438 -147.039428)
			(xy 158.913515 -146.987337) (xy 158.901389 -146.9329) (xy 158.897318 -146.877278) (xy 157.7467 -146.877278)
			(xy 157.7467 -147.508722) (xy 162.652962 -147.508722) (xy 162.657033 -147.4531) (xy 162.669159 -147.398663)
			(xy 162.689082 -147.346572) (xy 162.716378 -147.297937) (xy 162.750464 -147.253794) (xy 162.790613 -147.215085)
			(xy 162.835971 -147.182634) (xy 162.885571 -147.157133) (xy 162.938355 -147.139126) (xy 162.993198 -147.128996)
			(xy 163.048932 -147.126959) (xy 163.104369 -147.133059) (xy 163.158326 -147.147165) (xy 163.209655 -147.168977)
			(xy 163.257261 -147.198031) (xy 163.300129 -147.233706) (xy 163.337346 -147.275243) (xy 163.368119 -147.321756)
			(xy 163.391791 -147.372253) (xy 163.407859 -147.42566) (xy 163.415979 -147.480836) (xy 163.416488 -147.508722)
			(xy 163.416312 -147.518374) (xy 163.88791 -147.518374) (xy 163.891981 -147.462752) (xy 163.904107 -147.408315)
			(xy 163.92403 -147.356224) (xy 163.951326 -147.307589) (xy 163.985412 -147.263446) (xy 164.025561 -147.224737)
			(xy 164.070919 -147.192286) (xy 164.120519 -147.166785) (xy 164.173303 -147.148778) (xy 164.228146 -147.138648)
			(xy 164.28388 -147.136611) (xy 164.339317 -147.142711) (xy 164.393274 -147.156817) (xy 164.444603 -147.178629)
			(xy 164.492209 -147.207683) (xy 164.535077 -147.243358) (xy 164.572294 -147.284895) (xy 164.603067 -147.331408)
			(xy 164.626739 -147.381905) (xy 164.642807 -147.435312) (xy 164.650927 -147.490488) (xy 164.651436 -147.518374)
			(xy 164.650927 -147.54626) (xy 164.642807 -147.601436) (xy 164.626739 -147.654843) (xy 164.603067 -147.70534)
			(xy 164.572294 -147.751853) (xy 164.535077 -147.79339) (xy 164.492209 -147.829065) (xy 164.444603 -147.858119)
			(xy 164.393274 -147.879931) (xy 164.339317 -147.894037) (xy 164.28388 -147.900137) (xy 164.228146 -147.8981)
			(xy 164.173303 -147.88797) (xy 164.120519 -147.869963) (xy 164.070919 -147.844462) (xy 164.025561 -147.812011)
			(xy 163.985412 -147.773302) (xy 163.951326 -147.729159) (xy 163.92403 -147.680524) (xy 163.904107 -147.628433)
			(xy 163.891981 -147.573996) (xy 163.88791 -147.518374) (xy 163.416312 -147.518374) (xy 163.415979 -147.536608)
			(xy 163.407859 -147.591784) (xy 163.391791 -147.645191) (xy 163.368119 -147.695688) (xy 163.337346 -147.742201)
			(xy 163.300129 -147.783738) (xy 163.257261 -147.819413) (xy 163.209655 -147.848467) (xy 163.158326 -147.870279)
			(xy 163.104369 -147.884385) (xy 163.048932 -147.890485) (xy 162.993198 -147.888448) (xy 162.938355 -147.878318)
			(xy 162.885571 -147.860311) (xy 162.835971 -147.83481) (xy 162.790613 -147.802359) (xy 162.750464 -147.76365)
			(xy 162.716378 -147.719507) (xy 162.689082 -147.670872) (xy 162.669159 -147.618781) (xy 162.657033 -147.564344)
			(xy 162.652962 -147.508722) (xy 157.7467 -147.508722) (xy 157.7467 -147.936712) (xy 156.9339 -148.749512)
			(xy 156.9339 -148.777198) (xy 156.584904 -149.12594) (xy 156.584904 -154.734768) (xy 156.56306 -154.756612)
			(xy 156.56306 -155.344114) (xy 156.027374 -155.8798) (xy 158.0388 -155.8798) (xy 158.0388 -150.40229)
			(xy 158.240476 -150.200868) (xy 163.738814 -150.200868) (xy 163.971732 -150.433786) (xy 163.971732 -155.83789)
			(xy 163.7284 -156.081476) (xy 158.240476 -156.081476) (xy 158.0388 -155.8798) (xy 156.027374 -155.8798)
			(xy 155.926028 -155.981146) (xy 155.921964 -156.026866) (xy 155.919108 -156.053233) (xy 155.907034 -156.104876)
			(xy 155.887924 -156.154348) (xy 155.862147 -156.200697) (xy 155.830198 -156.243029) (xy 155.792695 -156.280528)
			(xy 155.750359 -156.312472) (xy 155.704007 -156.338244) (xy 155.654532 -156.357348) (xy 155.602888 -156.369415)
			(xy 155.576524 -156.372306) (xy 155.530804 -156.37637) (xy 154.7114 -157.195774) (xy 154.7114 -158.846774)
			(xy 155.252674 -159.388048)
		)
		(stroke
			(width 0)
			(type solid)
		)
		(fill yes)
		(layer "In2.Cu")
		(net "P1V05_LAN2")
	)
	(gr_poly
		(pts
			(xy 82.575908 -91.340432) (xy 82.593859 -91.32908) (xy 82.626042 -91.301367) (xy 82.653164 -91.268684)
			(xy 82.674469 -91.231944) (xy 82.689361 -91.19217) (xy 82.697426 -91.150472) (xy 82.698439 -91.108014)
			(xy 82.695796 -91.08694) (xy 82.691989 -91.059726) (xy 82.691305 -91.00478) (xy 82.698508 -90.950305)
			(xy 82.713451 -90.897426) (xy 82.735824 -90.847237) (xy 82.765164 -90.800776) (xy 82.800866 -90.759005)
			(xy 82.842189 -90.722786) (xy 82.888281 -90.692868) (xy 82.938187 -90.669872) (xy 82.990876 -90.654271)
			(xy 83.045257 -90.646389) (xy 83.100207 -90.646389) (xy 83.154588 -90.654271) (xy 83.207277 -90.669872)
			(xy 83.257183 -90.692868) (xy 83.303275 -90.722786) (xy 83.344598 -90.759005) (xy 83.3803 -90.800776)
			(xy 83.40964 -90.847237) (xy 83.432013 -90.897426) (xy 83.446956 -90.950305) (xy 83.454159 -91.00478)
			(xy 83.453475 -91.059726) (xy 83.449668 -91.08694) (xy 83.44708 -91.108015) (xy 83.448123 -91.150462)
			(xy 83.456202 -91.192145) (xy 83.471091 -91.231908) (xy 83.492377 -91.268645) (xy 83.519469 -91.301338)
			(xy 83.551614 -91.329076) (xy 83.569556 -91.340432) (xy 84.959952 -91.340432) (xy 84.960206 -91.339924)
			(xy 84.960968 -91.339924) (xy 85.97392 -90.326972) (xy 86.0806 -90.326972) (xy 87.961216 -88.44661)
			(xy 87.972564 -88.434461) (xy 87.989151 -88.405665) (xy 87.997742 -88.373564) (xy 87.9983 -88.356948)
			(xy 87.9983 -82.271616) (xy 87.997807 -82.25496) (xy 87.989189 -82.222782) (xy 87.972535 -82.193931)
			(xy 87.948981 -82.170375) (xy 87.920133 -82.153717) (xy 87.887956 -82.145095) (xy 87.8713 -82.144616)
			(xy 85.765894 -82.144616) (xy 85.749231 -82.145113) (xy 85.717043 -82.153744) (xy 85.688189 -82.170418)
			(xy 85.664637 -82.193994) (xy 85.647994 -82.222866) (xy 85.639395 -82.255063) (xy 85.639428 -82.288389)
			(xy 85.648091 -82.320568) (xy 85.664791 -82.349407) (xy 85.676232 -82.361532) (xy 85.708998 -82.394044)
			(xy 85.773768 -82.458814) (xy 85.773768 -82.999072) (xy 85.774296 -83.022526) (xy 85.782886 -83.068641)
			(xy 85.799797 -83.112394) (xy 85.824455 -83.152298) (xy 85.856021 -83.186997) (xy 85.893421 -83.215309)
			(xy 85.935384 -83.236272) (xy 85.980483 -83.249174) (xy 86.027184 -83.253575) (xy 86.073899 -83.249327)
			(xy 86.096602 -83.24342) (xy 86.1242 -83.236168) (xy 86.180816 -83.229049) (xy 86.23786 -83.230449)
			(xy 86.294058 -83.240336) (xy 86.348155 -83.25849) (xy 86.398941 -83.284505) (xy 86.445282 -83.317799)
			(xy 86.486142 -83.357629) (xy 86.503764 -83.380072) (xy 86.520689 -83.403188) (xy 86.548148 -83.45347)
			(xy 86.567778 -83.507293) (xy 86.579138 -83.563447) (xy 86.581972 -83.620668) (xy 86.576216 -83.677669)
			(xy 86.562001 -83.733169) (xy 86.539644 -83.785918) (xy 86.5251 -83.810602) (xy 86.514459 -83.829799)
			(xy 86.499225 -83.870959) (xy 86.491297 -83.914125) (xy 86.490911 -83.958012) (xy 86.498077 -84.001311)
			(xy 86.512583 -84.042733) (xy 86.533996 -84.081043) (xy 86.547452 -84.098384) (xy 86.565535 -84.12018)
			(xy 86.595731 -84.168089) (xy 86.618515 -84.219935) (xy 86.633384 -84.27458) (xy 86.640013 -84.330822)
			(xy 86.638256 -84.387426) (xy 86.628151 -84.443149) (xy 86.60992 -84.496766) (xy 86.583964 -84.547099)
			(xy 86.550853 -84.593042) (xy 86.511315 -84.633587) (xy 86.466218 -84.667841) (xy 86.416553 -84.695054)
			(xy 86.363411 -84.714626) (xy 86.30796 -84.726128) (xy 86.251418 -84.729307) (xy 86.195027 -84.724093)
			(xy 86.140026 -84.710601) (xy 86.11362 -84.700364) (xy 86.092633 -84.693338) (xy 86.049023 -84.685827)
			(xy 86.004771 -84.685984) (xy 85.961215 -84.693806) (xy 85.919673 -84.709056) (xy 85.881401 -84.731272)
			(xy 85.847557 -84.759783) (xy 85.819164 -84.793726) (xy 85.797081 -84.832074) (xy 85.781976 -84.873669)
			(xy 85.774306 -84.917252) (xy 85.773768 -84.939378) (xy 85.773768 -86.919054) (xy 85.52815 -87.164672)
			(xy 83.42249 -87.164672) (xy 83.123532 -86.865714) (xy 83.123532 -82.496914) (xy 83.213702 -82.406744)
			(xy 83.259168 -82.361532) (xy 83.270619 -82.349415) (xy 83.287321 -82.320573) (xy 83.295984 -82.28839)
			(xy 83.296017 -82.255062) (xy 83.287418 -82.222862) (xy 83.270773 -82.193987) (xy 83.247219 -82.170408)
			(xy 83.218361 -82.153733) (xy 83.18617 -82.1451) (xy 83.169506 -82.144616) (xy 81.768696 -82.144616)
			(xy 81.758536 -82.14614) (xy 81.728081 -82.150498) (xy 81.666563 -82.150498) (xy 81.636108 -82.14614)
			(xy 81.625948 -82.144616) (xy 81.133696 -82.144616) (xy 81.123536 -82.14614) (xy 81.093081 -82.150498)
			(xy 81.031563 -82.150498) (xy 81.001108 -82.14614) (xy 80.990948 -82.144616) (xy 80.498696 -82.144616)
			(xy 80.488536 -82.14614) (xy 80.458081 -82.150498) (xy 80.396563 -82.150498) (xy 80.366108 -82.14614)
			(xy 80.355948 -82.144616) (xy 79.956152 -82.144616) (xy 79.54645 -82.554318) (xy 79.54645 -82.648806)
			(xy 79.550768 -82.664808) (xy 79.557602 -82.692508) (xy 79.563925 -82.749208) (xy 79.561738 -82.806217)
			(xy 79.551088 -82.862265) (xy 79.532214 -82.916104) (xy 79.505535 -82.966533) (xy 79.471647 -83.012428)
			(xy 79.431304 -83.052768) (xy 79.385405 -83.086652) (xy 79.334974 -83.113327) (xy 79.281134 -83.132197)
			(xy 79.225084 -83.142841) (xy 79.168075 -83.145024) (xy 79.111376 -83.138696) (xy 79.083662 -83.131914)
			(xy 79.06766 -83.127596) (xy 78.973172 -83.127596) (xy 78.859634 -83.241134) (xy 81.600292 -83.241134)
			(xy 81.604363 -83.185512) (xy 81.616489 -83.131075) (xy 81.636412 -83.078984) (xy 81.663708 -83.030349)
			(xy 81.697794 -82.986206) (xy 81.737943 -82.947497) (xy 81.783301 -82.915046) (xy 81.832901 -82.889545)
			(xy 81.885685 -82.871538) (xy 81.940528 -82.861408) (xy 81.996262 -82.859371) (xy 82.051699 -82.865471)
			(xy 82.105656 -82.879577) (xy 82.156985 -82.901389) (xy 82.204591 -82.930443) (xy 82.247459 -82.966118)
			(xy 82.284676 -83.007655) (xy 82.315449 -83.054168) (xy 82.339121 -83.104665) (xy 82.355189 -83.158072)
			(xy 82.363309 -83.213248) (xy 82.363818 -83.241134) (xy 82.363309 -83.26902) (xy 82.355189 -83.324196)
			(xy 82.339121 -83.377603) (xy 82.315449 -83.4281) (xy 82.284676 -83.474613) (xy 82.247459 -83.51615)
			(xy 82.204591 -83.551825) (xy 82.156985 -83.580879) (xy 82.105656 -83.602691) (xy 82.051699 -83.616797)
			(xy 81.996262 -83.622897) (xy 81.940528 -83.62086) (xy 81.885685 -83.61073) (xy 81.832901 -83.592723)
			(xy 81.783301 -83.567222) (xy 81.737943 -83.534771) (xy 81.697794 -83.496062) (xy 81.663708 -83.451919)
			(xy 81.636412 -83.403284) (xy 81.616489 -83.351193) (xy 81.604363 -83.296756) (xy 81.600292 -83.241134)
			(xy 78.859634 -83.241134) (xy 78.22946 -83.871308) (xy 78.22946 -84.217256) (xy 79.513682 -84.217256)
			(xy 79.517753 -84.161634) (xy 79.529879 -84.107197) (xy 79.549802 -84.055106) (xy 79.577098 -84.006471)
			(xy 79.611184 -83.962328) (xy 79.651333 -83.923619) (xy 79.696691 -83.891168) (xy 79.746291 -83.865667)
			(xy 79.799075 -83.84766) (xy 79.853918 -83.83753) (xy 79.909652 -83.835493) (xy 79.965089 -83.841593)
			(xy 80.019046 -83.855699) (xy 80.070375 -83.877511) (xy 80.117981 -83.906565) (xy 80.160849 -83.94224)
			(xy 80.198066 -83.983777) (xy 80.228839 -84.03029) (xy 80.252511 -84.080787) (xy 80.268579 -84.134194)
			(xy 80.276699 -84.18937) (xy 80.277208 -84.217256) (xy 80.276699 -84.245142) (xy 80.268579 -84.300318)
			(xy 80.252511 -84.353725) (xy 80.228839 -84.404222) (xy 80.198066 -84.450735) (xy 80.160849 -84.492272)
			(xy 80.117981 -84.527947) (xy 80.070375 -84.557001) (xy 80.019046 -84.578813) (xy 79.965089 -84.592919)
			(xy 79.909652 -84.599019) (xy 79.853918 -84.596982) (xy 79.799075 -84.586852) (xy 79.746291 -84.568845)
			(xy 79.696691 -84.543344) (xy 79.651333 -84.510893) (xy 79.611184 -84.472184) (xy 79.577098 -84.428041)
			(xy 79.549802 -84.379406) (xy 79.529879 -84.327315) (xy 79.517753 -84.272878) (xy 79.513682 -84.217256)
			(xy 78.22946 -84.217256) (xy 78.22946 -85.296502) (xy 79.368902 -85.296502) (xy 79.372973 -85.24088)
			(xy 79.385099 -85.186443) (xy 79.405022 -85.134352) (xy 79.432318 -85.085717) (xy 79.466404 -85.041574)
			(xy 79.506553 -85.002865) (xy 79.551911 -84.970414) (xy 79.601511 -84.944913) (xy 79.654295 -84.926906)
			(xy 79.709138 -84.916776) (xy 79.764872 -84.914739) (xy 79.820309 -84.920839) (xy 79.874266 -84.934945)
			(xy 79.925595 -84.956757) (xy 79.973201 -84.985811) (xy 80.016069 -85.021486) (xy 80.053286 -85.063023)
			(xy 80.084059 -85.109536) (xy 80.090148 -85.122525) (xy 80.512581 -85.122525) (xy 80.513279 -85.067582)
			(xy 80.521852 -85.013307) (xy 80.538121 -84.960822) (xy 80.561749 -84.911214) (xy 80.592249 -84.865509)
			(xy 80.62899 -84.82465) (xy 80.671211 -84.789485) (xy 80.71804 -84.760738) (xy 80.768507 -84.739006)
			(xy 80.82157 -84.724738) (xy 80.876131 -84.718228) (xy 80.931062 -84.719612) (xy 80.985225 -84.72886)
			(xy 81.037503 -84.745782) (xy 81.086812 -84.770027) (xy 81.132134 -84.801094) (xy 81.172532 -84.838341)
			(xy 81.207168 -84.880998) (xy 81.235329 -84.928181) (xy 81.25643 -84.978915) (xy 81.270036 -85.032152)
			(xy 81.275865 -85.08679) (xy 81.273797 -85.141699) (xy 81.263874 -85.195743) (xy 81.246302 -85.247806)
			(xy 81.221444 -85.296809) (xy 81.189814 -85.34174) (xy 81.171288 -85.362034) (xy 81.160642 -85.374026)
			(xy 81.145104 -85.402062) (xy 81.137057 -85.43309) (xy 81.137011 -85.465144) (xy 81.144968 -85.496195)
			(xy 81.160425 -85.524276) (xy 81.182403 -85.54761) (xy 81.20951 -85.564718) (xy 81.224628 -85.57006)
			(xy 81.238304 -85.574574) (xy 81.265004 -85.585378) (xy 81.277968 -85.59165) (xy 81.29202 -85.598183)
			(xy 81.322254 -85.604938) (xy 81.353225 -85.604193) (xy 81.3831 -85.595992) (xy 81.41011 -85.58082)
			(xy 81.432658 -85.559575) (xy 81.449408 -85.533514) (xy 81.45937 -85.504179) (xy 81.461102 -85.48878)
			(xy 81.46398 -85.460926) (xy 81.476781 -85.406414) (xy 81.497411 -85.354359) (xy 81.525427 -85.305877)
			(xy 81.560227 -85.262009) (xy 81.601064 -85.223698) (xy 81.647061 -85.191766) (xy 81.69723 -85.166899)
			(xy 81.750495 -85.14963) (xy 81.805712 -85.14033) (xy 81.861695 -85.139199) (xy 81.917243 -85.146262)
			(xy 81.971161 -85.161366) (xy 82.022294 -85.184187) (xy 82.069543 -85.214236) (xy 82.111894 -85.250867)
			(xy 82.148437 -85.293293) (xy 82.178387 -85.340604) (xy 82.201102 -85.391784) (xy 82.216095 -85.445734)
			(xy 82.223042 -85.501296) (xy 82.221795 -85.557277) (xy 82.212381 -85.612474) (xy 82.195001 -85.665703)
			(xy 82.17003 -85.715821) (xy 82.138002 -85.761752) (xy 82.099607 -85.802509) (xy 82.055667 -85.837218)
			(xy 82.007127 -85.865133) (xy 81.955029 -85.885655) (xy 81.900491 -85.898344) (xy 81.844684 -85.902926)
			(xy 81.788807 -85.899303) (xy 81.76133 -85.89391) (xy 81.738758 -85.889645) (xy 81.692848 -85.888304)
			(xy 81.647443 -85.895232) (xy 81.604021 -85.910202) (xy 81.563994 -85.932728) (xy 81.528664 -85.962077)
			(xy 81.49918 -85.997295) (xy 81.476501 -86.037236) (xy 81.468468 -86.058756) (xy 81.459093 -86.084487)
			(xy 81.433879 -86.133104) (xy 81.401976 -86.177617) (xy 81.364037 -86.217113) (xy 81.320842 -86.250781)
			(xy 81.273279 -86.27793) (xy 81.222323 -86.298001) (xy 81.169022 -86.310583) (xy 81.11447 -86.315417)
			(xy 81.059787 -86.312404) (xy 81.006097 -86.301606) (xy 80.9545 -86.283244) (xy 80.906059 -86.257696)
			(xy 80.861766 -86.225487) (xy 80.822532 -86.187277) (xy 80.789162 -86.143852) (xy 80.762342 -86.096103)
			(xy 80.742622 -86.04501) (xy 80.730407 -85.991624) (xy 80.725949 -85.93704) (xy 80.729338 -85.882379)
			(xy 80.740505 -85.828764) (xy 80.759221 -85.777295) (xy 80.771746 -85.75294) (xy 80.782458 -85.731872)
			(xy 80.796725 -85.68682) (xy 80.802411 -85.639906) (xy 80.799318 -85.592749) (xy 80.787553 -85.54698)
			(xy 80.767523 -85.504177) (xy 80.739919 -85.465819) (xy 80.705695 -85.433232) (xy 80.686148 -85.419946)
			(xy 80.663388 -85.404549) (xy 80.622075 -85.36832) (xy 80.586386 -85.326541) (xy 80.557058 -85.280074)
			(xy 80.534699 -85.229881) (xy 80.51977 -85.177) (xy 80.512581 -85.122525) (xy 80.090148 -85.122525)
			(xy 80.107731 -85.160033) (xy 80.123799 -85.21344) (xy 80.131919 -85.268616) (xy 80.132428 -85.296502)
			(xy 80.131919 -85.324388) (xy 80.123799 -85.379564) (xy 80.107731 -85.432971) (xy 80.084059 -85.483468)
			(xy 80.053286 -85.529981) (xy 80.016069 -85.571518) (xy 79.973201 -85.607193) (xy 79.925595 -85.636247)
			(xy 79.874266 -85.658059) (xy 79.820309 -85.672165) (xy 79.764872 -85.678265) (xy 79.709138 -85.676228)
			(xy 79.654295 -85.666098) (xy 79.601511 -85.648091) (xy 79.551911 -85.62259) (xy 79.506553 -85.590139)
			(xy 79.466404 -85.55143) (xy 79.432318 -85.507287) (xy 79.405022 -85.458652) (xy 79.385099 -85.406561)
			(xy 79.372973 -85.352124) (xy 79.368902 -85.296502) (xy 78.22946 -85.296502) (xy 78.22946 -85.460586)
			(xy 78.26502 -85.496146) (xy 78.26502 -85.516212) (xy 79.48168 -86.732872) (xy 79.48168 -86.974172)
			(xy 81.185002 -86.974172) (xy 81.189073 -86.91855) (xy 81.201199 -86.864113) (xy 81.221122 -86.812022)
			(xy 81.248418 -86.763387) (xy 81.282504 -86.719244) (xy 81.322653 -86.680535) (xy 81.368011 -86.648084)
			(xy 81.417611 -86.622583) (xy 81.470395 -86.604576) (xy 81.525238 -86.594446) (xy 81.580972 -86.592409)
			(xy 81.636409 -86.598509) (xy 81.690366 -86.612615) (xy 81.741695 -86.634427) (xy 81.789301 -86.663481)
			(xy 81.832169 -86.699156) (xy 81.869386 -86.740693) (xy 81.900159 -86.787206) (xy 81.923831 -86.837703)
			(xy 81.939899 -86.89111) (xy 81.948019 -86.946286) (xy 81.948528 -86.974172) (xy 81.948019 -87.002058)
			(xy 81.939899 -87.057234) (xy 81.923831 -87.110641) (xy 81.900159 -87.161138) (xy 81.869386 -87.207651)
			(xy 81.832169 -87.249188) (xy 81.789301 -87.284863) (xy 81.741695 -87.313917) (xy 81.690366 -87.335729)
			(xy 81.636409 -87.349835) (xy 81.580972 -87.355935) (xy 81.525238 -87.353898) (xy 81.470395 -87.343768)
			(xy 81.417611 -87.325761) (xy 81.368011 -87.30026) (xy 81.322653 -87.267809) (xy 81.282504 -87.2291)
			(xy 81.248418 -87.184957) (xy 81.221122 -87.136322) (xy 81.201199 -87.084231) (xy 81.189073 -87.029794)
			(xy 81.185002 -86.974172) (xy 79.48168 -86.974172) (xy 79.48168 -87.979504) (xy 80.84896 -87.979504)
			(xy 80.853031 -87.923882) (xy 80.865157 -87.869445) (xy 80.88508 -87.817354) (xy 80.912376 -87.768719)
			(xy 80.946462 -87.724576) (xy 80.986611 -87.685867) (xy 81.031969 -87.653416) (xy 81.081569 -87.627915)
			(xy 81.134353 -87.609908) (xy 81.189196 -87.599778) (xy 81.24493 -87.597741) (xy 81.300367 -87.603841)
			(xy 81.354324 -87.617947) (xy 81.405653 -87.639759) (xy 81.453259 -87.668813) (xy 81.496127 -87.704488)
			(xy 81.533344 -87.746025) (xy 81.564117 -87.792538) (xy 81.587789 -87.843035) (xy 81.603857 -87.896442)
			(xy 81.611977 -87.951618) (xy 81.612486 -87.979504) (xy 81.611977 -88.00739) (xy 81.603857 -88.062566)
			(xy 81.587789 -88.115973) (xy 81.564117 -88.16647) (xy 81.533344 -88.212983) (xy 81.496127 -88.25452)
			(xy 81.453259 -88.290195) (xy 81.405653 -88.319249) (xy 81.354324 -88.341061) (xy 81.300367 -88.355167)
			(xy 81.24493 -88.361267) (xy 81.189196 -88.35923) (xy 81.134353 -88.3491) (xy 81.081569 -88.331093)
			(xy 81.031969 -88.305592) (xy 80.986611 -88.273141) (xy 80.946462 -88.234432) (xy 80.912376 -88.190289)
			(xy 80.88508 -88.141654) (xy 80.865157 -88.089563) (xy 80.853031 -88.035126) (xy 80.84896 -87.979504)
			(xy 79.48168 -87.979504) (xy 79.48168 -88.995504) (xy 80.717134 -88.995504) (xy 80.721205 -88.939882)
			(xy 80.733331 -88.885445) (xy 80.753254 -88.833354) (xy 80.78055 -88.784719) (xy 80.814636 -88.740576)
			(xy 80.854785 -88.701867) (xy 80.900143 -88.669416) (xy 80.949743 -88.643915) (xy 81.002527 -88.625908)
			(xy 81.05737 -88.615778) (xy 81.113104 -88.613741) (xy 81.168541 -88.619841) (xy 81.222498 -88.633947)
			(xy 81.273827 -88.655759) (xy 81.321433 -88.684813) (xy 81.342246 -88.702134) (xy 84.311742 -88.702134)
			(xy 84.315813 -88.646512) (xy 84.327939 -88.592075) (xy 84.347862 -88.539984) (xy 84.375158 -88.491349)
			(xy 84.409244 -88.447206) (xy 84.449393 -88.408497) (xy 84.494751 -88.376046) (xy 84.544351 -88.350545)
			(xy 84.597135 -88.332538) (xy 84.651978 -88.322408) (xy 84.707712 -88.320371) (xy 84.763149 -88.326471)
			(xy 84.817106 -88.340577) (xy 84.868435 -88.362389) (xy 84.916041 -88.391443) (xy 84.958909 -88.427118)
			(xy 84.996126 -88.468655) (xy 85.026899 -88.515168) (xy 85.050571 -88.565665) (xy 85.066639 -88.619072)
			(xy 85.074759 -88.674248) (xy 85.075268 -88.702134) (xy 85.074759 -88.73002) (xy 85.066639 -88.785196)
			(xy 85.050571 -88.838603) (xy 85.026899 -88.8891) (xy 84.996126 -88.935613) (xy 84.958909 -88.97715)
			(xy 84.916041 -89.012825) (xy 84.868435 -89.041879) (xy 84.817106 -89.063691) (xy 84.763149 -89.077797)
			(xy 84.707712 -89.083897) (xy 84.651978 -89.08186) (xy 84.597135 -89.07173) (xy 84.544351 -89.053723)
			(xy 84.494751 -89.028222) (xy 84.449393 -88.995771) (xy 84.409244 -88.957062) (xy 84.375158 -88.912919)
			(xy 84.347862 -88.864284) (xy 84.327939 -88.812193) (xy 84.315813 -88.757756) (xy 84.311742 -88.702134)
			(xy 81.342246 -88.702134) (xy 81.364301 -88.720488) (xy 81.401518 -88.762025) (xy 81.432291 -88.808538)
			(xy 81.455963 -88.859035) (xy 81.472031 -88.912442) (xy 81.480151 -88.967618) (xy 81.48066 -88.995504)
			(xy 81.480151 -89.02339) (xy 81.472031 -89.078566) (xy 81.455963 -89.131973) (xy 81.432291 -89.18247)
			(xy 81.401518 -89.228983) (xy 81.364301 -89.27052) (xy 81.321433 -89.306195) (xy 81.273827 -89.335249)
			(xy 81.222498 -89.357061) (xy 81.168541 -89.371167) (xy 81.113104 -89.377267) (xy 81.05737 -89.37523)
			(xy 81.002527 -89.3651) (xy 80.949743 -89.347093) (xy 80.900143 -89.321592) (xy 80.854785 -89.289141)
			(xy 80.814636 -89.250432) (xy 80.78055 -89.206289) (xy 80.753254 -89.157654) (xy 80.733331 -89.105563)
			(xy 80.721205 -89.051126) (xy 80.717134 -88.995504) (xy 79.48168 -88.995504) (xy 79.48168 -89.925652)
			(xy 79.58269 -90.026662) (xy 80.813509 -90.026662) (xy 80.815302 -89.971557) (xy 80.82501 -89.917283)
			(xy 80.842429 -89.864972) (xy 80.867197 -89.815714) (xy 80.898799 -89.770535) (xy 80.936575 -89.730375)
			(xy 80.979739 -89.696072) (xy 81.027392 -89.668341) (xy 81.078541 -89.647758) (xy 81.13212 -89.634753)
			(xy 81.187013 -89.629596) (xy 81.242076 -89.632395) (xy 81.296163 -89.643092) (xy 81.348147 -89.661464)
			(xy 81.396945 -89.687128) (xy 81.441539 -89.71955) (xy 81.46161 -89.738454) (xy 81.478829 -89.754475)
			(xy 81.517994 -89.78051) (xy 81.561278 -89.798899) (xy 81.607206 -89.809017) (xy 81.65421 -89.810518)
			(xy 81.700689 -89.80335) (xy 81.745058 -89.787759) (xy 81.785804 -89.764276) (xy 81.804002 -89.749376)
			(xy 81.82529 -89.731845) (xy 81.871903 -89.702379) (xy 81.922273 -89.679931) (xy 81.975349 -89.664968)
			(xy 82.030027 -89.657803) (xy 82.085167 -89.658584) (xy 82.13962 -89.667295) (xy 82.192252 -89.683755)
			(xy 82.241965 -89.707621) (xy 82.287725 -89.738395) (xy 82.328577 -89.775437) (xy 82.363671 -89.817974)
			(xy 82.392276 -89.86512) (xy 82.392418 -89.865454) (xy 84.384386 -89.865454) (xy 84.388457 -89.809832)
			(xy 84.400583 -89.755395) (xy 84.420506 -89.703304) (xy 84.447802 -89.654669) (xy 84.481888 -89.610526)
			(xy 84.522037 -89.571817) (xy 84.567395 -89.539366) (xy 84.616995 -89.513865) (xy 84.669779 -89.495858)
			(xy 84.724622 -89.485728) (xy 84.780356 -89.483691) (xy 84.835793 -89.489791) (xy 84.88975 -89.503897)
			(xy 84.941079 -89.525709) (xy 84.988685 -89.554763) (xy 85.031553 -89.590438) (xy 85.06877 -89.631975)
			(xy 85.099543 -89.678488) (xy 85.123215 -89.728985) (xy 85.139283 -89.782392) (xy 85.147403 -89.837568)
			(xy 85.147912 -89.865454) (xy 85.147403 -89.89334) (xy 85.139283 -89.948516) (xy 85.123215 -90.001923)
			(xy 85.099543 -90.05242) (xy 85.06877 -90.098933) (xy 85.031553 -90.14047) (xy 84.988685 -90.176145)
			(xy 84.941079 -90.205199) (xy 84.88975 -90.227011) (xy 84.835793 -90.241117) (xy 84.780356 -90.247217)
			(xy 84.724622 -90.24518) (xy 84.669779 -90.23505) (xy 84.616995 -90.217043) (xy 84.567395 -90.191542)
			(xy 84.522037 -90.159091) (xy 84.481888 -90.120382) (xy 84.447802 -90.076239) (xy 84.420506 -90.027604)
			(xy 84.400583 -89.975513) (xy 84.388457 -89.921076) (xy 84.384386 -89.865454) (xy 82.392418 -89.865454)
			(xy 82.413795 -89.915894) (xy 82.42778 -89.969236) (xy 82.43394 -90.024037) (xy 82.432146 -90.079153)
			(xy 82.422436 -90.133436) (xy 82.405012 -90.185757) (xy 82.380237 -90.235024) (xy 82.348628 -90.28021)
			(xy 82.310842 -90.320376) (xy 82.267668 -90.354682) (xy 82.220004 -90.382416) (xy 82.168844 -90.402999)
			(xy 82.115253 -90.416002) (xy 82.060349 -90.421154) (xy 82.005275 -90.418348) (xy 81.951179 -90.407643)
			(xy 81.899187 -90.389261) (xy 81.850384 -90.363585) (xy 81.805786 -90.331151) (xy 81.785714 -90.31224)
			(xy 81.768474 -90.296242) (xy 81.729314 -90.270207) (xy 81.686034 -90.251816) (xy 81.64011 -90.241696)
			(xy 81.593109 -90.240192) (xy 81.546632 -90.247356) (xy 81.502265 -90.262942) (xy 81.46152 -90.286421)
			(xy 81.443322 -90.301318) (xy 81.422039 -90.318847) (xy 81.375431 -90.348301) (xy 81.325068 -90.370738)
			(xy 81.272 -90.385692) (xy 81.217332 -90.39285) (xy 81.162203 -90.392064) (xy 81.107761 -90.38335)
			(xy 81.055141 -90.366889) (xy 81.005439 -90.343024) (xy 80.959689 -90.312253) (xy 80.918847 -90.275217)
			(xy 80.883761 -90.232687) (xy 80.855163 -90.185548) (xy 80.833649 -90.134784) (xy 80.819668 -90.081452)
			(xy 80.813509 -90.026662) (xy 79.58269 -90.026662) (xy 80.89646 -91.340432)
		)
		(stroke
			(width 0)
			(type solid)
		)
		(fill yes)
		(layer "In2.Cu")
		(net "P3V3_RTC_NODE1")
	)
	(gr_poly
		(pts
			(xy 104.761792 -162.296856) (xy 104.779469 -162.296289) (xy 104.813468 -162.286595) (xy 104.84349 -162.267925)
			(xy 104.855772 -162.2552) (xy 104.873934 -162.235881) (xy 104.914674 -162.201945) (xy 104.959721 -162.173977)
			(xy 105.008206 -162.152516) (xy 105.059196 -162.137974) (xy 105.111709 -162.130633) (xy 105.164731 -162.130633)
			(xy 105.217244 -162.137974) (xy 105.268234 -162.152516) (xy 105.316719 -162.173977) (xy 105.361766 -162.201945)
			(xy 105.402506 -162.235881) (xy 105.420668 -162.2552) (xy 105.432979 -162.267887) (xy 105.463002 -162.286527)
			(xy 105.496979 -162.296239) (xy 105.514648 -162.296856) (xy 107.727496 -162.296856) (xy 108.39831 -161.626042)
			(xy 110.710472 -161.626042) (xy 111.375698 -160.960816) (xy 111.390898 -160.94496) (xy 111.416151 -160.909025)
			(xy 111.434845 -160.869281) (xy 111.446423 -160.826915) (xy 111.450539 -160.783187) (xy 111.447072 -160.739404)
			(xy 111.436124 -160.69687) (xy 111.418022 -160.656853) (xy 111.393306 -160.620548) (xy 111.362712 -160.589035)
			(xy 111.345218 -160.575752) (xy 111.322928 -160.558955) (xy 111.283039 -160.519918) (xy 111.249263 -160.475487)
			(xy 111.22232 -160.426609) (xy 111.202786 -160.374327) (xy 111.191077 -160.319757) (xy 111.187443 -160.264063)
			(xy 111.191961 -160.208434) (xy 111.204536 -160.154057) (xy 111.224899 -160.102093) (xy 111.252616 -160.053649)
			(xy 111.287094 -160.00976) (xy 111.327599 -159.971362) (xy 111.373265 -159.939276) (xy 111.423119 -159.914184)
			(xy 111.476096 -159.896624) (xy 111.531067 -159.886969) (xy 111.586858 -159.885425) (xy 111.642278 -159.892026)
			(xy 111.696145 -159.906631) (xy 111.7219 -159.917384) (xy 111.743082 -159.926096) (xy 111.787659 -159.936598)
			(xy 111.833396 -159.938942) (xy 111.878813 -159.933051) (xy 111.922439 -159.919118) (xy 111.962862 -159.897593)
			(xy 111.998773 -159.869172) (xy 112.029011 -159.834776) (xy 112.052595 -159.795519) (xy 112.068763 -159.75267)
			(xy 112.076991 -159.707618) (xy 112.0775 -159.68472) (xy 112.0775 -157.049978) (xy 112.077016 -157.027146)
			(xy 112.068853 -156.982218) (xy 112.052795 -156.939471) (xy 112.029357 -156.900281) (xy 111.999294 -156.86591)
			(xy 111.963574 -156.837463) (xy 111.923346 -156.815856) (xy 111.879904 -156.801784) (xy 111.834648 -156.7957)
			(xy 111.811816 -156.796232) (xy 111.783778 -156.797024) (xy 111.727974 -156.791367) (xy 111.6736 -156.777598)
			(xy 111.621829 -156.756015) (xy 111.573778 -156.727082) (xy 111.530481 -156.691425) (xy 111.492873 -156.649811)
			(xy 111.461764 -156.603138) (xy 111.437827 -156.552413) (xy 111.421575 -156.498729) (xy 111.413361 -156.443243)
			(xy 111.413362 -156.387154) (xy 111.421576 -156.331668) (xy 111.437828 -156.277985) (xy 111.461766 -156.227259)
			(xy 111.492875 -156.180587) (xy 111.530483 -156.138973) (xy 111.57378 -156.103316) (xy 111.621832 -156.074384)
			(xy 111.673603 -156.052801) (xy 111.727977 -156.039033) (xy 111.783781 -156.033375) (xy 111.811816 -156.034232)
			(xy 111.834648 -156.034801) (xy 111.879909 -156.028716) (xy 111.923354 -156.014642) (xy 111.963585 -155.993031)
			(xy 111.999307 -155.964579) (xy 112.02937 -155.930202) (xy 112.052807 -155.891006) (xy 112.068862 -155.848254)
			(xy 112.07702 -155.80332) (xy 112.0775 -155.780486) (xy 112.0775 -155.20162) (xy 112.076979 -155.17825)
			(xy 112.068447 -155.132295) (xy 112.051651 -155.088678) (xy 112.027157 -155.04887) (xy 111.995792 -155.014217)
			(xy 111.958616 -154.985888) (xy 111.916883 -154.964841) (xy 111.872004 -154.951785) (xy 111.825493 -154.947163)
			(xy 111.802164 -154.948636) (xy 111.774756 -154.95046) (xy 111.719926 -154.947166) (xy 111.666135 -154.936043)
			(xy 111.614495 -154.917323) (xy 111.566073 -154.891391) (xy 111.521869 -154.858784) (xy 111.482798 -154.820176)
			(xy 111.449666 -154.776364) (xy 111.423159 -154.728255) (xy 111.403824 -154.676841) (xy 111.392061 -154.623187)
			(xy 111.388112 -154.5684) (xy 111.392061 -154.513613) (xy 111.403824 -154.459959) (xy 111.423159 -154.408546)
			(xy 111.449666 -154.360436) (xy 111.482798 -154.316625) (xy 111.521869 -154.278016) (xy 111.566073 -154.245409)
			(xy 111.614495 -154.219478) (xy 111.666135 -154.200757) (xy 111.719926 -154.189634) (xy 111.774756 -154.18634)
			(xy 111.802164 -154.18816) (xy 111.825485 -154.189585) (xy 111.871968 -154.184918) (xy 111.916816 -154.171836)
			(xy 111.958518 -154.150779) (xy 111.995671 -154.122457) (xy 112.027024 -154.087824) (xy 112.05152 -154.048044)
			(xy 112.068335 -154.004458) (xy 112.076903 -153.958534) (xy 112.0775 -153.935176) (xy 112.0775 -149.75967)
			(xy 111.793782 -149.475952) (xy 111.776899 -149.459814) (xy 111.738403 -149.43338) (xy 111.695725 -149.414424)
			(xy 111.650302 -149.403586) (xy 111.603663 -149.401231) (xy 111.557379 -149.407437) (xy 111.513008 -149.421996)
			(xy 111.472045 -149.444418) (xy 111.435868 -149.473947) (xy 111.420402 -149.491446) (xy 111.402336 -149.512074)
			(xy 111.361299 -149.548442) (xy 111.315478 -149.57856) (xy 111.265817 -149.601809) (xy 111.21334 -149.617707)
			(xy 111.159127 -149.625929) (xy 111.104295 -149.626305) (xy 111.049974 -149.618827) (xy 110.997284 -149.603648)
			(xy 110.947309 -149.581083) (xy 110.90108 -149.551595) (xy 110.859548 -149.515793) (xy 110.823571 -149.474413)
			(xy 110.793888 -149.428309) (xy 110.771112 -149.37843) (xy 110.755711 -149.325804) (xy 110.748003 -149.271515)
			(xy 110.748147 -149.216682) (xy 110.75614 -149.162435) (xy 110.771817 -149.109891) (xy 110.782862 -149.084792)
			(xy 110.792122 -149.063565) (xy 110.803635 -149.018713) (xy 110.806834 -148.972517) (xy 110.801613 -148.926506)
			(xy 110.788144 -148.882201) (xy 110.766873 -148.84107) (xy 110.738503 -148.804471) (xy 110.703974 -148.773616)
			(xy 110.664427 -148.749526) (xy 110.621171 -148.732997) (xy 110.575637 -148.724577) (xy 110.552484 -148.724112)
			(xy 100.359972 -148.724112) (xy 99.529138 -149.554946) (xy 99.529138 -150.198353) (xy 102.965836 -150.198353)
			(xy 102.969385 -150.143785) (xy 102.980691 -150.090283) (xy 102.99952 -150.038943) (xy 103.025487 -149.990819)
			(xy 103.05806 -149.946895) (xy 103.096571 -149.908072) (xy 103.140231 -149.875147) (xy 103.188145 -149.848793)
			(xy 103.239332 -149.829552) (xy 103.292741 -149.817816) (xy 103.347279 -149.813828) (xy 103.401828 -149.817667)
			(xy 103.455269 -149.829257) (xy 103.506508 -149.848359) (xy 103.554494 -149.874582) (xy 103.598243 -149.907388)
			(xy 103.63686 -149.946105) (xy 103.669553 -149.98994) (xy 103.695651 -150.037994) (xy 103.71462 -150.089282)
			(xy 103.726071 -150.142753) (xy 103.72977 -150.197312) (xy 103.72564 -150.251839) (xy 103.713766 -150.305218)
			(xy 103.694391 -150.356354) (xy 103.667914 -150.4042) (xy 103.634875 -150.447774) (xy 103.615744 -150.467314)
			(xy 103.604173 -150.479531) (xy 103.587232 -150.508588) (xy 103.578454 -150.541058) (xy 103.578448 -150.574693)
			(xy 103.587213 -150.607166) (xy 103.604143 -150.63623) (xy 103.615744 -150.648416) (xy 103.636178 -150.669225)
			(xy 103.671125 -150.715914) (xy 103.68534 -150.74138) (xy 103.693416 -150.755383) (xy 103.715289 -150.779166)
			(xy 103.742441 -150.796684) (xy 103.773125 -150.80681) (xy 103.80537 -150.808894) (xy 103.837102 -150.802801)
			(xy 103.866282 -150.788924) (xy 103.891035 -150.768154) (xy 103.909768 -150.741827) (xy 103.915972 -150.726902)
			(xy 103.926294 -150.701273) (xy 103.953184 -150.653011) (xy 103.986754 -150.609131) (xy 104.026302 -150.570553)
			(xy 104.071001 -150.538082) (xy 104.119916 -150.512397) (xy 104.172024 -150.494037) (xy 104.226235 -150.483384)
			(xy 104.281416 -150.480662) (xy 104.336413 -150.485927) (xy 104.390075 -150.49907) (xy 104.44128 -150.519815)
			(xy 104.488958 -150.547729) (xy 104.51084 -150.564596) (xy 104.524588 -150.574852) (xy 104.556113 -150.588332)
			(xy 104.590088 -150.592936) (xy 104.624063 -150.588332) (xy 104.655588 -150.574852) (xy 104.669336 -150.564596)
			(xy 104.691196 -150.547665) (xy 104.738911 -150.519724) (xy 104.79016 -150.498963) (xy 104.843868 -150.485817)
			(xy 104.898912 -150.480563) (xy 104.954138 -150.483309) (xy 105.008389 -150.493999) (xy 105.060528 -150.512408)
			(xy 105.109464 -150.538151) (xy 105.154171 -150.570688) (xy 105.193713 -150.609339) (xy 105.227262 -150.653292)
			(xy 105.254114 -150.701628) (xy 105.273707 -150.753335) (xy 105.285631 -150.807327) (xy 105.289636 -150.862476)
			(xy 105.285638 -150.917625) (xy 105.273721 -150.97162) (xy 105.254134 -151.023329) (xy 105.227288 -151.071668)
			(xy 105.193745 -151.115626) (xy 105.154208 -151.154281) (xy 105.109505 -151.186824) (xy 105.060572 -151.212573)
			(xy 105.008435 -151.230989) (xy 104.954185 -151.241685) (xy 104.89896 -151.244438) (xy 104.843915 -151.239191)
			(xy 104.790205 -151.226052) (xy 104.738954 -151.205297) (xy 104.691236 -151.177362) (xy 104.669336 -151.16048)
			(xy 104.655588 -151.150224) (xy 104.624063 -151.136744) (xy 104.590088 -151.13214) (xy 104.556113 -151.136744)
			(xy 104.524588 -151.150224) (xy 104.51084 -151.16048) (xy 104.489283 -151.177142) (xy 104.442325 -151.204772)
			(xy 104.391914 -151.225439) (xy 104.339075 -151.238724) (xy 104.284884 -151.244355) (xy 104.230442 -151.242219)
			(xy 104.176859 -151.232359) (xy 104.125223 -151.214975) (xy 104.076586 -151.190421) (xy 104.031938 -151.159197)
			(xy 104.01173 -151.140922) (xy 103.994554 -151.125543) (xy 103.95581 -151.100565) (xy 103.913196 -151.082989)
			(xy 103.868109 -151.073392) (xy 103.822031 -151.072087) (xy 103.776473 -151.079119) (xy 103.732932 -151.094256)
			(xy 103.692838 -151.117001) (xy 103.657506 -151.146608) (xy 103.642414 -151.164036) (xy 103.624117 -151.185399)
			(xy 103.582268 -151.222982) (xy 103.535355 -151.254013) (xy 103.484394 -151.27782) (xy 103.43049 -151.293888)
			(xy 103.374811 -151.301867) (xy 103.318564 -151.301584) (xy 103.262969 -151.293047) (xy 103.209229 -151.276439)
			(xy 103.158509 -151.252122) (xy 103.11191 -151.220621) (xy 103.07044 -151.18262) (xy 103.035 -151.138943)
			(xy 103.006356 -151.090535) (xy 102.985129 -151.038446) (xy 102.971781 -150.983805) (xy 102.966599 -150.927797)
			(xy 102.969697 -150.871635) (xy 102.981007 -150.816536) (xy 103.000284 -150.763695) (xy 103.02711 -150.714256)
			(xy 103.060904 -150.669292) (xy 103.080566 -150.649178) (xy 103.092191 -150.63699) (xy 103.109211 -150.607943)
			(xy 103.118031 -150.575452) (xy 103.118036 -150.541786) (xy 103.109225 -150.509292) (xy 103.092214 -150.48024)
			(xy 103.080566 -150.468076) (xy 103.061413 -150.448556) (xy 103.028256 -150.405072) (xy 103.001648 -150.357299)
			(xy 102.982134 -150.306216) (xy 102.970115 -150.252869) (xy 102.965836 -150.198353) (xy 99.529138 -150.198353)
			(xy 99.529138 -151.391874) (xy 99.529604 -151.40719) (xy 99.536926 -151.436936) (xy 99.55113 -151.464077)
			(xy 99.571397 -151.487047) (xy 99.596557 -151.504522) (xy 99.610672 -151.510492) (xy 99.635742 -151.520618)
			(xy 99.682979 -151.546925) (xy 99.726027 -151.579639) (xy 99.752063 -151.605996) (xy 108.670342 -151.605996)
			(xy 108.674413 -151.550374) (xy 108.686539 -151.495937) (xy 108.706462 -151.443846) (xy 108.733758 -151.395211)
			(xy 108.767844 -151.351068) (xy 108.807993 -151.312359) (xy 108.853351 -151.279908) (xy 108.902951 -151.254407)
			(xy 108.955735 -151.2364) (xy 109.010578 -151.22627) (xy 109.066312 -151.224233) (xy 109.121749 -151.230333)
			(xy 109.175706 -151.244439) (xy 109.227035 -151.266251) (xy 109.274641 -151.295305) (xy 109.317509 -151.33098)
			(xy 109.354726 -151.372517) (xy 109.385499 -151.41903) (xy 109.409171 -151.469527) (xy 109.425239 -151.522934)
			(xy 109.433359 -151.57811) (xy 109.433868 -151.605996) (xy 109.433359 -151.633882) (xy 109.425239 -151.689058)
			(xy 109.409171 -151.742465) (xy 109.385499 -151.792962) (xy 109.354726 -151.839475) (xy 109.317509 -151.881012)
			(xy 109.274641 -151.916687) (xy 109.227035 -151.945741) (xy 109.175706 -151.967553) (xy 109.121749 -151.981659)
			(xy 109.066312 -151.987759) (xy 109.010578 -151.985722) (xy 108.955735 -151.975592) (xy 108.902951 -151.957585)
			(xy 108.853351 -151.932084) (xy 108.807993 -151.899633) (xy 108.767844 -151.860924) (xy 108.733758 -151.816781)
			(xy 108.706462 -151.768146) (xy 108.686539 -151.716055) (xy 108.674413 -151.661618) (xy 108.670342 -151.605996)
			(xy 99.752063 -151.605996) (xy 99.764024 -151.618105) (xy 99.796209 -151.66155) (xy 99.821936 -151.709105)
			(xy 99.840689 -151.759816) (xy 99.852094 -151.812668) (xy 99.855921 -151.8666) (xy 99.852094 -151.920532)
			(xy 99.840689 -151.973384) (xy 99.821936 -152.024095) (xy 99.796209 -152.07165) (xy 99.764024 -152.115095)
			(xy 99.726027 -152.153561) (xy 99.682979 -152.186275) (xy 99.635742 -152.212582) (xy 99.610672 -152.222708)
			(xy 99.596526 -152.228617) (xy 99.571349 -152.246096) (xy 99.551073 -152.269079) (xy 99.53687 -152.296238)
			(xy 99.52956 -152.326002) (xy 99.529138 -152.341326) (xy 99.529138 -152.431242) (xy 110.189008 -152.431242)
			(xy 110.193079 -152.37562) (xy 110.205205 -152.321183) (xy 110.225128 -152.269092) (xy 110.252424 -152.220457)
			(xy 110.28651 -152.176314) (xy 110.326659 -152.137605) (xy 110.372017 -152.105154) (xy 110.421617 -152.079653)
			(xy 110.474401 -152.061646) (xy 110.529244 -152.051516) (xy 110.584978 -152.049479) (xy 110.640415 -152.055579)
			(xy 110.694372 -152.069685) (xy 110.745701 -152.091497) (xy 110.793307 -152.120551) (xy 110.836175 -152.156226)
			(xy 110.873392 -152.197763) (xy 110.904165 -152.244276) (xy 110.927837 -152.294773) (xy 110.943905 -152.34818)
			(xy 110.952025 -152.403356) (xy 110.952534 -152.431242) (xy 110.952025 -152.459128) (xy 110.943905 -152.514304)
			(xy 110.927837 -152.567711) (xy 110.904165 -152.618208) (xy 110.873392 -152.664721) (xy 110.836175 -152.706258)
			(xy 110.793307 -152.741933) (xy 110.745701 -152.770987) (xy 110.694372 -152.792799) (xy 110.640415 -152.806905)
			(xy 110.584978 -152.813005) (xy 110.529244 -152.810968) (xy 110.474401 -152.800838) (xy 110.421617 -152.782831)
			(xy 110.372017 -152.75733) (xy 110.326659 -152.724879) (xy 110.28651 -152.68617) (xy 110.252424 -152.642027)
			(xy 110.225128 -152.593392) (xy 110.205205 -152.541301) (xy 110.193079 -152.486864) (xy 110.189008 -152.431242)
			(xy 99.529138 -152.431242) (xy 99.529138 -152.553162) (xy 99.953826 -152.97785) (xy 106.06405 -152.97785)
			(xy 106.394504 -153.308304) (xy 106.394504 -153.757122) (xy 106.859322 -153.757122) (xy 106.863393 -153.7015)
			(xy 106.875519 -153.647063) (xy 106.895442 -153.594972) (xy 106.922738 -153.546337) (xy 106.956824 -153.502194)
			(xy 106.996973 -153.463485) (xy 107.042331 -153.431034) (xy 107.091931 -153.405533) (xy 107.144715 -153.387526)
			(xy 107.199558 -153.377396) (xy 107.255292 -153.375359) (xy 107.310729 -153.381459) (xy 107.364686 -153.395565)
			(xy 107.416015 -153.417377) (xy 107.463621 -153.446431) (xy 107.506489 -153.482106) (xy 107.543706 -153.523643)
			(xy 107.574479 -153.570156) (xy 107.598151 -153.620653) (xy 107.614219 -153.67406) (xy 107.622339 -153.729236)
			(xy 107.622848 -153.757122) (xy 107.622339 -153.785008) (xy 107.614219 -153.840184) (xy 107.598151 -153.893591)
			(xy 107.574479 -153.944088) (xy 107.543706 -153.990601) (xy 107.506489 -154.032138) (xy 107.463621 -154.067813)
			(xy 107.416015 -154.096867) (xy 107.364686 -154.118679) (xy 107.310729 -154.132785) (xy 107.255292 -154.138885)
			(xy 107.199558 -154.136848) (xy 107.144715 -154.126718) (xy 107.091931 -154.108711) (xy 107.042331 -154.08321)
			(xy 106.996973 -154.050759) (xy 106.956824 -154.01205) (xy 106.922738 -153.967907) (xy 106.895442 -153.919272)
			(xy 106.875519 -153.867181) (xy 106.863393 -153.812744) (xy 106.859322 -153.757122) (xy 106.394504 -153.757122)
			(xy 106.394504 -154.187906) (xy 109.224062 -154.187906) (xy 109.228133 -154.132284) (xy 109.240259 -154.077847)
			(xy 109.260182 -154.025756) (xy 109.287478 -153.977121) (xy 109.321564 -153.932978) (xy 109.361713 -153.894269)
			(xy 109.407071 -153.861818) (xy 109.456671 -153.836317) (xy 109.509455 -153.81831) (xy 109.564298 -153.80818)
			(xy 109.620032 -153.806143) (xy 109.675469 -153.812243) (xy 109.729426 -153.826349) (xy 109.780755 -153.848161)
			(xy 109.828361 -153.877215) (xy 109.871229 -153.91289) (xy 109.908446 -153.954427) (xy 109.939219 -154.00094)
			(xy 109.962891 -154.051437) (xy 109.978959 -154.104844) (xy 109.987079 -154.16002) (xy 109.987588 -154.187906)
			(xy 109.987079 -154.215792) (xy 109.978959 -154.270968) (xy 109.962891 -154.324375) (xy 109.939219 -154.374872)
			(xy 109.908446 -154.421385) (xy 109.871229 -154.462922) (xy 109.828361 -154.498597) (xy 109.780755 -154.527651)
			(xy 109.729426 -154.549463) (xy 109.675469 -154.563569) (xy 109.620032 -154.569669) (xy 109.564298 -154.567632)
			(xy 109.509455 -154.557502) (xy 109.456671 -154.539495) (xy 109.407071 -154.513994) (xy 109.361713 -154.481543)
			(xy 109.321564 -154.442834) (xy 109.287478 -154.398691) (xy 109.260182 -154.350056) (xy 109.240259 -154.297965)
			(xy 109.228133 -154.243528) (xy 109.224062 -154.187906) (xy 106.394504 -154.187906) (xy 106.394504 -155.005278)
			(xy 106.394992 -155.021105) (xy 106.40279 -155.051783) (xy 106.41789 -155.079604) (xy 106.439363 -155.10286)
			(xy 106.465895 -155.120126) (xy 106.495855 -155.130341) (xy 106.511598 -155.132024) (xy 106.538615 -155.134599)
			(xy 106.591583 -155.146424) (xy 106.642339 -155.165637) (xy 106.689859 -155.191851) (xy 106.733184 -155.224536)
			(xy 106.771439 -155.263032) (xy 106.803851 -155.306562) (xy 106.829765 -155.354246) (xy 106.848658 -155.405122)
			(xy 106.860149 -155.458163) (xy 106.864005 -155.512297) (xy 106.86015 -155.566431) (xy 106.84866 -155.619472)
			(xy 106.829767 -155.670349) (xy 106.821815 -155.684982) (xy 110.646462 -155.684982) (xy 110.650533 -155.62936)
			(xy 110.662659 -155.574923) (xy 110.682582 -155.522832) (xy 110.709878 -155.474197) (xy 110.743964 -155.430054)
			(xy 110.784113 -155.391345) (xy 110.829471 -155.358894) (xy 110.879071 -155.333393) (xy 110.931855 -155.315386)
			(xy 110.986698 -155.305256) (xy 111.042432 -155.303219) (xy 111.097869 -155.309319) (xy 111.151826 -155.323425)
			(xy 111.203155 -155.345237) (xy 111.250761 -155.374291) (xy 111.293629 -155.409966) (xy 111.330846 -155.451503)
			(xy 111.361619 -155.498016) (xy 111.385291 -155.548513) (xy 111.401359 -155.60192) (xy 111.409479 -155.657096)
			(xy 111.409988 -155.684982) (xy 111.409479 -155.712868) (xy 111.401359 -155.768044) (xy 111.385291 -155.821451)
			(xy 111.361619 -155.871948) (xy 111.330846 -155.918461) (xy 111.293629 -155.959998) (xy 111.250761 -155.995673)
			(xy 111.203155 -156.024727) (xy 111.151826 -156.046539) (xy 111.097869 -156.060645) (xy 111.042432 -156.066745)
			(xy 110.986698 -156.064708) (xy 110.931855 -156.054578) (xy 110.879071 -156.036571) (xy 110.829471 -156.01107)
			(xy 110.784113 -155.978619) (xy 110.743964 -155.93991) (xy 110.709878 -155.895767) (xy 110.682582 -155.847132)
			(xy 110.662659 -155.795041) (xy 110.650533 -155.740604) (xy 110.646462 -155.684982) (xy 106.821815 -155.684982)
			(xy 106.803854 -155.718033) (xy 106.771443 -155.761564) (xy 106.733189 -155.80006) (xy 106.689864 -155.832746)
			(xy 106.642344 -155.85896) (xy 106.591588 -155.878174) (xy 106.538621 -155.89) (xy 106.511598 -155.8925)
			(xy 106.49585 -155.894206) (xy 106.465857 -155.904364) (xy 106.439297 -155.921606) (xy 106.41781 -155.944867)
			(xy 106.402725 -155.972709) (xy 106.394974 -156.003412) (xy 106.394504 -156.019246) (xy 106.394504 -157.447742)
			(xy 106.862116 -157.447742) (xy 106.866187 -157.39212) (xy 106.878313 -157.337683) (xy 106.898236 -157.285592)
			(xy 106.925532 -157.236957) (xy 106.959618 -157.192814) (xy 106.999767 -157.154105) (xy 107.045125 -157.121654)
			(xy 107.094725 -157.096153) (xy 107.147509 -157.078146) (xy 107.202352 -157.068016) (xy 107.258086 -157.065979)
			(xy 107.313523 -157.072079) (xy 107.36748 -157.086185) (xy 107.418809 -157.107997) (xy 107.466415 -157.137051)
			(xy 107.509283 -157.172726) (xy 107.5465 -157.214263) (xy 107.577273 -157.260776) (xy 107.600945 -157.311273)
			(xy 107.617013 -157.36468) (xy 107.625133 -157.419856) (xy 107.625642 -157.447742) (xy 107.625133 -157.475628)
			(xy 107.617013 -157.530804) (xy 107.600945 -157.584211) (xy 107.577273 -157.634708) (xy 107.5465 -157.681221)
			(xy 107.509283 -157.722758) (xy 107.466415 -157.758433) (xy 107.418809 -157.787487) (xy 107.36748 -157.809299)
			(xy 107.313523 -157.823405) (xy 107.258086 -157.829505) (xy 107.202352 -157.827468) (xy 107.147509 -157.817338)
			(xy 107.094725 -157.799331) (xy 107.045125 -157.77383) (xy 106.999767 -157.741379) (xy 106.959618 -157.70267)
			(xy 106.925532 -157.658527) (xy 106.898236 -157.609892) (xy 106.878313 -157.557801) (xy 106.866187 -157.503364)
			(xy 106.862116 -157.447742) (xy 106.394504 -157.447742) (xy 106.394504 -158.403798) (xy 105.61574 -159.182562)
			(xy 103.43134 -159.182562) (xy 103.361236 -159.239966) (xy 103.352346 -159.28467) (xy 103.346436 -159.311613)
			(xy 103.327896 -159.363564) (xy 103.302071 -159.412304) (xy 103.269497 -159.456818) (xy 103.230854 -159.496179)
			(xy 103.186946 -159.529566) (xy 103.13869 -159.556284) (xy 103.087089 -159.575777) (xy 103.03322 -159.587637)
			(xy 102.978204 -159.591618) (xy 102.923188 -159.587637) (xy 102.869319 -159.575777) (xy 102.817718 -159.556284)
			(xy 102.769462 -159.529566) (xy 102.725554 -159.496179) (xy 102.686911 -159.456818) (xy 102.654337 -159.412304)
			(xy 102.628512 -159.363564) (xy 102.609972 -159.311613) (xy 102.604062 -159.28467) (xy 102.595172 -159.239966)
			(xy 102.525068 -159.182562) (xy 99.765104 -159.182562) (xy 99.529138 -159.418528) (xy 99.529138 -160.490154)
			(xy 102.767382 -160.490154) (xy 102.771453 -160.434532) (xy 102.783579 -160.380095) (xy 102.803502 -160.328004)
			(xy 102.830798 -160.279369) (xy 102.864884 -160.235226) (xy 102.905033 -160.196517) (xy 102.950391 -160.164066)
			(xy 102.999991 -160.138565) (xy 103.052775 -160.120558) (xy 103.107618 -160.110428) (xy 103.163352 -160.108391)
			(xy 103.218789 -160.114491) (xy 103.272746 -160.128597) (xy 103.324075 -160.150409) (xy 103.371681 -160.179463)
			(xy 103.414549 -160.215138) (xy 103.451766 -160.256675) (xy 103.482539 -160.303188) (xy 103.506211 -160.353685)
			(xy 103.522279 -160.407092) (xy 103.530399 -160.462268) (xy 103.530908 -160.490154) (xy 103.530399 -160.51804)
			(xy 103.522279 -160.573216) (xy 103.506211 -160.626623) (xy 103.482539 -160.67712) (xy 103.451766 -160.723633)
			(xy 103.414549 -160.76517) (xy 103.371681 -160.800845) (xy 103.324075 -160.829899) (xy 103.272746 -160.851711)
			(xy 103.218789 -160.865817) (xy 103.163352 -160.871917) (xy 103.107618 -160.86988) (xy 103.052775 -160.85975)
			(xy 102.999991 -160.841743) (xy 102.950391 -160.816242) (xy 102.905033 -160.783791) (xy 102.864884 -160.745082)
			(xy 102.830798 -160.700939) (xy 102.803502 -160.652304) (xy 102.783579 -160.600213) (xy 102.771453 -160.545776)
			(xy 102.767382 -160.490154) (xy 99.529138 -160.490154) (xy 99.529138 -161.919412) (xy 99.906582 -162.296856)
		)
		(stroke
			(width 0)
			(type solid)
		)
		(fill yes)
		(layer "In2.Cu")
		(net "P12V_AUX")
	)
	(gr_poly
		(pts
			(xy 165.232588 -106.62666) (xy 165.247578 -106.626244) (xy 165.276731 -106.619247) (xy 165.303444 -106.605638)
			(xy 165.326242 -106.586169) (xy 165.343865 -106.561915) (xy 165.355338 -106.534217) (xy 165.358064 -106.519472)
			(xy 165.359984 -106.504597) (xy 165.357606 -106.474705) (xy 165.348316 -106.446194) (xy 165.332628 -106.420639)
			(xy 165.311408 -106.399452) (xy 165.285829 -106.383803) (xy 165.271704 -106.378756) (xy 165.243266 -106.368966)
			(xy 165.189653 -106.341714) (xy 165.140975 -106.306394) (xy 165.119304 -106.285538) (xy 165.108139 -106.275059)
			(xy 165.081928 -106.259244) (xy 165.052704 -106.250128) (xy 165.022151 -106.248237) (xy 164.992026 -106.253677)
			(xy 164.964064 -106.266138) (xy 164.951664 -106.275124) (xy 164.929788 -106.291571) (xy 164.88225 -106.318694)
			(xy 164.831325 -106.338746) (xy 164.778056 -106.351313) (xy 164.723539 -106.35614) (xy 164.668891 -106.353125)
			(xy 164.615235 -106.342332) (xy 164.563672 -106.323982) (xy 164.515261 -106.298451) (xy 164.470995 -106.266264)
			(xy 164.431784 -106.228081) (xy 164.398431 -106.184687) (xy 164.371623 -106.136971) (xy 164.351908 -106.085914)
			(xy 164.339693 -106.032564) (xy 164.335227 -105.978016) (xy 164.338602 -105.923389) (xy 164.34975 -105.869806)
			(xy 164.36844 -105.818365) (xy 164.39429 -105.770124) (xy 164.426769 -105.726072) (xy 164.46521 -105.687113)
			(xy 164.508824 -105.654048) (xy 164.556715 -105.627555) (xy 164.607901 -105.608179) (xy 164.661331 -105.596316)
			(xy 164.715907 -105.59221) (xy 164.77051 -105.595946) (xy 164.824019 -105.607447) (xy 164.875335 -105.626477)
			(xy 164.923405 -105.652645) (xy 164.967241 -105.685414) (xy 164.98697 -105.704386) (xy 164.998136 -105.714867)
			(xy 165.024349 -105.730684) (xy 165.053574 -105.739803) (xy 165.08413 -105.7417) (xy 165.114259 -105.736264)
			(xy 165.142226 -105.723809) (xy 165.15461 -105.7148) (xy 165.176192 -105.698579) (xy 165.223033 -105.671735)
			(xy 165.273191 -105.651762) (xy 165.325663 -105.639058) (xy 165.379401 -105.633878) (xy 165.433334 -105.636324)
			(xy 165.486383 -105.646348) (xy 165.53749 -105.66375) (xy 165.585633 -105.688182) (xy 165.629852 -105.719156)
			(xy 165.669263 -105.756055) (xy 165.703079 -105.79814) (xy 165.730625 -105.844571) (xy 165.751352 -105.894422)
			(xy 165.764844 -105.946697) (xy 165.770833 -106.000352) (xy 165.769199 -106.054315) (xy 165.759975 -106.107509)
			(xy 165.743345 -106.158872) (xy 165.71964 -106.207378) (xy 165.704774 -106.229912) (xy 165.692277 -106.24918)
			(xy 165.67371 -106.29118) (xy 165.66299 -106.335833) (xy 165.660465 -106.381684) (xy 165.666217 -106.427244)
			(xy 165.680061 -106.471029) (xy 165.701544 -106.511615) (xy 165.729968 -106.547681) (xy 165.764409 -106.578055)
			(xy 165.803746 -106.601748) (xy 165.8467 -106.617989) (xy 165.891872 -106.62625) (xy 165.914832 -106.62666)
			(xy 167.9702 -106.62666) (xy 167.992064 -106.626204) (xy 168.035147 -106.61872) (xy 168.076313 -106.603973)
			(xy 168.114347 -106.582397) (xy 168.148128 -106.55463) (xy 168.176657 -106.521491) (xy 168.199094 -106.483958)
			(xy 168.214776 -106.443139) (xy 168.22324 -106.400238) (xy 168.224237 -106.356521) (xy 168.217736 -106.313279)
			(xy 168.211246 -106.292396) (xy 168.202786 -106.265411) (xy 168.193009 -106.209711) (xy 168.191562 -106.153178)
			(xy 168.198478 -106.097051) (xy 168.213604 -106.042561) (xy 168.23661 -105.9909) (xy 168.26699 -105.943202)
			(xy 168.30408 -105.900513) (xy 168.347066 -105.863767) (xy 168.395006 -105.83377) (xy 168.446849 -105.81118)
			(xy 168.50146 -105.796491) (xy 168.55764 -105.790026) (xy 168.61416 -105.791926) (xy 168.669779 -105.80215)
			(xy 168.72328 -105.820473) (xy 168.773489 -105.846494) (xy 168.796716 -105.862628) (xy 168.80941 -105.87124)
			(xy 168.83783 -105.882759) (xy 168.868178 -105.887164) (xy 168.8987 -105.884201) (xy 168.927634 -105.874041)
			(xy 168.953309 -105.857272) (xy 168.964102 -105.846372) (xy 168.983818 -105.82598) (xy 169.028207 -105.79067)
			(xy 169.077335 -105.762321) (xy 169.130118 -105.741557) (xy 169.185394 -105.728837) (xy 169.241943 -105.724441)
			(xy 169.298521 -105.728465) (xy 169.353879 -105.740821) (xy 169.406798 -105.761237) (xy 169.456111 -105.789262)
			(xy 169.497487 -105.821734) (xy 170.653454 -105.821734) (xy 170.657525 -105.766112) (xy 170.669651 -105.711675)
			(xy 170.689574 -105.659584) (xy 170.71687 -105.610949) (xy 170.750956 -105.566806) (xy 170.791105 -105.528097)
			(xy 170.836463 -105.495646) (xy 170.886063 -105.470145) (xy 170.938847 -105.452138) (xy 170.99369 -105.442008)
			(xy 171.049424 -105.439971) (xy 171.104861 -105.446071) (xy 171.158818 -105.460177) (xy 171.210147 -105.481989)
			(xy 171.257753 -105.511043) (xy 171.300621 -105.546718) (xy 171.337838 -105.588255) (xy 171.368611 -105.634768)
			(xy 171.392283 -105.685265) (xy 171.408351 -105.738672) (xy 171.416471 -105.793848) (xy 171.41698 -105.821734)
			(xy 171.416471 -105.84962) (xy 171.408351 -105.904796) (xy 171.392283 -105.958203) (xy 171.368611 -106.0087)
			(xy 171.337838 -106.055213) (xy 171.300621 -106.09675) (xy 171.257753 -106.132425) (xy 171.210147 -106.161479)
			(xy 171.158818 -106.183291) (xy 171.104861 -106.197397) (xy 171.049424 -106.203497) (xy 170.99369 -106.20146)
			(xy 170.938847 -106.19133) (xy 170.886063 -106.173323) (xy 170.836463 -106.147822) (xy 170.791105 -106.115371)
			(xy 170.750956 -106.076662) (xy 170.71687 -106.032519) (xy 170.689574 -105.983884) (xy 170.669651 -105.931793)
			(xy 170.657525 -105.877356) (xy 170.653454 -105.821734) (xy 169.497487 -105.821734) (xy 169.500731 -105.82428)
			(xy 169.539676 -105.865517) (xy 169.572086 -105.912066) (xy 169.597248 -105.9629) (xy 169.614606 -106.016899)
			(xy 169.623778 -106.072872) (xy 169.624563 -106.129587) (xy 169.616942 -106.185793) (xy 169.601084 -106.240252)
			(xy 169.589704 -106.266234) (xy 169.580465 -106.287464) (xy 169.568993 -106.332315) (xy 169.565835 -106.378502)
			(xy 169.571095 -106.424497) (xy 169.584599 -106.468778) (xy 169.6059 -106.509882) (xy 169.634294 -106.546447)
			(xy 169.668841 -106.577264) (xy 169.708399 -106.601314) (xy 169.751658 -106.617801) (xy 169.797189 -106.62618)
			(xy 169.820336 -106.62666) (xy 172.189394 -106.62666) (xy 173.043088 -105.772966) (xy 173.043088 -104.09809)
			(xy 173.042589 -104.074988) (xy 173.034249 -104.029542) (xy 173.017828 -103.986354) (xy 172.993867 -103.946847)
			(xy 172.963156 -103.912326) (xy 172.926709 -103.883928) (xy 172.885727 -103.862589) (xy 172.841561 -103.849014)
			(xy 172.795669 -103.84365) (xy 172.749564 -103.846674) (xy 172.704765 -103.857987) (xy 172.662751 -103.877214)
			(xy 172.643546 -103.890064) (xy 172.621238 -103.905131) (xy 172.573249 -103.929519) (xy 172.522308 -103.946919)
			(xy 172.469427 -103.956986) (xy 172.415656 -103.959521) (xy 172.362062 -103.954472) (xy 172.309711 -103.94194)
			(xy 172.25964 -103.922175) (xy 172.212845 -103.895567) (xy 172.170254 -103.862646) (xy 172.132713 -103.824066)
			(xy 172.100968 -103.780592) (xy 172.075649 -103.733088) (xy 172.057258 -103.682496) (xy 172.046161 -103.629821)
			(xy 172.042578 -103.57611) (xy 172.04658 -103.522428) (xy 172.058087 -103.469842) (xy 172.076872 -103.419395)
			(xy 172.089318 -103.395526) (xy 172.09643 -103.382572) (xy 172.113702 -103.319072) (xy 172.065188 -103.22052)
			(xy 172.046138 -103.203756) (xy 172.025692 -103.185152) (xy 171.989849 -103.14307) (xy 171.960453 -103.096256)
			(xy 171.93812 -103.04569) (xy 171.923316 -102.992432) (xy 171.916352 -102.937594) (xy 171.917373 -102.882326)
			(xy 171.926358 -102.827783) (xy 171.943119 -102.775107) (xy 171.967305 -102.725401) (xy 171.99841 -102.679705)
			(xy 172.035783 -102.638975) (xy 172.078642 -102.604064) (xy 172.126089 -102.575703) (xy 172.177132 -102.554484)
			(xy 172.230703 -102.540852) (xy 172.28568 -102.535092) (xy 172.340913 -102.537325) (xy 172.395245 -102.547505)
			(xy 172.44754 -102.565417) (xy 172.496704 -102.590687) (xy 172.541707 -102.622787) (xy 172.581607 -102.661044)
			(xy 172.61557 -102.704658) (xy 172.642884 -102.752716) (xy 172.662978 -102.804213) (xy 172.675432 -102.85807)
			(xy 172.679984 -102.91316) (xy 172.67654 -102.96833) (xy 172.665171 -103.022426) (xy 172.646116 -103.074316)
			(xy 172.633386 -103.098854) (xy 172.626274 -103.111808) (xy 172.609002 -103.175308) (xy 172.657516 -103.27386)
			(xy 172.676566 -103.290624) (xy 172.699987 -103.312064) (xy 172.740076 -103.361299) (xy 172.771485 -103.416479)
			(xy 172.782992 -103.446072) (xy 172.795692 -103.480616) (xy 172.838618 -103.513636) (xy 172.85137 -103.522861)
			(xy 172.880243 -103.535367) (xy 172.9113 -103.540422) (xy 172.942649 -103.537718) (xy 172.972381 -103.52742)
			(xy 172.998686 -103.510155) (xy 173.019962 -103.486974) (xy 173.034914 -103.459288) (xy 173.042632 -103.428784)
			(xy 173.043088 -103.413052) (xy 173.043088 -100.280978) (xy 173.042616 -100.258622) (xy 173.034791 -100.2146)
			(xy 173.019385 -100.172626) (xy 172.996873 -100.133995) (xy 172.967951 -100.099897) (xy 172.93351 -100.071384)
			(xy 172.894612 -100.049336) (xy 172.852457 -100.034433) (xy 172.808345 -100.027134) (xy 172.763636 -100.027665)
			(xy 172.71971 -100.036009) (xy 172.67792 -100.051908) (xy 172.658532 -100.063046) (xy 172.635059 -100.076554)
			(xy 172.585132 -100.097534) (xy 172.532739 -100.111242) (xy 172.478934 -100.117402) (xy 172.424799 -100.115891)
			(xy 172.371422 -100.106738) (xy 172.319876 -100.090128) (xy 172.271197 -100.066395) (xy 172.226363 -100.036016)
			(xy 172.186277 -99.999602) (xy 172.151745 -99.957884) (xy 172.123459 -99.911702) (xy 172.101989 -99.861983)
			(xy 172.087767 -99.809727) (xy 172.081078 -99.755986) (xy 172.082057 -99.701838) (xy 172.090684 -99.648374)
			(xy 172.098208 -99.622356) (xy 172.104406 -99.600907) (xy 172.110047 -99.556622) (xy 172.10787 -99.512032)
			(xy 172.097943 -99.468507) (xy 172.080569 -99.427383) (xy 172.056283 -99.389924) (xy 172.025831 -99.35728)
			(xy 172.008292 -99.343464) (xy 171.986361 -99.326372) (xy 171.947213 -99.28689) (xy 171.914211 -99.242144)
			(xy 171.888055 -99.19308) (xy 171.869299 -99.140739) (xy 171.85834 -99.086229) (xy 171.855411 -99.030706)
			(xy 171.860574 -98.975346) (xy 171.873719 -98.921322) (xy 171.894568 -98.869779) (xy 171.922679 -98.821809)
			(xy 171.957457 -98.778427) (xy 171.998163 -98.740555) (xy 172.043937 -98.708993) (xy 172.093808 -98.684411)
			(xy 172.146719 -98.66733) (xy 172.20155 -98.658111) (xy 172.257138 -98.656949) (xy 172.312306 -98.663871)
			(xy 172.365884 -98.678728) (xy 172.416738 -98.701206) (xy 172.46379 -98.730829) (xy 172.506043 -98.766968)
			(xy 172.542602 -98.808859) (xy 172.572691 -98.855614) (xy 172.595674 -98.906242) (xy 172.611064 -98.95967)
			(xy 172.618534 -99.014766) (xy 172.617926 -99.070363) (xy 172.609254 -99.125282) (xy 172.601382 -99.151948)
			(xy 172.595185 -99.173397) (xy 172.589545 -99.217682) (xy 172.591722 -99.262271) (xy 172.601649 -99.305796)
			(xy 172.619023 -99.346919) (xy 172.643308 -99.384379) (xy 172.67376 -99.417023) (xy 172.691298 -99.43084)
			(xy 172.714293 -99.448751) (xy 172.755095 -99.49037) (xy 172.789106 -99.537701) (xy 172.802804 -99.563428)
			(xy 172.810178 -99.577014) (xy 172.83037 -99.600408) (xy 172.855598 -99.618259) (xy 172.884378 -99.629516)
			(xy 172.915021 -99.63352) (xy 172.945728 -99.630035) (xy 172.974695 -99.619266) (xy 173.00022 -99.601845)
			(xy 173.020806 -99.578795) (xy 173.035242 -99.551471) (xy 173.042682 -99.521476) (xy 173.043088 -99.506024)
			(xy 173.043088 -96.383094) (xy 172.302932 -95.642938) (xy 172.291236 -95.63193) (xy 172.263562 -95.615647)
			(xy 172.2327 -95.606788) (xy 172.200603 -95.605912) (xy 172.169303 -95.613077) (xy 172.15485 -95.620078)
			(xy 172.130253 -95.632307) (xy 172.078373 -95.650359) (xy 172.024441 -95.660784) (xy 171.969572 -95.663366)
			(xy 171.914899 -95.658051) (xy 171.861554 -95.644949) (xy 171.81064 -95.624332) (xy 171.763209 -95.596625)
			(xy 171.720243 -95.562401) (xy 171.682629 -95.522369) (xy 171.651147 -95.477355) (xy 171.626446 -95.428292)
			(xy 171.609038 -95.376193) (xy 171.599283 -95.322135) (xy 171.597828 -95.294704) (xy 171.596778 -95.278437)
			(xy 171.587453 -95.247214) (xy 171.570515 -95.219376) (xy 171.547071 -95.196744) (xy 171.518654 -95.180796)
			(xy 171.487122 -95.172576) (xy 171.470828 -95.172022) (xy 168.782746 -95.172022) (xy 168.760099 -95.172523)
			(xy 168.715524 -95.180562) (xy 168.67308 -95.196375) (xy 168.634112 -95.219463) (xy 168.599853 -95.249092)
			(xy 168.57139 -95.284326) (xy 168.549623 -95.324047) (xy 168.535243 -95.366997) (xy 168.528704 -95.411817)
			(xy 168.530214 -95.457086) (xy 168.539725 -95.50137) (xy 168.556936 -95.543267) (xy 168.568624 -95.562674)
			(xy 168.582855 -95.58587) (xy 168.605316 -95.635436) (xy 168.620505 -95.687691) (xy 168.628114 -95.741575)
			(xy 168.627988 -95.795993) (xy 168.620131 -95.84984) (xy 168.610636 -95.881952) (xy 169.598592 -95.881952)
			(xy 169.602663 -95.82633) (xy 169.614789 -95.771893) (xy 169.634712 -95.719802) (xy 169.662008 -95.671167)
			(xy 169.696094 -95.627024) (xy 169.736243 -95.588315) (xy 169.781601 -95.555864) (xy 169.831201 -95.530363)
			(xy 169.883985 -95.512356) (xy 169.938828 -95.502226) (xy 169.994562 -95.500189) (xy 170.049999 -95.506289)
			(xy 170.103956 -95.520395) (xy 170.155285 -95.542207) (xy 170.202891 -95.571261) (xy 170.245759 -95.606936)
			(xy 170.282976 -95.648473) (xy 170.313749 -95.694986) (xy 170.337421 -95.745483) (xy 170.353489 -95.79889)
			(xy 170.361609 -95.854066) (xy 170.362118 -95.881952) (xy 170.361609 -95.909838) (xy 170.353489 -95.965014)
			(xy 170.337421 -96.018421) (xy 170.313749 -96.068918) (xy 170.282976 -96.115431) (xy 170.245759 -96.156968)
			(xy 170.202891 -96.192643) (xy 170.155285 -96.221697) (xy 170.103956 -96.243509) (xy 170.049999 -96.257615)
			(xy 169.994562 -96.263715) (xy 169.938828 -96.261678) (xy 169.883985 -96.251548) (xy 169.831201 -96.233541)
			(xy 169.781601 -96.20804) (xy 169.736243 -96.175589) (xy 169.696094 -96.13688) (xy 169.662008 -96.092737)
			(xy 169.634712 -96.044102) (xy 169.614789 -95.992011) (xy 169.602663 -95.937574) (xy 169.598592 -95.881952)
			(xy 168.610636 -95.881952) (xy 168.604701 -95.902025) (xy 168.582013 -95.951488) (xy 168.552525 -95.997224)
			(xy 168.516837 -96.038305) (xy 168.475673 -96.073898) (xy 168.429869 -96.103281) (xy 168.380355 -96.125856)
			(xy 168.328135 -96.141165) (xy 168.274269 -96.148898) (xy 168.219851 -96.148898) (xy 168.165985 -96.141165)
			(xy 168.113765 -96.125856) (xy 168.064251 -96.103281) (xy 168.018447 -96.073898) (xy 167.977283 -96.038305)
			(xy 167.941595 -95.997224) (xy 167.912107 -95.951488) (xy 167.889419 -95.902025) (xy 167.873989 -95.84984)
			(xy 167.866132 -95.795993) (xy 167.866006 -95.741575) (xy 167.873615 -95.687691) (xy 167.888804 -95.635436)
			(xy 167.911265 -95.58587) (xy 167.925496 -95.562674) (xy 167.937267 -95.543312) (xy 167.954489 -95.501404)
			(xy 167.964007 -95.457106) (xy 167.96552 -95.411823) (xy 167.95898 -95.366989) (xy 167.944593 -95.324025)
			(xy 167.922817 -95.284293) (xy 167.89434 -95.249051) (xy 167.860066 -95.219418) (xy 167.821081 -95.19633)
			(xy 167.77862 -95.180522) (xy 167.734028 -95.172493) (xy 167.711374 -95.172022) (xy 166.164514 -95.172022)
			(xy 166.141426 -95.172526) (xy 166.09601 -95.180866) (xy 166.052848 -95.197274) (xy 166.013361 -95.221211)
			(xy 165.978849 -95.251888) (xy 165.950447 -95.288295) (xy 165.92909 -95.329235) (xy 165.915481 -95.373359)
			(xy 165.910068 -95.419216) (xy 165.91303 -95.465297) (xy 165.924268 -95.510084) (xy 165.943413 -95.552103)
			(xy 165.956234 -95.57131) (xy 165.971708 -95.594347) (xy 165.996546 -95.643972) (xy 166.013935 -95.696671)
			(xy 166.023509 -95.751333) (xy 166.025064 -95.806806) (xy 166.018568 -95.861918) (xy 166.004159 -95.915509)
			(xy 165.982139 -95.966447) (xy 165.952974 -96.013659) (xy 165.917279 -96.05615) (xy 165.875805 -96.093022)
			(xy 165.829429 -96.123498) (xy 165.779128 -96.146937) (xy 165.725962 -96.162842) (xy 165.671053 -96.17088)
			(xy 165.615559 -96.17088) (xy 165.56065 -96.162842) (xy 165.507484 -96.146937) (xy 165.457183 -96.123498)
			(xy 165.410807 -96.093022) (xy 165.369333 -96.05615) (xy 165.333638 -96.013659) (xy 165.304473 -95.966447)
			(xy 165.282453 -95.915509) (xy 165.268044 -95.861918) (xy 165.261548 -95.806806) (xy 165.263103 -95.751333)
			(xy 165.272677 -95.696671) (xy 165.290066 -95.643972) (xy 165.314904 -95.594347) (xy 165.330378 -95.57131)
			(xy 165.343169 -95.552085) (xy 165.362304 -95.510065) (xy 165.373536 -95.465279) (xy 165.376493 -95.419202)
			(xy 165.37108 -95.373348) (xy 165.357474 -95.329226) (xy 165.336122 -95.288288) (xy 165.307728 -95.251879)
			(xy 165.273224 -95.221197) (xy 165.233747 -95.197252) (xy 165.190593 -95.180831) (xy 165.145184 -95.172474)
			(xy 165.122098 -95.172022) (xy 164.925756 -95.172022) (xy 164.89553 -95.190056) (xy 164.87005 -95.204637)
			(xy 164.81563 -95.22665) (xy 164.75848 -95.24007) (xy 164.69995 -95.244578) (xy 164.64142 -95.24007)
			(xy 164.58427 -95.22665) (xy 164.52985 -95.204637) (xy 164.50437 -95.190056) (xy 164.474144 -95.172022)
			(xy 164.169598 -95.172022) (xy 164.069522 -95.272098) (xy 164.054074 -95.288204) (xy 164.028514 -95.324783)
			(xy 164.009736 -95.365264) (xy 163.998318 -95.408403) (xy 163.994611 -95.452873) (xy 163.998728 -95.497307)
			(xy 164.010543 -95.540339) (xy 164.029693 -95.580646) (xy 164.05559 -95.616987) (xy 164.087435 -95.648247)
			(xy 164.10559 -95.661226) (xy 164.128341 -95.67741) (xy 164.169301 -95.715352) (xy 164.204294 -95.758859)
			(xy 164.232571 -95.807001) (xy 164.253529 -95.858751) (xy 164.266721 -95.913002) (xy 164.271865 -95.968598)
			(xy 164.26885 -96.024349) (xy 164.257741 -96.079065) (xy 164.238776 -96.131578) (xy 164.21236 -96.180766)
			(xy 164.179056 -96.225578) (xy 164.139576 -96.265058) (xy 164.094763 -96.298361) (xy 164.045575 -96.324778)
			(xy 163.993062 -96.343742) (xy 163.938346 -96.35485) (xy 163.882594 -96.357865) (xy 163.826999 -96.352721)
			(xy 163.772748 -96.339529) (xy 163.720998 -96.31857) (xy 163.672856 -96.290292) (xy 163.62935 -96.255299)
			(xy 163.591408 -96.214339) (xy 163.575238 -96.191578) (xy 163.562245 -96.173434) (xy 163.530987 -96.14159)
			(xy 163.494647 -96.115695) (xy 163.454343 -96.096545) (xy 163.411313 -96.08473) (xy 163.366881 -96.080611)
			(xy 163.322413 -96.084317) (xy 163.279276 -96.095733) (xy 163.238795 -96.114507) (xy 163.202217 -96.140064)
			(xy 163.18611 -96.15551) (xy 163.088828 -96.252792) (xy 163.073986 -96.268261) (xy 163.049194 -96.30323)
			(xy 163.030627 -96.341867) (xy 163.025871 -96.358456) (xy 170.873672 -96.358456) (xy 170.877743 -96.302834)
			(xy 170.889869 -96.248397) (xy 170.909792 -96.196306) (xy 170.937088 -96.147671) (xy 170.971174 -96.103528)
			(xy 171.011323 -96.064819) (xy 171.056681 -96.032368) (xy 171.106281 -96.006867) (xy 171.159065 -95.98886)
			(xy 171.213908 -95.97873) (xy 171.269642 -95.976693) (xy 171.325079 -95.982793) (xy 171.379036 -95.996899)
			(xy 171.430365 -96.018711) (xy 171.477971 -96.047765) (xy 171.520839 -96.08344) (xy 171.558056 -96.124977)
			(xy 171.588829 -96.17149) (xy 171.612501 -96.221987) (xy 171.628569 -96.275394) (xy 171.636689 -96.33057)
			(xy 171.637198 -96.358456) (xy 171.636689 -96.386342) (xy 171.628569 -96.441518) (xy 171.612501 -96.494925)
			(xy 171.588829 -96.545422) (xy 171.558056 -96.591935) (xy 171.520839 -96.633472) (xy 171.477971 -96.669147)
			(xy 171.430365 -96.698201) (xy 171.379036 -96.720013) (xy 171.325079 -96.734119) (xy 171.269642 -96.740219)
			(xy 171.213908 -96.738182) (xy 171.159065 -96.728052) (xy 171.106281 -96.710045) (xy 171.056681 -96.684544)
			(xy 171.011323 -96.652093) (xy 170.971174 -96.613384) (xy 170.937088 -96.569241) (xy 170.909792 -96.520606)
			(xy 170.889869 -96.468515) (xy 170.877743 -96.414078) (xy 170.873672 -96.358456) (xy 163.025871 -96.358456)
			(xy 163.018814 -96.383073) (xy 163.01409 -96.425678) (xy 163.016589 -96.468471) (xy 163.026241 -96.510236)
			(xy 163.042771 -96.549787) (xy 163.065709 -96.586) (xy 163.094404 -96.617845) (xy 163.110926 -96.631506)
			(xy 163.132548 -96.649274) (xy 163.170855 -96.690073) (xy 163.20279 -96.73603) (xy 163.22767 -96.786159)
			(xy 163.24496 -96.839384) (xy 163.254289 -96.894565) (xy 163.255458 -96.950516) (xy 163.248441 -97.006038)
			(xy 163.23339 -97.059939) (xy 163.210625 -97.111064) (xy 163.180637 -97.158315) (xy 163.144069 -97.200678)
			(xy 163.101704 -97.237245) (xy 163.054452 -97.267232) (xy 163.003327 -97.289994) (xy 162.949425 -97.305044)
			(xy 162.893903 -97.312059) (xy 162.837952 -97.310888) (xy 162.782772 -97.301556) (xy 162.729547 -97.284265)
			(xy 162.679419 -97.259383) (xy 162.633463 -97.227446) (xy 162.592665 -97.189139) (xy 162.574986 -97.167446)
			(xy 162.559788 -97.149101) (xy 162.523795 -97.117903) (xy 162.48262 -97.093956) (xy 162.437705 -97.0781)
			(xy 162.390621 -97.070889) (xy 162.343019 -97.072577) (xy 162.296565 -97.083104) (xy 162.252885 -97.102101)
			(xy 162.213509 -97.128904) (xy 162.196272 -97.145348) (xy 161.918396 -97.423224) (xy 161.90205 -97.44032)
			(xy 161.875379 -97.479376) (xy 161.856387 -97.52269) (xy 161.845728 -97.568767) (xy 161.843769 -97.616021)
			(xy 161.850578 -97.662822) (xy 161.865921 -97.707559) (xy 161.889268 -97.748689) (xy 161.919815 -97.784795)
			(xy 161.956509 -97.814633) (xy 161.97707 -97.826322) (xy 162.001455 -97.840075) (xy 162.046272 -97.873625)
			(xy 162.085705 -97.913364) (xy 162.118908 -97.958439) (xy 162.145167 -98.007882) (xy 162.16392 -98.060631)
			(xy 162.174764 -98.115554) (xy 162.177465 -98.171473) (xy 162.171966 -98.227186) (xy 162.158385 -98.281497)
			(xy 162.137013 -98.33324) (xy 162.10831 -98.381306) (xy 162.072891 -98.424661) (xy 162.031517 -98.462374)
			(xy 161.985076 -98.493638) (xy 161.934565 -98.517779) (xy 161.881068 -98.53428) (xy 161.825735 -98.542787)
			(xy 161.797746 -98.543364) (xy 161.774592 -98.544036) (xy 161.729103 -98.552744) (xy 161.685946 -98.569553)
			(xy 161.646549 -98.593906) (xy 161.612219 -98.624995) (xy 161.584092 -98.661791) (xy 161.5631 -98.703076)
			(xy 161.549938 -98.747482) (xy 161.545042 -98.793538) (xy 161.546286 -98.816668) (xy 161.547875 -98.843789)
			(xy 161.544282 -98.897997) (xy 161.533033 -98.951146) (xy 161.514356 -99.002161) (xy 161.488629 -99.05001)
			(xy 161.456372 -99.093724) (xy 161.418239 -99.132418) (xy 161.375001 -99.16531) (xy 161.327533 -99.191733)
			(xy 161.276796 -99.211153) (xy 161.223817 -99.223177) (xy 161.196782 -99.225862) (xy 161.173227 -99.228299)
			(xy 161.127556 -99.240799) (xy 161.084991 -99.261543) (xy 161.047004 -99.28981) (xy 161.01491 -99.324625)
			(xy 160.989819 -99.364781) (xy 160.9726 -99.40889) (xy 160.963848 -99.455425) (xy 160.963356 -99.4791)
			(xy 160.963356 -102.037642) (xy 161.540444 -102.037642) (xy 161.562416 -102.020301) (xy 161.610451 -101.99157)
			(xy 161.662169 -101.970167) (xy 161.716459 -101.95655) (xy 161.772156 -101.951012) (xy 161.828065 -101.953673)
			(xy 161.882985 -101.964475) (xy 161.935737 -101.983186) (xy 161.985188 -102.009404) (xy 162.030278 -102.042567)
			(xy 162.070037 -102.081963) (xy 162.103614 -102.126745) (xy 162.130286 -102.175954) (xy 162.149481 -102.228531)
			(xy 162.160787 -102.283349) (xy 162.163962 -102.339231) (xy 162.158937 -102.394977) (xy 162.14582 -102.44939)
			(xy 162.124893 -102.501303) (xy 162.096605 -102.5496) (xy 162.061563 -102.593245) (xy 162.020519 -102.631302)
			(xy 161.974355 -102.662952) (xy 161.924062 -102.687517) (xy 161.870719 -102.70447) (xy 161.815472 -102.713445)
			(xy 161.759505 -102.714252) (xy 161.731706 -102.710996) (xy 161.56559 -102.710996) (xy 160.963356 -103.31323)
			(xy 160.963356 -103.907336) (xy 160.963877 -103.923785) (xy 160.972298 -103.955587) (xy 160.98857 -103.984179)
			(xy 161.011611 -104.00766) (xy 161.039891 -104.024469) (xy 161.055558 -104.02951) (xy 161.083937 -104.038229)
			(xy 161.137781 -104.063228) (xy 161.162746 -104.079294) (xy 161.181844 -104.091499) (xy 161.223365 -104.10966)
			(xy 161.267448 -104.120169) (xy 161.312696 -104.122695) (xy 161.357675 -104.117156) (xy 161.400959 -104.103728)
			(xy 161.441175 -104.082838) (xy 161.459418 -104.069388) (xy 161.48181 -104.052689) (xy 161.530508 -104.025328)
			(xy 161.582675 -104.00536) (xy 161.637196 -103.993213) (xy 161.692906 -103.989145) (xy 161.748613 -103.993244)
			(xy 161.803127 -104.005421) (xy 161.846081 -104.02189) (xy 163.915344 -104.02189) (xy 163.915344 -97.960688)
			(xy 164.231066 -97.644966) (xy 168.472104 -97.644966) (xy 168.547542 -97.67951) (xy 168.547796 -97.67951)
			(xy 168.580956 -97.694138) (xy 168.649611 -97.717376) (xy 168.720273 -97.733512) (xy 168.79221 -97.742378)
			(xy 168.864675 -97.743882) (xy 168.936918 -97.73801) (xy 169.008189 -97.724821) (xy 169.043096 -97.71507)
			(xy 169.078012 -97.724861) (xy 169.149322 -97.73806) (xy 169.221604 -97.743938) (xy 169.294109 -97.742433)
			(xy 169.366086 -97.733561) (xy 169.436786 -97.717414) (xy 169.505478 -97.69416) (xy 169.53865 -97.67951)
			(xy 169.538904 -97.67951) (xy 169.614342 -97.644966) (xy 170.355006 -97.644966) (xy 170.55592 -97.846134)
			(xy 170.55592 -104.032558) (xy 170.313604 -104.274874) (xy 164.168582 -104.274874) (xy 163.915344 -104.02189)
			(xy 161.846081 -104.02189) (xy 161.855283 -104.025418) (xy 161.903966 -104.052806) (xy 161.948135 -104.086999)
			(xy 161.986846 -104.127268) (xy 162.019272 -104.172751) (xy 162.044719 -104.222475) (xy 162.062644 -104.275379)
			(xy 162.072663 -104.330331) (xy 162.074562 -104.386157) (xy 162.068301 -104.441663) (xy 162.054014 -104.495662)
			(xy 162.032005 -104.547002) (xy 162.002745 -104.594583) (xy 161.966861 -104.63739) (xy 161.925118 -104.674506)
			(xy 161.878409 -104.705139) (xy 161.827733 -104.728634) (xy 161.774172 -104.744489) (xy 161.718872 -104.752365)
			(xy 161.663015 -104.752092) (xy 161.607794 -104.743678) (xy 161.554391 -104.727303) (xy 161.503946 -104.703315)
			(xy 161.4805 -104.688132) (xy 161.461402 -104.675922) (xy 161.41988 -104.657751) (xy 161.375794 -104.647233)
			(xy 161.33054 -104.6447) (xy 161.285555 -104.650233) (xy 161.242265 -104.663657) (xy 161.202042 -104.684546)
			(xy 161.183828 -104.698038) (xy 161.16449 -104.712526) (xy 161.122841 -104.737023) (xy 161.078429 -104.756057)
			(xy 161.055304 -104.763062) (xy 161.039645 -104.768082) (xy 161.011408 -104.784913) (xy 160.988419 -104.808409)
			(xy 160.972208 -104.837006) (xy 160.963854 -104.868799) (xy 160.963356 -104.885236) (xy 160.963356 -105.686098)
			(xy 161.903918 -106.62666)
		)
		(stroke
			(width 0)
			(type solid)
		)
		(fill yes)
		(layer "In2.Cu")
		(net "P1V05_NODE1")
	)
	(gr_poly
		(pts
			(xy 137.259314 -118.10746) (xy 137.281559 -118.106999) (xy 137.325368 -118.099251) (xy 137.36716 -118.083995)
			(xy 137.405658 -118.061696) (xy 137.439686 -118.033035) (xy 137.468204 -117.998888) (xy 137.490342 -117.960298)
			(xy 137.505424 -117.918443) (xy 137.512989 -117.874601) (xy 137.512806 -117.830112) (xy 137.504881 -117.786334)
			(xy 137.497566 -117.765322) (xy 137.488601 -117.739637) (xy 137.477207 -117.686442) (xy 137.473486 -117.632168)
			(xy 137.477512 -117.577916) (xy 137.489205 -117.524787) (xy 137.508327 -117.473857) (xy 137.53449 -117.42616)
			(xy 137.567164 -117.382664) (xy 137.605685 -117.344251) (xy 137.649273 -117.311699) (xy 137.697043 -117.28567)
			(xy 137.748027 -117.266692) (xy 137.801189 -117.255148) (xy 137.855452 -117.251274) (xy 137.909715 -117.255148)
			(xy 137.962877 -117.266692) (xy 138.013861 -117.28567) (xy 138.061631 -117.311699) (xy 138.105219 -117.344251)
			(xy 138.14374 -117.382664) (xy 138.176414 -117.42616) (xy 138.183141 -117.438424) (xy 138.718034 -117.438424)
			(xy 138.722105 -117.382802) (xy 138.734231 -117.328365) (xy 138.754154 -117.276274) (xy 138.78145 -117.227639)
			(xy 138.815536 -117.183496) (xy 138.855685 -117.144787) (xy 138.901043 -117.112336) (xy 138.950643 -117.086835)
			(xy 139.003427 -117.068828) (xy 139.05827 -117.058698) (xy 139.114004 -117.056661) (xy 139.169441 -117.062761)
			(xy 139.223398 -117.076867) (xy 139.274727 -117.098679) (xy 139.322333 -117.127733) (xy 139.365201 -117.163408)
			(xy 139.402418 -117.204945) (xy 139.433191 -117.251458) (xy 139.456863 -117.301955) (xy 139.472931 -117.355362)
			(xy 139.481051 -117.410538) (xy 139.48156 -117.438424) (xy 139.481051 -117.46631) (xy 139.472931 -117.521486)
			(xy 139.456863 -117.574893) (xy 139.433191 -117.62539) (xy 139.402418 -117.671903) (xy 139.365201 -117.71344)
			(xy 139.322333 -117.749115) (xy 139.274727 -117.778169) (xy 139.223398 -117.799981) (xy 139.169441 -117.814087)
			(xy 139.114004 -117.820187) (xy 139.05827 -117.81815) (xy 139.003427 -117.80802) (xy 138.950643 -117.790013)
			(xy 138.901043 -117.764512) (xy 138.855685 -117.732061) (xy 138.815536 -117.693352) (xy 138.78145 -117.649209)
			(xy 138.754154 -117.600574) (xy 138.734231 -117.548483) (xy 138.722105 -117.494046) (xy 138.718034 -117.438424)
			(xy 138.183141 -117.438424) (xy 138.202577 -117.473857) (xy 138.221699 -117.524787) (xy 138.233392 -117.577916)
			(xy 138.237418 -117.632168) (xy 138.233697 -117.686442) (xy 138.222303 -117.739637) (xy 138.213338 -117.765322)
			(xy 138.206046 -117.786345) (xy 138.198101 -117.830123) (xy 138.197903 -117.874616) (xy 138.205457 -117.918464)
			(xy 138.220533 -117.960325) (xy 138.242669 -117.998921) (xy 138.27119 -118.033071) (xy 138.305223 -118.061732)
			(xy 138.343728 -118.084027) (xy 138.385527 -118.099275) (xy 138.429343 -118.107009) (xy 138.45159 -118.10746)
			(xy 143.329152 -118.10746) (xy 144.15516 -117.281452) (xy 144.15516 -113.79962) (xy 138.90498 -108.54944)
			(xy 138.90498 -108.312204) (xy 138.904481 -108.295521) (xy 138.895823 -108.263297) (xy 138.879101 -108.234424)
			(xy 138.867642 -108.222288) (xy 138.76782 -108.12272) (xy 138.76782 -106.677206) (xy 138.694668 -106.604054)
			(xy 138.694668 -104.2543) (xy 138.38682 -103.946452) (xy 133.2484 -103.946452) (xy 133.231749 -103.946995)
			(xy 133.199582 -103.955612) (xy 133.17074 -103.972259) (xy 133.147188 -103.995802) (xy 133.130531 -104.024638)
			(xy 133.121901 -104.056802) (xy 133.1214 -104.073452) (xy 133.1214 -106.559926) (xy 134.215226 -106.559926)
			(xy 134.217475 -106.504162) (xy 134.227823 -106.44932) (xy 134.246051 -106.39657) (xy 134.271769 -106.347039)
			(xy 134.304428 -106.301783) (xy 134.343331 -106.261767) (xy 134.387649 -106.227845) (xy 134.436436 -106.200742)
			(xy 134.488651 -106.181035) (xy 134.543179 -106.169144) (xy 134.598858 -106.165324) (xy 134.6545 -106.169656)
			(xy 134.708917 -106.182048) (xy 134.760948 -106.202235) (xy 134.809483 -106.229786) (xy 134.853487 -106.264114)
			(xy 134.89202 -106.304487) (xy 134.924261 -106.350042) (xy 134.949522 -106.399807) (xy 134.967264 -106.452722)
			(xy 134.977107 -106.507657) (xy 134.978843 -106.56344) (xy 134.972434 -106.618881) (xy 134.965694 -106.645964)
			(xy 134.96035 -106.66793) (xy 134.956602 -106.712976) (xy 134.960872 -106.757976) (xy 134.973026 -106.801513)
			(xy 134.992683 -106.842217) (xy 135.019222 -106.878808) (xy 135.051809 -106.910133) (xy 135.070342 -106.923078)
			(xy 135.093302 -106.938945) (xy 135.134746 -106.976326) (xy 135.170301 -107.019345) (xy 135.19921 -107.067085)
			(xy 135.220857 -107.118527) (xy 135.234778 -107.172573) (xy 135.240677 -107.228071) (xy 135.238428 -107.283837)
			(xy 135.228079 -107.33868) (xy 135.209852 -107.39143) (xy 135.184133 -107.440962) (xy 135.151474 -107.486219)
			(xy 135.11257 -107.526236) (xy 135.068251 -107.560158) (xy 135.019464 -107.587261) (xy 134.967248 -107.606969)
			(xy 134.912718 -107.618859) (xy 134.857038 -107.622678) (xy 134.801396 -107.618346) (xy 134.746979 -107.605953)
			(xy 134.694947 -107.585765) (xy 134.646411 -107.558213) (xy 134.602407 -107.523884) (xy 134.563874 -107.48351)
			(xy 134.531633 -107.437954) (xy 134.506373 -107.388187) (xy 134.488632 -107.335271) (xy 134.478789 -107.280335)
			(xy 134.477055 -107.224551) (xy 134.483465 -107.169109) (xy 134.490206 -107.142026) (xy 134.495559 -107.120062)
			(xy 134.499306 -107.075015) (xy 134.495035 -107.030015) (xy 134.482879 -106.986477) (xy 134.463221 -106.945773)
			(xy 134.43668 -106.909182) (xy 134.404092 -106.877857) (xy 134.385558 -106.864912) (xy 134.362595 -106.84905)
			(xy 134.321153 -106.811669) (xy 134.285598 -106.76865) (xy 134.25669 -106.720911) (xy 134.235045 -106.669469)
			(xy 134.221124 -106.615423) (xy 134.215226 -106.559926) (xy 133.1214 -106.559926) (xy 133.1214 -109.210856)
			(xy 133.121899 -109.233486) (xy 133.129919 -109.278029) (xy 133.145696 -109.320449) (xy 133.168731 -109.359408)
			(xy 133.198298 -109.393675) (xy 133.233463 -109.422167) (xy 133.273116 -109.443987) (xy 133.316005 -109.458444)
			(xy 133.360775 -109.465082) (xy 133.406013 -109.463691) (xy 133.45029 -109.454317) (xy 133.49221 -109.437253)
			(xy 133.511544 -109.425486) (xy 133.533151 -109.41226) (xy 133.579137 -109.391004) (xy 133.627528 -109.37601)
			(xy 133.677475 -109.367542) (xy 133.728104 -109.365749) (xy 133.753352 -109.367828) (xy 133.777053 -109.36966)
			(xy 133.824402 -109.365505) (xy 133.870151 -109.352611) (xy 133.9127 -109.331427) (xy 133.950563 -109.302694)
			(xy 133.982417 -109.267416) (xy 134.007149 -109.226826) (xy 134.015988 -109.20476) (xy 134.026173 -109.179093)
			(xy 134.052874 -109.130758) (xy 134.086263 -109.086776) (xy 134.125644 -109.048067) (xy 134.170192 -109.015439)
			(xy 134.218979 -108.989572) (xy 134.270985 -108.971008) (xy 134.325123 -108.960134) (xy 134.380263 -108.957177)
			(xy 134.435254 -108.962199) (xy 134.488947 -108.975095) (xy 134.54022 -108.995596) (xy 134.588003 -109.023273)
			(xy 134.631297 -109.057549) (xy 134.669198 -109.097707) (xy 134.700915 -109.142909) (xy 134.725786 -109.192211)
			(xy 134.735062 -109.218222) (xy 134.742813 -109.239822) (xy 134.764955 -109.280015) (xy 134.793949 -109.315583)
			(xy 134.828853 -109.345372) (xy 134.868535 -109.368416) (xy 134.911707 -109.383967) (xy 134.956969 -109.391521)
			(xy 134.979918 -109.391704) (xy 135.007948 -109.391773) (xy 135.063515 -109.399133) (xy 135.117407 -109.414544)
			(xy 135.168464 -109.437673) (xy 135.215588 -109.468024) (xy 135.257764 -109.504942) (xy 135.294085 -109.547635)
			(xy 135.323769 -109.595181) (xy 135.346177 -109.64656) (xy 135.360826 -109.700663) (xy 135.361745 -109.708442)
			(xy 135.873742 -109.708442) (xy 135.877813 -109.65282) (xy 135.889939 -109.598383) (xy 135.909862 -109.546292)
			(xy 135.937158 -109.497657) (xy 135.971244 -109.453514) (xy 136.011393 -109.414805) (xy 136.056751 -109.382354)
			(xy 136.106351 -109.356853) (xy 136.159135 -109.338846) (xy 136.213978 -109.328716) (xy 136.269712 -109.326679)
			(xy 136.325149 -109.332779) (xy 136.379106 -109.346885) (xy 136.430435 -109.368697) (xy 136.478041 -109.397751)
			(xy 136.520909 -109.433426) (xy 136.558126 -109.474963) (xy 136.588899 -109.521476) (xy 136.612571 -109.571973)
			(xy 136.628639 -109.62538) (xy 136.635779 -109.673898) (xy 137.143742 -109.673898) (xy 137.147813 -109.618276)
			(xy 137.159939 -109.563839) (xy 137.179862 -109.511748) (xy 137.207158 -109.463113) (xy 137.241244 -109.41897)
			(xy 137.281393 -109.380261) (xy 137.326751 -109.34781) (xy 137.376351 -109.322309) (xy 137.429135 -109.304302)
			(xy 137.483978 -109.294172) (xy 137.539712 -109.292135) (xy 137.595149 -109.298235) (xy 137.649106 -109.312341)
			(xy 137.700435 -109.334153) (xy 137.748041 -109.363207) (xy 137.790909 -109.398882) (xy 137.828126 -109.440419)
			(xy 137.858899 -109.486932) (xy 137.882571 -109.537429) (xy 137.898639 -109.590836) (xy 137.906759 -109.646012)
			(xy 137.907268 -109.673898) (xy 137.906759 -109.701784) (xy 137.898639 -109.75696) (xy 137.882571 -109.810367)
			(xy 137.858899 -109.860864) (xy 137.828126 -109.907377) (xy 137.790909 -109.948914) (xy 137.748041 -109.984589)
			(xy 137.700435 -110.013643) (xy 137.649106 -110.035455) (xy 137.595149 -110.049561) (xy 137.539712 -110.055661)
			(xy 137.483978 -110.053624) (xy 137.429135 -110.043494) (xy 137.376351 -110.025487) (xy 137.326751 -109.999986)
			(xy 137.281393 -109.967535) (xy 137.241244 -109.928826) (xy 137.207158 -109.884683) (xy 137.179862 -109.836048)
			(xy 137.159939 -109.783957) (xy 137.147813 -109.72952) (xy 137.143742 -109.673898) (xy 136.635779 -109.673898)
			(xy 136.636759 -109.680556) (xy 136.637268 -109.708442) (xy 136.636759 -109.736328) (xy 136.628639 -109.791504)
			(xy 136.612571 -109.844911) (xy 136.588899 -109.895408) (xy 136.558126 -109.941921) (xy 136.520909 -109.983458)
			(xy 136.478041 -110.019133) (xy 136.430435 -110.048187) (xy 136.379106 -110.069999) (xy 136.325149 -110.084105)
			(xy 136.269712 -110.090205) (xy 136.213978 -110.088168) (xy 136.159135 -110.078038) (xy 136.106351 -110.060031)
			(xy 136.056751 -110.03453) (xy 136.011393 -110.002079) (xy 135.971244 -109.96337) (xy 135.937158 -109.919227)
			(xy 135.909862 -109.870592) (xy 135.889939 -109.818501) (xy 135.877813 -109.764064) (xy 135.873742 -109.708442)
			(xy 135.361745 -109.708442) (xy 135.367402 -109.756328) (xy 135.365763 -109.812356) (xy 135.355944 -109.867542)
			(xy 135.338157 -109.920696) (xy 135.312784 -109.970677) (xy 135.280372 -110.016407) (xy 135.241617 -110.056903)
			(xy 135.197355 -110.091293) (xy 135.148538 -110.118837) (xy 135.096215 -110.138942) (xy 135.041515 -110.151176)
			(xy 134.985613 -110.155275) (xy 134.929713 -110.151151) (xy 134.875018 -110.138892) (xy 134.822705 -110.118763)
			(xy 134.7739 -110.091197) (xy 134.729653 -110.056786) (xy 134.690917 -110.016273) (xy 134.658526 -109.970528)
			(xy 134.633176 -109.920536) (xy 134.62381 -109.894116) (xy 134.616056 -109.872516) (xy 134.59391 -109.832326)
			(xy 134.564916 -109.796758) (xy 134.530013 -109.766967) (xy 134.490333 -109.743919) (xy 134.447163 -109.72836)
			(xy 134.401903 -109.720797) (xy 134.378954 -109.720634) (xy 134.36808 -109.72073) (xy 134.34635 -109.719838)
			(xy 134.33552 -109.718856) (xy 134.31182 -109.717027) (xy 134.264474 -109.721186) (xy 134.218729 -109.734083)
			(xy 134.176183 -109.755268) (xy 134.138322 -109.784001) (xy 134.106471 -109.819278) (xy 134.08174 -109.859866)
			(xy 134.072884 -109.881924) (xy 134.062423 -109.908281) (xy 134.034833 -109.957822) (xy 134.000215 -110.002733)
			(xy 133.959329 -110.042025) (xy 133.913078 -110.074831) (xy 133.86248 -110.10043) (xy 133.80865 -110.118257)
			(xy 133.752775 -110.127919) (xy 133.696084 -110.129203) (xy 133.639828 -110.122082) (xy 133.585246 -110.106712)
			(xy 133.533541 -110.083431) (xy 133.485851 -110.052753) (xy 133.443228 -110.015353) (xy 133.406611 -109.972056)
			(xy 133.376806 -109.923816) (xy 133.36524 -109.897926) (xy 133.359035 -109.884438) (xy 133.341363 -109.860589)
			(xy 133.31865 -109.841481) (xy 133.292129 -109.82815) (xy 133.263242 -109.821323) (xy 133.2484 -109.820964)
			(xy 133.23175 -109.821507) (xy 133.199584 -109.830124) (xy 133.170744 -109.846772) (xy 133.147194 -109.870315)
			(xy 133.130538 -109.899151) (xy 133.121912 -109.931314) (xy 133.1214 -109.947964) (xy 133.1214 -110.1852)
			(xy 132.785612 -110.520988) (xy 132.774168 -110.533105) (xy 132.757484 -110.561945) (xy 132.748844 -110.594124)
			(xy 132.74884 -110.627443) (xy 132.757471 -110.659624) (xy 132.774148 -110.688469) (xy 132.785612 -110.700566)
			(xy 133.074156 -110.988856) (xy 133.10743 -110.997492) (xy 133.134084 -111.004932) (xy 133.185068 -111.026448)
			(xy 133.232409 -111.055103) (xy 133.275114 -111.090296) (xy 133.312289 -111.131288) (xy 133.343152 -111.177219)
			(xy 133.367057 -111.227128) (xy 133.383502 -111.279965) (xy 133.392142 -111.334624) (xy 133.392797 -111.389958)
			(xy 133.385452 -111.444806) (xy 133.370262 -111.498019) (xy 133.347544 -111.548478) (xy 133.317777 -111.595128)
			(xy 133.281583 -111.636988) (xy 133.239722 -111.673181) (xy 133.193072 -111.702948) (xy 133.142612 -111.725664)
			(xy 133.089399 -111.740854) (xy 133.034551 -111.748197) (xy 132.979217 -111.747542) (xy 132.924558 -111.7389)
			(xy 132.871721 -111.722454) (xy 132.821813 -111.698548) (xy 132.775882 -111.667684) (xy 132.734891 -111.630509)
			(xy 132.699699 -111.587803) (xy 132.671045 -111.540462) (xy 132.64953 -111.489478) (xy 132.642102 -111.46282)
			(xy 132.633466 -111.429546) (xy 131.801108 -110.597188) (xy 131.158996 -110.597188) (xy 131.137914 -110.604808)
			(xy 131.112841 -110.613393) (xy 131.060989 -110.624348) (xy 131.00812 -110.628023) (xy 130.955251 -110.624348)
			(xy 130.903399 -110.613393) (xy 130.878326 -110.604808) (xy 130.857244 -110.597188) (xy 128.264412 -110.597188)
			(xy 128.242911 -110.597646) (xy 128.200524 -110.604898) (xy 128.159963 -110.619182) (xy 128.122385 -110.640089)
			(xy 128.088862 -110.667023) (xy 128.060351 -110.699215) (xy 128.037665 -110.735746) (xy 128.021452 -110.775575)
			(xy 128.012174 -110.817565) (xy 128.010095 -110.860517) (xy 128.01219 -110.881922) (xy 128.015098 -110.909861)
			(xy 128.013655 -110.966013) (xy 128.003995 -111.021347) (xy 127.986326 -111.074666) (xy 127.96103 -111.124818)
			(xy 127.928654 -111.170719) (xy 127.889897 -111.211378) (xy 127.845599 -111.245914) (xy 127.796715 -111.273582)
			(xy 127.744302 -111.293783) (xy 127.689495 -111.306081) (xy 127.633476 -111.31021) (xy 127.577457 -111.306081)
			(xy 127.52265 -111.293783) (xy 127.470237 -111.273582) (xy 127.421353 -111.245914) (xy 127.377055 -111.211378)
			(xy 127.338298 -111.170719) (xy 127.305922 -111.124818) (xy 127.280626 -111.074666) (xy 127.262957 -111.021347)
			(xy 127.253297 -110.966013) (xy 127.251854 -110.909861) (xy 127.254762 -110.881922) (xy 127.256924 -110.860516)
			(xy 127.254876 -110.817544) (xy 127.245616 -110.775531) (xy 127.229409 -110.73568) (xy 127.206718 -110.699129)
			(xy 127.178194 -110.666925) (xy 127.14465 -110.639987) (xy 127.107048 -110.619087) (xy 127.066461 -110.604821)
			(xy 127.024051 -110.597599) (xy 127.00254 -110.597188) (xy 125.671326 -110.597188) (xy 125.18644 -111.082074)
			(xy 125.18644 -111.82731) (xy 126.063754 -111.82731) (xy 126.067825 -111.771688) (xy 126.079951 -111.717251)
			(xy 126.099874 -111.66516) (xy 126.12717 -111.616525) (xy 126.161256 -111.572382) (xy 126.201405 -111.533673)
			(xy 126.246763 -111.501222) (xy 126.296363 -111.475721) (xy 126.349147 -111.457714) (xy 126.40399 -111.447584)
			(xy 126.459724 -111.445547) (xy 126.515161 -111.451647) (xy 126.569118 -111.465753) (xy 126.620447 -111.487565)
			(xy 126.668053 -111.516619) (xy 126.710921 -111.552294) (xy 126.748138 -111.593831) (xy 126.778911 -111.640344)
			(xy 126.796425 -111.677704) (xy 131.171948 -111.677704) (xy 131.176019 -111.622082) (xy 131.188145 -111.567645)
			(xy 131.208068 -111.515554) (xy 131.235364 -111.466919) (xy 131.26945 -111.422776) (xy 131.309599 -111.384067)
			(xy 131.354957 -111.351616) (xy 131.404557 -111.326115) (xy 131.457341 -111.308108) (xy 131.512184 -111.297978)
			(xy 131.567918 -111.295941) (xy 131.623355 -111.302041) (xy 131.677312 -111.316147) (xy 131.728641 -111.337959)
			(xy 131.776247 -111.367013) (xy 131.819115 -111.402688) (xy 131.856332 -111.444225) (xy 131.887105 -111.490738)
			(xy 131.910777 -111.541235) (xy 131.926845 -111.594642) (xy 131.934965 -111.649818) (xy 131.935474 -111.677704)
			(xy 131.934965 -111.70559) (xy 131.926845 -111.760766) (xy 131.910777 -111.814173) (xy 131.910453 -111.814864)
			(xy 134.229854 -111.814864) (xy 134.233925 -111.759242) (xy 134.246051 -111.704805) (xy 134.265974 -111.652714)
			(xy 134.29327 -111.604079) (xy 134.327356 -111.559936) (xy 134.367505 -111.521227) (xy 134.412863 -111.488776)
			(xy 134.462463 -111.463275) (xy 134.515247 -111.445268) (xy 134.57009 -111.435138) (xy 134.625824 -111.433101)
			(xy 134.681261 -111.439201) (xy 134.735218 -111.453307) (xy 134.786547 -111.475119) (xy 134.834153 -111.504173)
			(xy 134.877021 -111.539848) (xy 134.914238 -111.581385) (xy 134.945011 -111.627898) (xy 134.968683 -111.678395)
			(xy 134.984751 -111.731802) (xy 134.992871 -111.786978) (xy 134.99338 -111.814864) (xy 134.992871 -111.84275)
			(xy 134.989574 -111.865156) (xy 135.59739 -111.865156) (xy 135.601461 -111.809534) (xy 135.613587 -111.755097)
			(xy 135.63351 -111.703006) (xy 135.660806 -111.654371) (xy 135.694892 -111.610228) (xy 135.735041 -111.571519)
			(xy 135.780399 -111.539068) (xy 135.829999 -111.513567) (xy 135.882783 -111.49556) (xy 135.937626 -111.48543)
			(xy 135.99336 -111.483393) (xy 136.048797 -111.489493) (xy 136.102754 -111.503599) (xy 136.154083 -111.525411)
			(xy 136.201689 -111.554465) (xy 136.244557 -111.59014) (xy 136.281774 -111.631677) (xy 136.312547 -111.67819)
			(xy 136.336219 -111.728687) (xy 136.352287 -111.782094) (xy 136.360407 -111.83727) (xy 136.360916 -111.865156)
			(xy 136.360407 -111.893042) (xy 136.352287 -111.948218) (xy 136.336219 -112.001625) (xy 136.312547 -112.052122)
			(xy 136.281774 -112.098635) (xy 136.244557 -112.140172) (xy 136.201689 -112.175847) (xy 136.154083 -112.204901)
			(xy 136.102754 -112.226713) (xy 136.048797 -112.240819) (xy 135.99336 -112.246919) (xy 135.937626 -112.244882)
			(xy 135.882783 -112.234752) (xy 135.829999 -112.216745) (xy 135.780399 -112.191244) (xy 135.735041 -112.158793)
			(xy 135.694892 -112.120084) (xy 135.660806 -112.075941) (xy 135.63351 -112.027306) (xy 135.613587 -111.975215)
			(xy 135.601461 -111.920778) (xy 135.59739 -111.865156) (xy 134.989574 -111.865156) (xy 134.984751 -111.897926)
			(xy 134.968683 -111.951333) (xy 134.945011 -112.00183) (xy 134.914238 -112.048343) (xy 134.877021 -112.08988)
			(xy 134.834153 -112.125555) (xy 134.786547 -112.154609) (xy 134.735218 -112.176421) (xy 134.681261 -112.190527)
			(xy 134.625824 -112.196627) (xy 134.57009 -112.19459) (xy 134.515247 -112.18446) (xy 134.462463 -112.166453)
			(xy 134.412863 -112.140952) (xy 134.367505 -112.108501) (xy 134.327356 -112.069792) (xy 134.29327 -112.025649)
			(xy 134.265974 -111.977014) (xy 134.246051 -111.924923) (xy 134.233925 -111.870486) (xy 134.229854 -111.814864)
			(xy 131.910453 -111.814864) (xy 131.887105 -111.86467) (xy 131.856332 -111.911183) (xy 131.819115 -111.95272)
			(xy 131.776247 -111.988395) (xy 131.728641 -112.017449) (xy 131.677312 -112.039261) (xy 131.623355 -112.053367)
			(xy 131.567918 -112.059467) (xy 131.512184 -112.05743) (xy 131.457341 -112.0473) (xy 131.404557 -112.029293)
			(xy 131.354957 -112.003792) (xy 131.309599 -111.971341) (xy 131.26945 -111.932632) (xy 131.235364 -111.888489)
			(xy 131.208068 -111.839854) (xy 131.188145 -111.787763) (xy 131.176019 -111.733326) (xy 131.171948 -111.677704)
			(xy 126.796425 -111.677704) (xy 126.802583 -111.690841) (xy 126.818651 -111.744248) (xy 126.826771 -111.799424)
			(xy 126.82728 -111.82731) (xy 126.826771 -111.855196) (xy 126.818651 -111.910372) (xy 126.802583 -111.963779)
			(xy 126.778911 -112.014276) (xy 126.748138 -112.060789) (xy 126.710921 -112.102326) (xy 126.668053 -112.138001)
			(xy 126.620447 -112.167055) (xy 126.569118 -112.188867) (xy 126.515161 -112.202973) (xy 126.459724 -112.209073)
			(xy 126.40399 -112.207036) (xy 126.349147 -112.196906) (xy 126.296363 -112.178899) (xy 126.246763 -112.153398)
			(xy 126.201405 -112.120947) (xy 126.161256 -112.082238) (xy 126.12717 -112.038095) (xy 126.099874 -111.98946)
			(xy 126.079951 -111.937369) (xy 126.067825 -111.882932) (xy 126.063754 -111.82731) (xy 125.18644 -111.82731)
			(xy 125.18644 -112.694466) (xy 129.8862 -112.694466) (xy 129.890271 -112.638844) (xy 129.902397 -112.584407)
			(xy 129.92232 -112.532316) (xy 129.949616 -112.483681) (xy 129.983702 -112.439538) (xy 130.023851 -112.400829)
			(xy 130.069209 -112.368378) (xy 130.118809 -112.342877) (xy 130.171593 -112.32487) (xy 130.226436 -112.31474)
			(xy 130.28217 -112.312703) (xy 130.337607 -112.318803) (xy 130.391564 -112.332909) (xy 130.442893 -112.354721)
			(xy 130.490499 -112.383775) (xy 130.533367 -112.41945) (xy 130.570584 -112.460987) (xy 130.601357 -112.5075)
			(xy 130.625029 -112.557997) (xy 130.641097 -112.611404) (xy 130.649217 -112.66658) (xy 130.649726 -112.694466)
			(xy 130.649217 -112.722352) (xy 130.641097 -112.777528) (xy 130.625029 -112.830935) (xy 130.612322 -112.858042)
			(xy 134.247634 -112.858042) (xy 134.251705 -112.80242) (xy 134.263831 -112.747983) (xy 134.283754 -112.695892)
			(xy 134.31105 -112.647257) (xy 134.345136 -112.603114) (xy 134.385285 -112.564405) (xy 134.430643 -112.531954)
			(xy 134.480243 -112.506453) (xy 134.533027 -112.488446) (xy 134.58787 -112.478316) (xy 134.643604 -112.476279)
			(xy 134.699041 -112.482379) (xy 134.752998 -112.496485) (xy 134.804327 -112.518297) (xy 134.807897 -112.520476)
			(xy 136.813796 -112.520476) (xy 136.817867 -112.464854) (xy 136.829993 -112.410417) (xy 136.849916 -112.358326)
			(xy 136.877212 -112.309691) (xy 136.911298 -112.265548) (xy 136.951447 -112.226839) (xy 136.996805 -112.194388)
			(xy 137.046405 -112.168887) (xy 137.099189 -112.15088) (xy 137.154032 -112.14075) (xy 137.209766 -112.138713)
			(xy 137.265203 -112.144813) (xy 137.31916 -112.158919) (xy 137.370489 -112.180731) (xy 137.418095 -112.209785)
			(xy 137.460963 -112.24546) (xy 137.49818 -112.286997) (xy 137.528953 -112.33351) (xy 137.552625 -112.384007)
			(xy 137.568693 -112.437414) (xy 137.576813 -112.49259) (xy 137.577322 -112.520476) (xy 137.577252 -112.524286)
			(xy 141.085568 -112.524286) (xy 141.089639 -112.468664) (xy 141.101765 -112.414227) (xy 141.121688 -112.362136)
			(xy 141.148984 -112.313501) (xy 141.18307 -112.269358) (xy 141.223219 -112.230649) (xy 141.268577 -112.198198)
			(xy 141.318177 -112.172697) (xy 141.370961 -112.15469) (xy 141.425804 -112.14456) (xy 141.481538 -112.142523)
			(xy 141.536975 -112.148623) (xy 141.590932 -112.162729) (xy 141.642261 -112.184541) (xy 141.689867 -112.213595)
			(xy 141.732735 -112.24927) (xy 141.769952 -112.290807) (xy 141.800725 -112.33732) (xy 141.824397 -112.387817)
			(xy 141.840465 -112.441224) (xy 141.848585 -112.4964) (xy 141.849094 -112.524286) (xy 141.848585 -112.552172)
			(xy 141.840465 -112.607348) (xy 141.824397 -112.660755) (xy 141.800725 -112.711252) (xy 141.769952 -112.757765)
			(xy 141.732735 -112.799302) (xy 141.689867 -112.834977) (xy 141.642261 -112.864031) (xy 141.590932 -112.885843)
			(xy 141.536975 -112.899949) (xy 141.481538 -112.906049) (xy 141.425804 -112.904012) (xy 141.370961 -112.893882)
			(xy 141.318177 -112.875875) (xy 141.268577 -112.850374) (xy 141.223219 -112.817923) (xy 141.18307 -112.779214)
			(xy 141.148984 -112.735071) (xy 141.121688 -112.686436) (xy 141.101765 -112.634345) (xy 141.089639 -112.579908)
			(xy 141.085568 -112.524286) (xy 137.577252 -112.524286) (xy 137.576813 -112.548362) (xy 137.568693 -112.603538)
			(xy 137.552625 -112.656945) (xy 137.528953 -112.707442) (xy 137.49818 -112.753955) (xy 137.460963 -112.795492)
			(xy 137.418095 -112.831167) (xy 137.370489 -112.860221) (xy 137.31916 -112.882033) (xy 137.265203 -112.896139)
			(xy 137.209766 -112.902239) (xy 137.154032 -112.900202) (xy 137.099189 -112.890072) (xy 137.046405 -112.872065)
			(xy 136.996805 -112.846564) (xy 136.951447 -112.814113) (xy 136.911298 -112.775404) (xy 136.877212 -112.731261)
			(xy 136.849916 -112.682626) (xy 136.829993 -112.630535) (xy 136.817867 -112.576098) (xy 136.813796 -112.520476)
			(xy 134.807897 -112.520476) (xy 134.851933 -112.547351) (xy 134.894801 -112.583026) (xy 134.932018 -112.624563)
			(xy 134.962791 -112.671076) (xy 134.986463 -112.721573) (xy 135.002531 -112.77498) (xy 135.010651 -112.830156)
			(xy 135.01116 -112.858042) (xy 135.010651 -112.885928) (xy 135.002531 -112.941104) (xy 134.986463 -112.994511)
			(xy 134.962791 -113.045008) (xy 134.954739 -113.057178) (xy 138.399518 -113.057178) (xy 138.403589 -113.001556)
			(xy 138.415715 -112.947119) (xy 138.435638 -112.895028) (xy 138.462934 -112.846393) (xy 138.49702 -112.80225)
			(xy 138.537169 -112.763541) (xy 138.582527 -112.73109) (xy 138.632127 -112.705589) (xy 138.684911 -112.687582)
			(xy 138.739754 -112.677452) (xy 138.795488 -112.675415) (xy 138.850925 -112.681515) (xy 138.904882 -112.695621)
			(xy 138.956211 -112.717433) (xy 139.003817 -112.746487) (xy 139.046685 -112.782162) (xy 139.083902 -112.823699)
			(xy 139.114675 -112.870212) (xy 139.138347 -112.920709) (xy 139.154415 -112.974116) (xy 139.162535 -113.029292)
			(xy 139.163044 -113.057178) (xy 139.162535 -113.085064) (xy 139.154415 -113.14024) (xy 139.138347 -113.193647)
			(xy 139.121115 -113.230406) (xy 139.607542 -113.230406) (xy 139.611613 -113.174784) (xy 139.623739 -113.120347)
			(xy 139.643662 -113.068256) (xy 139.670958 -113.019621) (xy 139.705044 -112.975478) (xy 139.745193 -112.936769)
			(xy 139.790551 -112.904318) (xy 139.840151 -112.878817) (xy 139.892935 -112.86081) (xy 139.947778 -112.85068)
			(xy 140.003512 -112.848643) (xy 140.058949 -112.854743) (xy 140.112906 -112.868849) (xy 140.164235 -112.890661)
			(xy 140.211841 -112.919715) (xy 140.254709 -112.95539) (xy 140.291926 -112.996927) (xy 140.322699 -113.04344)
			(xy 140.346371 -113.093937) (xy 140.362439 -113.147344) (xy 140.370559 -113.20252) (xy 140.371068 -113.230406)
			(xy 140.370559 -113.258292) (xy 140.362439 -113.313468) (xy 140.346371 -113.366875) (xy 140.322699 -113.417372)
			(xy 140.291926 -113.463885) (xy 140.254709 -113.505422) (xy 140.211841 -113.541097) (xy 140.164235 -113.570151)
			(xy 140.112906 -113.591963) (xy 140.058949 -113.606069) (xy 140.003512 -113.612169) (xy 139.947778 -113.610132)
			(xy 139.892935 -113.600002) (xy 139.840151 -113.581995) (xy 139.790551 -113.556494) (xy 139.745193 -113.524043)
			(xy 139.705044 -113.485334) (xy 139.670958 -113.441191) (xy 139.643662 -113.392556) (xy 139.623739 -113.340465)
			(xy 139.611613 -113.286028) (xy 139.607542 -113.230406) (xy 139.121115 -113.230406) (xy 139.114675 -113.244144)
			(xy 139.083902 -113.290657) (xy 139.046685 -113.332194) (xy 139.003817 -113.367869) (xy 138.956211 -113.396923)
			(xy 138.904882 -113.418735) (xy 138.850925 -113.432841) (xy 138.795488 -113.438941) (xy 138.739754 -113.436904)
			(xy 138.684911 -113.426774) (xy 138.632127 -113.408767) (xy 138.582527 -113.383266) (xy 138.537169 -113.350815)
			(xy 138.49702 -113.312106) (xy 138.462934 -113.267963) (xy 138.435638 -113.219328) (xy 138.415715 -113.167237)
			(xy 138.403589 -113.1128) (xy 138.399518 -113.057178) (xy 134.954739 -113.057178) (xy 134.932018 -113.091521)
			(xy 134.894801 -113.133058) (xy 134.851933 -113.168733) (xy 134.804327 -113.197787) (xy 134.752998 -113.219599)
			(xy 134.699041 -113.233705) (xy 134.643604 -113.239805) (xy 134.58787 -113.237768) (xy 134.533027 -113.227638)
			(xy 134.480243 -113.209631) (xy 134.430643 -113.18413) (xy 134.385285 -113.151679) (xy 134.345136 -113.11297)
			(xy 134.31105 -113.068827) (xy 134.283754 -113.020192) (xy 134.263831 -112.968101) (xy 134.251705 -112.913664)
			(xy 134.247634 -112.858042) (xy 130.612322 -112.858042) (xy 130.601357 -112.881432) (xy 130.570584 -112.927945)
			(xy 130.533367 -112.969482) (xy 130.490499 -113.005157) (xy 130.442893 -113.034211) (xy 130.391564 -113.056023)
			(xy 130.337607 -113.070129) (xy 130.28217 -113.076229) (xy 130.226436 -113.074192) (xy 130.171593 -113.064062)
			(xy 130.118809 -113.046055) (xy 130.069209 -113.020554) (xy 130.023851 -112.988103) (xy 129.983702 -112.949394)
			(xy 129.949616 -112.905251) (xy 129.92232 -112.856616) (xy 129.902397 -112.804525) (xy 129.890271 -112.750088)
			(xy 129.8862 -112.694466) (xy 125.18644 -112.694466) (xy 125.18644 -113.519712) (xy 128.257806 -113.519712)
			(xy 128.261877 -113.46409) (xy 128.274003 -113.409653) (xy 128.293926 -113.357562) (xy 128.321222 -113.308927)
			(xy 128.355308 -113.264784) (xy 128.395457 -113.226075) (xy 128.440815 -113.193624) (xy 128.490415 -113.168123)
			(xy 128.543199 -113.150116) (xy 128.598042 -113.139986) (xy 128.653776 -113.137949) (xy 128.709213 -113.144049)
			(xy 128.76317 -113.158155) (xy 128.814499 -113.179967) (xy 128.862105 -113.209021) (xy 128.904973 -113.244696)
			(xy 128.94219 -113.286233) (xy 128.972963 -113.332746) (xy 128.996635 -113.383243) (xy 129.012703 -113.43665)
			(xy 129.020823 -113.491826) (xy 129.021332 -113.519712) (xy 129.020823 -113.547598) (xy 129.012703 -113.602774)
			(xy 128.996635 -113.656181) (xy 128.972963 -113.706678) (xy 128.94219 -113.753191) (xy 128.904973 -113.794728)
			(xy 128.862105 -113.830403) (xy 128.814499 -113.859457) (xy 128.76317 -113.881269) (xy 128.709213 -113.895375)
			(xy 128.66071 -113.900712) (xy 137.636756 -113.900712) (xy 137.640827 -113.84509) (xy 137.652953 -113.790653)
			(xy 137.672876 -113.738562) (xy 137.700172 -113.689927) (xy 137.734258 -113.645784) (xy 137.774407 -113.607075)
			(xy 137.819765 -113.574624) (xy 137.869365 -113.549123) (xy 137.922149 -113.531116) (xy 137.976992 -113.520986)
			(xy 138.032726 -113.518949) (xy 138.088163 -113.525049) (xy 138.14212 -113.539155) (xy 138.193449 -113.560967)
			(xy 138.241055 -113.590021) (xy 138.283923 -113.625696) (xy 138.32114 -113.667233) (xy 138.351913 -113.713746)
			(xy 138.375585 -113.764243) (xy 138.391653 -113.81765) (xy 138.399773 -113.872826) (xy 138.400282 -113.900712)
			(xy 138.399773 -113.928598) (xy 138.391653 -113.983774) (xy 138.375585 -114.037181) (xy 138.351913 -114.087678)
			(xy 138.32114 -114.134191) (xy 138.283923 -114.175728) (xy 138.241055 -114.211403) (xy 138.193449 -114.240457)
			(xy 138.14212 -114.262269) (xy 138.088163 -114.276375) (xy 138.032726 -114.282475) (xy 137.976992 -114.280438)
			(xy 137.922149 -114.270308) (xy 137.869365 -114.252301) (xy 137.819765 -114.2268) (xy 137.774407 -114.194349)
			(xy 137.734258 -114.15564) (xy 137.700172 -114.111497) (xy 137.672876 -114.062862) (xy 137.652953 -114.010771)
			(xy 137.640827 -113.956334) (xy 137.636756 -113.900712) (xy 128.66071 -113.900712) (xy 128.653776 -113.901475)
			(xy 128.598042 -113.899438) (xy 128.543199 -113.889308) (xy 128.490415 -113.871301) (xy 128.440815 -113.8458)
			(xy 128.395457 -113.813349) (xy 128.355308 -113.77464) (xy 128.321222 -113.730497) (xy 128.293926 -113.681862)
			(xy 128.274003 -113.629771) (xy 128.261877 -113.575334) (xy 128.257806 -113.519712) (xy 125.18644 -113.519712)
			(xy 125.18644 -114.714782) (xy 125.864874 -115.393216) (xy 128.195324 -115.393216) (xy 129.002028 -114.586512)
			(xy 129.013329 -114.574416) (xy 129.029881 -114.545763) (xy 129.038535 -114.513824) (xy 129.038712 -114.480734)
			(xy 129.035048 -114.464592) (xy 129.028372 -114.437339) (xy 129.022161 -114.381575) (xy 129.024189 -114.325503)
			(xy 129.03441 -114.270333) (xy 129.052604 -114.217256) (xy 129.078379 -114.167418) (xy 129.111178 -114.121894)
			(xy 129.150293 -114.081668) (xy 129.19488 -114.047606) (xy 129.243976 -114.020445) (xy 129.296522 -114.000771)
			(xy 129.351384 -113.989009) (xy 129.407378 -113.985411) (xy 129.463294 -113.990057) (xy 129.490724 -113.995962)
			(xy 129.504948 -113.999264) (xy 135.856218 -113.999264) (xy 136.42086 -114.563906) (xy 136.42086 -114.902742)
			(xy 138.679934 -114.902742) (xy 138.684005 -114.84712) (xy 138.696131 -114.792683) (xy 138.716054 -114.740592)
			(xy 138.74335 -114.691957) (xy 138.777436 -114.647814) (xy 138.817585 -114.609105) (xy 138.862943 -114.576654)
			(xy 138.912543 -114.551153) (xy 138.965327 -114.533146) (xy 139.02017 -114.523016) (xy 139.075904 -114.520979)
			(xy 139.131341 -114.527079) (xy 139.185298 -114.541185) (xy 139.236627 -114.562997) (xy 139.284233 -114.592051)
			(xy 139.327101 -114.627726) (xy 139.364318 -114.669263) (xy 139.395091 -114.715776) (xy 139.418763 -114.766273)
			(xy 139.434831 -114.81968) (xy 139.442951 -114.874856) (xy 139.44346 -114.902742) (xy 139.442951 -114.930628)
			(xy 139.434831 -114.985804) (xy 139.418763 -115.039211) (xy 139.395091 -115.089708) (xy 139.364318 -115.136221)
			(xy 139.327101 -115.177758) (xy 139.284233 -115.213433) (xy 139.236627 -115.242487) (xy 139.185298 -115.264299)
			(xy 139.131341 -115.278405) (xy 139.075904 -115.284505) (xy 139.02017 -115.282468) (xy 138.965327 -115.272338)
			(xy 138.912543 -115.254331) (xy 138.862943 -115.22883) (xy 138.817585 -115.196379) (xy 138.777436 -115.15767)
			(xy 138.74335 -115.113527) (xy 138.716054 -115.064892) (xy 138.696131 -115.012801) (xy 138.684005 -114.958364)
			(xy 138.679934 -114.902742) (xy 136.42086 -114.902742) (xy 136.42086 -115.764477) (xy 137.473749 -115.764477)
			(xy 137.479927 -115.709153) (xy 137.494079 -115.655315) (xy 137.515905 -115.604105) (xy 137.544942 -115.556611)
			(xy 137.580572 -115.51384) (xy 137.62204 -115.476702) (xy 137.668465 -115.445985) (xy 137.718861 -115.42234)
			(xy 137.772159 -115.40627) (xy 137.827225 -115.398116) (xy 137.882893 -115.398052) (xy 137.937978 -115.406078)
			(xy 137.991313 -115.422025) (xy 138.041763 -115.445552) (xy 138.088259 -115.476163) (xy 138.129813 -115.513205)
			(xy 138.165543 -115.555892) (xy 138.194689 -115.60332) (xy 138.216634 -115.654479) (xy 138.22426 -115.681252)
			(xy 138.230806 -115.703943) (xy 138.25112 -115.746572) (xy 138.278964 -115.784711) (xy 138.313378 -115.817046)
			(xy 138.353176 -115.842462) (xy 138.396985 -115.860085) (xy 138.443298 -115.869307) (xy 138.490517 -115.869809)
			(xy 138.537015 -115.861574) (xy 138.559286 -115.853718) (xy 138.585497 -115.84432) (xy 138.639909 -115.832485)
			(xy 138.695463 -115.828684) (xy 138.75098 -115.832997) (xy 138.80528 -115.845334) (xy 138.852542 -115.863624)
			(xy 141.037816 -115.863624) (xy 141.041887 -115.808002) (xy 141.054013 -115.753565) (xy 141.073936 -115.701474)
			(xy 141.101232 -115.652839) (xy 141.135318 -115.608696) (xy 141.175467 -115.569987) (xy 141.220825 -115.537536)
			(xy 141.270425 -115.512035) (xy 141.323209 -115.494028) (xy 141.378052 -115.483898) (xy 141.433786 -115.481861)
			(xy 141.489223 -115.487961) (xy 141.54318 -115.502067) (xy 141.594509 -115.523879) (xy 141.642115 -115.552933)
			(xy 141.684983 -115.588608) (xy 141.7222 -115.630145) (xy 141.752973 -115.676658) (xy 141.776645 -115.727155)
			(xy 141.792713 -115.780562) (xy 141.800833 -115.835738) (xy 141.801342 -115.863624) (xy 141.800833 -115.89151)
			(xy 141.792713 -115.946686) (xy 141.776645 -116.000093) (xy 141.752973 -116.05059) (xy 141.7222 -116.097103)
			(xy 141.684983 -116.13864) (xy 141.642115 -116.174315) (xy 141.594509 -116.203369) (xy 141.54318 -116.225181)
			(xy 141.489223 -116.239287) (xy 141.433786 -116.245387) (xy 141.378052 -116.24335) (xy 141.323209 -116.23322)
			(xy 141.270425 -116.215213) (xy 141.220825 -116.189712) (xy 141.175467 -116.157261) (xy 141.135318 -116.118552)
			(xy 141.101232 -116.074409) (xy 141.073936 -116.025774) (xy 141.054013 -115.973683) (xy 141.041887 -115.919246)
			(xy 141.037816 -115.863624) (xy 138.852542 -115.863624) (xy 138.857211 -115.865431) (xy 138.905669 -115.892862)
			(xy 138.949627 -115.927044) (xy 138.988149 -115.967253) (xy 139.020419 -116.012633) (xy 139.045751 -116.062221)
			(xy 139.063607 -116.114965) (xy 139.073608 -116.169743) (xy 139.075541 -116.225393) (xy 139.069366 -116.280734)
			(xy 139.055213 -116.334589) (xy 139.033384 -116.385816) (xy 139.004341 -116.433326) (xy 138.968702 -116.476111)
			(xy 138.927223 -116.513262) (xy 138.880784 -116.543989) (xy 138.830374 -116.567642) (xy 138.77706 -116.583717)
			(xy 138.721977 -116.591872) (xy 138.666293 -116.591936) (xy 138.611191 -116.583906) (xy 138.557841 -116.567953)
			(xy 138.507377 -116.544415) (xy 138.460868 -116.513794) (xy 138.419305 -116.476738) (xy 138.383568 -116.434034)
			(xy 138.354416 -116.386591) (xy 138.33247 -116.335414) (xy 138.324844 -116.308632) (xy 138.318303 -116.28594)
			(xy 138.297986 -116.243312) (xy 138.270141 -116.205175) (xy 138.235726 -116.172841) (xy 138.195928 -116.147424)
			(xy 138.152119 -116.129802) (xy 138.105806 -116.12058) (xy 138.058588 -116.120077) (xy 138.01209 -116.128311)
			(xy 137.989818 -116.136166) (xy 137.963598 -116.145519) (xy 137.9092 -116.157338) (xy 137.853662 -116.161127)
			(xy 137.798163 -116.156804) (xy 137.743881 -116.144462) (xy 137.69197 -116.124362) (xy 137.64353 -116.096931)
			(xy 137.599591 -116.062752) (xy 137.561086 -116.02255) (xy 137.528831 -115.97718) (xy 137.503513 -115.927603)
			(xy 137.485668 -115.874874) (xy 137.475676 -115.820111) (xy 137.473749 -115.764477) (xy 136.42086 -115.764477)
			(xy 136.42086 -117.006624) (xy 141.088616 -117.006624) (xy 141.092687 -116.951002) (xy 141.104813 -116.896565)
			(xy 141.124736 -116.844474) (xy 141.152032 -116.795839) (xy 141.186118 -116.751696) (xy 141.226267 -116.712987)
			(xy 141.271625 -116.680536) (xy 141.321225 -116.655035) (xy 141.374009 -116.637028) (xy 141.428852 -116.626898)
			(xy 141.484586 -116.624861) (xy 141.540023 -116.630961) (xy 141.59398 -116.645067) (xy 141.645309 -116.666879)
			(xy 141.692915 -116.695933) (xy 141.735783 -116.731608) (xy 141.773 -116.773145) (xy 141.803773 -116.819658)
			(xy 141.827445 -116.870155) (xy 141.843513 -116.923562) (xy 141.851633 -116.978738) (xy 141.852142 -117.006624)
			(xy 141.851633 -117.03451) (xy 141.843513 -117.089686) (xy 141.827445 -117.143093) (xy 141.803773 -117.19359)
			(xy 141.773 -117.240103) (xy 141.735783 -117.28164) (xy 141.692915 -117.317315) (xy 141.645309 -117.346369)
			(xy 141.59398 -117.368181) (xy 141.540023 -117.382287) (xy 141.484586 -117.388387) (xy 141.428852 -117.38635)
			(xy 141.374009 -117.37622) (xy 141.321225 -117.358213) (xy 141.271625 -117.332712) (xy 141.226267 -117.300261)
			(xy 141.186118 -117.261552) (xy 141.152032 -117.217409) (xy 141.124736 -117.168774) (xy 141.104813 -117.116683)
			(xy 141.092687 -117.062246) (xy 141.088616 -117.006624) (xy 136.42086 -117.006624) (xy 136.42086 -117.88775)
			(xy 136.64057 -118.10746)
		)
		(stroke
			(width 0)
			(type solid)
		)
		(fill yes)
		(layer "In2.Cu")
		(net "P3V3_CLK_NODE1")
	)
	(gr_poly
		(pts
			(xy 39.493444 -161.312352) (xy 39.5152 -161.311901) (xy 39.558076 -161.30448) (xy 39.59906 -161.289861)
			(xy 39.636953 -161.268473) (xy 39.670648 -161.240941) (xy 39.69916 -161.20807) (xy 39.721653 -161.170822)
			(xy 39.737471 -161.130286) (xy 39.74615 -161.087647) (xy 39.747438 -161.044153) (xy 39.744904 -161.022538)
			(xy 39.74154 -160.995509) (xy 39.741599 -160.941043) (xy 39.749404 -160.887139) (xy 39.764795 -160.834893)
			(xy 39.78746 -160.785366) (xy 39.816938 -160.739567) (xy 39.852631 -160.698425) (xy 39.893811 -160.662778)
			(xy 39.939643 -160.633349) (xy 39.989193 -160.610738) (xy 40.041456 -160.595403) (xy 40.095369 -160.587657)
			(xy 40.149835 -160.587657) (xy 40.203748 -160.595403) (xy 40.256011 -160.610738) (xy 40.305561 -160.633349)
			(xy 40.351393 -160.662778) (xy 40.392573 -160.698425) (xy 40.428266 -160.739567) (xy 40.457744 -160.785366)
			(xy 40.480409 -160.834893) (xy 40.4958 -160.887139) (xy 40.503605 -160.941043) (xy 40.503664 -160.995509)
			(xy 40.5003 -161.022538) (xy 40.49767 -161.044148) (xy 40.498958 -161.087658) (xy 40.507641 -161.130312)
			(xy 40.523465 -161.170863) (xy 40.545967 -161.208125) (xy 40.574489 -161.241008) (xy 40.608197 -161.26855)
			(xy 40.646105 -161.289946) (xy 40.687104 -161.304569) (xy 40.729995 -161.311993) (xy 40.75176 -161.312352)
			(xy 41.111932 -161.312352) (xy 41.135554 -161.302446) (xy 41.163654 -161.291331) (xy 41.222384 -161.277119)
			(xy 41.28262 -161.272341) (xy 41.342856 -161.277119) (xy 41.401586 -161.291331) (xy 41.429686 -161.302446)
			(xy 41.453308 -161.312352) (xy 42.728896 -161.312352) (xy 42.793412 -161.268664) (xy 42.80789 -161.232342)
			(xy 42.818898 -161.206136) (xy 42.847545 -161.157044) (xy 42.883158 -161.112746) (xy 42.924951 -161.074224)
			(xy 42.971997 -161.042329) (xy 43.023256 -161.017769) (xy 43.077591 -161.001087) (xy 43.133801 -160.992653)
			(xy 43.190639 -160.992653) (xy 43.246849 -161.001087) (xy 43.301184 -161.017769) (xy 43.352443 -161.042329)
			(xy 43.399489 -161.074224) (xy 43.441282 -161.112746) (xy 43.476895 -161.157044) (xy 43.505542 -161.206136)
			(xy 43.51655 -161.232342) (xy 43.531028 -161.268664) (xy 43.595544 -161.312352) (xy 45.841412 -161.312352)
			(xy 45.858063 -161.311856) (xy 45.89023 -161.303232) (xy 45.919068 -161.286575) (xy 45.942612 -161.263021)
			(xy 45.959255 -161.234175) (xy 45.967864 -161.202004) (xy 45.968412 -161.185352) (xy 45.968412 -161.185098)
			(xy 45.968841 -161.157821) (xy 45.976539 -161.103815) (xy 45.991851 -161.051457) (xy 46.014464 -161.001813)
			(xy 46.043919 -160.955896) (xy 46.079612 -160.914642) (xy 46.120818 -160.878893) (xy 46.166696 -160.849378)
			(xy 46.21631 -160.826698) (xy 46.268648 -160.811317) (xy 46.322644 -160.803547) (xy 46.377196 -160.803547)
			(xy 46.431192 -160.811317) (xy 46.48353 -160.826698) (xy 46.533144 -160.849378) (xy 46.579022 -160.878893)
			(xy 46.620228 -160.914642) (xy 46.655921 -160.955896) (xy 46.685376 -161.001813) (xy 46.707989 -161.051457)
			(xy 46.723301 -161.103815) (xy 46.730999 -161.157821) (xy 46.731428 -161.185098) (xy 46.731428 -161.185352)
			(xy 46.731917 -161.20201) (xy 46.74053 -161.234192) (xy 46.757183 -161.263046) (xy 46.780738 -161.286605)
			(xy 46.80959 -161.303262) (xy 46.84177 -161.31188) (xy 46.858428 -161.312352) (xy 49.61128 -161.312352)
			(xy 50.570892 -160.35274) (xy 50.586691 -160.336247) (xy 50.612682 -160.298695) (xy 50.631549 -160.257105)
			(xy 50.642686 -160.212814) (xy 50.645734 -160.167247) (xy 50.640595 -160.121868) (xy 50.627436 -160.078135)
			(xy 50.606677 -160.037456) (xy 50.593244 -160.018984) (xy 50.576886 -159.996732) (xy 50.550074 -159.948451)
			(xy 50.530504 -159.896809) (xy 50.518583 -159.842885) (xy 50.514562 -159.787805) (xy 50.518524 -159.732721)
			(xy 50.530387 -159.678784) (xy 50.549902 -159.627121) (xy 50.576662 -159.578811) (xy 50.610108 -159.534864)
			(xy 50.64954 -159.496199) (xy 50.694136 -159.463623) (xy 50.742962 -159.437817) (xy 50.794998 -159.41932)
			(xy 50.849158 -159.408519) (xy 50.876708 -159.40659) (xy 50.898109 -159.405036) (xy 50.939976 -159.395652)
			(xy 50.97967 -159.379364) (xy 51.016062 -159.356638) (xy 51.048117 -159.328118) (xy 51.074923 -159.294617)
			(xy 51.095718 -159.257087) (xy 51.10991 -159.216597) (xy 51.117094 -159.174297) (xy 51.1175 -159.152844)
			(xy 51.1175 -158.707328) (xy 51.10226 -158.67888) (xy 51.089792 -158.654868) (xy 51.071008 -158.604128)
			(xy 51.059586 -158.551243) (xy 51.055756 -158.497274) (xy 51.059594 -158.443305) (xy 51.071023 -158.390421)
			(xy 51.089813 -158.339684) (xy 51.10226 -158.31566) (xy 51.1175 -158.287212) (xy 51.1175 -157.823408)
			(xy 51.117025 -157.801082) (xy 51.109208 -157.757118) (xy 51.093831 -157.715197) (xy 51.071367 -157.676606)
			(xy 51.042507 -157.642533) (xy 51.008137 -157.614027) (xy 50.969317 -157.591962) (xy 50.927238 -157.577019)
			(xy 50.883197 -157.569657) (xy 50.838546 -157.570102) (xy 50.81651 -157.573726) (xy 50.788967 -157.578432)
			(xy 50.733136 -157.580683) (xy 50.677574 -157.574767) (xy 50.623468 -157.56081) (xy 50.571977 -157.539112)
			(xy 50.524201 -157.510136) (xy 50.481162 -157.474502) (xy 50.44378 -157.432972) (xy 50.412855 -157.386434)
			(xy 50.389048 -157.335883) (xy 50.372869 -157.2824) (xy 50.364663 -157.22713) (xy 50.364605 -157.171254)
			(xy 50.372698 -157.115966) (xy 50.388767 -157.062451) (xy 50.41247 -157.011851) (xy 50.443299 -156.965249)
			(xy 50.480596 -156.923642) (xy 50.523561 -156.88792) (xy 50.571278 -156.858846) (xy 50.622724 -156.837042)
			(xy 50.649632 -156.829506) (xy 50.682906 -156.82087) (xy 50.828448 -156.675328) (xy 50.828448 -149.947122)
			(xy 50.738532 -149.856952) (xy 50.722141 -149.841284) (xy 50.68489 -149.815439) (xy 50.643647 -149.796608)
			(xy 50.599718 -149.785388) (xy 50.554496 -149.782134) (xy 50.509413 -149.786949) (xy 50.465899 -149.799682)
			(xy 50.425331 -149.819927) (xy 50.388996 -149.847045) (xy 50.358044 -149.880175) (xy 50.333457 -149.918268)
			(xy 50.324258 -149.938994) (xy 50.313159 -149.964419) (xy 50.284685 -150.012028) (xy 50.249615 -150.055011)
			(xy 50.208688 -150.092459) (xy 50.162768 -150.123584) (xy 50.112823 -150.147729) (xy 50.059908 -150.164384)
			(xy 50.005138 -150.173198) (xy 49.949669 -150.173985) (xy 49.894672 -150.166728) (xy 49.841305 -150.151581)
			(xy 49.790696 -150.128863) (xy 49.743911 -150.099053) (xy 49.701938 -150.062781) (xy 49.665663 -150.020811)
			(xy 49.63585 -149.974028) (xy 49.613128 -149.92342) (xy 49.597977 -149.870055) (xy 49.590717 -149.815058)
			(xy 49.5915 -149.759589) (xy 49.60031 -149.704818) (xy 49.616961 -149.651902) (xy 49.641102 -149.601955)
			(xy 49.672224 -149.556033) (xy 49.70967 -149.515104) (xy 49.75265 -149.48003) (xy 49.800257 -149.451553)
			(xy 49.825656 -149.440392) (xy 49.84641 -149.431234) (xy 49.884546 -149.40668) (xy 49.917717 -149.375743)
			(xy 49.944866 -149.339408) (xy 49.965132 -149.29883) (xy 49.97787 -149.255297) (xy 49.982676 -149.210195)
			(xy 49.979396 -149.164956) (xy 49.968134 -149.121018) (xy 49.94925 -149.079778) (xy 49.923342 -149.042548)
			(xy 49.907698 -149.026118) (xy 49.768252 -148.886926) (xy 49.768252 -148.57603) (xy 49.767761 -148.559375)
			(xy 49.759144 -148.527199) (xy 49.74249 -148.498351) (xy 49.718935 -148.474799) (xy 49.690084 -148.458149)
			(xy 49.657907 -148.449537) (xy 49.641252 -148.44903) (xy 45.529754 -148.44903) (xy 45.513009 -148.449531)
			(xy 45.480671 -148.45824) (xy 45.451717 -148.475071) (xy 45.439584 -148.486622) (xy 45.41996 -148.505724)
			(xy 45.376221 -148.538677) (xy 45.32822 -148.565037) (xy 45.276942 -148.584263) (xy 45.223442 -148.595959)
			(xy 45.16882 -148.599884) (xy 45.114198 -148.595959) (xy 45.060698 -148.584263) (xy 45.00942 -148.565037)
			(xy 44.961419 -148.538677) (xy 44.91768 -148.505724) (xy 44.898056 -148.486622) (xy 44.885909 -148.475087)
			(xy 44.85696 -148.458253) (xy 44.82463 -148.449524) (xy 44.807886 -148.44903) (xy 44.250356 -148.44903)
			(xy 44.232859 -148.449596) (xy 44.199183 -148.45911) (xy 44.169341 -148.477387) (xy 44.145562 -148.503062)
			(xy 44.137072 -148.518372) (xy 44.123921 -148.543058) (xy 44.091492 -148.588628) (xy 44.052757 -148.628976)
			(xy 44.008547 -148.663237) (xy 43.959809 -148.690677) (xy 43.907588 -148.710709) (xy 43.853002 -148.722902)
			(xy 43.79722 -148.726995) (xy 43.741438 -148.722902) (xy 43.686852 -148.710709) (xy 43.634631 -148.690677)
			(xy 43.585893 -148.663237) (xy 43.541683 -148.628976) (xy 43.502948 -148.588628) (xy 43.470519 -148.543058)
			(xy 43.457368 -148.518372) (xy 43.448938 -148.503019) (xy 43.425173 -148.477306) (xy 43.395306 -148.459036)
			(xy 43.361592 -148.449587) (xy 43.344084 -148.44903) (xy 42.738548 -148.44903) (xy 42.722521 -148.449496)
			(xy 42.691478 -148.457484) (xy 42.663398 -148.472944) (xy 42.640048 -148.494904) (xy 42.631106 -148.508212)
			(xy 42.615882 -148.531323) (xy 42.579821 -148.573301) (xy 42.538073 -148.609628) (xy 42.491513 -148.63954)
			(xy 42.441119 -148.66241) (xy 42.38795 -148.677756) (xy 42.33312 -148.685258) (xy 42.277782 -148.684757)
			(xy 42.223097 -148.676263) (xy 42.170214 -148.659957) (xy 42.120242 -148.636178) (xy 42.096944 -148.621242)
			(xy 42.082087 -148.61202) (xy 42.048822 -148.60128) (xy 42.013891 -148.599965) (xy 41.979913 -148.608174)
			(xy 41.949435 -148.62529) (xy 41.93667 -148.637244) (xy 41.260268 -149.313646) (xy 44.935646 -149.313646)
			(xy 44.939717 -149.258024) (xy 44.951843 -149.203587) (xy 44.971766 -149.151496) (xy 44.999062 -149.102861)
			(xy 45.033148 -149.058718) (xy 45.073297 -149.020009) (xy 45.118655 -148.987558) (xy 45.168255 -148.962057)
			(xy 45.221039 -148.94405) (xy 45.275882 -148.93392) (xy 45.331616 -148.931883) (xy 45.387053 -148.937983)
			(xy 45.44101 -148.952089) (xy 45.492339 -148.973901) (xy 45.539945 -149.002955) (xy 45.582813 -149.03863)
			(xy 45.62003 -149.080167) (xy 45.650803 -149.12668) (xy 45.674475 -149.177177) (xy 45.690543 -149.230584)
			(xy 45.698663 -149.28576) (xy 45.699172 -149.313646) (xy 45.698663 -149.341532) (xy 45.690543 -149.396708)
			(xy 45.674475 -149.450115) (xy 45.650803 -149.500612) (xy 45.62003 -149.547125) (xy 45.582813 -149.588662)
			(xy 45.539945 -149.624337) (xy 45.492339 -149.653391) (xy 45.44101 -149.675203) (xy 45.387053 -149.689309)
			(xy 45.331616 -149.695409) (xy 45.275882 -149.693372) (xy 45.221039 -149.683242) (xy 45.168255 -149.665235)
			(xy 45.118655 -149.639734) (xy 45.073297 -149.607283) (xy 45.033148 -149.568574) (xy 44.999062 -149.524431)
			(xy 44.971766 -149.475796) (xy 44.951843 -149.423705) (xy 44.939717 -149.369268) (xy 44.935646 -149.313646)
			(xy 41.260268 -149.313646) (xy 41.197784 -149.37613) (xy 41.189656 -149.411944) (xy 41.183278 -149.438021)
			(xy 41.164191 -149.488198) (xy 41.13826 -149.535204) (xy 41.105997 -149.578111) (xy 41.068038 -149.616073)
			(xy 41.025134 -149.648341) (xy 40.97813 -149.674276) (xy 40.927956 -149.693367) (xy 40.901874 -149.699726)
			(xy 40.86606 -149.707854) (xy 39.271448 -151.302466) (xy 39.265606 -151.398986) (xy 39.295578 -151.436832)
			(xy 39.313048 -151.459858) (xy 39.341571 -151.510125) (xy 39.362189 -151.564118) (xy 39.374432 -151.620602)
			(xy 39.378019 -151.678286) (xy 39.372868 -151.735852) (xy 39.359098 -151.791983) (xy 39.337022 -151.845397)
			(xy 39.307145 -151.894871) (xy 39.270151 -151.939276) (xy 39.248842 -151.958802) (xy 39.236849 -151.970082)
			(xy 39.218574 -151.997454) (xy 39.208151 -152.02789) (xy 49.663602 -152.02789) (xy 49.667673 -151.972268)
			(xy 49.679799 -151.917831) (xy 49.699722 -151.86574) (xy 49.727018 -151.817105) (xy 49.761104 -151.772962)
			(xy 49.801253 -151.734253) (xy 49.846611 -151.701802) (xy 49.896211 -151.676301) (xy 49.948995 -151.658294)
			(xy 50.003838 -151.648164) (xy 50.059572 -151.646127) (xy 50.115009 -151.652227) (xy 50.168966 -151.666333)
			(xy 50.220295 -151.688145) (xy 50.267901 -151.717199) (xy 50.310769 -151.752874) (xy 50.347986 -151.794411)
			(xy 50.378759 -151.840924) (xy 50.402431 -151.891421) (xy 50.418499 -151.944828) (xy 50.426619 -152.000004)
			(xy 50.427128 -152.02789) (xy 50.426619 -152.055776) (xy 50.418499 -152.110952) (xy 50.402431 -152.164359)
			(xy 50.378759 -152.214856) (xy 50.347986 -152.261369) (xy 50.310769 -152.302906) (xy 50.267901 -152.338581)
			(xy 50.220295 -152.367635) (xy 50.168966 -152.389447) (xy 50.115009 -152.403553) (xy 50.059572 -152.409653)
			(xy 50.003838 -152.407616) (xy 49.948995 -152.397486) (xy 49.896211 -152.379479) (xy 49.846611 -152.353978)
			(xy 49.801253 -152.321527) (xy 49.761104 -152.282818) (xy 49.727018 -152.238675) (xy 49.699722 -152.19004)
			(xy 49.679799 -152.137949) (xy 49.667673 -152.083512) (xy 49.663602 -152.02789) (xy 39.208151 -152.02789)
			(xy 39.207911 -152.028591) (xy 39.20557 -152.06142) (xy 39.211708 -152.093755) (xy 39.225916 -152.123442)
			(xy 39.236142 -152.136348) (xy 39.253961 -152.158065) (xy 39.283689 -152.205727) (xy 39.306106 -152.257235)
			(xy 39.320726 -152.311472) (xy 39.327233 -152.367268) (xy 39.325487 -152.423415) (xy 39.315525 -152.478698)
			(xy 39.313196 -152.485598) (xy 41.73931 -152.485598) (xy 41.743381 -152.429976) (xy 41.755507 -152.375539)
			(xy 41.77543 -152.323448) (xy 41.802726 -152.274813) (xy 41.836812 -152.23067) (xy 41.876961 -152.191961)
			(xy 41.922319 -152.15951) (xy 41.971919 -152.134009) (xy 42.024703 -152.116002) (xy 42.079546 -152.105872)
			(xy 42.13528 -152.103835) (xy 42.190717 -152.109935) (xy 42.244674 -152.124041) (xy 42.296003 -152.145853)
			(xy 42.343609 -152.174907) (xy 42.386477 -152.210582) (xy 42.423694 -152.252119) (xy 42.454467 -152.298632)
			(xy 42.478139 -152.349129) (xy 42.494207 -152.402536) (xy 42.502327 -152.457712) (xy 42.502836 -152.485598)
			(xy 42.502372 -152.510998) (xy 43.66971 -152.510998) (xy 43.673781 -152.455376) (xy 43.685907 -152.400939)
			(xy 43.70583 -152.348848) (xy 43.733126 -152.300213) (xy 43.767212 -152.25607) (xy 43.807361 -152.217361)
			(xy 43.852719 -152.18491) (xy 43.902319 -152.159409) (xy 43.955103 -152.141402) (xy 44.009946 -152.131272)
			(xy 44.06568 -152.129235) (xy 44.121117 -152.135335) (xy 44.175074 -152.149441) (xy 44.226403 -152.171253)
			(xy 44.274009 -152.200307) (xy 44.316877 -152.235982) (xy 44.354094 -152.277519) (xy 44.384867 -152.324032)
			(xy 44.408539 -152.374529) (xy 44.424607 -152.427936) (xy 44.432727 -152.483112) (xy 44.433236 -152.510998)
			(xy 45.21911 -152.510998) (xy 45.223181 -152.455376) (xy 45.235307 -152.400939) (xy 45.25523 -152.348848)
			(xy 45.282526 -152.300213) (xy 45.316612 -152.25607) (xy 45.356761 -152.217361) (xy 45.402119 -152.18491)
			(xy 45.451719 -152.159409) (xy 45.504503 -152.141402) (xy 45.559346 -152.131272) (xy 45.61508 -152.129235)
			(xy 45.670517 -152.135335) (xy 45.724474 -152.149441) (xy 45.775803 -152.171253) (xy 45.823409 -152.200307)
			(xy 45.866277 -152.235982) (xy 45.903494 -152.277519) (xy 45.934267 -152.324032) (xy 45.957939 -152.374529)
			(xy 45.974007 -152.427936) (xy 45.982127 -152.483112) (xy 45.982636 -152.510998) (xy 45.982172 -152.536398)
			(xy 46.59071 -152.536398) (xy 46.594781 -152.480776) (xy 46.606907 -152.426339) (xy 46.62683 -152.374248)
			(xy 46.654126 -152.325613) (xy 46.688212 -152.28147) (xy 46.728361 -152.242761) (xy 46.773719 -152.21031)
			(xy 46.823319 -152.184809) (xy 46.876103 -152.166802) (xy 46.930946 -152.156672) (xy 46.98668 -152.154635)
			(xy 47.042117 -152.160735) (xy 47.096074 -152.174841) (xy 47.147403 -152.196653) (xy 47.195009 -152.225707)
			(xy 47.237877 -152.261382) (xy 47.275094 -152.302919) (xy 47.305867 -152.349432) (xy 47.329539 -152.399929)
			(xy 47.345607 -152.453336) (xy 47.353727 -152.508512) (xy 47.354236 -152.536398) (xy 47.353727 -152.564284)
			(xy 47.345607 -152.61946) (xy 47.329539 -152.672867) (xy 47.305867 -152.723364) (xy 47.275094 -152.769877)
			(xy 47.237877 -152.811414) (xy 47.195009 -152.847089) (xy 47.147403 -152.876143) (xy 47.096074 -152.897955)
			(xy 47.042117 -152.912061) (xy 46.98668 -152.918161) (xy 46.930946 -152.916124) (xy 46.876103 -152.905994)
			(xy 46.823319 -152.887987) (xy 46.773719 -152.862486) (xy 46.728361 -152.830035) (xy 46.688212 -152.791326)
			(xy 46.654126 -152.747183) (xy 46.62683 -152.698548) (xy 46.606907 -152.646457) (xy 46.594781 -152.59202)
			(xy 46.59071 -152.536398) (xy 45.982172 -152.536398) (xy 45.982127 -152.538884) (xy 45.974007 -152.59406)
			(xy 45.957939 -152.647467) (xy 45.934267 -152.697964) (xy 45.903494 -152.744477) (xy 45.866277 -152.786014)
			(xy 45.823409 -152.821689) (xy 45.775803 -152.850743) (xy 45.724474 -152.872555) (xy 45.670517 -152.886661)
			(xy 45.61508 -152.892761) (xy 45.559346 -152.890724) (xy 45.504503 -152.880594) (xy 45.451719 -152.862587)
			(xy 45.402119 -152.837086) (xy 45.356761 -152.804635) (xy 45.316612 -152.765926) (xy 45.282526 -152.721783)
			(xy 45.25523 -152.673148) (xy 45.235307 -152.621057) (xy 45.223181 -152.56662) (xy 45.21911 -152.510998)
			(xy 44.433236 -152.510998) (xy 44.432727 -152.538884) (xy 44.424607 -152.59406) (xy 44.408539 -152.647467)
			(xy 44.384867 -152.697964) (xy 44.354094 -152.744477) (xy 44.316877 -152.786014) (xy 44.274009 -152.821689)
			(xy 44.226403 -152.850743) (xy 44.175074 -152.872555) (xy 44.121117 -152.886661) (xy 44.06568 -152.892761)
			(xy 44.009946 -152.890724) (xy 43.955103 -152.880594) (xy 43.902319 -152.862587) (xy 43.852719 -152.837086)
			(xy 43.807361 -152.804635) (xy 43.767212 -152.765926) (xy 43.733126 -152.721783) (xy 43.70583 -152.673148)
			(xy 43.685907 -152.621057) (xy 43.673781 -152.56662) (xy 43.66971 -152.510998) (xy 42.502372 -152.510998)
			(xy 42.502327 -152.513484) (xy 42.494207 -152.56866) (xy 42.478139 -152.622067) (xy 42.454467 -152.672564)
			(xy 42.423694 -152.719077) (xy 42.386477 -152.760614) (xy 42.343609 -152.796289) (xy 42.296003 -152.825343)
			(xy 42.244674 -152.847155) (xy 42.190717 -152.861261) (xy 42.13528 -152.867361) (xy 42.079546 -152.865324)
			(xy 42.024703 -152.855194) (xy 41.971919 -152.837187) (xy 41.922319 -152.811686) (xy 41.876961 -152.779235)
			(xy 41.836812 -152.740526) (xy 41.802726 -152.696383) (xy 41.77543 -152.647748) (xy 41.755507 -152.595657)
			(xy 41.743381 -152.54122) (xy 41.73931 -152.485598) (xy 39.313196 -152.485598) (xy 39.297563 -152.531923)
			(xy 39.271989 -152.581937) (xy 39.239356 -152.62766) (xy 39.200371 -152.668103) (xy 39.155875 -152.702391)
			(xy 39.106832 -152.729782) (xy 39.054303 -152.749684) (xy 38.999422 -152.761667) (xy 38.943377 -152.765472)
			(xy 38.91534 -152.763728) (xy 38.892056 -152.762385) (xy 38.845671 -152.767194) (xy 38.800942 -152.780384)
			(xy 38.759371 -152.801514) (xy 38.722352 -152.829873) (xy 38.691128 -152.864511) (xy 38.666747 -152.904263)
			(xy 38.650028 -152.947796) (xy 38.641532 -152.993649) (xy 38.64102 -153.016966) (xy 38.64102 -153.933398)
			(xy 41.73931 -153.933398) (xy 41.743381 -153.877776) (xy 41.755507 -153.823339) (xy 41.77543 -153.771248)
			(xy 41.802726 -153.722613) (xy 41.836812 -153.67847) (xy 41.876961 -153.639761) (xy 41.922319 -153.60731)
			(xy 41.971919 -153.581809) (xy 42.024703 -153.563802) (xy 42.079546 -153.553672) (xy 42.13528 -153.551635)
			(xy 42.190717 -153.557735) (xy 42.244674 -153.571841) (xy 42.296003 -153.593653) (xy 42.343609 -153.622707)
			(xy 42.386477 -153.658382) (xy 42.399618 -153.673048) (xy 49.63236 -153.673048) (xy 49.636431 -153.617426)
			(xy 49.648557 -153.562989) (xy 49.66848 -153.510898) (xy 49.695776 -153.462263) (xy 49.729862 -153.41812)
			(xy 49.770011 -153.379411) (xy 49.815369 -153.34696) (xy 49.864969 -153.321459) (xy 49.917753 -153.303452)
			(xy 49.972596 -153.293322) (xy 50.02833 -153.291285) (xy 50.083767 -153.297385) (xy 50.137724 -153.311491)
			(xy 50.189053 -153.333303) (xy 50.236659 -153.362357) (xy 50.279527 -153.398032) (xy 50.316744 -153.439569)
			(xy 50.347517 -153.486082) (xy 50.371189 -153.536579) (xy 50.387257 -153.589986) (xy 50.395377 -153.645162)
			(xy 50.395886 -153.673048) (xy 50.395377 -153.700934) (xy 50.387257 -153.75611) (xy 50.371189 -153.809517)
			(xy 50.347517 -153.860014) (xy 50.316744 -153.906527) (xy 50.279527 -153.948064) (xy 50.236659 -153.983739)
			(xy 50.189053 -154.012793) (xy 50.137724 -154.034605) (xy 50.083767 -154.048711) (xy 50.02833 -154.054811)
			(xy 49.972596 -154.052774) (xy 49.917753 -154.042644) (xy 49.864969 -154.024637) (xy 49.815369 -153.999136)
			(xy 49.770011 -153.966685) (xy 49.729862 -153.927976) (xy 49.695776 -153.883833) (xy 49.66848 -153.835198)
			(xy 49.648557 -153.783107) (xy 49.636431 -153.72867) (xy 49.63236 -153.673048) (xy 42.399618 -153.673048)
			(xy 42.423694 -153.699919) (xy 42.454467 -153.746432) (xy 42.478139 -153.796929) (xy 42.494207 -153.850336)
			(xy 42.502327 -153.905512) (xy 42.502836 -153.933398) (xy 42.502327 -153.961284) (xy 42.494207 -154.01646)
			(xy 42.478139 -154.069867) (xy 42.458764 -154.111198) (xy 46.61611 -154.111198) (xy 46.620181 -154.055576)
			(xy 46.632307 -154.001139) (xy 46.65223 -153.949048) (xy 46.679526 -153.900413) (xy 46.713612 -153.85627)
			(xy 46.753761 -153.817561) (xy 46.799119 -153.78511) (xy 46.848719 -153.759609) (xy 46.901503 -153.741602)
			(xy 46.956346 -153.731472) (xy 47.01208 -153.729435) (xy 47.067517 -153.735535) (xy 47.121474 -153.749641)
			(xy 47.172803 -153.771453) (xy 47.220409 -153.800507) (xy 47.263277 -153.836182) (xy 47.300494 -153.877719)
			(xy 47.331267 -153.924232) (xy 47.354939 -153.974729) (xy 47.371007 -154.028136) (xy 47.379127 -154.083312)
			(xy 47.379636 -154.111198) (xy 47.379127 -154.139084) (xy 47.371007 -154.19426) (xy 47.354939 -154.247667)
			(xy 47.331267 -154.298164) (xy 47.300494 -154.344677) (xy 47.263277 -154.386214) (xy 47.220409 -154.421889)
			(xy 47.172803 -154.450943) (xy 47.121474 -154.472755) (xy 47.067517 -154.486861) (xy 47.01208 -154.492961)
			(xy 46.956346 -154.490924) (xy 46.901503 -154.480794) (xy 46.848719 -154.462787) (xy 46.799119 -154.437286)
			(xy 46.753761 -154.404835) (xy 46.713612 -154.366126) (xy 46.679526 -154.321983) (xy 46.65223 -154.273348)
			(xy 46.632307 -154.221257) (xy 46.620181 -154.16682) (xy 46.61611 -154.111198) (xy 42.458764 -154.111198)
			(xy 42.454467 -154.120364) (xy 42.423694 -154.166877) (xy 42.386477 -154.208414) (xy 42.343609 -154.244089)
			(xy 42.296003 -154.273143) (xy 42.244674 -154.294955) (xy 42.190717 -154.309061) (xy 42.13528 -154.315161)
			(xy 42.079546 -154.313124) (xy 42.024703 -154.302994) (xy 41.971919 -154.284987) (xy 41.922319 -154.259486)
			(xy 41.876961 -154.227035) (xy 41.836812 -154.188326) (xy 41.802726 -154.144183) (xy 41.77543 -154.095548)
			(xy 41.755507 -154.043457) (xy 41.743381 -153.98902) (xy 41.73931 -153.933398) (xy 38.64102 -153.933398)
			(xy 38.64102 -154.554936) (xy 38.641508 -154.57789) (xy 38.649746 -154.623053) (xy 38.665966 -154.666)
			(xy 38.68964 -154.705333) (xy 38.719996 -154.739771) (xy 38.756047 -154.768194) (xy 38.796619 -154.789675)
			(xy 38.840391 -154.803516) (xy 38.885937 -154.809266) (xy 38.931775 -154.806738) (xy 38.954202 -154.801824)
			(xy 38.981121 -154.795896) (xy 39.036018 -154.790944) (xy 39.091057 -154.793944) (xy 39.14509 -154.804833)
			(xy 39.196995 -154.823385) (xy 39.245689 -154.849214) (xy 39.290159 -154.881781) (xy 39.329479 -154.920409)
			(xy 39.362831 -154.964294) (xy 39.38952 -155.012521) (xy 39.408992 -155.064088) (xy 39.420839 -155.117919)
			(xy 39.424816 -155.172896) (xy 39.42084 -155.227872) (xy 39.408994 -155.281704) (xy 39.389524 -155.333271)
			(xy 39.362836 -155.381499) (xy 39.329485 -155.425384) (xy 39.290165 -155.464013) (xy 39.245696 -155.496582)
			(xy 39.197002 -155.522411) (xy 39.145098 -155.540964) (xy 39.091065 -155.551855) (xy 39.036027 -155.554856)
			(xy 38.98113 -155.549906) (xy 38.954202 -155.544012) (xy 38.931773 -155.539153) (xy 38.885953 -155.536662)
			(xy 38.840429 -155.542437) (xy 38.796682 -155.556289) (xy 38.756132 -155.577769) (xy 38.720096 -155.606179)
			(xy 38.689745 -155.640596) (xy 38.666065 -155.679902) (xy 38.649824 -155.72282) (xy 38.647262 -155.736798)
			(xy 41.73931 -155.736798) (xy 41.743381 -155.681176) (xy 41.755507 -155.626739) (xy 41.77543 -155.574648)
			(xy 41.802726 -155.526013) (xy 41.836812 -155.48187) (xy 41.876961 -155.443161) (xy 41.922319 -155.41071)
			(xy 41.971919 -155.385209) (xy 42.024703 -155.367202) (xy 42.079546 -155.357072) (xy 42.13528 -155.355035)
			(xy 42.190717 -155.361135) (xy 42.244674 -155.375241) (xy 42.296003 -155.397053) (xy 42.343609 -155.426107)
			(xy 42.386477 -155.461782) (xy 42.423694 -155.503319) (xy 42.454467 -155.549832) (xy 42.478139 -155.600329)
			(xy 42.494207 -155.653736) (xy 42.498955 -155.685998) (xy 46.61611 -155.685998) (xy 46.620181 -155.630376)
			(xy 46.632307 -155.575939) (xy 46.65223 -155.523848) (xy 46.679526 -155.475213) (xy 46.713612 -155.43107)
			(xy 46.753761 -155.392361) (xy 46.799119 -155.35991) (xy 46.848719 -155.334409) (xy 46.901503 -155.316402)
			(xy 46.956346 -155.306272) (xy 47.01208 -155.304235) (xy 47.067517 -155.310335) (xy 47.121474 -155.324441)
			(xy 47.172803 -155.346253) (xy 47.220409 -155.375307) (xy 47.263277 -155.410982) (xy 47.300494 -155.452519)
			(xy 47.331267 -155.499032) (xy 47.354939 -155.549529) (xy 47.371007 -155.602936) (xy 47.379127 -155.658112)
			(xy 47.379636 -155.685998) (xy 47.379127 -155.713884) (xy 47.371007 -155.76906) (xy 47.354939 -155.822467)
			(xy 47.331267 -155.872964) (xy 47.300494 -155.919477) (xy 47.263277 -155.961014) (xy 47.220409 -155.996689)
			(xy 47.172803 -156.025743) (xy 47.121474 -156.047555) (xy 47.067517 -156.061661) (xy 47.01208 -156.067761)
			(xy 46.956346 -156.065724) (xy 46.901503 -156.055594) (xy 46.848719 -156.037587) (xy 46.799119 -156.012086)
			(xy 46.753761 -155.979635) (xy 46.713612 -155.940926) (xy 46.679526 -155.896783) (xy 46.65223 -155.848148)
			(xy 46.632307 -155.796057) (xy 46.620181 -155.74162) (xy 46.61611 -155.685998) (xy 42.498955 -155.685998)
			(xy 42.502327 -155.708912) (xy 42.502836 -155.736798) (xy 42.502327 -155.764684) (xy 42.494207 -155.81986)
			(xy 42.478139 -155.873267) (xy 42.454467 -155.923764) (xy 42.423694 -155.970277) (xy 42.386477 -156.011814)
			(xy 42.343609 -156.047489) (xy 42.296003 -156.076543) (xy 42.244674 -156.098355) (xy 42.190717 -156.112461)
			(xy 42.13528 -156.118561) (xy 42.079546 -156.116524) (xy 42.024703 -156.106394) (xy 41.971919 -156.088387)
			(xy 41.922319 -156.062886) (xy 41.876961 -156.030435) (xy 41.836812 -155.991726) (xy 41.802726 -155.947583)
			(xy 41.77543 -155.898948) (xy 41.755507 -155.846857) (xy 41.743381 -155.79242) (xy 41.73931 -155.736798)
			(xy 38.647262 -155.736798) (xy 38.641552 -155.767956) (xy 38.64102 -155.7909) (xy 38.64102 -157.073092)
			(xy 38.64149 -157.095124) (xy 38.64909 -157.138528) (xy 38.664065 -157.179971) (xy 38.685964 -157.218208)
			(xy 38.714132 -157.252094) (xy 38.747723 -157.280613) (xy 38.78573 -157.30291) (xy 38.827014 -157.318315)
			(xy 38.870337 -157.326367) (xy 38.914399 -157.326824) (xy 38.957879 -157.319674) (xy 38.97884 -157.312868)
			(xy 39.005426 -157.304105) (xy 39.060403 -157.293572) (xy 39.11633 -157.291187) (xy 39.172004 -157.297)
			(xy 39.226232 -157.310888) (xy 39.277847 -157.332552) (xy 39.285196 -157.336998) (xy 41.73931 -157.336998)
			(xy 41.743381 -157.281376) (xy 41.755507 -157.226939) (xy 41.77543 -157.174848) (xy 41.802726 -157.126213)
			(xy 41.836812 -157.08207) (xy 41.876961 -157.043361) (xy 41.922319 -157.01091) (xy 41.971919 -156.985409)
			(xy 42.024703 -156.967402) (xy 42.079546 -156.957272) (xy 42.13528 -156.955235) (xy 42.190717 -156.961335)
			(xy 42.244674 -156.975441) (xy 42.296003 -156.997253) (xy 42.343609 -157.026307) (xy 42.386477 -157.061982)
			(xy 42.423694 -157.103519) (xy 42.454467 -157.150032) (xy 42.478139 -157.200529) (xy 42.494207 -157.253936)
			(xy 42.502327 -157.309112) (xy 42.502836 -157.336998) (xy 42.502372 -157.362398) (xy 43.44111 -157.362398)
			(xy 43.445181 -157.306776) (xy 43.457307 -157.252339) (xy 43.47723 -157.200248) (xy 43.504526 -157.151613)
			(xy 43.538612 -157.10747) (xy 43.578761 -157.068761) (xy 43.624119 -157.03631) (xy 43.673719 -157.010809)
			(xy 43.726503 -156.992802) (xy 43.781346 -156.982672) (xy 43.83708 -156.980635) (xy 43.892517 -156.986735)
			(xy 43.946474 -157.000841) (xy 43.997803 -157.022653) (xy 44.045409 -157.051707) (xy 44.088277 -157.087382)
			(xy 44.125494 -157.128919) (xy 44.156267 -157.175432) (xy 44.179939 -157.225929) (xy 44.196007 -157.279336)
			(xy 44.204127 -157.334512) (xy 44.204172 -157.336998) (xy 44.99051 -157.336998) (xy 44.994581 -157.281376)
			(xy 45.006707 -157.226939) (xy 45.02663 -157.174848) (xy 45.053926 -157.126213) (xy 45.088012 -157.08207)
			(xy 45.128161 -157.043361) (xy 45.173519 -157.01091) (xy 45.223119 -156.985409) (xy 45.275903 -156.967402)
			(xy 45.330746 -156.957272) (xy 45.38648 -156.955235) (xy 45.441917 -156.961335) (xy 45.495874 -156.975441)
			(xy 45.547203 -156.997253) (xy 45.594809 -157.026307) (xy 45.637677 -157.061982) (xy 45.674894 -157.103519)
			(xy 45.705667 -157.150032) (xy 45.729339 -157.200529) (xy 45.745407 -157.253936) (xy 45.753527 -157.309112)
			(xy 45.754036 -157.336998) (xy 46.59071 -157.336998) (xy 46.594781 -157.281376) (xy 46.606907 -157.226939)
			(xy 46.62683 -157.174848) (xy 46.654126 -157.126213) (xy 46.688212 -157.08207) (xy 46.728361 -157.043361)
			(xy 46.773719 -157.01091) (xy 46.823319 -156.985409) (xy 46.876103 -156.967402) (xy 46.930946 -156.957272)
			(xy 46.98668 -156.955235) (xy 47.042117 -156.961335) (xy 47.096074 -156.975441) (xy 47.147403 -156.997253)
			(xy 47.195009 -157.026307) (xy 47.237877 -157.061982) (xy 47.275094 -157.103519) (xy 47.305867 -157.150032)
			(xy 47.329539 -157.200529) (xy 47.345607 -157.253936) (xy 47.353727 -157.309112) (xy 47.354236 -157.336998)
			(xy 47.353727 -157.364884) (xy 47.345607 -157.42006) (xy 47.329539 -157.473467) (xy 47.305867 -157.523964)
			(xy 47.275094 -157.570477) (xy 47.237877 -157.612014) (xy 47.195009 -157.647689) (xy 47.147403 -157.676743)
			(xy 47.096074 -157.698555) (xy 47.042117 -157.712661) (xy 46.98668 -157.718761) (xy 46.930946 -157.716724)
			(xy 46.876103 -157.706594) (xy 46.823319 -157.688587) (xy 46.773719 -157.663086) (xy 46.728361 -157.630635)
			(xy 46.688212 -157.591926) (xy 46.654126 -157.547783) (xy 46.62683 -157.499148) (xy 46.606907 -157.447057)
			(xy 46.594781 -157.39262) (xy 46.59071 -157.336998) (xy 45.754036 -157.336998) (xy 45.753527 -157.364884)
			(xy 45.745407 -157.42006) (xy 45.729339 -157.473467) (xy 45.705667 -157.523964) (xy 45.674894 -157.570477)
			(xy 45.637677 -157.612014) (xy 45.594809 -157.647689) (xy 45.547203 -157.676743) (xy 45.495874 -157.698555)
			(xy 45.441917 -157.712661) (xy 45.38648 -157.718761) (xy 45.330746 -157.716724) (xy 45.275903 -157.706594)
			(xy 45.223119 -157.688587) (xy 45.173519 -157.663086) (xy 45.128161 -157.630635) (xy 45.088012 -157.591926)
			(xy 45.053926 -157.547783) (xy 45.02663 -157.499148) (xy 45.006707 -157.447057) (xy 44.994581 -157.39262)
			(xy 44.99051 -157.336998) (xy 44.204172 -157.336998) (xy 44.204636 -157.362398) (xy 44.204127 -157.390284)
			(xy 44.196007 -157.44546) (xy 44.179939 -157.498867) (xy 44.156267 -157.549364) (xy 44.125494 -157.595877)
			(xy 44.088277 -157.637414) (xy 44.045409 -157.673089) (xy 43.997803 -157.702143) (xy 43.946474 -157.723955)
			(xy 43.892517 -157.738061) (xy 43.83708 -157.744161) (xy 43.781346 -157.742124) (xy 43.726503 -157.731994)
			(xy 43.673719 -157.713987) (xy 43.624119 -157.688486) (xy 43.578761 -157.656035) (xy 43.538612 -157.617326)
			(xy 43.504526 -157.573183) (xy 43.47723 -157.524548) (xy 43.457307 -157.472457) (xy 43.445181 -157.41802)
			(xy 43.44111 -157.362398) (xy 42.502372 -157.362398) (xy 42.502327 -157.364884) (xy 42.494207 -157.42006)
			(xy 42.478139 -157.473467) (xy 42.454467 -157.523964) (xy 42.423694 -157.570477) (xy 42.386477 -157.612014)
			(xy 42.343609 -157.647689) (xy 42.296003 -157.676743) (xy 42.244674 -157.698555) (xy 42.190717 -157.712661)
			(xy 42.13528 -157.718761) (xy 42.079546 -157.716724) (xy 42.024703 -157.706594) (xy 41.971919 -157.688587)
			(xy 41.922319 -157.663086) (xy 41.876961 -157.630635) (xy 41.836812 -157.591926) (xy 41.802726 -157.547783)
			(xy 41.77543 -157.499148) (xy 41.755507 -157.447057) (xy 41.743381 -157.39262) (xy 41.73931 -157.336998)
			(xy 39.285196 -157.336998) (xy 39.325742 -157.361527) (xy 39.368888 -157.39719) (xy 39.406359 -157.438776)
			(xy 39.43735 -157.485392) (xy 39.461195 -157.536037) (xy 39.477383 -157.589622) (xy 39.485566 -157.644998)
			(xy 39.485568 -157.700975) (xy 39.477389 -157.756352) (xy 39.461205 -157.809939) (xy 39.437363 -157.860585)
			(xy 39.406375 -157.907203) (xy 39.368907 -157.948791) (xy 39.325763 -157.984458) (xy 39.27787 -158.013436)
			(xy 39.226257 -158.035103) (xy 39.17203 -158.048995) (xy 39.116356 -158.054813) (xy 39.06043 -158.052431)
			(xy 39.005451 -158.041902) (xy 38.97884 -158.033212) (xy 38.957885 -158.026384) (xy 38.914399 -158.019233)
			(xy 38.870332 -158.019691) (xy 38.827004 -158.027744) (xy 38.785716 -158.04315) (xy 38.747703 -158.065448)
			(xy 38.714108 -158.093969) (xy 38.685936 -158.127858) (xy 38.664032 -158.166099) (xy 38.649054 -158.207545)
			(xy 38.641449 -158.250953) (xy 38.64102 -158.272988) (xy 38.64102 -159.03829) (xy 49.689002 -159.03829)
			(xy 49.693073 -158.982668) (xy 49.705199 -158.928231) (xy 49.725122 -158.87614) (xy 49.752418 -158.827505)
			(xy 49.786504 -158.783362) (xy 49.826653 -158.744653) (xy 49.872011 -158.712202) (xy 49.921611 -158.686701)
			(xy 49.974395 -158.668694) (xy 50.029238 -158.658564) (xy 50.084972 -158.656527) (xy 50.140409 -158.662627)
			(xy 50.194366 -158.676733) (xy 50.245695 -158.698545) (xy 50.293301 -158.727599) (xy 50.336169 -158.763274)
			(xy 50.373386 -158.804811) (xy 50.404159 -158.851324) (xy 50.427831 -158.901821) (xy 50.443899 -158.955228)
			(xy 50.452019 -159.010404) (xy 50.452528 -159.03829) (xy 50.452019 -159.066176) (xy 50.443899 -159.121352)
			(xy 50.427831 -159.174759) (xy 50.404159 -159.225256) (xy 50.373386 -159.271769) (xy 50.336169 -159.313306)
			(xy 50.293301 -159.348981) (xy 50.245695 -159.378035) (xy 50.194366 -159.399847) (xy 50.140409 -159.413953)
			(xy 50.084972 -159.420053) (xy 50.029238 -159.418016) (xy 49.974395 -159.407886) (xy 49.921611 -159.389879)
			(xy 49.872011 -159.364378) (xy 49.826653 -159.331927) (xy 49.786504 -159.293218) (xy 49.752418 -159.249075)
			(xy 49.725122 -159.20044) (xy 49.705199 -159.148349) (xy 49.693073 -159.093912) (xy 49.689002 -159.03829)
			(xy 38.64102 -159.03829) (xy 38.64102 -160.501838) (xy 40.935654 -160.501838) (xy 40.939725 -160.446216)
			(xy 40.951851 -160.391779) (xy 40.971774 -160.339688) (xy 40.99907 -160.291053) (xy 41.033156 -160.24691)
			(xy 41.073305 -160.208201) (xy 41.118663 -160.17575) (xy 41.168263 -160.150249) (xy 41.221047 -160.132242)
			(xy 41.27589 -160.122112) (xy 41.331624 -160.120075) (xy 41.387061 -160.126175) (xy 41.441018 -160.140281)
			(xy 41.492347 -160.162093) (xy 41.539953 -160.191147) (xy 41.582821 -160.226822) (xy 41.620038 -160.268359)
			(xy 41.650811 -160.314872) (xy 41.674483 -160.365369) (xy 41.690551 -160.418776) (xy 41.698671 -160.473952)
			(xy 41.69918 -160.501838) (xy 41.699004 -160.51149) (xy 42.170602 -160.51149) (xy 42.174673 -160.455868)
			(xy 42.186799 -160.401431) (xy 42.206722 -160.34934) (xy 42.234018 -160.300705) (xy 42.268104 -160.256562)
			(xy 42.308253 -160.217853) (xy 42.353611 -160.185402) (xy 42.403211 -160.159901) (xy 42.455995 -160.141894)
			(xy 42.510838 -160.131764) (xy 42.566572 -160.129727) (xy 42.622009 -160.135827) (xy 42.675966 -160.149933)
			(xy 42.727295 -160.171745) (xy 42.774901 -160.200799) (xy 42.817769 -160.236474) (xy 42.854986 -160.278011)
			(xy 42.885759 -160.324524) (xy 42.909431 -160.375021) (xy 42.925499 -160.428428) (xy 42.933619 -160.483604)
			(xy 42.934128 -160.51149) (xy 42.933619 -160.539376) (xy 42.926509 -160.58769) (xy 48.419002 -160.58769)
			(xy 48.423073 -160.532068) (xy 48.435199 -160.477631) (xy 48.455122 -160.42554) (xy 48.482418 -160.376905)
			(xy 48.516504 -160.332762) (xy 48.556653 -160.294053) (xy 48.602011 -160.261602) (xy 48.651611 -160.236101)
			(xy 48.704395 -160.218094) (xy 48.759238 -160.207964) (xy 48.814972 -160.205927) (xy 48.870409 -160.212027)
			(xy 48.924366 -160.226133) (xy 48.975695 -160.247945) (xy 49.023301 -160.276999) (xy 49.066169 -160.312674)
			(xy 49.103386 -160.354211) (xy 49.134159 -160.400724) (xy 49.157831 -160.451221) (xy 49.173899 -160.504628)
			(xy 49.182019 -160.559804) (xy 49.182528 -160.58769) (xy 49.182019 -160.615576) (xy 49.173899 -160.670752)
			(xy 49.157831 -160.724159) (xy 49.134159 -160.774656) (xy 49.103386 -160.821169) (xy 49.066169 -160.862706)
			(xy 49.023301 -160.898381) (xy 48.975695 -160.927435) (xy 48.924366 -160.949247) (xy 48.870409 -160.963353)
			(xy 48.814972 -160.969453) (xy 48.759238 -160.967416) (xy 48.704395 -160.957286) (xy 48.651611 -160.939279)
			(xy 48.602011 -160.913778) (xy 48.556653 -160.881327) (xy 48.516504 -160.842618) (xy 48.482418 -160.798475)
			(xy 48.455122 -160.74984) (xy 48.435199 -160.697749) (xy 48.423073 -160.643312) (xy 48.419002 -160.58769)
			(xy 42.926509 -160.58769) (xy 42.925499 -160.594552) (xy 42.909431 -160.647959) (xy 42.885759 -160.698456)
			(xy 42.854986 -160.744969) (xy 42.817769 -160.786506) (xy 42.774901 -160.822181) (xy 42.727295 -160.851235)
			(xy 42.675966 -160.873047) (xy 42.622009 -160.887153) (xy 42.566572 -160.893253) (xy 42.510838 -160.891216)
			(xy 42.455995 -160.881086) (xy 42.403211 -160.863079) (xy 42.353611 -160.837578) (xy 42.308253 -160.805127)
			(xy 42.268104 -160.766418) (xy 42.234018 -160.722275) (xy 42.206722 -160.67364) (xy 42.186799 -160.621549)
			(xy 42.174673 -160.567112) (xy 42.170602 -160.51149) (xy 41.699004 -160.51149) (xy 41.698671 -160.529724)
			(xy 41.690551 -160.5849) (xy 41.674483 -160.638307) (xy 41.650811 -160.688804) (xy 41.620038 -160.735317)
			(xy 41.582821 -160.776854) (xy 41.539953 -160.812529) (xy 41.492347 -160.841583) (xy 41.441018 -160.863395)
			(xy 41.387061 -160.877501) (xy 41.331624 -160.883601) (xy 41.27589 -160.881564) (xy 41.221047 -160.871434)
			(xy 41.168263 -160.853427) (xy 41.118663 -160.827926) (xy 41.073305 -160.795475) (xy 41.033156 -160.756766)
			(xy 40.99907 -160.712623) (xy 40.971774 -160.663988) (xy 40.951851 -160.611897) (xy 40.939725 -160.55746)
			(xy 40.935654 -160.501838) (xy 38.64102 -160.501838) (xy 38.64102 -160.844992) (xy 39.10838 -161.312352)
		)
		(stroke
			(width 0)
			(type solid)
		)
		(fill yes)
		(layer "In2.Cu")
		(net "P1V05_LAN1")
	)
	(gr_poly
		(pts
			(xy 144.69872 -70.569074) (xy 148.68398 -70.569074) (xy 151.20493 -68.048124) (xy 151.212042 -68.037456)
			(xy 151.2264 -68.016595) (xy 151.25976 -67.978495) (xy 151.297868 -67.945144) (xy 151.318722 -67.930776)
			(xy 151.32939 -67.923664) (xy 151.359362 -67.893692) (xy 151.388064 -67.893692) (xy 151.407876 -67.887088)
			(xy 151.437486 -67.877744) (xy 151.498753 -67.867689) (xy 151.560839 -67.867689) (xy 151.622106 -67.877744)
			(xy 151.651716 -67.887088) (xy 151.671528 -67.893692) (xy 152.233122 -67.893692) (xy 155.813252 -64.313562)
			(xy 155.813252 -57.557162) (xy 154.479752 -56.223662) (xy 153.479246 -56.223662) (xy 153.432764 -56.270144)
			(xy 151.710644 -56.270144) (xy 151.652732 -56.302656) (xy 151.63546 -56.331104) (xy 151.620528 -56.354699)
			(xy 151.584852 -56.397653) (xy 151.543296 -56.434948) (xy 151.496748 -56.465787) (xy 151.446202 -56.489512)
			(xy 151.392738 -56.505616) (xy 151.337497 -56.513755) (xy 151.281659 -56.513755) (xy 151.226418 -56.505616)
			(xy 151.172954 -56.489512) (xy 151.122408 -56.465787) (xy 151.07586 -56.434948) (xy 151.034304 -56.397653)
			(xy 150.998628 -56.354699) (xy 150.983696 -56.331104) (xy 150.974836 -56.317417) (xy 150.951445 -56.29472)
			(xy 150.923057 -56.278705) (xy 150.891534 -56.270421) (xy 150.875238 -56.26989) (xy 150.707344 -56.26989)
			(xy 150.646892 -56.306212) (xy 150.630382 -56.337454) (xy 150.61702 -56.361523) (xy 150.584434 -56.405893)
			(xy 150.54581 -56.445119) (xy 150.50195 -56.478388) (xy 150.453764 -56.505008) (xy 150.402253 -56.524427)
			(xy 150.348485 -56.536243) (xy 150.293578 -56.540208) (xy 150.238671 -56.536243) (xy 150.184903 -56.524427)
			(xy 150.133392 -56.505008) (xy 150.085206 -56.478388) (xy 150.041346 -56.445119) (xy 150.002722 -56.405893)
			(xy 149.970136 -56.361523) (xy 149.956774 -56.337454) (xy 149.940264 -56.306212) (xy 149.880066 -56.270144)
			(xy 149.662388 -56.270144) (xy 149.644257 -56.270715) (xy 149.60946 -56.280917) (xy 149.578952 -56.300518)
			(xy 149.56663 -56.313832) (xy 149.566376 -56.314086) (xy 149.548178 -56.334461) (xy 149.506955 -56.370309)
			(xy 149.461039 -56.399909) (xy 149.41137 -56.422656) (xy 149.358964 -56.438084) (xy 149.304893 -56.445878)
			(xy 149.250263 -56.445878) (xy 149.196192 -56.438084) (xy 149.143786 -56.422656) (xy 149.094117 -56.399909)
			(xy 149.048201 -56.370309) (xy 149.006978 -56.334461) (xy 148.98878 -56.314086) (xy 148.976392 -56.300768)
			(xy 148.945818 -56.281096) (xy 148.910945 -56.270821) (xy 148.892768 -56.270144) (xy 148.653754 -56.270144)
			(xy 148.639741 -56.270519) (xy 148.612394 -56.276649) (xy 148.587046 -56.288603) (xy 148.56492 -56.305804)
			(xy 148.55571 -56.316372) (xy 148.5375 -56.337655) (xy 148.495908 -56.375169) (xy 148.449276 -56.406197)
			(xy 148.398608 -56.430071) (xy 148.344992 -56.446278) (xy 148.289584 -56.45447) (xy 148.233572 -56.45447)
			(xy 148.178164 -56.446278) (xy 148.124548 -56.430071) (xy 148.07388 -56.406197) (xy 148.027248 -56.375169)
			(xy 147.985656 -56.337655) (xy 147.967446 -56.316372) (xy 147.95825 -56.305788) (xy 147.936129 -56.288571)
			(xy 147.910775 -56.276614) (xy 147.883418 -56.270499) (xy 147.869402 -56.270144) (xy 147.615402 -56.270144)
			(xy 147.598123 -56.270732) (xy 147.564834 -56.280014) (xy 147.535246 -56.297871) (xy 147.522946 -56.310022)
			(xy 147.503184 -56.33021) (xy 147.458767 -56.365118) (xy 147.409689 -56.393093) (xy 147.357021 -56.413524)
			(xy 147.301915 -56.425965) (xy 147.245578 -56.430142) (xy 147.189241 -56.425965) (xy 147.134135 -56.413524)
			(xy 147.081467 -56.393093) (xy 147.032389 -56.365118) (xy 146.987972 -56.33021) (xy 146.96821 -56.310022)
			(xy 146.955935 -56.297842) (xy 146.926342 -56.279981) (xy 146.893037 -56.27073) (xy 146.875754 -56.270144)
			(xy 145.71726 -56.270144) (xy 145.686018 -56.239156) (xy 141.927072 -56.239156) (xy 140.729208 -57.43702)
			(xy 140.729208 -58.26633) (xy 146.86356 -58.26633) (xy 146.867631 -58.210708) (xy 146.879757 -58.156271)
			(xy 146.89968 -58.10418) (xy 146.926976 -58.055545) (xy 146.961062 -58.011402) (xy 147.001211 -57.972693)
			(xy 147.046569 -57.940242) (xy 147.096169 -57.914741) (xy 147.148953 -57.896734) (xy 147.203796 -57.886604)
			(xy 147.25953 -57.884567) (xy 147.314967 -57.890667) (xy 147.368924 -57.904773) (xy 147.420253 -57.926585)
			(xy 147.467859 -57.955639) (xy 147.510727 -57.991314) (xy 147.547944 -58.032851) (xy 147.578717 -58.079364)
			(xy 147.602389 -58.129861) (xy 147.618457 -58.183268) (xy 147.626577 -58.238444) (xy 147.627086 -58.26633)
			(xy 147.626577 -58.294216) (xy 147.618457 -58.349392) (xy 147.602389 -58.402799) (xy 147.583014 -58.44413)
			(xy 148.355048 -58.44413) (xy 148.359119 -58.388508) (xy 148.371245 -58.334071) (xy 148.391168 -58.28198)
			(xy 148.418464 -58.233345) (xy 148.45255 -58.189202) (xy 148.492699 -58.150493) (xy 148.538057 -58.118042)
			(xy 148.587657 -58.092541) (xy 148.640441 -58.074534) (xy 148.695284 -58.064404) (xy 148.751018 -58.062367)
			(xy 148.806455 -58.068467) (xy 148.860412 -58.082573) (xy 148.911741 -58.104385) (xy 148.959347 -58.133439)
			(xy 149.002215 -58.169114) (xy 149.039432 -58.210651) (xy 149.070205 -58.257164) (xy 149.093877 -58.307661)
			(xy 149.109945 -58.361068) (xy 149.118065 -58.416244) (xy 149.118574 -58.44413) (xy 149.118263 -58.461148)
			(xy 149.91156 -58.461148) (xy 149.915631 -58.405526) (xy 149.927757 -58.351089) (xy 149.94768 -58.298998)
			(xy 149.974976 -58.250363) (xy 150.009062 -58.20622) (xy 150.049211 -58.167511) (xy 150.094569 -58.13506)
			(xy 150.144169 -58.109559) (xy 150.196953 -58.091552) (xy 150.251796 -58.081422) (xy 150.30753 -58.079385)
			(xy 150.362967 -58.085485) (xy 150.416924 -58.099591) (xy 150.468253 -58.121403) (xy 150.515859 -58.150457)
			(xy 150.558727 -58.186132) (xy 150.595944 -58.227669) (xy 150.626717 -58.274182) (xy 150.650389 -58.324679)
			(xy 150.666457 -58.378086) (xy 150.674577 -58.433262) (xy 150.675086 -58.461148) (xy 150.674577 -58.489034)
			(xy 150.666457 -58.54421) (xy 150.650389 -58.597617) (xy 150.626717 -58.648114) (xy 150.595944 -58.694627)
			(xy 150.558727 -58.736164) (xy 150.515859 -58.771839) (xy 150.468253 -58.800893) (xy 150.416924 -58.822705)
			(xy 150.362967 -58.836811) (xy 150.30753 -58.842911) (xy 150.251796 -58.840874) (xy 150.196953 -58.830744)
			(xy 150.144169 -58.812737) (xy 150.094569 -58.787236) (xy 150.049211 -58.754785) (xy 150.009062 -58.716076)
			(xy 149.974976 -58.671933) (xy 149.94768 -58.623298) (xy 149.927757 -58.571207) (xy 149.915631 -58.51677)
			(xy 149.91156 -58.461148) (xy 149.118263 -58.461148) (xy 149.118065 -58.472016) (xy 149.109945 -58.527192)
			(xy 149.093877 -58.580599) (xy 149.070205 -58.631096) (xy 149.039432 -58.677609) (xy 149.002215 -58.719146)
			(xy 148.959347 -58.754821) (xy 148.911741 -58.783875) (xy 148.860412 -58.805687) (xy 148.806455 -58.819793)
			(xy 148.751018 -58.825893) (xy 148.695284 -58.823856) (xy 148.640441 -58.813726) (xy 148.587657 -58.795719)
			(xy 148.538057 -58.770218) (xy 148.492699 -58.737767) (xy 148.45255 -58.699058) (xy 148.418464 -58.654915)
			(xy 148.391168 -58.60628) (xy 148.371245 -58.554189) (xy 148.359119 -58.499752) (xy 148.355048 -58.44413)
			(xy 147.583014 -58.44413) (xy 147.578717 -58.453296) (xy 147.547944 -58.499809) (xy 147.510727 -58.541346)
			(xy 147.467859 -58.577021) (xy 147.420253 -58.606075) (xy 147.368924 -58.627887) (xy 147.314967 -58.641993)
			(xy 147.25953 -58.648093) (xy 147.203796 -58.646056) (xy 147.148953 -58.635926) (xy 147.096169 -58.617919)
			(xy 147.046569 -58.592418) (xy 147.001211 -58.559967) (xy 146.961062 -58.521258) (xy 146.926976 -58.477115)
			(xy 146.89968 -58.42848) (xy 146.879757 -58.376389) (xy 146.867631 -58.321952) (xy 146.86356 -58.26633)
			(xy 140.729208 -58.26633) (xy 140.729208 -58.87593) (xy 144.365978 -58.87593) (xy 144.370049 -58.820308)
			(xy 144.382175 -58.765871) (xy 144.402098 -58.71378) (xy 144.429394 -58.665145) (xy 144.46348 -58.621002)
			(xy 144.503629 -58.582293) (xy 144.548987 -58.549842) (xy 144.598587 -58.524341) (xy 144.651371 -58.506334)
			(xy 144.706214 -58.496204) (xy 144.761948 -58.494167) (xy 144.817385 -58.500267) (xy 144.871342 -58.514373)
			(xy 144.922671 -58.536185) (xy 144.970277 -58.565239) (xy 145.013145 -58.600914) (xy 145.050362 -58.642451)
			(xy 145.081135 -58.688964) (xy 145.104807 -58.739461) (xy 145.120875 -58.792868) (xy 145.128995 -58.848044)
			(xy 145.129504 -58.87593) (xy 145.128995 -58.903816) (xy 145.120875 -58.958992) (xy 145.104807 -59.012399)
			(xy 145.081135 -59.062896) (xy 145.050362 -59.109409) (xy 145.013145 -59.150946) (xy 144.970277 -59.186621)
			(xy 144.922671 -59.215675) (xy 144.871342 -59.237487) (xy 144.817385 -59.251593) (xy 144.761948 -59.257693)
			(xy 144.706214 -59.255656) (xy 144.651371 -59.245526) (xy 144.598587 -59.227519) (xy 144.548987 -59.202018)
			(xy 144.503629 -59.169567) (xy 144.46348 -59.130858) (xy 144.429394 -59.086715) (xy 144.402098 -59.03808)
			(xy 144.382175 -58.985989) (xy 144.370049 -58.931552) (xy 144.365978 -58.87593) (xy 140.729208 -58.87593)
			(xy 140.729208 -59.082686) (xy 140.560044 -59.25185) (xy 140.139674 -59.67222) (xy 139.436094 -59.67222)
			(xy 139.061444 -60.04687) (xy 139.054332 -60.085732) (xy 139.048614 -60.113972) (xy 139.02981 -60.168435)
			(xy 139.027384 -60.173056) (xy 150.844117 -60.173056) (xy 150.844171 -60.117999) (xy 150.85214 -60.063522)
			(xy 150.867858 -60.010757) (xy 150.890999 -59.960799) (xy 150.921083 -59.914688) (xy 150.957483 -59.873381)
			(xy 150.999444 -59.837736) (xy 151.046094 -59.808495) (xy 151.096463 -59.786264) (xy 151.149505 -59.771506)
			(xy 151.204117 -59.764527) (xy 151.259166 -59.765473) (xy 151.313507 -59.774323) (xy 151.366011 -59.790893)
			(xy 151.415587 -59.814841) (xy 151.461205 -59.845667) (xy 151.501917 -59.882731) (xy 151.536878 -59.925264)
			(xy 151.56536 -59.972381) (xy 151.586772 -60.023104) (xy 151.600669 -60.076378) (xy 151.606763 -60.131096)
			(xy 151.604926 -60.186122) (xy 151.595197 -60.240313) (xy 151.586946 -60.26658) (xy 151.580176 -60.288435)
			(xy 151.573752 -60.333731) (xy 151.575536 -60.379446) (xy 151.58547 -60.424104) (xy 151.603233 -60.466264)
			(xy 151.628252 -60.504566) (xy 151.65972 -60.537774) (xy 151.696622 -60.564816) (xy 151.737767 -60.584819)
			(xy 151.759666 -60.591446) (xy 151.784275 -60.598769) (xy 151.831413 -60.619118) (xy 151.875395 -60.64561)
			(xy 151.915423 -60.677765) (xy 151.933402 -60.696094) (xy 151.948897 -60.711673) (xy 151.98415 -60.73789)
			(xy 152.02339 -60.757648) (xy 152.065444 -60.770356) (xy 152.109058 -60.775637) (xy 152.152931 -60.773331)
			(xy 152.195751 -60.763509) (xy 152.236242 -60.746462) (xy 152.273195 -60.7227) (xy 152.305505 -60.692933)
			(xy 152.319228 -60.675774) (xy 152.335971 -60.654697) (xy 152.374404 -60.617008) (xy 152.417752 -60.585096)
			(xy 152.465156 -60.559593) (xy 152.515673 -60.541007) (xy 152.568302 -60.529705) (xy 152.621996 -60.525912)
			(xy 152.67569 -60.529705) (xy 152.728319 -60.541007) (xy 152.778836 -60.559593) (xy 152.82624 -60.585096)
			(xy 152.869588 -60.617008) (xy 152.908021 -60.654697) (xy 152.924764 -60.675774) (xy 152.938547 -60.692876)
			(xy 152.970869 -60.722609) (xy 153.00782 -60.746343) (xy 153.048301 -60.763373) (xy 153.091107 -60.773191)
			(xy 153.134963 -60.775506) (xy 153.178565 -60.770247) (xy 153.220613 -60.757573) (xy 153.259857 -60.737859)
			(xy 153.295129 -60.711694) (xy 153.31059 -60.696094) (xy 153.327379 -60.678958) (xy 153.364475 -60.648539)
			(xy 153.405084 -60.622998) (xy 153.426668 -60.612528) (xy 153.446536 -60.602699) (xy 153.482896 -60.577358)
			(xy 153.514306 -60.546092) (xy 153.539814 -60.509849) (xy 153.558645 -60.46973) (xy 153.570228 -60.426951)
			(xy 153.574212 -60.382811) (xy 153.570475 -60.33865) (xy 153.559131 -60.295808) (xy 153.540525 -60.255584)
			(xy 153.528268 -60.237116) (xy 153.512962 -60.214338) (xy 153.488351 -60.165289) (xy 153.471022 -60.113219)
			(xy 153.461329 -60.059205) (xy 153.459474 -60.004359) (xy 153.465495 -59.949813) (xy 153.479268 -59.896691)
			(xy 153.500508 -59.846091) (xy 153.528777 -59.799055) (xy 153.563493 -59.756554) (xy 153.603939 -59.719464)
			(xy 153.64928 -59.68855) (xy 153.698583 -59.664451) (xy 153.750829 -59.647662) (xy 153.804942 -59.638531)
			(xy 153.859804 -59.637246) (xy 153.914285 -59.643833) (xy 153.96726 -59.658156) (xy 154.017637 -59.67992)
			(xy 154.064377 -59.708676) (xy 154.106516 -59.743831) (xy 154.143184 -59.78466) (xy 154.173625 -59.83032)
			(xy 154.197212 -59.87987) (xy 154.213457 -59.932288) (xy 154.222026 -59.986492) (xy 154.222742 -60.041365)
			(xy 154.21559 -60.095774) (xy 154.200717 -60.148598) (xy 154.178431 -60.198747) (xy 154.149192 -60.245185)
			(xy 154.113601 -60.286957) (xy 154.072394 -60.323199) (xy 154.02642 -60.353165) (xy 154.001724 -60.365132)
			(xy 153.981815 -60.374882) (xy 153.945452 -60.400233) (xy 153.91404 -60.431509) (xy 153.888533 -60.467762)
			(xy 153.869704 -60.507892) (xy 153.858125 -60.55068) (xy 153.854147 -60.594829) (xy 153.857892 -60.638998)
			(xy 153.869245 -60.681847) (xy 153.887862 -60.722075) (xy 153.900124 -60.740544) (xy 153.915786 -60.76393)
			(xy 153.940851 -60.814322) (xy 153.958241 -60.86785) (xy 153.967577 -60.923352) (xy 153.968225 -60.957138)
			(xy 154.246622 -60.957138) (xy 154.250765 -60.90257) (xy 154.262664 -60.849154) (xy 154.282073 -60.797986)
			(xy 154.308595 -60.750117) (xy 154.341685 -60.70653) (xy 154.380665 -60.668118) (xy 154.424733 -60.635671)
			(xy 154.472985 -60.609854) (xy 154.498548 -60.600082) (xy 154.520635 -60.591523) (xy 154.561413 -60.567435)
			(xy 154.59702 -60.536204) (xy 154.62622 -60.498915) (xy 154.648002 -60.456859) (xy 154.66161 -60.411494)
			(xy 154.666573 -60.364393) (xy 154.665172 -60.340748) (xy 154.663391 -60.313436) (xy 154.66682 -60.258811)
			(xy 154.678021 -60.205236) (xy 154.696763 -60.153812) (xy 154.72266 -60.105593) (xy 154.755183 -60.061571)
			(xy 154.793663 -60.022648) (xy 154.83731 -59.989623) (xy 154.885229 -59.963174) (xy 154.936435 -59.943845)
			(xy 154.989878 -59.932031) (xy 155.04446 -59.927976) (xy 155.099062 -59.931763) (xy 155.152563 -59.943313)
			(xy 155.203864 -59.962391) (xy 155.251912 -59.988603) (xy 155.295721 -60.021413) (xy 155.334391 -60.060146)
			(xy 155.36713 -60.104008) (xy 155.393265 -60.152099) (xy 155.412259 -60.20343) (xy 155.423723 -60.256949)
			(xy 155.427422 -60.311557) (xy 155.423278 -60.366133) (xy 155.411378 -60.419557) (xy 155.391966 -60.470732)
			(xy 155.36544 -60.518608) (xy 155.332345 -60.562201) (xy 155.29336 -60.600618) (xy 155.249285 -60.63307)
			(xy 155.201025 -60.65889) (xy 155.175458 -60.668662) (xy 155.153373 -60.677222) (xy 155.112601 -60.701317)
			(xy 155.077001 -60.73255) (xy 155.047804 -60.769839) (xy 155.026022 -60.811893) (xy 155.012409 -60.857254)
			(xy 155.007438 -60.904352) (xy 155.008834 -60.927996) (xy 155.010566 -60.955308) (xy 155.007131 -61.009925)
			(xy 154.995926 -61.063491) (xy 154.977182 -61.114906) (xy 154.951283 -61.163114) (xy 154.918761 -61.207127)
			(xy 154.880284 -61.246042) (xy 154.83664 -61.279058) (xy 154.788726 -61.305499) (xy 154.737526 -61.324821)
			(xy 154.68409 -61.336629) (xy 154.629515 -61.34068) (xy 154.574921 -61.336891) (xy 154.521429 -61.325339)
			(xy 154.470137 -61.306262) (xy 154.422097 -61.280051) (xy 154.378296 -61.247244) (xy 154.339632 -61.208515)
			(xy 154.3069 -61.164658) (xy 154.28077 -61.116574) (xy 154.26178 -61.065249) (xy 154.250319 -61.011738)
			(xy 154.246622 -60.957138) (xy 153.968225 -60.957138) (xy 153.968657 -60.979623) (xy 153.961458 -61.035442)
			(xy 153.946136 -61.089598) (xy 153.923023 -61.140915) (xy 153.892622 -61.188279) (xy 153.855591 -61.230663)
			(xy 153.812735 -61.267146) (xy 153.764984 -61.296936) (xy 153.713375 -61.319387) (xy 153.659026 -61.334012)
			(xy 153.603119 -61.340493) (xy 153.546866 -61.33869) (xy 153.491489 -61.328641) (xy 153.438189 -61.310566)
			(xy 153.388123 -61.284855) (xy 153.342378 -61.252067) (xy 153.301947 -61.212914) (xy 153.284428 -61.190886)
			(xy 153.270652 -61.173776) (xy 153.238332 -61.144037) (xy 153.201381 -61.120298) (xy 153.160898 -61.103264)
			(xy 153.118089 -61.093444) (xy 153.07423 -61.09113) (xy 153.030626 -61.096391) (xy 152.988576 -61.10907)
			(xy 152.949331 -61.128789) (xy 152.914061 -61.154962) (xy 152.898602 -61.170566) (xy 152.878857 -61.19063)
			(xy 152.834518 -61.225312) (xy 152.785563 -61.253101) (xy 152.733055 -61.273393) (xy 152.678135 -61.285747)
			(xy 152.621996 -61.289895) (xy 152.565857 -61.285747) (xy 152.510937 -61.273393) (xy 152.458429 -61.253101)
			(xy 152.409474 -61.225312) (xy 152.365135 -61.19063) (xy 152.34539 -61.170566) (xy 152.329908 -61.154972)
			(xy 152.294655 -61.128749) (xy 152.255414 -61.108986) (xy 152.213356 -61.096274) (xy 152.169738 -61.090993)
			(xy 152.125862 -61.0933) (xy 152.083038 -61.103126) (xy 152.042545 -61.120179) (xy 152.005593 -61.143947)
			(xy 151.973284 -61.173723) (xy 151.959564 -61.190886) (xy 151.941972 -61.212954) (xy 151.901408 -61.252188)
			(xy 151.855507 -61.285019) (xy 151.80527 -61.31073) (xy 151.751794 -61.32876) (xy 151.696246 -61.338716)
			(xy 151.639837 -61.340381) (xy 151.583798 -61.333719) (xy 151.529351 -61.318874) (xy 151.477686 -61.296171)
			(xy 151.429928 -61.266105) (xy 151.387121 -61.229332) (xy 151.350197 -61.186654) (xy 151.319963 -61.139002)
			(xy 151.297077 -61.087417) (xy 151.282041 -61.033023) (xy 151.275181 -60.977008) (xy 151.276647 -60.920594)
			(xy 151.286407 -60.86501) (xy 151.294846 -60.83808) (xy 151.301552 -60.816206) (xy 151.307985 -60.770917)
			(xy 151.30621 -60.725207) (xy 151.296285 -60.680552) (xy 151.27853 -60.638394) (xy 151.253518 -60.600094)
			(xy 151.222057 -60.566887) (xy 151.185161 -60.539845) (xy 151.144022 -60.519841) (xy 151.122126 -60.513214)
			(xy 151.09576 -60.505284) (xy 151.045434 -60.482954) (xy 150.998842 -60.453622) (xy 150.95695 -60.417895)
			(xy 150.920631 -60.376517) (xy 150.890638 -60.330347) (xy 150.867594 -60.280344) (xy 150.851979 -60.227548)
			(xy 150.844117 -60.173056) (xy 139.027384 -60.173056) (xy 139.003027 -60.219449) (xy 138.968876 -60.265854)
			(xy 138.928133 -60.306594) (xy 138.881725 -60.340742) (xy 138.830709 -60.367521) (xy 138.776245 -60.386322)
			(xy 138.748008 -60.392056) (xy 138.709146 -60.399168) (xy 137.892536 -61.215778) (xy 137.892536 -61.957966)
			(xy 139.328142 -61.957966) (xy 139.332213 -61.902344) (xy 139.344339 -61.847907) (xy 139.364262 -61.795816)
			(xy 139.391558 -61.747181) (xy 139.425644 -61.703038) (xy 139.465793 -61.664329) (xy 139.511151 -61.631878)
			(xy 139.560751 -61.606377) (xy 139.613535 -61.58837) (xy 139.668378 -61.57824) (xy 139.724112 -61.576203)
			(xy 139.779549 -61.582303) (xy 139.833506 -61.596409) (xy 139.884835 -61.618221) (xy 139.932441 -61.647275)
			(xy 139.975309 -61.68295) (xy 140.012526 -61.724487) (xy 140.043299 -61.771) (xy 140.066971 -61.821497)
			(xy 140.083039 -61.874904) (xy 140.091159 -61.93008) (xy 140.091668 -61.957966) (xy 140.091159 -61.985852)
			(xy 140.083039 -62.041028) (xy 140.066971 -62.094435) (xy 140.043299 -62.144932) (xy 140.012526 -62.191445)
			(xy 139.975309 -62.232982) (xy 139.932441 -62.268657) (xy 139.884835 -62.297711) (xy 139.833506 -62.319523)
			(xy 139.779549 -62.333629) (xy 139.724112 -62.339729) (xy 139.668378 -62.337692) (xy 139.613535 -62.327562)
			(xy 139.560751 -62.309555) (xy 139.511151 -62.284054) (xy 139.465793 -62.251603) (xy 139.425644 -62.212894)
			(xy 139.391558 -62.168751) (xy 139.364262 -62.120116) (xy 139.344339 -62.068025) (xy 139.332213 -62.013588)
			(xy 139.328142 -61.957966) (xy 137.892536 -61.957966) (xy 137.892536 -62.41415) (xy 138.226544 -62.41415)
			(xy 138.230615 -62.358528) (xy 138.242741 -62.304091) (xy 138.262664 -62.252) (xy 138.28996 -62.203365)
			(xy 138.324046 -62.159222) (xy 138.364195 -62.120513) (xy 138.409553 -62.088062) (xy 138.459153 -62.062561)
			(xy 138.511937 -62.044554) (xy 138.56678 -62.034424) (xy 138.622514 -62.032387) (xy 138.677951 -62.038487)
			(xy 138.731908 -62.052593) (xy 138.783237 -62.074405) (xy 138.830843 -62.103459) (xy 138.873711 -62.139134)
			(xy 138.910928 -62.180671) (xy 138.941701 -62.227184) (xy 138.965373 -62.277681) (xy 138.981441 -62.331088)
			(xy 138.989561 -62.386264) (xy 138.99007 -62.41415) (xy 138.989561 -62.442036) (xy 138.981441 -62.497212)
			(xy 138.965373 -62.550619) (xy 138.941701 -62.601116) (xy 138.910928 -62.647629) (xy 138.899824 -62.660022)
			(xy 143.045686 -62.660022) (xy 143.049757 -62.6044) (xy 143.061883 -62.549963) (xy 143.081806 -62.497872)
			(xy 143.109102 -62.449237) (xy 143.143188 -62.405094) (xy 143.183337 -62.366385) (xy 143.228695 -62.333934)
			(xy 143.278295 -62.308433) (xy 143.331079 -62.290426) (xy 143.385922 -62.280296) (xy 143.441656 -62.278259)
			(xy 143.497093 -62.284359) (xy 143.55105 -62.298465) (xy 143.602379 -62.320277) (xy 143.649985 -62.349331)
			(xy 143.692853 -62.385006) (xy 143.73007 -62.426543) (xy 143.760843 -62.473056) (xy 143.784515 -62.523553)
			(xy 143.800583 -62.57696) (xy 143.808703 -62.632136) (xy 143.809212 -62.660022) (xy 144.798286 -62.660022)
			(xy 144.802357 -62.6044) (xy 144.814483 -62.549963) (xy 144.834406 -62.497872) (xy 144.861702 -62.449237)
			(xy 144.895788 -62.405094) (xy 144.935937 -62.366385) (xy 144.981295 -62.333934) (xy 145.030895 -62.308433)
			(xy 145.083679 -62.290426) (xy 145.138522 -62.280296) (xy 145.194256 -62.278259) (xy 145.249693 -62.284359)
			(xy 145.30365 -62.298465) (xy 145.354979 -62.320277) (xy 145.402585 -62.349331) (xy 145.445453 -62.385006)
			(xy 145.48267 -62.426543) (xy 145.513443 -62.473056) (xy 145.537115 -62.523553) (xy 145.553183 -62.57696)
			(xy 145.561303 -62.632136) (xy 145.561812 -62.660022) (xy 146.449286 -62.660022) (xy 146.453357 -62.6044)
			(xy 146.465483 -62.549963) (xy 146.485406 -62.497872) (xy 146.512702 -62.449237) (xy 146.546788 -62.405094)
			(xy 146.586937 -62.366385) (xy 146.632295 -62.333934) (xy 146.681895 -62.308433) (xy 146.734679 -62.290426)
			(xy 146.789522 -62.280296) (xy 146.845256 -62.278259) (xy 146.900693 -62.284359) (xy 146.95465 -62.298465)
			(xy 147.005979 -62.320277) (xy 147.053585 -62.349331) (xy 147.096453 -62.385006) (xy 147.13367 -62.426543)
			(xy 147.164443 -62.473056) (xy 147.188115 -62.523553) (xy 147.204183 -62.57696) (xy 147.212303 -62.632136)
			(xy 147.212812 -62.660022) (xy 147.212303 -62.687908) (xy 147.204319 -62.74216) (xy 150.204447 -62.74216)
			(xy 150.210774 -62.68708) (xy 150.225008 -62.633495) (xy 150.24685 -62.582536) (xy 150.275838 -62.535275)
			(xy 150.311362 -62.492709) (xy 150.352674 -62.455733) (xy 150.398904 -62.425127) (xy 150.449077 -62.401536)
			(xy 150.502136 -62.385456) (xy 150.556965 -62.377227) (xy 150.612407 -62.377021) (xy 150.667295 -62.384843)
			(xy 150.720473 -62.400529) (xy 150.77082 -62.423747) (xy 150.817275 -62.454009) (xy 150.85886 -62.490677)
			(xy 150.8947 -62.532978) (xy 150.924038 -62.580023) (xy 150.946257 -62.630818) (xy 150.960888 -62.684296)
			(xy 150.967625 -62.739327) (xy 150.966323 -62.794755) (xy 150.957012 -62.84941) (xy 150.939887 -62.902142)
			(xy 150.915309 -62.951839) (xy 150.883796 -62.997455) (xy 150.846011 -63.038028) (xy 150.824692 -63.055754)
			(xy 150.80717 -63.07042) (xy 150.777211 -63.104917) (xy 150.753902 -63.144213) (xy 150.737993 -63.187044)
			(xy 150.729998 -63.232029) (xy 150.730173 -63.277718) (xy 150.738514 -63.32264) (xy 150.754751 -63.365348)
			(xy 150.778361 -63.404464) (xy 150.808584 -63.43873) (xy 150.819745 -63.44793) (xy 151.198578 -63.44793)
			(xy 151.202649 -63.392308) (xy 151.214775 -63.337871) (xy 151.234698 -63.28578) (xy 151.261994 -63.237145)
			(xy 151.29608 -63.193002) (xy 151.336229 -63.154293) (xy 151.381587 -63.121842) (xy 151.431187 -63.096341)
			(xy 151.483971 -63.078334) (xy 151.538814 -63.068204) (xy 151.594548 -63.066167) (xy 151.649985 -63.072267)
			(xy 151.703942 -63.086373) (xy 151.755271 -63.108185) (xy 151.802877 -63.137239) (xy 151.845745 -63.172914)
			(xy 151.882962 -63.214451) (xy 151.913735 -63.260964) (xy 151.937407 -63.311461) (xy 151.953475 -63.364868)
			(xy 151.961595 -63.420044) (xy 151.962104 -63.44793) (xy 151.9616 -63.475548) (xy 152.240944 -63.475548)
			(xy 152.240948 -63.420206) (xy 152.248947 -63.365444) (xy 152.264773 -63.312413) (xy 152.288095 -63.262225)
			(xy 152.318423 -63.215933) (xy 152.355121 -63.174508) (xy 152.397418 -63.138819) (xy 152.444428 -63.109616)
			(xy 152.495164 -63.087511) (xy 152.548561 -63.072967) (xy 152.603499 -63.066291) (xy 152.658825 -63.067622)
			(xy 152.713379 -63.076931) (xy 152.766015 -63.094025) (xy 152.815629 -63.118544) (xy 152.861181 -63.149973)
			(xy 152.901714 -63.187654) (xy 152.91943 -63.208916) (xy 152.934053 -63.226285) (xy 152.96835 -63.256032)
			(xy 153.007386 -63.279211) (xy 153.049919 -63.295087) (xy 153.094596 -63.303153) (xy 153.139996 -63.303153)
			(xy 153.184673 -63.295087) (xy 153.227206 -63.279211) (xy 153.266242 -63.256032) (xy 153.300539 -63.226285)
			(xy 153.315162 -63.208916) (xy 153.332197 -63.188559) (xy 153.370863 -63.152198) (xy 153.414197 -63.121547)
			(xy 153.46136 -63.097198) (xy 153.511443 -63.079622) (xy 153.563479 -63.069156) (xy 153.616463 -63.066005)
			(xy 153.669372 -63.070227) (xy 153.721186 -63.081742) (xy 153.770903 -63.100328) (xy 153.817564 -63.125626)
			(xy 153.860269 -63.157147) (xy 153.87955 -63.175388) (xy 153.895499 -63.190343) (xy 153.93153 -63.215103)
			(xy 153.971268 -63.23333) (xy 154.013539 -63.244485) (xy 154.057096 -63.248241) (xy 154.100653 -63.244485)
			(xy 154.142924 -63.23333) (xy 154.182662 -63.215103) (xy 154.218693 -63.190343) (xy 154.234642 -63.175388)
			(xy 154.254945 -63.156126) (xy 154.300217 -63.123223) (xy 154.34981 -63.097286) (xy 154.40266 -63.078872)
			(xy 154.457633 -63.068377) (xy 154.513549 -63.066026) (xy 154.569209 -63.071869) (xy 154.623419 -63.08578)
			(xy 154.675014 -63.107462) (xy 154.722888 -63.136448) (xy 154.766014 -63.172118) (xy 154.803466 -63.213705)
			(xy 154.834441 -63.260318) (xy 154.858275 -63.310955) (xy 154.874454 -63.364531) (xy 154.882633 -63.419896)
			(xy 154.882636 -63.475862) (xy 154.874463 -63.531228) (xy 154.85829 -63.584806) (xy 154.834462 -63.635446)
			(xy 154.803492 -63.682062) (xy 154.766045 -63.723653) (xy 154.722922 -63.759327) (xy 154.675051 -63.788319)
			(xy 154.623458 -63.810007) (xy 154.569251 -63.823924) (xy 154.513591 -63.829773) (xy 154.457675 -63.827428)
			(xy 154.4027 -63.816939) (xy 154.349848 -63.798531) (xy 154.300253 -63.7726) (xy 154.254977 -63.739701)
			(xy 154.234642 -63.720472) (xy 154.218693 -63.705517) (xy 154.182662 -63.680757) (xy 154.142924 -63.66253)
			(xy 154.100653 -63.651375) (xy 154.057096 -63.647619) (xy 154.013539 -63.651375) (xy 153.971268 -63.66253)
			(xy 153.93153 -63.680757) (xy 153.895499 -63.705517) (xy 153.87955 -63.720472) (xy 153.860226 -63.738674)
			(xy 153.817531 -63.770214) (xy 153.770875 -63.79553) (xy 153.721159 -63.814132) (xy 153.669345 -63.825661)
			(xy 153.616432 -63.829895) (xy 153.563443 -63.826752) (xy 153.511402 -63.816292) (xy 153.461314 -63.798717)
			(xy 153.414147 -63.774367) (xy 153.370811 -63.743713) (xy 153.332144 -63.707346) (xy 153.315162 -63.686944)
			(xy 153.300539 -63.669575) (xy 153.266242 -63.639828) (xy 153.227206 -63.616649) (xy 153.184673 -63.600773)
			(xy 153.139996 -63.592707) (xy 153.094596 -63.592707) (xy 153.049919 -63.600773) (xy 153.007386 -63.616649)
			(xy 152.96835 -63.639828) (xy 152.934053 -63.669575) (xy 152.91943 -63.686944) (xy 152.901682 -63.70818)
			(xy 152.861144 -63.745856) (xy 152.815589 -63.77728) (xy 152.765971 -63.801793) (xy 152.713333 -63.81888)
			(xy 152.658779 -63.828183) (xy 152.603452 -63.829507) (xy 152.548515 -63.822824) (xy 152.49512 -63.808274)
			(xy 152.444387 -63.786162) (xy 152.39738 -63.756953) (xy 152.355087 -63.721259) (xy 152.318394 -63.67983)
			(xy 152.288072 -63.633534) (xy 152.264756 -63.583343) (xy 152.248936 -63.53031) (xy 152.240944 -63.475548)
			(xy 151.9616 -63.475548) (xy 151.961595 -63.475816) (xy 151.953475 -63.530992) (xy 151.937407 -63.584399)
			(xy 151.913735 -63.634896) (xy 151.882962 -63.681409) (xy 151.845745 -63.722946) (xy 151.802877 -63.758621)
			(xy 151.755271 -63.787675) (xy 151.703942 -63.809487) (xy 151.649985 -63.823593) (xy 151.594548 -63.829693)
			(xy 151.538814 -63.827656) (xy 151.483971 -63.817526) (xy 151.431187 -63.799519) (xy 151.381587 -63.774018)
			(xy 151.336229 -63.741567) (xy 151.29608 -63.702858) (xy 151.261994 -63.658715) (xy 151.234698 -63.61008)
			(xy 151.214775 -63.557989) (xy 151.202649 -63.503552) (xy 151.198578 -63.44793) (xy 150.819745 -63.44793)
			(xy 150.826216 -63.453264) (xy 150.847631 -63.470874) (xy 150.885712 -63.511167) (xy 150.91756 -63.556547)
			(xy 150.942503 -63.60606) (xy 150.960015 -63.658662) (xy 150.969729 -63.713246) (xy 150.971438 -63.76866)
			(xy 150.965108 -63.823738) (xy 150.950871 -63.87732) (xy 150.929028 -63.928276) (xy 150.900038 -63.975533)
			(xy 150.864513 -64.018096) (xy 150.8232 -64.055069) (xy 150.776971 -64.085671) (xy 150.726798 -64.109259)
			(xy 150.673739 -64.125335) (xy 150.618912 -64.133561) (xy 150.563472 -64.133763) (xy 150.508586 -64.125938)
			(xy 150.455411 -64.11025) (xy 150.405068 -64.08703) (xy 150.358616 -64.056766) (xy 150.317034 -64.020097)
			(xy 150.281199 -63.977795) (xy 150.251864 -63.93075) (xy 150.229649 -63.879955) (xy 150.215021 -63.826479)
			(xy 150.208289 -63.771448) (xy 150.209593 -63.716023) (xy 150.218907 -63.66137) (xy 150.236035 -63.608642)
			(xy 150.260615 -63.558948) (xy 150.29213 -63.513336) (xy 150.329916 -63.472766) (xy 150.351236 -63.455042)
			(xy 150.36876 -63.440379) (xy 150.398716 -63.405881) (xy 150.422022 -63.366583) (xy 150.437929 -63.323752)
			(xy 150.445923 -63.278768) (xy 150.445747 -63.23308) (xy 150.437407 -63.188158) (xy 150.421171 -63.145451)
			(xy 150.397563 -63.106334) (xy 150.367342 -63.072068) (xy 150.349712 -63.057532) (xy 150.328274 -63.039949)
			(xy 150.290189 -62.999658) (xy 150.258338 -62.954277) (xy 150.233392 -62.904764) (xy 150.215876 -62.852161)
			(xy 150.206159 -62.797576) (xy 150.204447 -62.74216) (xy 147.204319 -62.74216) (xy 147.204183 -62.743084)
			(xy 147.188115 -62.796491) (xy 147.164443 -62.846988) (xy 147.13367 -62.893501) (xy 147.096453 -62.935038)
			(xy 147.053585 -62.970713) (xy 147.005979 -62.999767) (xy 146.95465 -63.021579) (xy 146.900693 -63.035685)
			(xy 146.845256 -63.041785) (xy 146.789522 -63.039748) (xy 146.734679 -63.029618) (xy 146.681895 -63.011611)
			(xy 146.632295 -62.98611) (xy 146.586937 -62.953659) (xy 146.546788 -62.91495) (xy 146.512702 -62.870807)
			(xy 146.485406 -62.822172) (xy 146.465483 -62.770081) (xy 146.453357 -62.715644) (xy 146.449286 -62.660022)
			(xy 145.561812 -62.660022) (xy 145.561303 -62.687908) (xy 145.553183 -62.743084) (xy 145.537115 -62.796491)
			(xy 145.513443 -62.846988) (xy 145.48267 -62.893501) (xy 145.445453 -62.935038) (xy 145.402585 -62.970713)
			(xy 145.354979 -62.999767) (xy 145.30365 -63.021579) (xy 145.249693 -63.035685) (xy 145.194256 -63.041785)
			(xy 145.138522 -63.039748) (xy 145.083679 -63.029618) (xy 145.030895 -63.011611) (xy 144.981295 -62.98611)
			(xy 144.935937 -62.953659) (xy 144.895788 -62.91495) (xy 144.861702 -62.870807) (xy 144.834406 -62.822172)
			(xy 144.814483 -62.770081) (xy 144.802357 -62.715644) (xy 144.798286 -62.660022) (xy 143.809212 -62.660022)
			(xy 143.808703 -62.687908) (xy 143.800583 -62.743084) (xy 143.784515 -62.796491) (xy 143.760843 -62.846988)
			(xy 143.73007 -62.893501) (xy 143.692853 -62.935038) (xy 143.649985 -62.970713) (xy 143.602379 -62.999767)
			(xy 143.55105 -63.021579) (xy 143.497093 -63.035685) (xy 143.441656 -63.041785) (xy 143.385922 -63.039748)
			(xy 143.331079 -63.029618) (xy 143.278295 -63.011611) (xy 143.228695 -62.98611) (xy 143.183337 -62.953659)
			(xy 143.143188 -62.91495) (xy 143.109102 -62.870807) (xy 143.081806 -62.822172) (xy 143.061883 -62.770081)
			(xy 143.049757 -62.715644) (xy 143.045686 -62.660022) (xy 138.899824 -62.660022) (xy 138.873711 -62.689166)
			(xy 138.830843 -62.724841) (xy 138.783237 -62.753895) (xy 138.731908 -62.775707) (xy 138.677951 -62.789813)
			(xy 138.622514 -62.795913) (xy 138.56678 -62.793876) (xy 138.511937 -62.783746) (xy 138.459153 -62.765739)
			(xy 138.409553 -62.740238) (xy 138.364195 -62.707787) (xy 138.324046 -62.669078) (xy 138.28996 -62.624935)
			(xy 138.262664 -62.5763) (xy 138.242741 -62.524209) (xy 138.230615 -62.469772) (xy 138.226544 -62.41415)
			(xy 137.892536 -62.41415) (xy 137.892536 -64.438022) (xy 143.045686 -64.438022) (xy 143.049757 -64.3824)
			(xy 143.061883 -64.327963) (xy 143.081806 -64.275872) (xy 143.109102 -64.227237) (xy 143.143188 -64.183094)
			(xy 143.183337 -64.144385) (xy 143.228695 -64.111934) (xy 143.278295 -64.086433) (xy 143.331079 -64.068426)
			(xy 143.385922 -64.058296) (xy 143.441656 -64.056259) (xy 143.497093 -64.062359) (xy 143.55105 -64.076465)
			(xy 143.602379 -64.098277) (xy 143.649985 -64.127331) (xy 143.692853 -64.163006) (xy 143.73007 -64.204543)
			(xy 143.760843 -64.251056) (xy 143.784515 -64.301553) (xy 143.800583 -64.35496) (xy 143.801593 -64.361822)
			(xy 146.449286 -64.361822) (xy 146.453357 -64.3062) (xy 146.465483 -64.251763) (xy 146.485406 -64.199672)
			(xy 146.512702 -64.151037) (xy 146.546788 -64.106894) (xy 146.586937 -64.068185) (xy 146.632295 -64.035734)
			(xy 146.681895 -64.010233) (xy 146.734679 -63.992226) (xy 146.789522 -63.982096) (xy 146.845256 -63.980059)
			(xy 146.900693 -63.986159) (xy 146.95465 -64.000265) (xy 147.005979 -64.022077) (xy 147.053585 -64.051131)
			(xy 147.096453 -64.086806) (xy 147.13367 -64.128343) (xy 147.164443 -64.174856) (xy 147.188115 -64.225353)
			(xy 147.204183 -64.27876) (xy 147.212303 -64.333936) (xy 147.212812 -64.361822) (xy 147.212303 -64.389708)
			(xy 147.204183 -64.444884) (xy 147.188115 -64.498291) (xy 147.164443 -64.548788) (xy 147.13367 -64.595301)
			(xy 147.096453 -64.636838) (xy 147.053585 -64.672513) (xy 147.005979 -64.701567) (xy 146.95465 -64.723379)
			(xy 146.900693 -64.737485) (xy 146.845256 -64.743585) (xy 146.789522 -64.741548) (xy 146.734679 -64.731418)
			(xy 146.681895 -64.713411) (xy 146.632295 -64.68791) (xy 146.586937 -64.655459) (xy 146.546788 -64.61675)
			(xy 146.512702 -64.572607) (xy 146.485406 -64.523972) (xy 146.465483 -64.471881) (xy 146.453357 -64.417444)
			(xy 146.449286 -64.361822) (xy 143.801593 -64.361822) (xy 143.808703 -64.410136) (xy 143.809212 -64.438022)
			(xy 143.808703 -64.465908) (xy 143.800583 -64.521084) (xy 143.784515 -64.574491) (xy 143.760843 -64.624988)
			(xy 143.73007 -64.671501) (xy 143.692853 -64.713038) (xy 143.649985 -64.748713) (xy 143.602379 -64.777767)
			(xy 143.55105 -64.799579) (xy 143.497093 -64.813685) (xy 143.441656 -64.819785) (xy 143.385922 -64.817748)
			(xy 143.331079 -64.807618) (xy 143.278295 -64.789611) (xy 143.228695 -64.76411) (xy 143.183337 -64.731659)
			(xy 143.143188 -64.69295) (xy 143.109102 -64.648807) (xy 143.081806 -64.600172) (xy 143.061883 -64.548081)
			(xy 143.049757 -64.493644) (xy 143.045686 -64.438022) (xy 137.892536 -64.438022) (xy 137.892536 -65.20053)
			(xy 150.538178 -65.20053) (xy 150.542249 -65.144908) (xy 150.554375 -65.090471) (xy 150.574298 -65.03838)
			(xy 150.601594 -64.989745) (xy 150.63568 -64.945602) (xy 150.675829 -64.906893) (xy 150.721187 -64.874442)
			(xy 150.770787 -64.848941) (xy 150.823571 -64.830934) (xy 150.878414 -64.820804) (xy 150.934148 -64.818767)
			(xy 150.989585 -64.824867) (xy 151.043542 -64.838973) (xy 151.094871 -64.860785) (xy 151.142477 -64.889839)
			(xy 151.185345 -64.925514) (xy 151.222562 -64.967051) (xy 151.253335 -65.013564) (xy 151.277007 -65.064061)
			(xy 151.293075 -65.117468) (xy 151.301195 -65.172644) (xy 151.301704 -65.20053) (xy 151.301195 -65.228416)
			(xy 151.293075 -65.283592) (xy 151.277007 -65.336999) (xy 151.253335 -65.387496) (xy 151.222562 -65.434009)
			(xy 151.185345 -65.475546) (xy 151.142477 -65.511221) (xy 151.094871 -65.540275) (xy 151.043542 -65.562087)
			(xy 150.989585 -65.576193) (xy 150.934148 -65.582293) (xy 150.878414 -65.580256) (xy 150.823571 -65.570126)
			(xy 150.770787 -65.552119) (xy 150.721187 -65.526618) (xy 150.675829 -65.494167) (xy 150.63568 -65.455458)
			(xy 150.601594 -65.411315) (xy 150.574298 -65.36268) (xy 150.554375 -65.310589) (xy 150.542249 -65.256152)
			(xy 150.538178 -65.20053) (xy 137.892536 -65.20053) (xy 137.892536 -65.64376) (xy 137.802112 -65.734184)
			(xy 137.802112 -66.063622) (xy 143.045686 -66.063622) (xy 143.049757 -66.008) (xy 143.061883 -65.953563)
			(xy 143.081806 -65.901472) (xy 143.109102 -65.852837) (xy 143.143188 -65.808694) (xy 143.183337 -65.769985)
			(xy 143.228695 -65.737534) (xy 143.278295 -65.712033) (xy 143.331079 -65.694026) (xy 143.385922 -65.683896)
			(xy 143.441656 -65.681859) (xy 143.497093 -65.687959) (xy 143.55105 -65.702065) (xy 143.602379 -65.723877)
			(xy 143.649985 -65.752931) (xy 143.692853 -65.788606) (xy 143.73007 -65.830143) (xy 143.760843 -65.876656)
			(xy 143.784515 -65.927153) (xy 143.800583 -65.98056) (xy 143.808703 -66.035736) (xy 143.809212 -66.063622)
			(xy 144.772886 -66.063622) (xy 144.776957 -66.008) (xy 144.789083 -65.953563) (xy 144.809006 -65.901472)
			(xy 144.836302 -65.852837) (xy 144.870388 -65.808694) (xy 144.910537 -65.769985) (xy 144.955895 -65.737534)
			(xy 145.005495 -65.712033) (xy 145.058279 -65.694026) (xy 145.113122 -65.683896) (xy 145.168856 -65.681859)
			(xy 145.224293 -65.687959) (xy 145.27825 -65.702065) (xy 145.329579 -65.723877) (xy 145.377185 -65.752931)
			(xy 145.420053 -65.788606) (xy 145.45727 -65.830143) (xy 145.488043 -65.876656) (xy 145.511715 -65.927153)
			(xy 145.527783 -65.98056) (xy 145.535903 -66.035736) (xy 145.536412 -66.063622) (xy 146.449286 -66.063622)
			(xy 146.453357 -66.008) (xy 146.465483 -65.953563) (xy 146.485406 -65.901472) (xy 146.512702 -65.852837)
			(xy 146.546788 -65.808694) (xy 146.586937 -65.769985) (xy 146.632295 -65.737534) (xy 146.681895 -65.712033)
			(xy 146.734679 -65.694026) (xy 146.789522 -65.683896) (xy 146.845256 -65.681859) (xy 146.900693 -65.687959)
			(xy 146.95465 -65.702065) (xy 147.005979 -65.723877) (xy 147.053585 -65.752931) (xy 147.096453 -65.788606)
			(xy 147.13367 -65.830143) (xy 147.164443 -65.876656) (xy 147.188115 -65.927153) (xy 147.204183 -65.98056)
			(xy 147.212303 -66.035736) (xy 147.212812 -66.063622) (xy 147.212303 -66.091508) (xy 147.204183 -66.146684)
			(xy 147.188115 -66.200091) (xy 147.164443 -66.250588) (xy 147.13367 -66.297101) (xy 147.096453 -66.338638)
			(xy 147.053585 -66.374313) (xy 147.005979 -66.403367) (xy 146.95465 -66.425179) (xy 146.900693 -66.439285)
			(xy 146.845256 -66.445385) (xy 146.789522 -66.443348) (xy 146.734679 -66.433218) (xy 146.681895 -66.415211)
			(xy 146.632295 -66.38971) (xy 146.586937 -66.357259) (xy 146.546788 -66.31855) (xy 146.512702 -66.274407)
			(xy 146.485406 -66.225772) (xy 146.465483 -66.173681) (xy 146.453357 -66.119244) (xy 146.449286 -66.063622)
			(xy 145.536412 -66.063622) (xy 145.535903 -66.091508) (xy 145.527783 -66.146684) (xy 145.511715 -66.200091)
			(xy 145.488043 -66.250588) (xy 145.45727 -66.297101) (xy 145.420053 -66.338638) (xy 145.377185 -66.374313)
			(xy 145.329579 -66.403367) (xy 145.27825 -66.425179) (xy 145.224293 -66.439285) (xy 145.168856 -66.445385)
			(xy 145.113122 -66.443348) (xy 145.058279 -66.433218) (xy 145.005495 -66.415211) (xy 144.955895 -66.38971)
			(xy 144.910537 -66.357259) (xy 144.870388 -66.31855) (xy 144.836302 -66.274407) (xy 144.809006 -66.225772)
			(xy 144.789083 -66.173681) (xy 144.776957 -66.119244) (xy 144.772886 -66.063622) (xy 143.809212 -66.063622)
			(xy 143.808703 -66.091508) (xy 143.800583 -66.146684) (xy 143.784515 -66.200091) (xy 143.760843 -66.250588)
			(xy 143.73007 -66.297101) (xy 143.692853 -66.338638) (xy 143.649985 -66.374313) (xy 143.602379 -66.403367)
			(xy 143.55105 -66.425179) (xy 143.497093 -66.439285) (xy 143.441656 -66.445385) (xy 143.385922 -66.443348)
			(xy 143.331079 -66.433218) (xy 143.278295 -66.415211) (xy 143.228695 -66.38971) (xy 143.183337 -66.357259)
			(xy 143.143188 -66.31855) (xy 143.109102 -66.274407) (xy 143.081806 -66.225772) (xy 143.061883 -66.173681)
			(xy 143.049757 -66.119244) (xy 143.045686 -66.063622) (xy 137.802112 -66.063622) (xy 137.802112 -66.660933)
			(xy 150.462148 -66.660933) (xy 150.464378 -66.605197) (xy 150.4747 -66.550379) (xy 150.492895 -66.497649)
			(xy 150.518573 -66.44813) (xy 150.551189 -66.402878) (xy 150.590046 -66.362857) (xy 150.634316 -66.328921)
			(xy 150.683056 -66.301792) (xy 150.735226 -66.28205) (xy 150.789716 -66.270115) (xy 150.845362 -66.266241)
			(xy 150.900979 -66.270512) (xy 150.955382 -66.282835) (xy 151.007411 -66.302949) (xy 151.055956 -66.330424)
			(xy 151.099983 -66.364675) (xy 151.138554 -66.404972) (xy 151.170846 -66.450455) (xy 151.19617 -66.500156)
			(xy 151.213988 -66.553015) (xy 151.22392 -66.607905) (xy 151.225752 -66.663656) (xy 151.219448 -66.719079)
			(xy 151.20514 -66.772994) (xy 151.183134 -66.824251) (xy 151.153899 -66.871757) (xy 151.13635 -66.89344)
			(xy 151.126263 -66.90622) (xy 151.112353 -66.935647) (xy 151.106329 -66.967634) (xy 151.108581 -67.000106)
			(xy 151.118963 -67.030955) (xy 151.136802 -67.05818) (xy 151.148542 -67.069462) (xy 151.168949 -67.088477)
			(xy 151.204482 -67.131474) (xy 151.233375 -67.179187) (xy 151.255012 -67.230599) (xy 151.268933 -67.284613)
			(xy 151.274841 -67.340078) (xy 151.272609 -67.395813) (xy 151.262285 -67.450628) (xy 151.24409 -67.503356)
			(xy 151.218411 -67.552873) (xy 151.185795 -67.598123) (xy 151.146939 -67.638141) (xy 151.102669 -67.672075)
			(xy 151.05393 -67.699201) (xy 151.001761 -67.718941) (xy 150.947273 -67.730874) (xy 150.891628 -67.734747)
			(xy 150.836013 -67.730475) (xy 150.781612 -67.718151) (xy 150.729586 -67.698037) (xy 150.681043 -67.670561)
			(xy 150.637018 -67.63631) (xy 150.59845 -67.596014) (xy 150.56616 -67.550531) (xy 150.540837 -67.500831)
			(xy 150.523021 -67.447974) (xy 150.513092 -67.393086) (xy 150.51126 -67.337337) (xy 150.517566 -67.281915)
			(xy 150.531874 -67.228002) (xy 150.55388 -67.176748) (xy 150.583115 -67.129244) (xy 150.600664 -67.107562)
			(xy 150.610762 -67.094787) (xy 150.624682 -67.06536) (xy 150.630711 -67.033369) (xy 150.628458 -67.000894)
			(xy 150.618069 -66.970042) (xy 150.600218 -66.942819) (xy 150.588472 -66.93154) (xy 150.56805 -66.912539)
			(xy 150.532515 -66.869542) (xy 150.50362 -66.821828) (xy 150.48198 -66.770416) (xy 150.468057 -66.7164)
			(xy 150.462148 -66.660933) (xy 137.802112 -66.660933) (xy 137.802112 -67.966082) (xy 139.238482 -69.402452)
			(xy 139.757658 -69.402452) (xy 139.793218 -69.372226) (xy 139.814017 -69.355111) (xy 139.85952 -69.326291)
			(xy 139.908626 -69.304159) (xy 139.960356 -69.289155) (xy 140.013683 -69.281578) (xy 140.067545 -69.281578)
			(xy 140.120872 -69.289155) (xy 140.172602 -69.304159) (xy 140.221708 -69.326291) (xy 140.267211 -69.355111)
			(xy 140.28801 -69.372226) (xy 140.32357 -69.402452) (xy 141.753082 -69.402452) (xy 142.14856 -69.79793)
			(xy 147.312378 -69.79793) (xy 147.316449 -69.742308) (xy 147.328575 -69.687871) (xy 147.348498 -69.63578)
			(xy 147.375794 -69.587145) (xy 147.40988 -69.543002) (xy 147.450029 -69.504293) (xy 147.495387 -69.471842)
			(xy 147.544987 -69.446341) (xy 147.597771 -69.428334) (xy 147.652614 -69.418204) (xy 147.708348 -69.416167)
			(xy 147.763785 -69.422267) (xy 147.817742 -69.436373) (xy 147.869071 -69.458185) (xy 147.916677 -69.487239)
			(xy 147.959545 -69.522914) (xy 147.996762 -69.564451) (xy 148.027535 -69.610964) (xy 148.051207 -69.661461)
			(xy 148.067275 -69.714868) (xy 148.075395 -69.770044) (xy 148.075904 -69.79793) (xy 148.075395 -69.825816)
			(xy 148.067275 -69.880992) (xy 148.051207 -69.934399) (xy 148.027535 -69.984896) (xy 147.996762 -70.031409)
			(xy 147.959545 -70.072946) (xy 147.916677 -70.108621) (xy 147.869071 -70.137675) (xy 147.817742 -70.159487)
			(xy 147.763785 -70.173593) (xy 147.708348 -70.179693) (xy 147.652614 -70.177656) (xy 147.597771 -70.167526)
			(xy 147.544987 -70.149519) (xy 147.495387 -70.124018) (xy 147.450029 -70.091567) (xy 147.40988 -70.052858)
			(xy 147.375794 -70.008715) (xy 147.348498 -69.96008) (xy 147.328575 -69.907989) (xy 147.316449 -69.853552)
			(xy 147.312378 -69.79793) (xy 142.14856 -69.79793) (xy 142.926562 -70.575932) (xy 144.692116 -70.575932)
		)
		(stroke
			(width 0)
			(type solid)
		)
		(fill yes)
		(layer "In2.Cu")
		(net "P1V0_SATA")
	)
	(gr_poly
		(pts
			(xy 98.388932 -124.571252) (xy 100.929186 -124.571252) (xy 102.34422 -123.156218) (xy 102.34422 -117.328696)
			(xy 104.96296 -114.709956) (xy 104.97536 -114.696664) (xy 104.992821 -114.664802) (xy 105.000633 -114.629319)
			(xy 105.000044 -114.61115) (xy 104.999282 -114.602006) (xy 104.998774 -114.598196) (xy 104.995659 -114.571069)
			(xy 104.996294 -114.516472) (xy 105.004706 -114.462522) (xy 105.020723 -114.410322) (xy 105.044018 -114.360939)
			(xy 105.074115 -114.315382) (xy 105.110399 -114.27458) (xy 105.15213 -114.239368) (xy 105.198454 -114.210464)
			(xy 105.248426 -114.18846) (xy 105.301024 -114.173805) (xy 105.355174 -114.166798) (xy 105.40977 -114.167582)
			(xy 105.463697 -114.176141) (xy 105.515852 -114.192301) (xy 105.565171 -114.215731) (xy 105.610646 -114.245953)
			(xy 105.651349 -114.282349) (xy 105.686446 -114.324176) (xy 105.715223 -114.370579) (xy 105.73709 -114.420611)
			(xy 105.744772 -114.446812) (xy 105.749669 -114.462651) (xy 105.766371 -114.491276) (xy 105.789881 -114.514634)
			(xy 105.818614 -114.531149) (xy 105.85063 -114.539709) (xy 105.8672 -114.540284) (xy 106.681016 -114.540284)
			(xy 106.703421 -114.5398) (xy 106.747535 -114.531926) (xy 106.789586 -114.516444) (xy 106.828272 -114.493831)
			(xy 106.862397 -114.464788) (xy 106.890904 -114.430215) (xy 106.912911 -114.39118) (xy 106.927736 -114.348893)
			(xy 106.93492 -114.304662) (xy 106.934242 -114.259856) (xy 106.930444 -114.23777) (xy 106.925612 -114.210447)
			(xy 106.922972 -114.155025) (xy 106.928386 -114.099804) (xy 106.941743 -114.045951) (xy 106.962758 -113.9946)
			(xy 106.990991 -113.946834) (xy 107.025844 -113.903662) (xy 107.066583 -113.865993) (xy 107.089194 -113.849912)
			(xy 107.107642 -113.836678) (xy 107.139951 -113.804788) (xy 107.166077 -113.767662) (xy 107.185189 -113.726485)
			(xy 107.196678 -113.682566) (xy 107.200178 -113.637304) (xy 107.195578 -113.592141) (xy 107.183024 -113.548515)
			(xy 107.162915 -113.507815) (xy 107.135893 -113.471336) (xy 107.119674 -113.45545) (xy 107.100286 -113.436552)
			(xy 107.066502 -113.394246) (xy 107.039034 -113.347591) (xy 107.018435 -113.297523) (xy 107.005116 -113.245046)
			(xy 106.999346 -113.191214) (xy 107.001241 -113.137107) (xy 107.010761 -113.083811) (xy 107.027717 -113.032394)
			(xy 107.051768 -112.983889) (xy 107.082431 -112.939269) (xy 107.119091 -112.89943) (xy 107.13974 -112.881918)
			(xy 107.156403 -112.867755) (xy 107.185073 -112.834738) (xy 107.207664 -112.797298) (xy 107.223508 -112.756542)
			(xy 107.232138 -112.713674) (xy 107.233297 -112.669962) (xy 107.226952 -112.626697) (xy 107.21329 -112.585158)
			(xy 107.192715 -112.546574) (xy 107.165835 -112.512083) (xy 107.1499 -112.497108) (xy 107.130014 -112.478411)
			(xy 107.09526 -112.436324) (xy 107.066856 -112.389714) (xy 107.045384 -112.339533) (xy 107.031282 -112.286804)
			(xy 107.024836 -112.232604) (xy 107.02618 -112.178038) (xy 107.035284 -112.124221) (xy 107.051964 -112.07225)
			(xy 107.075879 -112.023186) (xy 107.106542 -111.97803) (xy 107.143325 -111.937704) (xy 107.185479 -111.903031)
			(xy 107.232144 -111.874718) (xy 107.282367 -111.853343) (xy 107.335123 -111.839343) (xy 107.389335 -111.833002)
			(xy 107.443898 -111.834451) (xy 107.497698 -111.84366) (xy 107.549637 -111.860441) (xy 107.598654 -111.884451)
			(xy 107.64375 -111.9152) (xy 107.684005 -111.952062) (xy 107.718596 -111.994283) (xy 107.746819 -112.041003)
			(xy 107.768096 -112.091267) (xy 107.781995 -112.14405) (xy 107.78823 -112.198275) (xy 107.786676 -112.252835)
			(xy 107.777363 -112.306616) (xy 107.760481 -112.358522) (xy 107.736376 -112.407493) (xy 107.705539 -112.45253)
			(xy 107.6686 -112.492713) (xy 107.64774 -112.510316) (xy 107.631081 -112.52448) (xy 107.602419 -112.557497)
			(xy 107.579835 -112.594935) (xy 107.563997 -112.635688) (xy 107.555373 -112.678551) (xy 107.554218 -112.722259)
			(xy 107.560566 -112.765518) (xy 107.574229 -112.80705) (xy 107.594804 -112.845629) (xy 107.621682 -112.880114)
			(xy 107.63758 -112.895126) (xy 107.658465 -112.914794) (xy 107.694677 -112.95929) (xy 107.723816 -113.008707)
			(xy 107.745228 -113.061929) (xy 107.758428 -113.117758) (xy 107.76312 -113.174934) (xy 107.759197 -113.232168)
			(xy 107.746747 -113.288169) (xy 107.726053 -113.341675) (xy 107.72127 -113.35004) (xy 110.542322 -113.35004)
			(xy 110.546393 -113.294418) (xy 110.558519 -113.239981) (xy 110.578442 -113.18789) (xy 110.605738 -113.139255)
			(xy 110.639824 -113.095112) (xy 110.679973 -113.056403) (xy 110.725331 -113.023952) (xy 110.774931 -112.998451)
			(xy 110.827715 -112.980444) (xy 110.882558 -112.970314) (xy 110.938292 -112.968277) (xy 110.993729 -112.974377)
			(xy 111.047686 -112.988483) (xy 111.099015 -113.010295) (xy 111.146621 -113.039349) (xy 111.189489 -113.075024)
			(xy 111.226706 -113.116561) (xy 111.257479 -113.163074) (xy 111.281151 -113.213571) (xy 111.297219 -113.266978)
			(xy 111.305339 -113.322154) (xy 111.305848 -113.35004) (xy 111.305339 -113.377926) (xy 111.297219 -113.433102)
			(xy 111.281151 -113.486509) (xy 111.257479 -113.537006) (xy 111.226706 -113.583519) (xy 111.189489 -113.625056)
			(xy 111.146621 -113.660731) (xy 111.099015 -113.689785) (xy 111.047686 -113.711597) (xy 110.993729 -113.725703)
			(xy 110.938292 -113.731803) (xy 110.882558 -113.729766) (xy 110.827715 -113.719636) (xy 110.774931 -113.701629)
			(xy 110.725331 -113.676128) (xy 110.679973 -113.643677) (xy 110.639824 -113.604968) (xy 110.605738 -113.560825)
			(xy 110.578442 -113.51219) (xy 110.558519 -113.460099) (xy 110.546393 -113.405662) (xy 110.542322 -113.35004)
			(xy 107.72127 -113.35004) (xy 107.697579 -113.391478) (xy 107.661969 -113.436456) (xy 107.620025 -113.475595)
			(xy 107.596686 -113.49228) (xy 107.578239 -113.505515) (xy 107.545931 -113.537406) (xy 107.519805 -113.574532)
			(xy 107.500694 -113.61571) (xy 107.489205 -113.659629) (xy 107.485704 -113.70489) (xy 107.490303 -113.750053)
			(xy 107.502855 -113.79368) (xy 107.522962 -113.834382) (xy 107.549981 -113.870862) (xy 107.566206 -113.886742)
			(xy 107.568238 -113.888774) (xy 107.585859 -113.904817) (xy 107.625876 -113.93068) (xy 107.670011 -113.948637)
			(xy 107.716718 -113.958059) (xy 107.764362 -113.958615) (xy 107.811277 -113.950286) (xy 107.855818 -113.933365)
			(xy 107.896429 -113.908442) (xy 107.91444 -113.892838) (xy 107.935468 -113.8744) (xy 107.98191 -113.843244)
			(xy 108.032403 -113.8192) (xy 108.085864 -113.802784) (xy 108.141149 -113.794347) (xy 108.197073 -113.79407)
			(xy 108.252438 -113.801958) (xy 108.30606 -113.817843) (xy 108.356788 -113.841385) (xy 108.403537 -113.872079)
			(xy 108.445305 -113.909268) (xy 108.463588 -113.93043) (xy 108.478016 -113.946917) (xy 108.511506 -113.975155)
			(xy 108.549343 -113.997232) (xy 108.590405 -114.012492) (xy 108.633476 -114.020485) (xy 108.67728 -114.020972)
			(xy 108.720518 -114.013941) (xy 108.76191 -113.999598) (xy 108.800229 -113.978369) (xy 108.834339 -113.950883)
			(xy 108.84916 -113.934748) (xy 108.867665 -113.914349) (xy 108.90953 -113.878561) (xy 108.956105 -113.849165)
			(xy 109.006422 -113.826771) (xy 109.059437 -113.811845) (xy 109.114047 -113.804696) (xy 109.169118 -113.805474)
			(xy 109.223504 -113.814162) (xy 109.276076 -113.83058) (xy 109.325742 -113.854387) (xy 109.371468 -113.885087)
			(xy 109.412304 -113.922043) (xy 109.447403 -113.964487) (xy 109.476034 -114.011536) (xy 109.497602 -114.062213)
			(xy 109.51166 -114.115465) (xy 109.517915 -114.170184) (xy 109.516237 -114.225235) (xy 109.506661 -114.279472)
			(xy 109.489386 -114.331769) (xy 109.477556 -114.356642) (xy 109.464348 -114.383312) (xy 109.464348 -114.413284)
			(xy 109.464841 -114.429938) (xy 109.47346 -114.462111) (xy 109.490115 -114.490955) (xy 109.51367 -114.514504)
			(xy 109.542519 -114.531152) (xy 109.574694 -114.539763) (xy 109.591348 -114.540284) (xy 109.721396 -114.540284)
			(xy 109.73805 -114.53979) (xy 109.770224 -114.531169) (xy 109.79907 -114.514514) (xy 109.822622 -114.49096)
			(xy 109.839274 -114.462113) (xy 109.847891 -114.429938) (xy 109.848396 -114.413284) (xy 109.848396 -114.38001)
			(xy 109.83214 -114.351054) (xy 109.819276 -114.327113) (xy 109.799709 -114.27641) (xy 109.787536 -114.223443)
			(xy 109.783005 -114.169285) (xy 109.786206 -114.115031) (xy 109.797076 -114.061782) (xy 109.815394 -114.010614)
			(xy 109.840789 -113.962565) (xy 109.872747 -113.918606) (xy 109.910622 -113.879629) (xy 109.953645 -113.846422)
			(xy 110.000945 -113.819658) (xy 110.051566 -113.799879) (xy 110.104482 -113.787485) (xy 110.158621 -113.782727)
			(xy 110.212887 -113.785702) (xy 110.266181 -113.79635) (xy 110.317425 -113.814454) (xy 110.36558 -113.839648)
			(xy 110.409672 -113.871423) (xy 110.448807 -113.909134) (xy 110.482193 -113.952018) (xy 110.509154 -113.999206)
			(xy 110.529145 -114.049744) (xy 110.541759 -114.102607) (xy 110.546743 -114.156726) (xy 110.543995 -114.211004)
			(xy 110.539276 -114.23777) (xy 110.53546 -114.25986) (xy 110.534748 -114.304679) (xy 110.541909 -114.348928)
			(xy 110.556722 -114.391234) (xy 110.578727 -114.430286) (xy 110.607241 -114.464871) (xy 110.641381 -114.493918)
			(xy 110.680087 -114.516525) (xy 110.722159 -114.531992) (xy 110.766292 -114.539837) (xy 110.788704 -114.540284)
			(xy 111.230664 -114.540284) (xy 111.252 -114.53241) (xy 111.273122 -114.524972) (xy 111.31667 -114.514531)
			(xy 111.338868 -114.511582) (xy 111.382556 -114.506248) (xy 111.824516 -114.064288) (xy 111.84023 -114.047899)
			(xy 111.866157 -114.010629) (xy 111.88505 -113.969346) (xy 111.896307 -113.925363) (xy 111.899571 -113.88008)
			(xy 111.894737 -113.834938) (xy 111.881959 -113.791372) (xy 111.861644 -113.75077) (xy 111.834439 -113.714424)
			(xy 111.801208 -113.683489) (xy 111.782352 -113.670842) (xy 111.759453 -113.655546) (xy 111.717894 -113.619417)
			(xy 111.681963 -113.577686) (xy 111.652407 -113.531223) (xy 111.62984 -113.480991) (xy 111.614732 -113.428037)
			(xy 111.607396 -113.37346) (xy 111.607984 -113.318396) (xy 111.616486 -113.263988) (xy 111.632723 -113.211369)
			(xy 111.656358 -113.161632) (xy 111.686901 -113.11581) (xy 111.723716 -113.074857) (xy 111.766037 -113.039625)
			(xy 111.812985 -113.010844) (xy 111.863584 -112.989115) (xy 111.916782 -112.974888) (xy 111.971473 -112.968459)
			(xy 112.02652 -112.969962) (xy 112.080779 -112.979365) (xy 112.133122 -112.996474) (xy 112.18246 -113.020932)
			(xy 112.227767 -113.052232) (xy 112.268103 -113.089721) (xy 112.302628 -113.132622) (xy 112.330625 -113.180041)
			(xy 112.351512 -113.230994) (xy 112.358678 -113.257584) (xy 112.358678 -113.257838) (xy 112.367314 -113.292128)
			(xy 112.42929 -113.354104) (xy 112.5347 -113.354104) (xy 112.623854 -113.26495) (xy 112.633506 -113.238534)
			(xy 112.643471 -113.212719) (xy 112.669782 -113.164041) (xy 112.702848 -113.119673) (xy 112.741975 -113.080546)
			(xy 112.786343 -113.047481) (xy 112.835022 -113.02117) (xy 112.860836 -113.011204) (xy 112.887252 -113.001552)
			(xy 115.93068 -109.958124) (xy 115.93068 -102.003606) (xy 115.40998 -101.482906) (xy 108.540804 -101.482906)
			(xy 107.974638 -102.048818) (xy 107.328716 -102.69474) (xy 101.883718 -102.69474) (xy 101.867034 -102.695238)
			(xy 101.83481 -102.703893) (xy 101.805935 -102.720616) (xy 101.793802 -102.732078) (xy 100.873306 -103.652828)
			(xy 100.863908 -103.673148) (xy 100.852232 -103.697167) (xy 100.82316 -103.741966) (xy 100.788125 -103.782274)
			(xy 100.747811 -103.817302) (xy 100.703007 -103.846366) (xy 100.678996 -103.85806) (xy 100.658676 -103.867458)
			(xy 100.284788 -104.241346) (xy 100.274008 -104.252751) (xy 100.257874 -104.279657) (xy 100.248796 -104.309688)
			(xy 100.247323 -104.341026) (xy 100.253544 -104.371776) (xy 100.259896 -104.386126) (xy 100.271332 -104.411093)
			(xy 100.287721 -104.463504) (xy 100.296424 -104.517724) (xy 100.297263 -104.572632) (xy 100.290221 -104.627092)
			(xy 100.275442 -104.67998) (xy 100.253231 -104.730203) (xy 100.224049 -104.776721) (xy 100.188499 -104.818574)
			(xy 100.147314 -104.854897) (xy 100.101346 -104.88494) (xy 100.051546 -104.90808) (xy 99.998942 -104.923841)
			(xy 99.944622 -104.931895) (xy 99.889708 -104.932077) (xy 99.835336 -104.924384) (xy 99.782628 -104.908973)
			(xy 99.757484 -104.897936) (xy 99.75723 -104.897936) (xy 99.743035 -104.891943) (xy 99.712757 -104.886273)
			(xy 99.682003 -104.88803) (xy 99.652568 -104.897113) (xy 99.626171 -104.91299) (xy 99.61499 -104.92359)
			(xy 98.371091 -106.167489) (xy 102.013946 -106.167489) (xy 102.022058 -106.11216) (xy 102.03816 -106.058608)
			(xy 102.061907 -106.00798) (xy 102.09279 -105.96136) (xy 102.130148 -105.919749) (xy 102.17318 -105.884036)
			(xy 102.220964 -105.854988) (xy 102.272476 -105.833226) (xy 102.326613 -105.819217) (xy 102.382216 -105.813261)
			(xy 102.438092 -105.815485) (xy 102.493045 -105.825841) (xy 102.545898 -105.844109) (xy 102.595518 -105.869896)
			(xy 102.640842 -105.902651) (xy 102.661212 -105.92181) (xy 102.673028 -105.932589) (xy 102.700784 -105.948459)
			(xy 102.731615 -105.956926) (xy 102.763583 -105.957457) (xy 102.794678 -105.950019) (xy 102.822945 -105.93508)
			(xy 102.846608 -105.913578) (xy 102.855776 -105.900474) (xy 102.861364 -105.892346) (xy 102.873269 -105.87445)
			(xy 102.89144 -105.835498) (xy 102.902801 -105.794045) (xy 102.907029 -105.751272) (xy 102.904003 -105.708396)
			(xy 102.893809 -105.666641) (xy 102.876737 -105.627195) (xy 102.853275 -105.591182) (xy 102.839012 -105.5751)
			(xy 102.820751 -105.554646) (xy 102.789649 -105.50949) (xy 102.765334 -105.460346) (xy 102.748307 -105.408226)
			(xy 102.738919 -105.354206) (xy 102.737365 -105.299397) (xy 102.743675 -105.244931) (xy 102.757719 -105.19193)
			(xy 102.779209 -105.141487) (xy 102.807701 -105.09464) (xy 102.824788 -105.073196) (xy 102.838731 -105.05563)
			(xy 102.86076 -105.016567) (xy 102.875594 -104.974246) (xy 102.882774 -104.929979) (xy 102.882078 -104.885138)
			(xy 102.873525 -104.841116) (xy 102.857383 -104.799276) (xy 102.834151 -104.760916) (xy 102.819708 -104.743758)
			(xy 102.80153 -104.722424) (xy 102.771091 -104.675359) (xy 102.747866 -104.624347) (xy 102.732357 -104.570486)
			(xy 102.724896 -104.514934) (xy 102.725645 -104.458889) (xy 102.734587 -104.403557) (xy 102.751529 -104.350129)
			(xy 102.776108 -104.299755) (xy 102.807794 -104.253521) (xy 102.845904 -104.212421) (xy 102.889618 -104.17734)
			(xy 102.937995 -104.149034) (xy 102.989994 -104.128111) (xy 103.044495 -104.115024) (xy 103.100324 -104.110052)
			(xy 103.15628 -104.113304) (xy 103.211157 -104.124709) (xy 103.263775 -104.144022) (xy 103.313 -104.170826)
			(xy 103.357773 -104.204546) (xy 103.397129 -104.244454) (xy 103.405075 -104.255316) (xy 106.826302 -104.255316)
			(xy 106.830373 -104.199694) (xy 106.842499 -104.145257) (xy 106.862422 -104.093166) (xy 106.889718 -104.044531)
			(xy 106.923804 -104.000388) (xy 106.963953 -103.961679) (xy 107.009311 -103.929228) (xy 107.058911 -103.903727)
			(xy 107.111695 -103.88572) (xy 107.166538 -103.87559) (xy 107.222272 -103.873553) (xy 107.277709 -103.879653)
			(xy 107.331666 -103.893759) (xy 107.382995 -103.915571) (xy 107.430601 -103.944625) (xy 107.473469 -103.9803)
			(xy 107.510686 -104.021837) (xy 107.541459 -104.06835) (xy 107.565131 -104.118847) (xy 107.581199 -104.172254)
			(xy 107.589319 -104.22743) (xy 107.589828 -104.255316) (xy 107.589587 -104.268543) (xy 110.456136 -104.268543)
			(xy 110.461558 -104.213103) (xy 110.474985 -104.15904) (xy 110.496133 -104.107505) (xy 110.524552 -104.059594)
			(xy 110.559637 -104.016325) (xy 110.600642 -103.97862) (xy 110.646695 -103.94728) (xy 110.696816 -103.922971)
			(xy 110.749941 -103.906211) (xy 110.804938 -103.897355) (xy 110.860638 -103.896593) (xy 110.915857 -103.90394)
			(xy 110.969419 -103.919241) (xy 111.020187 -103.942169) (xy 111.067081 -103.972238) (xy 111.088424 -103.99014)
			(xy 111.10504 -104.003941) (xy 111.141957 -104.026356) (xy 111.182132 -104.042205) (xy 111.224409 -104.051032)
			(xy 111.26757 -104.052584) (xy 111.310372 -104.046815) (xy 111.351582 -104.033892) (xy 111.390013 -104.014186)
			(xy 111.424559 -103.988265) (xy 111.439706 -103.972868) (xy 111.459183 -103.952951) (xy 111.502946 -103.918481)
			(xy 111.551256 -103.890743) (xy 111.603087 -103.870326) (xy 111.657337 -103.857665) (xy 111.712851 -103.853029)
			(xy 111.768449 -103.856516) (xy 111.822949 -103.868053) (xy 111.875191 -103.887394) (xy 111.924064 -103.914127)
			(xy 111.96853 -103.947685) (xy 112.007642 -103.987354) (xy 112.040568 -104.032289) (xy 112.066609 -104.081535)
			(xy 112.08521 -104.134045) (xy 112.095976 -104.188703) (xy 112.097531 -104.220745) (xy 112.399364 -104.220745)
			(xy 112.405505 -104.165327) (xy 112.419649 -104.111393) (xy 112.441493 -104.060093) (xy 112.470572 -104.012519)
			(xy 112.506266 -103.969685) (xy 112.547816 -103.932503) (xy 112.594336 -103.901766) (xy 112.644835 -103.878128)
			(xy 112.698237 -103.862093) (xy 112.753404 -103.854003) (xy 112.809162 -103.85403) (xy 112.864321 -103.862173)
			(xy 112.917707 -103.878259) (xy 112.968184 -103.901945) (xy 113.014674 -103.932727) (xy 113.056188 -103.969949)
			(xy 113.091842 -104.012817) (xy 113.120875 -104.060419) (xy 113.14267 -104.11174) (xy 113.156761 -104.165688)
			(xy 113.16285 -104.221111) (xy 113.160805 -104.276831) (xy 113.156238 -104.304338) (xy 113.152527 -104.327255)
			(xy 113.152483 -104.373674) (xy 113.160871 -104.419329) (xy 113.177409 -104.462703) (xy 113.201549 -104.502351)
			(xy 113.232487 -104.536957) (xy 113.269195 -104.565369) (xy 113.310452 -104.586643) (xy 113.354887 -104.600071)
			(xy 113.401021 -104.605207) (xy 113.424208 -104.604058) (xy 113.451613 -104.602638) (xy 113.506346 -104.606567)
			(xy 113.55995 -104.618298) (xy 113.61132 -104.637589) (xy 113.659396 -104.664042) (xy 113.703186 -104.697111)
			(xy 113.741785 -104.736113) (xy 113.774397 -104.780243) (xy 113.80035 -104.828591) (xy 113.819106 -104.880159)
			(xy 113.83028 -104.933882) (xy 113.833641 -104.988652) (xy 113.829119 -105.043339) (xy 113.816808 -105.096813)
			(xy 113.796961 -105.147971) (xy 113.769989 -105.195758) (xy 113.736447 -105.239186) (xy 113.71707 -105.258616)
			(xy 113.701346 -105.274444) (xy 113.675161 -105.310564) (xy 113.655685 -105.350701) (xy 113.643518 -105.393623)
			(xy 113.639034 -105.438009) (xy 113.642369 -105.482497) (xy 113.653422 -105.525719) (xy 113.671853 -105.566346)
			(xy 113.697095 -105.603131) (xy 113.728374 -105.634942) (xy 113.74628 -105.648252) (xy 113.768381 -105.664593)
			(xy 113.808141 -105.702539) (xy 113.842044 -105.745799) (xy 113.869388 -105.793476) (xy 113.889608 -105.844583)
			(xy 113.902284 -105.898063) (xy 113.907154 -105.952809) (xy 113.904118 -106.007687) (xy 113.893239 -106.061561)
			(xy 113.87474 -106.113316) (xy 113.849006 -106.161881) (xy 113.816569 -106.206251) (xy 113.778101 -106.245506)
			(xy 113.734398 -106.278835) (xy 113.686364 -106.305547) (xy 113.634994 -106.32509) (xy 113.581351 -106.337059)
			(xy 113.526546 -106.341206) (xy 113.471713 -106.337445) (xy 113.417987 -106.325854) (xy 113.366481 -106.306674)
			(xy 113.31826 -106.280301) (xy 113.274323 -106.247281) (xy 113.235579 -106.208298) (xy 113.20283 -106.164158)
			(xy 113.176754 -106.115775) (xy 113.157892 -106.064152) (xy 113.146633 -106.010355) (xy 113.14321 -105.9555)
			(xy 113.147695 -105.900722) (xy 113.159994 -105.847154) (xy 113.179853 -105.795905) (xy 113.20686 -105.748037)
			(xy 113.240458 -105.70454) (xy 113.25987 -105.685082) (xy 113.275591 -105.669251) (xy 113.301771 -105.633131)
			(xy 113.321243 -105.592994) (xy 113.333408 -105.550074) (xy 113.337891 -105.505689) (xy 113.334556 -105.461203)
			(xy 113.323505 -105.417982) (xy 113.305077 -105.377356) (xy 113.279838 -105.340571) (xy 113.248564 -105.308757)
			(xy 113.23066 -105.295446) (xy 113.208826 -105.279402) (xy 113.169536 -105.242094) (xy 113.135923 -105.199599)
			(xy 113.108664 -105.152774) (xy 113.088309 -105.102562) (xy 113.075266 -105.049974) (xy 113.0698 -104.996069)
			(xy 113.072019 -104.941933) (xy 113.076482 -104.915208) (xy 113.080229 -104.892294) (xy 113.08028 -104.845868)
			(xy 113.071897 -104.800205) (xy 113.055359 -104.756824) (xy 113.031216 -104.717169) (xy 113.000272 -104.68256)
			(xy 112.963555 -104.654147) (xy 112.922289 -104.632876) (xy 112.877845 -104.619456) (xy 112.831702 -104.614332)
			(xy 112.808512 -104.615488) (xy 112.78067 -104.617002) (xy 112.725066 -104.61287) (xy 112.670656 -104.600688)
			(xy 112.618599 -104.580715) (xy 112.570003 -104.553377) (xy 112.525905 -104.519256) (xy 112.487244 -104.479079)
			(xy 112.454844 -104.433702) (xy 112.429394 -104.384092) (xy 112.411437 -104.331305) (xy 112.401355 -104.276467)
			(xy 112.399364 -104.220745) (xy 112.097531 -104.220745) (xy 112.098677 -104.244344) (xy 112.093258 -104.299788)
			(xy 112.079831 -104.353853) (xy 112.058684 -104.40539) (xy 112.030266 -104.453304) (xy 111.995181 -104.496575)
			(xy 111.954176 -104.534283) (xy 111.908123 -104.565626) (xy 111.858 -104.589937) (xy 111.804874 -104.6067)
			(xy 111.749876 -104.615557) (xy 111.694173 -104.616321) (xy 111.638952 -104.608975) (xy 111.585387 -104.593676)
			(xy 111.534617 -104.570748) (xy 111.487721 -104.54068) (xy 111.466376 -104.522778) (xy 111.449761 -104.508975)
			(xy 111.412844 -104.486559) (xy 111.372669 -104.470708) (xy 111.330391 -104.46188) (xy 111.28723 -104.460328)
			(xy 111.244427 -104.466098) (xy 111.203217 -104.479022) (xy 111.164786 -104.49873) (xy 111.130241 -104.524652)
			(xy 111.115094 -104.54005) (xy 111.095598 -104.559947) (xy 111.051836 -104.594415) (xy 111.003526 -104.62215)
			(xy 110.951696 -104.642565) (xy 110.897448 -104.655224) (xy 110.841936 -104.659858) (xy 110.78634 -104.656369)
			(xy 110.731843 -104.644831) (xy 110.679603 -104.625489) (xy 110.630732 -104.598754) (xy 110.586269 -104.565196)
			(xy 110.54716 -104.525528) (xy 110.514237 -104.480593) (xy 110.488198 -104.431348) (xy 110.4696 -104.378839)
			(xy 110.458836 -104.324183) (xy 110.456136 -104.268543) (xy 107.589587 -104.268543) (xy 107.589319 -104.283202)
			(xy 107.581199 -104.338378) (xy 107.565131 -104.391785) (xy 107.541459 -104.442282) (xy 107.510686 -104.488795)
			(xy 107.473469 -104.530332) (xy 107.430601 -104.566007) (xy 107.382995 -104.595061) (xy 107.331666 -104.616873)
			(xy 107.277709 -104.630979) (xy 107.222272 -104.637079) (xy 107.166538 -104.635042) (xy 107.111695 -104.624912)
			(xy 107.058911 -104.606905) (xy 107.009311 -104.581404) (xy 106.963953 -104.548953) (xy 106.923804 -104.510244)
			(xy 106.889718 -104.466101) (xy 106.862422 -104.417466) (xy 106.842499 -104.365375) (xy 106.830373 -104.310938)
			(xy 106.826302 -104.255316) (xy 103.405075 -104.255316) (xy 103.430222 -104.289692) (xy 103.456339 -104.339286)
			(xy 103.474917 -104.392167) (xy 103.485557 -104.447198) (xy 103.488029 -104.503194) (xy 103.482281 -104.558948)
			(xy 103.468435 -104.613262) (xy 103.446791 -104.664964) (xy 103.417814 -104.712942) (xy 103.400352 -104.734868)
			(xy 103.386442 -104.752459) (xy 103.364407 -104.791515) (xy 103.349567 -104.833831) (xy 103.342381 -104.878095)
			(xy 103.343073 -104.922932) (xy 103.351622 -104.966953) (xy 103.367761 -105.008791) (xy 103.39099 -105.047149)
			(xy 103.405432 -105.064306) (xy 103.423618 -105.085787) (xy 103.454167 -105.133055) (xy 103.477436 -105.184301)
			(xy 103.492918 -105.238411) (xy 103.500278 -105.294209) (xy 103.499665 -105.331563) (xy 106.826608 -105.331563)
			(xy 106.828869 -105.276423) (xy 106.839055 -105.222185) (xy 106.856951 -105.169981) (xy 106.882185 -105.120902)
			(xy 106.91423 -105.075972) (xy 106.952416 -105.03613) (xy 106.995945 -105.002209) (xy 107.04391 -104.974915)
			(xy 107.095307 -104.95482) (xy 107.149064 -104.942343) (xy 107.204059 -104.937744) (xy 107.259141 -104.94112)
			(xy 107.313162 -104.9524) (xy 107.364994 -104.971349) (xy 107.413552 -104.99757) (xy 107.457825 -105.030517)
			(xy 107.496886 -105.0695) (xy 107.529921 -105.113707) (xy 107.556239 -105.162214) (xy 107.57529 -105.214007)
			(xy 107.586678 -105.268005) (xy 107.590163 -105.323081) (xy 107.585674 -105.378085) (xy 107.573304 -105.431867)
			(xy 107.553311 -105.483304) (xy 107.526113 -105.531323) (xy 107.492278 -105.57492) (xy 107.472734 -105.594404)
			(xy 107.456432 -105.610712) (xy 107.429507 -105.64814) (xy 107.409772 -105.68981) (xy 107.397877 -105.734356)
			(xy 107.394211 -105.780318) (xy 107.398043 -105.817854) (xy 108.924517 -105.817854) (xy 108.927434 -105.761769)
			(xy 108.938544 -105.706718) (xy 108.957605 -105.653891) (xy 108.984207 -105.60443) (xy 109.017774 -105.559404)
			(xy 109.05758 -105.519787) (xy 109.102765 -105.486435) (xy 109.152352 -105.460069) (xy 109.205269 -105.441258)
			(xy 109.260372 -105.430411) (xy 109.31647 -105.42776) (xy 109.34446 -105.430066) (xy 109.36576 -105.431724)
			(xy 109.408378 -105.428799) (xy 109.449907 -105.418788) (xy 109.489177 -105.401973) (xy 109.525082 -105.378829)
			(xy 109.556612 -105.350006) (xy 109.582877 -105.316316) (xy 109.603139 -105.278709) (xy 109.610398 -105.258616)
			(xy 109.619486 -105.232999) (xy 109.644049 -105.184509) (xy 109.675244 -105.139995) (xy 109.712439 -105.100356)
			(xy 109.754881 -105.066396) (xy 109.801713 -105.038802) (xy 109.851986 -105.018131) (xy 109.904683 -105.004803)
			(xy 109.958738 -104.999086) (xy 110.013058 -105.001096) (xy 110.066542 -105.010793) (xy 110.11811 -105.027981)
			(xy 110.166718 -105.052311) (xy 110.211381 -105.083292) (xy 110.251197 -105.120297) (xy 110.28536 -105.162576)
			(xy 110.313179 -105.209275) (xy 110.33409 -105.259448) (xy 110.347671 -105.312081) (xy 110.353647 -105.366108)
			(xy 110.351897 -105.420436) (xy 110.342457 -105.473967) (xy 110.325516 -105.525616) (xy 110.301419 -105.57434)
			(xy 110.270653 -105.619151) (xy 110.23384 -105.659144) (xy 110.191725 -105.69351) (xy 110.16869 -105.707942)
			(xy 110.149364 -105.720082) (xy 110.115099 -105.750226) (xy 110.086771 -105.786008) (xy 110.065291 -105.826275)
			(xy 110.051351 -105.869731) (xy 110.045399 -105.914979) (xy 110.047627 -105.960562) (xy 110.057964 -106.005014)
			(xy 110.076075 -106.046904) (xy 110.101379 -106.084884) (xy 110.116874 -106.101642) (xy 110.135899 -106.122026)
			(xy 110.168366 -106.167356) (xy 110.19389 -106.216929) (xy 110.211929 -106.269689) (xy 110.222097 -106.324512)
			(xy 110.224179 -106.380231) (xy 110.218129 -106.43566) (xy 110.204078 -106.489618) (xy 110.182324 -106.540957)
			(xy 110.153331 -106.588584) (xy 110.117715 -106.631485) (xy 110.076234 -106.668745) (xy 110.029773 -106.699573)
			(xy 109.979321 -106.72331) (xy 109.925951 -106.739453) (xy 109.8708 -106.747657) (xy 109.815042 -106.747748)
			(xy 109.759864 -106.739724) (xy 109.706442 -106.723755) (xy 109.655912 -106.700182) (xy 109.609351 -106.669506)
			(xy 109.56775 -106.63238) (xy 109.531994 -106.589596) (xy 109.502845 -106.542064) (xy 109.480924 -106.490796)
			(xy 109.466697 -106.436884) (xy 109.463078 -106.409236) (xy 109.459945 -106.385706) (xy 109.445952 -106.340348)
			(xy 109.423777 -106.29838) (xy 109.394192 -106.261261) (xy 109.358227 -106.230283) (xy 109.317133 -106.206526)
			(xy 109.272341 -106.190816) (xy 109.248956 -106.186732) (xy 109.221278 -106.181967) (xy 109.167597 -106.165461)
			(xy 109.116917 -106.141262) (xy 109.070334 -106.109893) (xy 109.028853 -106.072033) (xy 108.993373 -106.028499)
			(xy 108.964659 -105.980234) (xy 108.943332 -105.92828) (xy 108.929854 -105.87376) (xy 108.924517 -105.817854)
			(xy 107.398043 -105.817854) (xy 107.398893 -105.826186) (xy 107.411772 -105.870458) (xy 107.432423 -105.911682)
			(xy 107.460171 -105.948505) (xy 107.476798 -105.964482) (xy 107.496735 -105.983563) (xy 107.531525 -106.026396)
			(xy 107.559779 -106.073796) (xy 107.580906 -106.124774) (xy 107.594465 -106.178264) (xy 107.600172 -106.233151)
			(xy 107.597909 -106.288286) (xy 107.587723 -106.34252) (xy 107.569827 -106.39472) (xy 107.544593 -106.443795)
			(xy 107.51255 -106.48872) (xy 107.474367 -106.528558) (xy 107.43084 -106.562477) (xy 107.382879 -106.589768)
			(xy 107.331485 -106.609861) (xy 107.277732 -106.622337) (xy 107.222741 -106.626936) (xy 107.167663 -106.62356)
			(xy 107.113646 -106.612281) (xy 107.061818 -106.593334) (xy 107.013263 -106.567116) (xy 106.968993 -106.534172)
			(xy 106.929934 -106.495192) (xy 106.896901 -106.450989) (xy 106.870584 -106.402487) (xy 106.851532 -106.350698)
			(xy 106.840144 -106.296704) (xy 106.836657 -106.241632) (xy 106.841143 -106.186632) (xy 106.853511 -106.132854)
			(xy 106.8735 -106.08142) (xy 106.900694 -106.033403) (xy 106.934524 -105.989808) (xy 106.954066 -105.970324)
			(xy 106.970339 -105.95399) (xy 106.997266 -105.916567) (xy 107.017002 -105.874901) (xy 107.028899 -105.830359)
			(xy 107.032569 -105.784402) (xy 107.02789 -105.738536) (xy 107.015016 -105.694267) (xy 106.994369 -105.653045)
			(xy 106.966627 -105.616223) (xy 106.950002 -105.600246) (xy 106.930063 -105.581165) (xy 106.895268 -105.53833)
			(xy 106.86701 -105.490927) (xy 106.84588 -105.439947) (xy 106.832318 -105.386453) (xy 106.826608 -105.331563)
			(xy 103.499665 -105.331563) (xy 103.499354 -105.350482) (xy 103.490169 -105.406008) (xy 103.47292 -105.459581)
			(xy 103.447983 -105.510036) (xy 103.432356 -105.533444) (xy 103.42047 -105.551352) (xy 103.402305 -105.590302)
			(xy 103.390947 -105.631752) (xy 103.386719 -105.674522) (xy 103.389743 -105.717393) (xy 103.399932 -105.759146)
			(xy 103.416997 -105.798591) (xy 103.44045 -105.834606) (xy 103.454708 -105.85069) (xy 103.472984 -105.871141)
			(xy 103.504103 -105.916305) (xy 103.528433 -105.96546) (xy 103.545473 -106.017592) (xy 103.554872 -106.071627)
			(xy 103.556435 -106.126451) (xy 103.550131 -106.180934) (xy 103.53609 -106.233953) (xy 103.5146 -106.284414)
			(xy 103.486106 -106.331278) (xy 103.451194 -106.373577) (xy 103.410584 -106.410442) (xy 103.365113 -106.44111)
			(xy 103.315719 -106.464951) (xy 103.26342 -106.481472) (xy 103.209295 -106.490333) (xy 103.154458 -106.491352)
			(xy 103.10004 -106.484507) (xy 103.047163 -106.469939) (xy 102.996918 -106.447949) (xy 102.973378 -106.433874)
			(xy 102.952553 -106.421623) (xy 102.907458 -106.404304) (xy 102.859903 -106.39582) (xy 102.811601 -106.396478)
			(xy 102.764293 -106.406253) (xy 102.719687 -106.424794) (xy 102.679388 -106.451432) (xy 102.66172 -106.46791)
			(xy 102.641377 -106.487098) (xy 102.596113 -106.519936) (xy 102.546541 -106.545814) (xy 102.493722 -106.564178)
			(xy 102.438788 -106.574636) (xy 102.382915 -106.576962) (xy 102.327302 -106.571108) (xy 102.273139 -106.557198)
			(xy 102.221587 -106.53553) (xy 102.17375 -106.506569) (xy 102.130653 -106.470936) (xy 102.093219 -106.429393)
			(xy 102.062251 -106.38283) (xy 102.038411 -106.332246) (xy 102.022211 -106.278723) (xy 102.013997 -106.223409)
			(xy 102.013946 -106.167489) (xy 98.371091 -106.167489) (xy 98.284284 -106.254296) (xy 98.284284 -107.890564)
			(xy 102.777542 -107.890564) (xy 102.781613 -107.834942) (xy 102.793739 -107.780505) (xy 102.813662 -107.728414)
			(xy 102.840958 -107.679779) (xy 102.875044 -107.635636) (xy 102.915193 -107.596927) (xy 102.960551 -107.564476)
			(xy 103.010151 -107.538975) (xy 103.062935 -107.520968) (xy 103.117778 -107.510838) (xy 103.173512 -107.508801)
			(xy 103.228949 -107.514901) (xy 103.282906 -107.529007) (xy 103.334235 -107.550819) (xy 103.381841 -107.579873)
			(xy 103.424709 -107.615548) (xy 103.461926 -107.657085) (xy 103.492699 -107.703598) (xy 103.516371 -107.754095)
			(xy 103.532439 -107.807502) (xy 103.535729 -107.829858) (xy 106.732322 -107.829858) (xy 106.736393 -107.774236)
			(xy 106.748519 -107.719799) (xy 106.768442 -107.667708) (xy 106.795738 -107.619073) (xy 106.829824 -107.57493)
			(xy 106.869973 -107.536221) (xy 106.915331 -107.50377) (xy 106.964931 -107.478269) (xy 107.017715 -107.460262)
			(xy 107.072558 -107.450132) (xy 107.128292 -107.448095) (xy 107.183729 -107.454195) (xy 107.237686 -107.468301)
			(xy 107.289015 -107.490113) (xy 107.336621 -107.519167) (xy 107.379489 -107.554842) (xy 107.416706 -107.596379)
			(xy 107.447479 -107.642892) (xy 107.471151 -107.693389) (xy 107.487219 -107.746796) (xy 107.495339 -107.801972)
			(xy 107.495848 -107.829858) (xy 107.495339 -107.857744) (xy 107.487219 -107.91292) (xy 107.471151 -107.966327)
			(xy 107.447479 -108.016824) (xy 107.416706 -108.063337) (xy 107.379489 -108.104874) (xy 107.336621 -108.140549)
			(xy 107.289015 -108.169603) (xy 107.237686 -108.191415) (xy 107.183729 -108.205521) (xy 107.128292 -108.211621)
			(xy 107.072558 -108.209584) (xy 107.017715 -108.199454) (xy 106.964931 -108.181447) (xy 106.915331 -108.155946)
			(xy 106.869973 -108.123495) (xy 106.829824 -108.084786) (xy 106.795738 -108.040643) (xy 106.768442 -107.992008)
			(xy 106.748519 -107.939917) (xy 106.736393 -107.88548) (xy 106.732322 -107.829858) (xy 103.535729 -107.829858)
			(xy 103.540559 -107.862678) (xy 103.541068 -107.890564) (xy 103.540559 -107.91845) (xy 103.532439 -107.973626)
			(xy 103.516371 -108.027033) (xy 103.492699 -108.07753) (xy 103.461926 -108.124043) (xy 103.424709 -108.16558)
			(xy 103.381841 -108.201255) (xy 103.334235 -108.230309) (xy 103.282906 -108.252121) (xy 103.228949 -108.266227)
			(xy 103.173512 -108.272327) (xy 103.117778 -108.27029) (xy 103.062935 -108.26016) (xy 103.010151 -108.242153)
			(xy 102.960551 -108.216652) (xy 102.915193 -108.184201) (xy 102.875044 -108.145492) (xy 102.840958 -108.101349)
			(xy 102.813662 -108.052714) (xy 102.793739 -108.000623) (xy 102.781613 -107.946186) (xy 102.777542 -107.890564)
			(xy 98.284284 -107.890564) (xy 98.284284 -110.033562) (xy 102.780082 -110.033562) (xy 102.784153 -109.97794)
			(xy 102.796279 -109.923503) (xy 102.816202 -109.871412) (xy 102.843498 -109.822777) (xy 102.877584 -109.778634)
			(xy 102.917733 -109.739925) (xy 102.963091 -109.707474) (xy 103.012691 -109.681973) (xy 103.065475 -109.663966)
			(xy 103.120318 -109.653836) (xy 103.176052 -109.651799) (xy 103.231489 -109.657899) (xy 103.285446 -109.672005)
			(xy 103.336775 -109.693817) (xy 103.384381 -109.722871) (xy 103.427249 -109.758546) (xy 103.464466 -109.800083)
			(xy 103.495239 -109.846596) (xy 103.518911 -109.897093) (xy 103.534979 -109.9505) (xy 103.543099 -110.005676)
			(xy 103.543534 -110.029498) (xy 106.747562 -110.029498) (xy 106.751633 -109.973876) (xy 106.763759 -109.919439)
			(xy 106.783682 -109.867348) (xy 106.810978 -109.818713) (xy 106.845064 -109.77457) (xy 106.885213 -109.735861)
			(xy 106.930571 -109.70341) (xy 106.980171 -109.677909) (xy 107.032955 -109.659902) (xy 107.087798 -109.649772)
			(xy 107.143532 -109.647735) (xy 107.198969 -109.653835) (xy 107.252926 -109.667941) (xy 107.304255 -109.689753)
			(xy 107.351861 -109.718807) (xy 107.394729 -109.754482) (xy 107.431946 -109.796019) (xy 107.462719 -109.842532)
			(xy 107.486391 -109.893029) (xy 107.502459 -109.946436) (xy 107.510579 -110.001612) (xy 107.511088 -110.029498)
			(xy 107.510579 -110.057384) (xy 107.502459 -110.11256) (xy 107.486391 -110.165967) (xy 107.462719 -110.216464)
			(xy 107.431946 -110.262977) (xy 107.394729 -110.304514) (xy 107.351861 -110.340189) (xy 107.304255 -110.369243)
			(xy 107.252926 -110.391055) (xy 107.198969 -110.405161) (xy 107.143532 -110.411261) (xy 107.087798 -110.409224)
			(xy 107.032955 -110.399094) (xy 106.980171 -110.381087) (xy 106.930571 -110.355586) (xy 106.885213 -110.323135)
			(xy 106.845064 -110.284426) (xy 106.810978 -110.240283) (xy 106.783682 -110.191648) (xy 106.763759 -110.139557)
			(xy 106.751633 -110.08512) (xy 106.747562 -110.029498) (xy 103.543534 -110.029498) (xy 103.543608 -110.033562)
			(xy 103.543099 -110.061448) (xy 103.534979 -110.116624) (xy 103.518911 -110.170031) (xy 103.495239 -110.220528)
			(xy 103.464466 -110.267041) (xy 103.427249 -110.308578) (xy 103.384381 -110.344253) (xy 103.336775 -110.373307)
			(xy 103.285446 -110.395119) (xy 103.231489 -110.409225) (xy 103.176052 -110.415325) (xy 103.120318 -110.413288)
			(xy 103.065475 -110.403158) (xy 103.012691 -110.385151) (xy 102.963091 -110.35965) (xy 102.917733 -110.327199)
			(xy 102.877584 -110.28849) (xy 102.843498 -110.244347) (xy 102.816202 -110.195712) (xy 102.796279 -110.143621)
			(xy 102.784153 -110.089184) (xy 102.780082 -110.033562) (xy 98.284284 -110.033562) (xy 98.284284 -111.39678)
			(xy 98.185986 -111.495078) (xy 98.09988 -111.581438) (xy 98.09988 -111.929418) (xy 102.876602 -111.929418)
			(xy 102.880673 -111.873796) (xy 102.892799 -111.819359) (xy 102.912722 -111.767268) (xy 102.940018 -111.718633)
			(xy 102.974104 -111.67449) (xy 103.014253 -111.635781) (xy 103.059611 -111.60333) (xy 103.109211 -111.577829)
			(xy 103.161995 -111.559822) (xy 103.216838 -111.549692) (xy 103.272572 -111.547655) (xy 103.328009 -111.553755)
			(xy 103.381966 -111.567861) (xy 103.433295 -111.589673) (xy 103.480901 -111.618727) (xy 103.523769 -111.654402)
			(xy 103.560986 -111.695939) (xy 103.591759 -111.742452) (xy 103.615431 -111.792949) (xy 103.631499 -111.846356)
			(xy 103.639619 -111.901532) (xy 103.640128 -111.929418) (xy 103.639619 -111.957304) (xy 103.631499 -112.01248)
			(xy 103.615431 -112.065887) (xy 103.591759 -112.116384) (xy 103.560986 -112.162897) (xy 103.523769 -112.204434)
			(xy 103.480901 -112.240109) (xy 103.433295 -112.269163) (xy 103.381966 -112.290975) (xy 103.328009 -112.305081)
			(xy 103.272572 -112.311181) (xy 103.216838 -112.309144) (xy 103.161995 -112.299014) (xy 103.109211 -112.281007)
			(xy 103.059611 -112.255506) (xy 103.014253 -112.223055) (xy 102.974104 -112.184346) (xy 102.940018 -112.140203)
			(xy 102.912722 -112.091568) (xy 102.892799 -112.039477) (xy 102.880673 -111.98504) (xy 102.876602 -111.929418)
			(xy 98.09988 -111.929418) (xy 98.09988 -112.052608) (xy 97.618804 -112.533684) (xy 97.618804 -113.000867)
			(xy 101.954941 -113.000867) (xy 101.957353 -112.945797) (xy 101.967668 -112.891647) (xy 101.985671 -112.839546)
			(xy 102.010986 -112.790579) (xy 102.043087 -112.745767) (xy 102.081305 -112.706043) (xy 102.124844 -112.672234)
			(xy 102.172796 -112.645046) (xy 102.224162 -112.625043) (xy 102.277873 -112.612644) (xy 102.33281 -112.608106)
			(xy 102.387827 -112.611524) (xy 102.44178 -112.622827) (xy 102.493543 -112.641778) (xy 102.542039 -112.667984)
			(xy 102.564438 -112.684052) (xy 102.581741 -112.696375) (xy 102.61954 -112.715749) (xy 102.660037 -112.72856)
			(xy 102.702101 -112.734449) (xy 102.744559 -112.733254) (xy 102.786225 -112.725007) (xy 102.825937 -112.709938)
			(xy 102.862587 -112.688468) (xy 102.879144 -112.675162) (xy 102.900636 -112.657904) (xy 102.94756 -112.62899)
			(xy 102.998157 -112.607133) (xy 103.051373 -112.592787) (xy 103.106101 -112.586251) (xy 103.161199 -112.587662)
			(xy 103.21552 -112.59699) (xy 103.267933 -112.614041) (xy 103.317345 -112.63846) (xy 103.362727 -112.669737)
			(xy 103.403133 -112.707222) (xy 103.437723 -112.750133) (xy 103.465775 -112.797577) (xy 103.486704 -112.848565)
			(xy 103.500076 -112.902035) (xy 103.50561 -112.956872) (xy 103.503193 -113.011936) (xy 103.492874 -113.066077)
			(xy 103.474869 -113.11817) (xy 103.449551 -113.167127) (xy 103.41745 -113.21193) (xy 103.379233 -113.251646)
			(xy 103.335697 -113.285445) (xy 103.287749 -113.312626) (xy 103.236387 -113.33262) (xy 103.182682 -113.345013)
			(xy 103.127752 -113.349545) (xy 103.072742 -113.346122) (xy 103.018798 -113.334815) (xy 102.967044 -113.315861)
			(xy 102.918557 -113.289654) (xy 102.896162 -113.273586) (xy 102.878857 -113.261267) (xy 102.841057 -113.241898)
			(xy 102.800561 -113.229091) (xy 102.758498 -113.223203) (xy 102.716042 -113.224398) (xy 102.674377 -113.232643)
			(xy 102.634665 -113.247708) (xy 102.598015 -113.269173) (xy 102.581456 -113.282476) (xy 102.560025 -113.299813)
			(xy 102.513098 -113.328735) (xy 102.462497 -113.350601) (xy 102.409275 -113.364955) (xy 102.354541 -113.371497)
			(xy 102.299435 -113.370091) (xy 102.245106 -113.360768) (xy 102.192685 -113.34372) (xy 102.143264 -113.319303)
			(xy 102.097872 -113.288026) (xy 102.057457 -113.25054) (xy 102.022858 -113.207627) (xy 101.994798 -113.16018)
			(xy 101.973861 -113.109187) (xy 101.960482 -113.055712) (xy 101.954941 -113.000867) (xy 97.618804 -113.000867)
			(xy 97.618804 -116.360731) (xy 100.913188 -116.360731) (xy 100.915244 -116.304848) (xy 100.925433 -116.249864)
			(xy 100.943536 -116.196956) (xy 100.969167 -116.147255) (xy 101.001776 -116.101827) (xy 101.040666 -116.061645)
			(xy 101.062536 -116.044218) (xy 101.079299 -116.030771) (xy 101.108441 -115.999192) (xy 101.131859 -115.963163)
			(xy 101.148885 -115.923708) (xy 101.159034 -115.881953) (xy 101.162018 -115.839086) (xy 101.157751 -115.796327)
			(xy 101.146356 -115.754894) (xy 101.128156 -115.715968) (xy 101.103669 -115.680656) (xy 101.088952 -115.664996)
			(xy 101.069162 -115.644112) (xy 101.035486 -115.597465) (xy 101.009196 -115.54629) (xy 100.99089 -115.491748)
			(xy 100.980981 -115.435075) (xy 100.979695 -115.377556) (xy 100.987061 -115.320497) (xy 101.002912 -115.26519)
			(xy 101.026888 -115.212891) (xy 101.058445 -115.164786) (xy 101.077268 -115.143026) (xy 101.092508 -115.125323)
			(xy 101.116861 -115.085466) (xy 101.133518 -115.04183) (xy 101.141917 -114.995884) (xy 101.141775 -114.949176)
			(xy 101.133097 -114.903282) (xy 101.116175 -114.859747) (xy 101.09158 -114.82004) (xy 101.076252 -114.802412)
			(xy 101.058169 -114.781697) (xy 101.02743 -114.736108) (xy 101.003554 -114.686578) (xy 100.987036 -114.634133)
			(xy 100.978219 -114.57986) (xy 100.977285 -114.524884) (xy 100.984254 -114.470343) (xy 100.99898 -114.417367)
			(xy 101.02116 -114.367055) (xy 101.050333 -114.320448) (xy 101.085895 -114.278512) (xy 101.127109 -114.242116)
			(xy 101.173122 -114.212014) (xy 101.222979 -114.18883) (xy 101.275649 -114.173044) (xy 101.330039 -114.164983)
			(xy 101.385023 -114.164815) (xy 101.439462 -114.172542) (xy 101.492227 -114.188004) (xy 101.542226 -114.210882)
			(xy 101.588422 -114.240701) (xy 101.629859 -114.276843) (xy 101.665678 -114.31856) (xy 101.695136 -114.364987)
			(xy 101.717624 -114.415163) (xy 101.732676 -114.468047) (xy 101.739979 -114.522544) (xy 101.739382 -114.577525)
			(xy 101.730898 -114.631851) (xy 101.714703 -114.684396) (xy 101.691131 -114.734071) (xy 101.660672 -114.779848)
			(xy 101.642672 -114.800634) (xy 101.627475 -114.818371) (xy 101.603125 -114.858222) (xy 101.586469 -114.901851)
			(xy 101.578068 -114.94779) (xy 101.578205 -114.994491) (xy 101.586874 -115.04038) (xy 101.603785 -115.083911)
			(xy 101.628367 -115.123619) (xy 101.643688 -115.141248) (xy 101.662656 -115.16277) (xy 101.69445 -115.210525)
			(xy 101.718735 -115.262501) (xy 101.734965 -115.317527) (xy 101.742773 -115.374363) (xy 101.741983 -115.431728)
			(xy 101.732613 -115.488327) (xy 101.714875 -115.542886) (xy 101.689168 -115.594174) (xy 101.656072 -115.641034)
			(xy 101.616332 -115.682412) (xy 101.593904 -115.700302) (xy 101.577122 -115.713724) (xy 101.547985 -115.74531)
			(xy 101.524573 -115.781344) (xy 101.507552 -115.820801) (xy 101.497407 -115.862558) (xy 101.494426 -115.905427)
			(xy 101.498693 -115.948186) (xy 101.510089 -115.98962) (xy 101.528288 -116.028548) (xy 101.552772 -116.063862)
			(xy 101.567488 -116.079524) (xy 101.586731 -116.099814) (xy 101.619652 -116.145017) (xy 101.645624 -116.194539)
			(xy 101.664091 -116.247322) (xy 101.674658 -116.302235) (xy 101.677098 -116.358102) (xy 101.67136 -116.413726)
			(xy 101.657565 -116.467918) (xy 101.63601 -116.519517) (xy 101.607155 -116.567418) (xy 101.571619 -116.610595)
			(xy 101.530163 -116.648124) (xy 101.483674 -116.679201) (xy 101.433147 -116.703162) (xy 101.379665 -116.719492)
			(xy 101.324372 -116.727843) (xy 101.268452 -116.728035) (xy 101.213103 -116.720065) (xy 101.159509 -116.704103)
			(xy 101.108819 -116.680491) (xy 101.062117 -116.649734) (xy 101.020403 -116.612492) (xy 100.984571 -116.56956)
			(xy 100.955387 -116.521859) (xy 100.933477 -116.47041) (xy 100.91931 -116.416315) (xy 100.913188 -116.360731)
			(xy 97.618804 -116.360731) (xy 97.618804 -117.410992) (xy 100.913182 -117.410992) (xy 100.917253 -117.35537)
			(xy 100.929379 -117.300933) (xy 100.949302 -117.248842) (xy 100.976598 -117.200207) (xy 101.010684 -117.156064)
			(xy 101.050833 -117.117355) (xy 101.096191 -117.084904) (xy 101.145791 -117.059403) (xy 101.198575 -117.041396)
			(xy 101.253418 -117.031266) (xy 101.309152 -117.029229) (xy 101.364589 -117.035329) (xy 101.418546 -117.049435)
			(xy 101.469875 -117.071247) (xy 101.517481 -117.100301) (xy 101.560349 -117.135976) (xy 101.597566 -117.177513)
			(xy 101.628339 -117.224026) (xy 101.652011 -117.274523) (xy 101.668079 -117.32793) (xy 101.676199 -117.383106)
			(xy 101.676708 -117.410992) (xy 101.676199 -117.438878) (xy 101.668079 -117.494054) (xy 101.652011 -117.547461)
			(xy 101.628339 -117.597958) (xy 101.597566 -117.644471) (xy 101.560349 -117.686008) (xy 101.517481 -117.721683)
			(xy 101.469875 -117.750737) (xy 101.418546 -117.772549) (xy 101.364589 -117.786655) (xy 101.309152 -117.792755)
			(xy 101.253418 -117.790718) (xy 101.198575 -117.780588) (xy 101.145791 -117.762581) (xy 101.096191 -117.73708)
			(xy 101.050833 -117.704629) (xy 101.010684 -117.66592) (xy 100.976598 -117.621777) (xy 100.949302 -117.573142)
			(xy 100.929379 -117.521051) (xy 100.917253 -117.466614) (xy 100.913182 -117.410992) (xy 97.618804 -117.410992)
			(xy 97.618804 -119.62638) (xy 99.205286 -119.62638) (xy 99.209357 -119.570758) (xy 99.221483 -119.516321)
			(xy 99.241406 -119.46423) (xy 99.268702 -119.415595) (xy 99.302788 -119.371452) (xy 99.342937 -119.332743)
			(xy 99.388295 -119.300292) (xy 99.437895 -119.274791) (xy 99.490679 -119.256784) (xy 99.545522 -119.246654)
			(xy 99.601256 -119.244617) (xy 99.656693 -119.250717) (xy 99.71065 -119.264823) (xy 99.761979 -119.286635)
			(xy 99.809585 -119.315689) (xy 99.852453 -119.351364) (xy 99.88967 -119.392901) (xy 99.920443 -119.439414)
			(xy 99.944115 -119.489911) (xy 99.960183 -119.543318) (xy 99.968303 -119.598494) (xy 99.968812 -119.62638)
			(xy 99.968303 -119.654266) (xy 99.960183 -119.709442) (xy 99.944115 -119.762849) (xy 99.920443 -119.813346)
			(xy 99.88967 -119.859859) (xy 99.852453 -119.901396) (xy 99.809585 -119.937071) (xy 99.761979 -119.966125)
			(xy 99.71065 -119.987937) (xy 99.656693 -120.002043) (xy 99.601256 -120.008143) (xy 99.545522 -120.006106)
			(xy 99.490679 -119.995976) (xy 99.437895 -119.977969) (xy 99.388295 -119.952468) (xy 99.342937 -119.920017)
			(xy 99.302788 -119.881308) (xy 99.268702 -119.837165) (xy 99.241406 -119.78853) (xy 99.221483 -119.736439)
			(xy 99.209357 -119.682002) (xy 99.205286 -119.62638) (xy 97.618804 -119.62638) (xy 97.618804 -124.527056)
			(xy 97.67062 -124.578872) (xy 98.381312 -124.578872)
		)
		(stroke
			(width 0)
			(type solid)
		)
		(fill yes)
		(layer "In2.Cu")
		(net "P1V8_NODE1")
	)
	(gr_poly
		(pts
			(xy 71.468996 -98.903282) (xy 71.475346 -98.894646) (xy 71.48195 -98.885756) (xy 71.485506 -98.881184)
			(xy 71.50014 -98.863018) (xy 71.533127 -98.830033) (xy 71.551292 -98.815398) (xy 71.555864 -98.811842)
			(xy 71.564754 -98.805238) (xy 71.57339 -98.798888) (xy 71.684642 -98.687636) (xy 71.696004 -98.675558)
			(xy 71.712658 -98.646896) (xy 71.721362 -98.614911) (xy 71.721529 -98.581763) (xy 71.713148 -98.549692)
			(xy 71.696784 -98.520864) (xy 71.673543 -98.497228) (xy 71.644996 -98.48038) (xy 71.613071 -98.471458)
			(xy 71.596504 -98.47072) (xy 71.593964 -98.47072) (xy 71.565693 -98.470242) (xy 71.509762 -98.461966)
			(xy 71.455665 -98.445525) (xy 71.404587 -98.421281) (xy 71.357646 -98.389764) (xy 71.31587 -98.351665)
			(xy 71.280175 -98.307817) (xy 71.251341 -98.259182) (xy 71.230002 -98.206823) (xy 71.216623 -98.151889)
			(xy 71.211498 -98.095581) (xy 71.214739 -98.039134) (xy 71.226276 -97.983784) (xy 71.245855 -97.930742)
			(xy 71.273047 -97.88117) (xy 71.307258 -97.836155) (xy 71.347738 -97.796681) (xy 71.3936 -97.763614)
			(xy 71.41845 -97.750122) (xy 71.443117 -97.737934) (xy 71.495126 -97.719986) (xy 71.549175 -97.709696)
			(xy 71.604141 -97.707279) (xy 71.658884 -97.712783) (xy 71.712268 -97.726094) (xy 71.763186 -97.746937)
			(xy 71.810582 -97.774879) (xy 71.853472 -97.80934) (xy 71.872602 -97.829116) (xy 71.888157 -97.845093)
			(xy 71.923807 -97.871875) (xy 71.96358 -97.892031) (xy 72.006259 -97.904942) (xy 72.050535 -97.910214)
			(xy 72.095052 -97.907685) (xy 72.138446 -97.897433) (xy 72.159114 -97.88906) (xy 72.18423 -97.878731)
			(xy 72.236625 -97.864456) (xy 72.263508 -97.860612) (xy 72.281406 -97.858615) (xy 72.317407 -97.857601)
			(xy 72.33539 -97.85858) (xy 72.361298 -97.86112) (xy 72.385682 -97.865184) (xy 72.410574 -97.87128)
			(xy 72.426841 -97.875162) (xy 72.460273 -97.875226) (xy 72.492579 -97.866623) (xy 72.521552 -97.849942)
			(xy 72.533764 -97.838514) (xy 74.44486 -95.927418) (xy 74.44867 -95.927418) (xy 74.471684 -95.926921)
			(xy 74.516958 -95.918632) (xy 74.559998 -95.902319) (xy 74.599393 -95.878518) (xy 74.633854 -95.848007)
			(xy 74.662253 -95.811785) (xy 74.683659 -95.771038) (xy 74.697371 -95.727101) (xy 74.702941 -95.681413)
			(xy 74.700187 -95.635468) (xy 74.689198 -95.590772) (xy 74.680318 -95.569532) (xy 74.673663 -95.554223)
			(xy 74.662724 -95.522683) (xy 74.658474 -95.50654) (xy 74.654339 -95.491833) (xy 74.640112 -95.464809)
			(xy 74.619866 -95.441943) (xy 74.594765 -95.424546) (xy 74.566247 -95.413617) (xy 74.535948 -95.409782)
			(xy 74.505606 -95.413261) (xy 74.476961 -95.423855) (xy 74.451658 -95.440956) (xy 74.431146 -95.463584)
			(xy 74.423524 -95.476822) (xy 74.410158 -95.50048) (xy 74.377755 -95.544099) (xy 74.339492 -95.58268)
			(xy 74.296144 -95.615443) (xy 74.248587 -95.641727) (xy 74.197782 -95.661) (xy 74.144758 -95.672871)
			(xy 74.117708 -95.67545) (xy 74.09099 -95.67707) (xy 74.037569 -95.673711) (xy 73.985142 -95.662919)
			(xy 73.934738 -95.644906) (xy 73.887345 -95.620027) (xy 73.843894 -95.588768) (xy 73.805238 -95.551745)
			(xy 73.772135 -95.509682) (xy 73.745235 -95.463406) (xy 73.725067 -95.413825) (xy 73.712024 -95.361912)
			(xy 73.708768 -95.335344) (xy 73.70774 -95.324707) (xy 73.706721 -95.303359) (xy 73.706736 -95.292672)
			(xy 73.707366 -95.265713) (xy 73.715283 -95.212372) (xy 73.730632 -95.160677) (xy 73.753106 -95.111659)
			(xy 73.782258 -95.066292) (xy 73.817507 -95.025482) (xy 73.85815 -94.990042) (xy 73.903378 -94.960676)
			(xy 73.95229 -94.937971) (xy 74.003912 -94.922378) (xy 74.057214 -94.914208) (xy 74.111136 -94.913624)
			(xy 74.164603 -94.920638) (xy 74.21655 -94.93511) (xy 74.265942 -94.956752) (xy 74.311796 -94.985131)
			(xy 74.353196 -95.019684) (xy 74.38932 -95.059722) (xy 74.404728 -95.081852) (xy 74.418809 -95.100589)
			(xy 74.452616 -95.133042) (xy 74.491795 -95.158755) (xy 74.535021 -95.176856) (xy 74.580832 -95.186734)
			(xy 74.627676 -95.188054) (xy 74.67397 -95.180771) (xy 74.718147 -95.165133) (xy 74.758712 -95.141668)
			(xy 74.776838 -95.12681) (xy 74.788014 -95.117412) (xy 74.809061 -95.100893) (xy 74.854895 -95.073289)
			(xy 74.904137 -95.052363) (xy 74.95582 -95.038524) (xy 74.982324 -95.034862) (xy 75.00785 -95.032146)
			(xy 75.059178 -95.032782) (xy 75.109956 -95.04031) (xy 75.134724 -95.047054) (xy 75.157378 -95.053053)
			(xy 75.204015 -95.057606) (xy 75.250695 -95.053525) (xy 75.295834 -95.040948) (xy 75.3379 -95.020303)
			(xy 75.375463 -94.992291) (xy 75.407249 -94.957862) (xy 75.42022 -94.938342) (xy 75.435871 -94.914392)
			(xy 75.473197 -94.871035) (xy 75.516577 -94.833735) (xy 75.565037 -94.803327) (xy 75.617494 -94.780492)
			(xy 75.672771 -94.765743) (xy 75.701144 -94.762066) (xy 75.706478 -94.761558) (xy 75.734453 -94.759344)
			(xy 75.790498 -94.762168) (xy 75.845525 -94.773172) (xy 75.898346 -94.792117) (xy 75.947823 -94.818595)
			(xy 75.992887 -94.852035) (xy 76.032567 -94.891715) (xy 76.066007 -94.936779) (xy 76.092484 -94.986256)
			(xy 76.111429 -95.039078) (xy 76.114192 -95.052896) (xy 76.623416 -95.052896) (xy 76.627487 -94.997274)
			(xy 76.639613 -94.942837) (xy 76.659536 -94.890746) (xy 76.686832 -94.842111) (xy 76.720918 -94.797968)
			(xy 76.761067 -94.759259) (xy 76.806425 -94.726808) (xy 76.856025 -94.701307) (xy 76.908809 -94.6833)
			(xy 76.963652 -94.67317) (xy 77.019386 -94.671133) (xy 77.074823 -94.677233) (xy 77.12878 -94.691339)
			(xy 77.180109 -94.713151) (xy 77.227715 -94.742205) (xy 77.270583 -94.77788) (xy 77.3078 -94.819417)
			(xy 77.338573 -94.86593) (xy 77.362245 -94.916427) (xy 77.378313 -94.969834) (xy 77.386433 -95.02501)
			(xy 77.386942 -95.052896) (xy 77.386433 -95.080782) (xy 77.378313 -95.135958) (xy 77.376633 -95.141542)
			(xy 78.137256 -95.141542) (xy 78.141327 -95.08592) (xy 78.153453 -95.031483) (xy 78.173376 -94.979392)
			(xy 78.200672 -94.930757) (xy 78.234758 -94.886614) (xy 78.274907 -94.847905) (xy 78.320265 -94.815454)
			(xy 78.369865 -94.789953) (xy 78.422649 -94.771946) (xy 78.477492 -94.761816) (xy 78.533226 -94.759779)
			(xy 78.588663 -94.765879) (xy 78.64262 -94.779985) (xy 78.693949 -94.801797) (xy 78.741555 -94.830851)
			(xy 78.784423 -94.866526) (xy 78.82164 -94.908063) (xy 78.852413 -94.954576) (xy 78.876085 -95.005073)
			(xy 78.890855 -95.054166) (xy 79.17637 -95.054166) (xy 79.180441 -94.998544) (xy 79.192567 -94.944107)
			(xy 79.21249 -94.892016) (xy 79.239786 -94.843381) (xy 79.273872 -94.799238) (xy 79.314021 -94.760529)
			(xy 79.359379 -94.728078) (xy 79.408979 -94.702577) (xy 79.461763 -94.68457) (xy 79.516606 -94.67444)
			(xy 79.57234 -94.672403) (xy 79.627777 -94.678503) (xy 79.681734 -94.692609) (xy 79.733063 -94.714421)
			(xy 79.780669 -94.743475) (xy 79.823537 -94.77915) (xy 79.860754 -94.820687) (xy 79.891527 -94.8672)
			(xy 79.915199 -94.917697) (xy 79.931267 -94.971104) (xy 79.939387 -95.02628) (xy 79.939896 -95.054166)
			(xy 79.939387 -95.082052) (xy 79.931267 -95.137228) (xy 79.915199 -95.190635) (xy 79.891527 -95.241132)
			(xy 79.860754 -95.287645) (xy 79.823537 -95.329182) (xy 79.780669 -95.364857) (xy 79.733063 -95.393911)
			(xy 79.681734 -95.415723) (xy 79.627777 -95.429829) (xy 79.57234 -95.435929) (xy 79.516606 -95.433892)
			(xy 79.461763 -95.423762) (xy 79.408979 -95.405755) (xy 79.359379 -95.380254) (xy 79.314021 -95.347803)
			(xy 79.273872 -95.309094) (xy 79.239786 -95.264951) (xy 79.21249 -95.216316) (xy 79.192567 -95.164225)
			(xy 79.180441 -95.109788) (xy 79.17637 -95.054166) (xy 78.890855 -95.054166) (xy 78.892153 -95.05848)
			(xy 78.900273 -95.113656) (xy 78.900782 -95.141542) (xy 78.900273 -95.169428) (xy 78.892153 -95.224604)
			(xy 78.876085 -95.278011) (xy 78.852413 -95.328508) (xy 78.82164 -95.375021) (xy 78.784423 -95.416558)
			(xy 78.741555 -95.452233) (xy 78.693949 -95.481287) (xy 78.64262 -95.503099) (xy 78.588663 -95.517205)
			(xy 78.533226 -95.523305) (xy 78.477492 -95.521268) (xy 78.422649 -95.511138) (xy 78.369865 -95.493131)
			(xy 78.320265 -95.46763) (xy 78.274907 -95.435179) (xy 78.234758 -95.39647) (xy 78.200672 -95.352327)
			(xy 78.173376 -95.303692) (xy 78.153453 -95.251601) (xy 78.141327 -95.197164) (xy 78.137256 -95.141542)
			(xy 77.376633 -95.141542) (xy 77.362245 -95.189365) (xy 77.338573 -95.239862) (xy 77.3078 -95.286375)
			(xy 77.270583 -95.327912) (xy 77.227715 -95.363587) (xy 77.180109 -95.392641) (xy 77.12878 -95.414453)
			(xy 77.074823 -95.428559) (xy 77.019386 -95.434659) (xy 76.963652 -95.432622) (xy 76.908809 -95.422492)
			(xy 76.856025 -95.404485) (xy 76.806425 -95.378984) (xy 76.761067 -95.346533) (xy 76.720918 -95.307824)
			(xy 76.686832 -95.263681) (xy 76.659536 -95.215046) (xy 76.639613 -95.162955) (xy 76.627487 -95.108518)
			(xy 76.623416 -95.052896) (xy 76.114192 -95.052896) (xy 76.122432 -95.094105) (xy 76.125256 -95.15015)
			(xy 76.119839 -95.206004) (xy 76.1063 -95.260462) (xy 76.084929 -95.31235) (xy 76.056188 -95.360547)
			(xy 76.020697 -95.404015) (xy 75.979222 -95.441815) (xy 75.932657 -95.473131) (xy 75.882008 -95.49729)
			(xy 75.828365 -95.513768) (xy 75.772888 -95.522211) (xy 75.744832 -95.522796) (xy 75.717541 -95.522456)
			(xy 75.663484 -95.514931) (xy 75.637136 -95.50781) (xy 75.614479 -95.501806) (xy 75.567836 -95.497243)
			(xy 75.521148 -95.501315) (xy 75.475999 -95.513884) (xy 75.433922 -95.534523) (xy 75.396347 -95.562531)
			(xy 75.364547 -95.596958) (xy 75.35164 -95.616522) (xy 75.338891 -95.636149) (xy 75.309346 -95.672448)
			(xy 75.292712 -95.688912) (xy 75.27544 -95.705422) (xy 75.256136 -95.747332) (xy 75.249935 -95.761989)
			(xy 75.24421 -95.793283) (xy 75.246411 -95.825021) (xy 75.256402 -95.855226) (xy 75.27356 -95.882016)
			(xy 75.296817 -95.903724) (xy 75.324725 -95.918998) (xy 75.355545 -95.926887) (xy 75.371452 -95.927418)
			(xy 82.059018 -95.927418) (xy 82.764884 -95.221552) (xy 82.764884 -93.36786) (xy 82.603848 -93.206824)
			(xy 80.605376 -93.206824) (xy 80.58233 -93.207327) (xy 80.536995 -93.215641) (xy 80.493901 -93.231991)
			(xy 80.45446 -93.255843) (xy 80.419966 -93.286414) (xy 80.391548 -93.322702) (xy 80.370138 -93.363519)
			(xy 80.356437 -93.407527) (xy 80.353154 -93.430344) (xy 80.349293 -93.458152) (xy 80.334461 -93.512299)
			(xy 80.311853 -93.563687) (xy 80.281956 -93.611206) (xy 80.245416 -93.653829) (xy 80.203022 -93.690634)
			(xy 80.155691 -93.720828) (xy 80.104445 -93.743757) (xy 80.050392 -93.758926) (xy 79.994699 -93.766007)
			(xy 79.938569 -93.764848) (xy 79.883216 -93.755473) (xy 79.829835 -93.738085) (xy 79.77958 -93.713059)
			(xy 79.733536 -93.680937) (xy 79.692699 -93.642413) (xy 79.65795 -93.598318) (xy 79.63004 -93.549605)
			(xy 79.609573 -93.497327) (xy 79.59699 -93.442614) (xy 79.592564 -93.386647) (xy 79.59639 -93.330636)
			(xy 79.601822 -93.30309) (xy 79.605429 -93.281077) (xy 79.605777 -93.236474) (xy 79.598332 -93.192496)
			(xy 79.583323 -93.150494) (xy 79.561211 -93.111757) (xy 79.532676 -93.077475) (xy 79.498593 -93.048702)
			(xy 79.460011 -93.026322) (xy 79.418113 -93.011021) (xy 79.374188 -93.003271) (xy 79.351886 -93.002862)
			(xy 71.714106 -93.002862) (xy 71.690406 -93.003397) (xy 71.643829 -93.012194) (xy 71.599687 -93.029464)
			(xy 71.559508 -93.054612) (xy 71.524681 -93.086766) (xy 71.496412 -93.124814) (xy 71.475679 -93.167439)
			(xy 71.4632 -93.213167) (xy 71.459406 -93.260416) (xy 71.461376 -93.28404) (xy 71.465551 -93.311408)
			(xy 71.46689 -93.366753) (xy 71.460219 -93.42171) (xy 71.445677 -93.475126) (xy 71.423569 -93.525881)
			(xy 71.394359 -93.572909) (xy 71.358661 -93.615223) (xy 71.317223 -93.651934) (xy 71.270916 -93.682273)
			(xy 71.220711 -93.705603) (xy 71.167662 -93.721433) (xy 71.112882 -93.729432) (xy 71.057522 -93.729432)
			(xy 71.002742 -93.721433) (xy 70.949693 -93.705603) (xy 70.899488 -93.682273) (xy 70.853181 -93.651934)
			(xy 70.811743 -93.615223) (xy 70.776045 -93.572909) (xy 70.746835 -93.525881) (xy 70.724727 -93.475126)
			(xy 70.710185 -93.42171) (xy 70.703514 -93.366753) (xy 70.704853 -93.311408) (xy 70.709028 -93.28404)
			(xy 70.711045 -93.260411) (xy 70.707298 -93.213142) (xy 70.694846 -93.167388) (xy 70.674121 -93.124739)
			(xy 70.645844 -93.086676) (xy 70.610996 -93.054519) (xy 70.570786 -93.029386) (xy 70.526612 -93.01215)
			(xy 70.480008 -93.003408) (xy 70.456298 -93.002862) (xy 68.041266 -93.002862) (xy 66.78041 -91.742006)
			(xy 66.78041 -86.952328) (xy 66.728086 -86.900004) (xy 66.72072 -86.894416) (xy 66.698419 -86.877222)
			(xy 66.658644 -86.837361) (xy 66.625163 -86.792085) (xy 66.598705 -86.742377) (xy 66.579845 -86.689318)
			(xy 66.568993 -86.634062) (xy 66.566385 -86.577812) (xy 66.572077 -86.521789) (xy 66.57848 -86.494366)
			(xy 66.583798 -86.471255) (xy 66.586734 -86.423928) (xy 66.580841 -86.376877) (xy 66.566324 -86.331735)
			(xy 66.543687 -86.29007) (xy 66.513715 -86.253325) (xy 66.477447 -86.222777) (xy 66.457068 -86.210648)
			(xy 66.433935 -86.197105) (xy 66.391363 -86.164531) (xy 66.35377 -86.126318) (xy 66.321897 -86.083219)
			(xy 66.296371 -86.036082) (xy 66.277695 -85.985836) (xy 66.266236 -85.933471) (xy 66.26222 -85.880017)
			(xy 66.265727 -85.826528) (xy 66.276687 -85.774056) (xy 66.294884 -85.723634) (xy 66.319961 -85.676257)
			(xy 66.351423 -85.632857) (xy 66.369692 -85.61324) (xy 66.385082 -85.596548) (xy 66.410273 -85.558782)
			(xy 66.428354 -85.517141) (xy 66.43875 -85.47295) (xy 66.441129 -85.427616) (xy 66.435415 -85.38258)
			(xy 66.421791 -85.339275) (xy 66.400691 -85.29908) (xy 66.372784 -85.263273) (xy 66.35623 -85.247734)
			(xy 66.335656 -85.227922) (xy 66.317745 -85.208649) (xy 66.286845 -85.166064) (xy 66.262088 -85.119639)
			(xy 66.243944 -85.070252) (xy 66.232757 -85.018841) (xy 66.228739 -84.966381) (xy 66.231966 -84.913866)
			(xy 66.242376 -84.862292) (xy 66.259774 -84.812637) (xy 66.283827 -84.765844) (xy 66.298572 -84.744052)
			(xy 66.317741 -84.718018) (xy 66.36332 -84.672175) (xy 66.38925 -84.652866) (xy 66.406278 -84.63931)
			(xy 66.435869 -84.607396) (xy 66.459584 -84.570904) (xy 66.476729 -84.530903) (xy 66.486801 -84.488563)
			(xy 66.489506 -84.445127) (xy 66.484764 -84.401865) (xy 66.479166 -84.380832) (xy 66.475864 -84.36864)
			(xy 66.469184 -84.339731) (xy 66.463813 -84.280644) (xy 66.467653 -84.221437) (xy 66.473578 -84.192364)
			(xy 66.479844 -84.166486) (xy 66.498586 -84.116649) (xy 66.510916 -84.09305) (xy 66.517037 -84.08207)
			(xy 66.530512 -84.060846) (xy 66.53784 -84.050632) (xy 66.548686 -84.034053) (xy 66.565643 -83.99825)
			(xy 66.576819 -83.960243) (xy 66.57975 -83.94065) (xy 66.581289 -83.925766) (xy 66.578164 -83.896016)
			(xy 66.568182 -83.867816) (xy 66.551894 -83.842724) (xy 66.530201 -83.822126) (xy 66.5043 -83.807158)
			(xy 66.490088 -83.802474) (xy 66.464633 -83.794429) (xy 66.41609 -83.772213) (xy 66.371117 -83.743448)
			(xy 66.330592 -83.708696) (xy 66.295305 -83.668635) (xy 66.265945 -83.624048) (xy 66.243086 -83.575805)
			(xy 66.227173 -83.524846) (xy 66.218518 -83.472167) (xy 66.217288 -83.418796) (xy 66.223508 -83.365775)
			(xy 66.237056 -83.314137) (xy 66.257669 -83.264892) (xy 66.284944 -83.219) (xy 66.301366 -83.197954)
			(xy 66.329306 -83.163156) (xy 66.329306 -82.324956) (xy 66.291968 -82.236056) (xy 66.276728 -82.219546)
			(xy 66.268005 -82.209943) (xy 66.251734 -82.189733) (xy 66.244216 -82.17916) (xy 66.227281 -82.153927)
			(xy 66.200777 -82.099244) (xy 66.183274 -82.041052) (xy 66.178684 -82.011012) (xy 66.175633 -81.984569)
			(xy 66.176016 -81.931341) (xy 66.183796 -81.878684) (xy 66.190876 -81.853024) (xy 66.200782 -81.819496)
			(xy 66.18351 -81.752186) (xy 65.513458 -81.082134) (xy 62.42558 -81.082134) (xy 62.292738 -81.214976)
			(xy 62.292738 -82.01914) (xy 62.556388 -82.01914) (xy 62.560459 -81.963518) (xy 62.572585 -81.909081)
			(xy 62.592508 -81.85699) (xy 62.619804 -81.808355) (xy 62.65389 -81.764212) (xy 62.694039 -81.725503)
			(xy 62.739397 -81.693052) (xy 62.788997 -81.667551) (xy 62.841781 -81.649544) (xy 62.896624 -81.639414)
			(xy 62.952358 -81.637377) (xy 63.007795 -81.643477) (xy 63.061752 -81.657583) (xy 63.113081 -81.679395)
			(xy 63.160687 -81.708449) (xy 63.203555 -81.744124) (xy 63.240772 -81.785661) (xy 63.271545 -81.832174)
			(xy 63.295217 -81.882671) (xy 63.311285 -81.936078) (xy 63.319405 -81.991254) (xy 63.319914 -82.01914)
			(xy 63.319405 -82.047026) (xy 63.311285 -82.102202) (xy 63.295217 -82.155609) (xy 63.271545 -82.206106)
			(xy 63.240772 -82.252619) (xy 63.203555 -82.294156) (xy 63.160687 -82.329831) (xy 63.113081 -82.358885)
			(xy 63.061752 -82.380697) (xy 63.007795 -82.394803) (xy 62.952358 -82.400903) (xy 62.896624 -82.398866)
			(xy 62.841781 -82.388736) (xy 62.788997 -82.370729) (xy 62.739397 -82.345228) (xy 62.694039 -82.312777)
			(xy 62.65389 -82.274068) (xy 62.619804 -82.229925) (xy 62.592508 -82.18129) (xy 62.572585 -82.129199)
			(xy 62.560459 -82.074762) (xy 62.556388 -82.01914) (xy 62.292738 -82.01914) (xy 62.292738 -82.33791)
			(xy 62.292992 -82.33791) (xy 62.292992 -82.473274) (xy 64.294335 -82.473274) (xy 64.299031 -82.41801)
			(xy 64.31168 -82.364008) (xy 64.332017 -82.312407) (xy 64.359611 -82.264295) (xy 64.393882 -82.220686)
			(xy 64.434106 -82.1825) (xy 64.479437 -82.150541) (xy 64.528917 -82.125484) (xy 64.581505 -82.107856)
			(xy 64.60871 -82.102452) (xy 64.62367 -82.099345) (xy 64.651595 -82.086964) (xy 64.675767 -82.068289)
			(xy 64.694796 -82.044393) (xy 64.707585 -82.016653) (xy 64.713399 -81.986665) (xy 64.713104 -81.971388)
			(xy 64.712257 -81.944081) (xy 64.717521 -81.889702) (xy 64.730489 -81.83663) (xy 64.750896 -81.785952)
			(xy 64.778325 -81.738703) (xy 64.812213 -81.69585) (xy 64.851869 -81.658271) (xy 64.896481 -81.626734)
			(xy 64.945135 -81.601884) (xy 64.996837 -81.584229) (xy 65.050529 -81.574131) (xy 65.105113 -81.571797)
			(xy 65.159471 -81.577273) (xy 65.212491 -81.590449) (xy 65.26309 -81.611054) (xy 65.310231 -81.638668)
			(xy 65.35295 -81.672724) (xy 65.390374 -81.712526) (xy 65.421737 -81.757261) (xy 65.446397 -81.806012)
			(xy 65.463849 -81.857783) (xy 65.473736 -81.911514) (xy 65.475857 -81.966106) (xy 65.470168 -82.020442)
			(xy 65.456785 -82.073411) (xy 65.435982 -82.123928) (xy 65.408184 -82.170961) (xy 65.373961 -82.213547)
			(xy 65.334013 -82.250815) (xy 65.289156 -82.282002) (xy 65.240308 -82.306471) (xy 65.18847 -82.323721)
			(xy 65.161668 -82.32902) (xy 65.146712 -82.332139) (xy 65.11879 -82.344521) (xy 65.09462 -82.363195)
			(xy 65.075592 -82.387088) (xy 65.062801 -82.414824) (xy 65.056982 -82.444808) (xy 65.057274 -82.460084)
			(xy 65.058092 -82.489443) (xy 65.051797 -82.547836) (xy 65.03663 -82.604574) (xy 65.012948 -82.658319)
			(xy 64.997584 -82.68335) (xy 64.988757 -82.698201) (xy 64.978661 -82.731227) (xy 64.977785 -82.765751)
			(xy 64.986192 -82.799248) (xy 65.003268 -82.829266) (xy 65.01511 -82.841846) (xy 65.03433 -82.861692)
			(xy 65.067459 -82.905901) (xy 65.093863 -82.954428) (xy 65.112988 -83.006257) (xy 65.124435 -83.060303)
			(xy 65.127964 -83.115436) (xy 65.123502 -83.1705) (xy 65.11114 -83.224344) (xy 65.09114 -83.275842)
			(xy 65.063917 -83.323914) (xy 65.047368 -83.346036) (xy 65.038626 -83.357928) (xy 65.026397 -83.384785)
			(xy 65.020661 -83.413732) (xy 65.021727 -83.443223) (xy 65.029536 -83.471681) (xy 65.043671 -83.497585)
			(xy 65.05321 -83.50885) (xy 65.070558 -83.528873) (xy 65.100184 -83.572793) (xy 65.123447 -83.620389)
			(xy 65.1399 -83.670747) (xy 65.149227 -83.722897) (xy 65.151248 -83.775836) (xy 65.145924 -83.828546)
			(xy 65.133357 -83.880011) (xy 65.11379 -83.929243) (xy 65.087599 -83.975293) (xy 65.055287 -84.017276)
			(xy 65.0367 -84.036154) (xy 65.025987 -84.04724) (xy 65.00985 -84.073501) (xy 65.00049 -84.102869)
			(xy 64.998455 -84.133625) (xy 65.003863 -84.16397) (xy 65.016399 -84.192129) (xy 65.025524 -84.204556)
			(xy 65.042449 -84.227269) (xy 65.070187 -84.276652) (xy 65.090314 -84.329595) (xy 65.102385 -84.384934)
			(xy 65.106136 -84.441449) (xy 65.101483 -84.497898) (xy 65.088529 -84.553037) (xy 65.067559 -84.605652)
			(xy 65.039036 -84.654585) (xy 65.021714 -84.676996) (xy 65.011835 -84.69033) (xy 64.998558 -84.720725)
			(xy 64.993559 -84.753515) (xy 64.997174 -84.786486) (xy 65.009162 -84.817413) (xy 65.028711 -84.844208)
			(xy 65.041272 -84.85505) (xy 65.062456 -84.872767) (xy 65.099979 -84.913284) (xy 65.131266 -84.958791)
			(xy 65.155662 -85.008334) (xy 65.172656 -85.060878) (xy 65.181892 -85.115324) (xy 65.183179 -85.170533)
			(xy 65.176488 -85.22535) (xy 65.16196 -85.278628) (xy 65.139899 -85.329254) (xy 65.110766 -85.376168)
			(xy 65.093342 -85.397594) (xy 65.078312 -85.416377) (xy 65.054811 -85.458341) (xy 65.039622 -85.503976)
			(xy 65.033287 -85.551654) (xy 65.036032 -85.599673) (xy 65.047758 -85.646318) (xy 65.068048 -85.689925)
			(xy 65.081658 -85.70976) (xy 65.097291 -85.732373) (xy 65.122697 -85.781121) (xy 65.140842 -85.83301)
			(xy 65.15135 -85.886968) (xy 65.154002 -85.941875) (xy 65.148744 -85.996594) (xy 65.135685 -86.049991)
			(xy 65.115095 -86.10096) (xy 65.087402 -86.148446) (xy 65.053178 -86.191463) (xy 65.013133 -86.229122)
			(xy 64.968096 -86.260641) (xy 64.919 -86.285369) (xy 64.866863 -86.302792) (xy 64.812765 -86.312549)
			(xy 64.757827 -86.314439) (xy 64.703186 -86.308423) (xy 64.649976 -86.294624) (xy 64.599297 -86.273329)
			(xy 64.552201 -86.244978) (xy 64.509662 -86.210161) (xy 64.472563 -86.169597) (xy 64.441671 -86.124127)
			(xy 64.417628 -86.074693) (xy 64.40093 -86.022319) (xy 64.391924 -85.968091) (xy 64.390797 -85.913132)
			(xy 64.397572 -85.85858) (xy 64.412108 -85.805566) (xy 64.434104 -85.755187) (xy 64.463105 -85.708489)
			(xy 64.48044 -85.687154) (xy 64.495518 -85.668408) (xy 64.519017 -85.626435) (xy 64.534201 -85.580791)
			(xy 64.54053 -85.533106) (xy 64.537777 -85.485082) (xy 64.526041 -85.438432) (xy 64.50574 -85.394823)
			(xy 64.492124 -85.374988) (xy 64.476399 -85.352347) (xy 64.450918 -85.303466) (xy 64.432743 -85.251424)
			(xy 64.422252 -85.197308) (xy 64.419664 -85.142245) (xy 64.425033 -85.087383) (xy 64.438247 -85.033867)
			(xy 64.45903 -84.982811) (xy 64.48695 -84.935281) (xy 64.503808 -84.91347) (xy 64.513738 -84.90017)
			(xy 64.527022 -84.869765) (xy 64.532019 -84.836963) (xy 64.528394 -84.803982) (xy 64.516391 -84.773049)
			(xy 64.496822 -84.746254) (xy 64.48425 -84.735416) (xy 64.463663 -84.718222) (xy 64.427089 -84.678986)
			(xy 64.396367 -84.635017) (xy 64.372102 -84.58718) (xy 64.354771 -84.536418) (xy 64.344717 -84.48373)
			(xy 64.342137 -84.430153) (xy 64.347082 -84.376743) (xy 64.359454 -84.32455) (xy 64.37901 -84.274603)
			(xy 64.405365 -84.227886) (xy 64.438 -84.185317) (xy 64.456818 -84.166202) (xy 64.467479 -84.15507)
			(xy 64.483618 -84.128821) (xy 64.492983 -84.099465) (xy 64.495027 -84.06872) (xy 64.489632 -84.038382)
			(xy 64.477111 -84.010227) (xy 64.467994 -83.9978) (xy 64.45119 -83.975405) (xy 64.423703 -83.926626)
			(xy 64.403638 -83.874355) (xy 64.391425 -83.819713) (xy 64.387328 -83.763873) (xy 64.391433 -83.708034)
			(xy 64.403653 -83.653393) (xy 64.423726 -83.601125) (xy 64.45122 -83.55235) (xy 64.467994 -83.529932)
			(xy 64.476673 -83.517996) (xy 64.488913 -83.491154) (xy 64.494661 -83.462217) (xy 64.493607 -83.432735)
			(xy 64.48581 -83.404282) (xy 64.471686 -83.378382) (xy 64.462152 -83.367118) (xy 64.444044 -83.346304)
			(xy 64.413482 -83.300371) (xy 64.389854 -83.250515) (xy 64.37365 -83.197777) (xy 64.365209 -83.143256)
			(xy 64.364706 -83.088087) (xy 64.372153 -83.033421) (xy 64.387393 -82.980396) (xy 64.41011 -82.930119)
			(xy 64.42456 -82.906616) (xy 64.433331 -82.891734) (xy 64.443443 -82.85872) (xy 64.444334 -82.824204)
			(xy 64.435939 -82.790713) (xy 64.418872 -82.760699) (xy 64.407034 -82.74812) (xy 64.387735 -82.728199)
			(xy 64.354531 -82.683773) (xy 64.32811 -82.635007) (xy 64.309029 -82.582928) (xy 64.297691 -82.528636)
			(xy 64.294335 -82.473274) (xy 62.292992 -82.473274) (xy 62.292992 -82.664808) (xy 62.294117 -82.687033)
			(xy 62.303186 -82.730596) (xy 62.311026 -82.751422) (xy 62.318777 -82.769626) (xy 62.339082 -82.803582)
			(xy 62.364398 -82.833986) (xy 62.394114 -82.860105) (xy 62.410594 -82.871056) (xy 62.417963 -82.875631)
			(xy 62.433217 -82.88389) (xy 62.441074 -82.887566) (xy 62.442598 -82.888328) (xy 62.451234 -82.892392)
			(xy 62.474423 -82.90112) (xy 62.52308 -82.91044) (xy 62.57262 -82.910177) (xy 62.621174 -82.90034)
			(xy 62.644274 -82.891376) (xy 62.665398 -82.881468) (xy 62.709523 -82.866301) (xy 62.755173 -82.856649)
			(xy 62.778386 -82.854292) (xy 62.805866 -82.852369) (xy 62.860863 -82.855502) (xy 62.914837 -82.866512)
			(xy 62.966666 -82.885171) (xy 63.015273 -82.911092) (xy 63.059645 -82.943734) (xy 63.098861 -82.98242)
			(xy 63.132105 -83.026344) (xy 63.158685 -83.074592) (xy 63.178049 -83.126163) (xy 63.189794 -83.179982)
			(xy 63.193675 -83.234931) (xy 63.189612 -83.289867) (xy 63.17769 -83.343647) (xy 63.158156 -83.395153)
			(xy 63.145162 -83.419442) (xy 63.131593 -83.442898) (xy 63.098848 -83.486071) (xy 63.060323 -83.524178)
			(xy 63.016795 -83.556451) (xy 62.969138 -83.58224) (xy 62.918313 -83.601028) (xy 62.86534 -83.612436)
			(xy 62.811286 -83.616234) (xy 62.784228 -83.614768) (xy 62.765432 -83.614006) (xy 62.714886 -83.63331)
			(xy 62.628018 -83.720178) (xy 62.60592 -83.74253) (xy 62.561724 -83.786726) (xy 62.561724 -83.96732)
			(xy 62.562966 -83.990793) (xy 62.573042 -84.0367) (xy 62.591386 -84.079972) (xy 62.617372 -84.119135)
			(xy 62.650115 -84.152853) (xy 62.688498 -84.179977) (xy 62.731213 -84.199584) (xy 62.776804 -84.211004)
			(xy 62.80023 -84.212938) (xy 62.827932 -84.21393) (xy 62.882626 -84.222929) (xy 62.935444 -84.239747)
			(xy 62.985272 -84.264029) (xy 63.031063 -84.295264) (xy 63.071854 -84.332795) (xy 63.106786 -84.375833)
			(xy 63.135124 -84.423472) (xy 63.156272 -84.474709) (xy 63.16345 -84.501482) (xy 63.165805 -84.511168)
			(xy 63.169618 -84.530736) (xy 63.17107 -84.540598) (xy 63.172848 -84.55406) (xy 63.175474 -84.584326)
			(xy 63.172244 -84.644988) (xy 63.159444 -84.704372) (xy 63.137397 -84.760978) (xy 63.122556 -84.787486)
			(xy 63.114272 -84.8013) (xy 63.095707 -84.827626) (xy 63.085472 -84.840064) (xy 63.072264 -84.855812)
			(xy 63.038482 -84.940902) (xy 63.038482 -85.180678) (xy 63.038482 -85.187536) (xy 63.038482 -85.612986)
			(xy 63.039034 -85.630089) (xy 63.048116 -85.663067) (xy 63.065632 -85.692448) (xy 63.077598 -85.70468)
			(xy 63.152274 -85.776308) (xy 63.189866 -85.783166) (xy 63.216397 -85.788485) (xy 63.267721 -85.805618)
			(xy 63.316111 -85.829831) (xy 63.360594 -85.860638) (xy 63.400278 -85.89742) (xy 63.434367 -85.93944)
			(xy 63.462177 -85.985855) (xy 63.483151 -86.035734) (xy 63.496868 -86.088076) (xy 63.503051 -86.14183)
			(xy 63.501578 -86.195919) (xy 63.492478 -86.249257) (xy 63.475933 -86.300775) (xy 63.452275 -86.349438)
			(xy 63.421979 -86.39427) (xy 63.385653 -86.434373) (xy 63.344026 -86.46894) (xy 63.321184 -86.483444)
			(xy 63.29299 -86.500716) (xy 63.260732 -86.558374) (xy 63.260732 -86.845648) (xy 63.261207 -86.867694)
			(xy 63.26882 -86.911123) (xy 63.283811 -86.952587) (xy 63.305729 -86.990845) (xy 63.333918 -87.024748)
			(xy 63.367533 -87.053281) (xy 63.405565 -87.075587) (xy 63.446875 -87.091) (xy 63.490224 -87.099055)
			(xy 63.534313 -87.099512) (xy 63.556134 -87.096346) (xy 63.583436 -87.092324) (xy 63.638611 -87.091256)
			(xy 63.693365 -87.098147) (xy 63.746555 -87.112854) (xy 63.797071 -87.13507) (xy 63.843859 -87.164332)
			(xy 63.885945 -87.200029) (xy 63.922449 -87.241416) (xy 63.95261 -87.28763) (xy 63.975799 -87.337706)
			(xy 63.991533 -87.390602) (xy 63.999482 -87.445212) (xy 63.999481 -87.500397) (xy 63.991531 -87.555007)
			(xy 63.975796 -87.607901) (xy 63.952606 -87.657978) (xy 63.922444 -87.704191) (xy 63.885939 -87.745577)
			(xy 63.843853 -87.781273) (xy 63.797063 -87.810534) (xy 63.746546 -87.832749) (xy 63.693357 -87.847455)
			(xy 63.638603 -87.854345) (xy 63.583428 -87.853275) (xy 63.556134 -87.849202) (xy 63.534303 -87.846071)
			(xy 63.490206 -87.846496) (xy 63.446844 -87.854528) (xy 63.40552 -87.869925) (xy 63.367475 -87.892225)
			(xy 63.333851 -87.920757) (xy 63.305657 -87.954667) (xy 63.28374 -87.992934) (xy 63.268759 -88.03441)
			(xy 63.261163 -88.07785) (xy 63.260732 -88.0999) (xy 63.260732 -89.07907) (xy 63.261195 -89.101376)
			(xy 63.268981 -89.145303) (xy 63.284317 -89.187196) (xy 63.306734 -89.225766) (xy 63.335542 -89.25983)
			(xy 63.369856 -89.288339) (xy 63.408621 -89.310418) (xy 63.450646 -89.325388) (xy 63.494639 -89.33279)
			(xy 63.539249 -89.332395) (xy 63.583105 -89.324216) (xy 63.624858 -89.308504) (xy 63.644272 -89.29751)
			(xy 63.668368 -89.283805) (xy 63.719643 -89.262739) (xy 63.773426 -89.249315) (xy 63.828586 -89.243817)
			(xy 63.883961 -89.246359) (xy 63.938385 -89.256888) (xy 63.990712 -89.275183) (xy 64.039841 -89.300859)
			(xy 64.084736 -89.333374) (xy 64.124453 -89.372044) (xy 64.158156 -89.416055) (xy 64.185134 -89.464481)
			(xy 64.20482 -89.516301) (xy 64.2168 -89.570424) (xy 64.22082 -89.625711) (xy 64.216796 -89.680998)
			(xy 64.204814 -89.735121) (xy 64.185125 -89.78694) (xy 64.158144 -89.835364) (xy 64.124439 -89.879373)
			(xy 64.084719 -89.918041) (xy 64.039822 -89.950553) (xy 63.990691 -89.976226) (xy 63.951534 -89.989914)
			(xy 65.516758 -89.989914) (xy 65.520829 -89.934292) (xy 65.532955 -89.879855) (xy 65.552878 -89.827764)
			(xy 65.580174 -89.779129) (xy 65.61426 -89.734986) (xy 65.654409 -89.696277) (xy 65.699767 -89.663826)
			(xy 65.749367 -89.638325) (xy 65.802151 -89.620318) (xy 65.856994 -89.610188) (xy 65.912728 -89.608151)
			(xy 65.968165 -89.614251) (xy 66.022122 -89.628357) (xy 66.073451 -89.650169) (xy 66.121057 -89.679223)
			(xy 66.163925 -89.714898) (xy 66.201142 -89.756435) (xy 66.231915 -89.802948) (xy 66.255587 -89.853445)
			(xy 66.271655 -89.906852) (xy 66.279775 -89.962028) (xy 66.280284 -89.989914) (xy 66.279775 -90.0178)
			(xy 66.271655 -90.072976) (xy 66.255587 -90.126383) (xy 66.231915 -90.17688) (xy 66.201142 -90.223393)
			(xy 66.163925 -90.26493) (xy 66.121057 -90.300605) (xy 66.073451 -90.329659) (xy 66.022122 -90.351471)
			(xy 65.968165 -90.365577) (xy 65.912728 -90.371677) (xy 65.856994 -90.36964) (xy 65.802151 -90.35951)
			(xy 65.749367 -90.341503) (xy 65.699767 -90.316002) (xy 65.654409 -90.283551) (xy 65.61426 -90.244842)
			(xy 65.580174 -90.200699) (xy 65.552878 -90.152064) (xy 65.532955 -90.099973) (xy 65.520829 -90.045536)
			(xy 65.516758 -89.989914) (xy 63.951534 -89.989914) (xy 63.938363 -89.994518) (xy 63.883939 -90.005044)
			(xy 63.828563 -90.007583) (xy 63.773404 -90.002081) (xy 63.719621 -89.988654) (xy 63.668348 -89.967585)
			(xy 63.644272 -89.953846) (xy 63.62485 -89.942868) (xy 63.583097 -89.927159) (xy 63.539243 -89.918982)
			(xy 63.494634 -89.918588) (xy 63.450643 -89.92599) (xy 63.408619 -89.940958) (xy 63.369854 -89.963035)
			(xy 63.33554 -89.991541) (xy 63.30673 -90.025601) (xy 63.28431 -90.064167) (xy 63.268968 -90.106057)
			(xy 63.261177 -90.149981) (xy 63.260732 -90.172286) (xy 63.260732 -90.191082) (xy 63.261239 -90.213876)
			(xy 63.269367 -90.258735) (xy 63.285365 -90.301424) (xy 63.30872 -90.340575) (xy 63.338684 -90.374934)
			(xy 63.374295 -90.403397) (xy 63.414412 -90.425053) (xy 63.457748 -90.439206) (xy 63.502913 -90.445404)
			(xy 63.548459 -90.443447) (xy 63.592927 -90.433397) (xy 63.634889 -90.415578) (xy 63.654178 -90.403426)
			(xy 63.677105 -90.387352) (xy 63.726708 -90.361379) (xy 63.779574 -90.342933) (xy 63.834569 -90.332409)
			(xy 63.89051 -90.330035) (xy 63.946198 -90.335861) (xy 64.000437 -90.349762) (xy 64.052063 -90.371439)
			(xy 64.099967 -90.400427) (xy 64.14312 -90.436104) (xy 64.180597 -90.477704) (xy 64.211594 -90.524334)
			(xy 64.235443 -90.574993) (xy 64.251634 -90.628592) (xy 64.259819 -90.683983) (xy 64.259822 -90.739975)
			(xy 64.251643 -90.795366) (xy 64.235458 -90.848968) (xy 64.211614 -90.899629) (xy 64.180623 -90.946262)
			(xy 64.143151 -90.987867) (xy 64.100001 -91.023548) (xy 64.052101 -91.052542) (xy 64.000477 -91.074225)
			(xy 63.94624 -91.088132) (xy 63.890553 -91.093964) (xy 63.834611 -91.091596) (xy 63.779615 -91.081078)
			(xy 63.726747 -91.062638) (xy 63.677141 -91.03667) (xy 63.654178 -91.020646) (xy 63.634849 -91.008554)
			(xy 63.592894 -90.990717) (xy 63.54843 -90.980652) (xy 63.502883 -90.978681) (xy 63.457716 -90.984868)
			(xy 63.414377 -90.999015) (xy 63.374258 -91.020666) (xy 63.338646 -91.049129) (xy 63.308683 -91.083488)
			(xy 63.285331 -91.122643) (xy 63.269339 -91.165335) (xy 63.26537 -91.18727) (xy 64.791334 -91.18727)
			(xy 64.795405 -91.131648) (xy 64.807531 -91.077211) (xy 64.827454 -91.02512) (xy 64.85475 -90.976485)
			(xy 64.888836 -90.932342) (xy 64.928985 -90.893633) (xy 64.974343 -90.861182) (xy 65.023943 -90.835681)
			(xy 65.076727 -90.817674) (xy 65.13157 -90.807544) (xy 65.187304 -90.805507) (xy 65.242741 -90.811607)
			(xy 65.296698 -90.825713) (xy 65.348027 -90.847525) (xy 65.395633 -90.876579) (xy 65.438501 -90.912254)
			(xy 65.475718 -90.953791) (xy 65.506491 -91.000304) (xy 65.530163 -91.050801) (xy 65.546231 -91.104208)
			(xy 65.554351 -91.159384) (xy 65.55486 -91.18727) (xy 65.554351 -91.215156) (xy 65.546231 -91.270332)
			(xy 65.530163 -91.323739) (xy 65.506491 -91.374236) (xy 65.475718 -91.420749) (xy 65.438501 -91.462286)
			(xy 65.395633 -91.497961) (xy 65.348027 -91.527015) (xy 65.296698 -91.548827) (xy 65.242741 -91.562933)
			(xy 65.187304 -91.569033) (xy 65.13157 -91.566996) (xy 65.076727 -91.556866) (xy 65.023943 -91.538859)
			(xy 64.974343 -91.513358) (xy 64.928985 -91.480907) (xy 64.888836 -91.442198) (xy 64.85475 -91.398055)
			(xy 64.827454 -91.34942) (xy 64.807531 -91.297329) (xy 64.795405 -91.242892) (xy 64.791334 -91.18727)
			(xy 63.26537 -91.18727) (xy 63.261221 -91.210195) (xy 63.260732 -91.23299) (xy 63.260732 -95.050864)
			(xy 65.794126 -95.050864) (xy 65.798197 -94.995242) (xy 65.810323 -94.940805) (xy 65.830246 -94.888714)
			(xy 65.857542 -94.840079) (xy 65.891628 -94.795936) (xy 65.931777 -94.757227) (xy 65.977135 -94.724776)
			(xy 66.026735 -94.699275) (xy 66.079519 -94.681268) (xy 66.134362 -94.671138) (xy 66.190096 -94.669101)
			(xy 66.245533 -94.675201) (xy 66.29949 -94.689307) (xy 66.350819 -94.711119) (xy 66.398425 -94.740173)
			(xy 66.441293 -94.775848) (xy 66.44533 -94.780354) (xy 71.106282 -94.780354) (xy 71.110353 -94.724732)
			(xy 71.122479 -94.670295) (xy 71.142402 -94.618204) (xy 71.169698 -94.569569) (xy 71.203784 -94.525426)
			(xy 71.243933 -94.486717) (xy 71.289291 -94.454266) (xy 71.338891 -94.428765) (xy 71.391675 -94.410758)
			(xy 71.446518 -94.400628) (xy 71.502252 -94.398591) (xy 71.557689 -94.404691) (xy 71.611646 -94.418797)
			(xy 71.662975 -94.440609) (xy 71.710581 -94.469663) (xy 71.753449 -94.505338) (xy 71.790666 -94.546875)
			(xy 71.821439 -94.593388) (xy 71.845111 -94.643885) (xy 71.861179 -94.697292) (xy 71.869299 -94.752468)
			(xy 71.869808 -94.780354) (xy 71.869299 -94.80824) (xy 71.861179 -94.863416) (xy 71.845111 -94.916823)
			(xy 71.821439 -94.96732) (xy 71.790666 -95.013833) (xy 71.753449 -95.05537) (xy 71.710581 -95.091045)
			(xy 71.699008 -95.098108) (xy 72.401682 -95.098108) (xy 72.405753 -95.042486) (xy 72.417879 -94.988049)
			(xy 72.437802 -94.935958) (xy 72.465098 -94.887323) (xy 72.499184 -94.84318) (xy 72.539333 -94.804471)
			(xy 72.584691 -94.77202) (xy 72.634291 -94.746519) (xy 72.687075 -94.728512) (xy 72.741918 -94.718382)
			(xy 72.797652 -94.716345) (xy 72.853089 -94.722445) (xy 72.907046 -94.736551) (xy 72.958375 -94.758363)
			(xy 73.005981 -94.787417) (xy 73.048849 -94.823092) (xy 73.086066 -94.864629) (xy 73.116839 -94.911142)
			(xy 73.140511 -94.961639) (xy 73.156579 -95.015046) (xy 73.164699 -95.070222) (xy 73.165208 -95.098108)
			(xy 73.164699 -95.125994) (xy 73.156579 -95.18117) (xy 73.140511 -95.234577) (xy 73.116839 -95.285074)
			(xy 73.086066 -95.331587) (xy 73.048849 -95.373124) (xy 73.005981 -95.408799) (xy 72.958375 -95.437853)
			(xy 72.907046 -95.459665) (xy 72.853089 -95.473771) (xy 72.797652 -95.479871) (xy 72.741918 -95.477834)
			(xy 72.687075 -95.467704) (xy 72.634291 -95.449697) (xy 72.584691 -95.424196) (xy 72.539333 -95.391745)
			(xy 72.499184 -95.353036) (xy 72.465098 -95.308893) (xy 72.437802 -95.260258) (xy 72.417879 -95.208167)
			(xy 72.405753 -95.15373) (xy 72.401682 -95.098108) (xy 71.699008 -95.098108) (xy 71.662975 -95.120099)
			(xy 71.611646 -95.141911) (xy 71.557689 -95.156017) (xy 71.502252 -95.162117) (xy 71.446518 -95.16008)
			(xy 71.391675 -95.14995) (xy 71.338891 -95.131943) (xy 71.289291 -95.106442) (xy 71.243933 -95.073991)
			(xy 71.203784 -95.035282) (xy 71.169698 -94.991139) (xy 71.142402 -94.942504) (xy 71.122479 -94.890413)
			(xy 71.110353 -94.835976) (xy 71.106282 -94.780354) (xy 66.44533 -94.780354) (xy 66.47851 -94.817385)
			(xy 66.509283 -94.863898) (xy 66.532955 -94.914395) (xy 66.549023 -94.967802) (xy 66.557143 -95.022978)
			(xy 66.557652 -95.050864) (xy 66.557143 -95.07875) (xy 66.549023 -95.133926) (xy 66.532955 -95.187333)
			(xy 66.509283 -95.23783) (xy 66.47851 -95.284343) (xy 66.441293 -95.32588) (xy 66.398425 -95.361555)
			(xy 66.350819 -95.390609) (xy 66.29949 -95.412421) (xy 66.245533 -95.426527) (xy 66.190096 -95.432627)
			(xy 66.134362 -95.43059) (xy 66.079519 -95.42046) (xy 66.026735 -95.402453) (xy 65.977135 -95.376952)
			(xy 65.931777 -95.344501) (xy 65.891628 -95.305792) (xy 65.857542 -95.261649) (xy 65.830246 -95.213014)
			(xy 65.810323 -95.160923) (xy 65.798197 -95.106486) (xy 65.794126 -95.050864) (xy 63.260732 -95.050864)
			(xy 63.260732 -95.547688) (xy 69.986142 -95.547688) (xy 69.990213 -95.492066) (xy 70.002339 -95.437629)
			(xy 70.022262 -95.385538) (xy 70.049558 -95.336903) (xy 70.083644 -95.29276) (xy 70.123793 -95.254051)
			(xy 70.169151 -95.2216) (xy 70.218751 -95.196099) (xy 70.271535 -95.178092) (xy 70.326378 -95.167962)
			(xy 70.382112 -95.165925) (xy 70.437549 -95.172025) (xy 70.491506 -95.186131) (xy 70.542835 -95.207943)
			(xy 70.590441 -95.236997) (xy 70.633309 -95.272672) (xy 70.670526 -95.314209) (xy 70.701299 -95.360722)
			(xy 70.724971 -95.411219) (xy 70.741039 -95.464626) (xy 70.749159 -95.519802) (xy 70.749668 -95.547688)
			(xy 70.749159 -95.575574) (xy 70.741039 -95.63075) (xy 70.724971 -95.684157) (xy 70.701299 -95.734654)
			(xy 70.670526 -95.781167) (xy 70.633309 -95.822704) (xy 70.590441 -95.858379) (xy 70.542835 -95.887433)
			(xy 70.491506 -95.909245) (xy 70.437549 -95.923351) (xy 70.382112 -95.929451) (xy 70.326378 -95.927414)
			(xy 70.271535 -95.917284) (xy 70.218751 -95.899277) (xy 70.169151 -95.873776) (xy 70.123793 -95.841325)
			(xy 70.083644 -95.802616) (xy 70.049558 -95.758473) (xy 70.022262 -95.709838) (xy 70.002339 -95.657747)
			(xy 69.990213 -95.60331) (xy 69.986142 -95.547688) (xy 63.260732 -95.547688) (xy 63.260732 -97.117408)
			(xy 63.261227 -97.140468) (xy 63.269536 -97.185832) (xy 63.285899 -97.228952) (xy 63.309778 -97.268408)
			(xy 63.340387 -97.302906) (xy 63.376721 -97.33131) (xy 63.417586 -97.352689) (xy 63.461639 -97.366339)
			(xy 63.507433 -97.371811) (xy 63.553462 -97.368926) (xy 63.575946 -97.363788) (xy 63.602364 -97.357721)
			(xy 63.656289 -97.352244) (xy 63.683388 -97.352866) (xy 63.708289 -97.354264) (xy 63.757433 -97.362766)
			(xy 63.805047 -97.377611) (xy 63.850315 -97.398544) (xy 63.871602 -97.41154) (xy 63.903352 -97.433892)
			(xy 63.91707 -97.444907) (xy 63.942637 -97.469076) (xy 63.954406 -97.482152) (xy 63.971407 -97.49887)
			(xy 64.010426 -97.526264) (xy 64.053869 -97.545899) (xy 64.100213 -97.557087) (xy 64.14783 -97.559435)
			(xy 64.195049 -97.552861) (xy 64.240214 -97.537595) (xy 64.261238 -97.526348) (xy 64.284229 -97.513267)
			(xy 64.333036 -97.492875) (xy 64.384192 -97.479423) (xy 64.436717 -97.473169) (xy 64.463168 -97.473262)
			(xy 64.488619 -97.474192) (xy 64.538953 -97.481961) (xy 64.563498 -97.488756) (xy 64.579029 -97.493532)
			(xy 64.609297 -97.505357) (xy 64.62395 -97.512378) (xy 64.639728 -97.520412) (xy 64.669873 -97.538988)
			(xy 64.684148 -97.549462) (xy 64.697551 -97.558885) (xy 64.727891 -97.571217) (xy 64.760373 -97.575408)
			(xy 64.79285 -97.57118) (xy 64.823176 -97.558813) (xy 64.849348 -97.539123) (xy 64.859916 -97.526602)
			(xy 64.877018 -97.505737) (xy 64.916117 -97.468566) (xy 64.960061 -97.437271) (xy 65.007974 -97.412477)
			(xy 65.058901 -97.394677) (xy 65.111828 -97.384227) (xy 65.165698 -97.381334) (xy 65.219439 -97.386057)
			(xy 65.27198 -97.398301) (xy 65.322273 -97.417822) (xy 65.369315 -97.444232) (xy 65.412169 -97.477003)
			(xy 65.449981 -97.515482) (xy 65.481997 -97.558904) (xy 65.507579 -97.606401) (xy 65.526217 -97.657027)
			(xy 65.532254 -97.68332) (xy 65.536769 -97.705966) (xy 65.540928 -97.751958) (xy 65.53949 -97.798115)
			(xy 65.536318 -97.820988) (xy 65.53327 -97.83826) (xy 65.53073 -97.850452) (xy 65.53073 -97.863152)
			(xy 65.531219 -97.879809) (xy 65.539832 -97.911991) (xy 65.556485 -97.940846) (xy 65.58004 -97.964404)
			(xy 65.608892 -97.981061) (xy 65.641073 -97.989679) (xy 65.65773 -97.990152) (xy 65.835276 -97.990152)
			(xy 65.857646 -97.989674) (xy 65.901693 -97.981832) (xy 65.943689 -97.966401) (xy 65.982335 -97.94386)
			(xy 66.016441 -97.914903) (xy 66.044953 -97.880424) (xy 66.06699 -97.841488) (xy 66.081874 -97.799296)
			(xy 66.085974 -97.7773) (xy 66.090968 -97.749942) (xy 66.107837 -97.69695) (xy 66.132223 -97.64697)
			(xy 66.163607 -97.60106) (xy 66.201325 -97.560194) (xy 66.244578 -97.525239) (xy 66.292448 -97.496934)
			(xy 66.34392 -97.475881) (xy 66.397904 -97.462525) (xy 66.453256 -97.45715) (xy 66.508801 -97.45987)
			(xy 66.563363 -97.470626) (xy 66.615784 -97.489191) (xy 66.664954 -97.515172) (xy 66.6877 -97.531174)
			(xy 66.70116 -97.540376) (xy 66.731498 -97.552295) (xy 66.763864 -97.556155) (xy 66.796154 -97.551706)
			(xy 66.826271 -97.539237) (xy 66.852255 -97.519559) (xy 66.862706 -97.507044) (xy 66.880298 -97.485383)
			(xy 66.920751 -97.446947) (xy 66.966372 -97.414815) (xy 67.016188 -97.389673) (xy 67.069136 -97.372059)
			(xy 67.124086 -97.362348) (xy 67.179864 -97.360748) (xy 67.23528 -97.367292) (xy 67.289151 -97.381841)
			(xy 67.340327 -97.404085) (xy 67.387715 -97.433548) (xy 67.430305 -97.469602) (xy 67.467187 -97.511477)
			(xy 67.497573 -97.558279) (xy 67.520815 -97.609009) (xy 67.536417 -97.662584) (xy 67.544046 -97.717861)
			(xy 67.543539 -97.77366) (xy 67.534907 -97.82879) (xy 67.518334 -97.882073) (xy 67.494174 -97.932372)
			(xy 67.462942 -97.978614) (xy 67.425306 -98.019812) (xy 67.382068 -98.055086) (xy 67.334152 -98.083683)
			(xy 67.28258 -98.104993) (xy 67.228454 -98.118561) (xy 67.172928 -98.124097) (xy 67.117188 -98.121484)
			(xy 67.062424 -98.110776) (xy 67.009805 -98.092202) (xy 66.960454 -98.06616) (xy 66.937636 -98.050096)
			(xy 66.924177 -98.040885) (xy 66.893836 -98.028951) (xy 66.861464 -98.025081) (xy 66.829165 -98.029526)
			(xy 66.799041 -98.041997) (xy 66.773053 -98.061684) (xy 66.76263 -98.074226) (xy 66.743072 -98.09734)
			(xy 66.733431 -98.108467) (xy 66.719041 -98.134144) (xy 66.710936 -98.16244) (xy 66.709803 -98.186432)
			(xy 68.400895 -98.186432) (xy 68.407877 -98.13179) (xy 68.422646 -98.07872) (xy 68.444895 -98.028326)
			(xy 68.474161 -97.981657) (xy 68.509836 -97.939682) (xy 68.551177 -97.903275) (xy 68.597325 -97.873194)
			(xy 68.64732 -97.850063) (xy 68.700122 -97.834363) (xy 68.754634 -97.826422) (xy 68.80972 -97.826404)
			(xy 68.837048 -97.829878) (xy 68.858053 -97.832514) (xy 68.900373 -97.831527) (xy 68.941944 -97.823541)
			(xy 68.981618 -97.808777) (xy 69.018296 -97.787643) (xy 69.050965 -97.760723) (xy 69.078721 -97.728761)
			(xy 69.100798 -97.692642) (xy 69.109082 -97.67316) (xy 69.119812 -97.647633) (xy 69.147667 -97.599776)
			(xy 69.182146 -97.556447) (xy 69.222526 -97.518556) (xy 69.267958 -97.4869) (xy 69.31749 -97.462144)
			(xy 69.370079 -97.444807) (xy 69.424622 -97.435253) (xy 69.479973 -97.433684) (xy 69.53497 -97.440131)
			(xy 69.588458 -97.45446) (xy 69.639312 -97.47637) (xy 69.686466 -97.5054) (xy 69.708014 -97.522792)
			(xy 69.725284 -97.536603) (xy 69.763608 -97.558654) (xy 69.805173 -97.573735) (xy 69.84872 -97.581392)
			(xy 69.892936 -97.581392) (xy 69.936483 -97.573735) (xy 69.978048 -97.558654) (xy 70.016372 -97.536603)
			(xy 70.033642 -97.522792) (xy 70.055369 -97.505245) (xy 70.102965 -97.476032) (xy 70.154311 -97.454068)
			(xy 70.208311 -97.439825) (xy 70.26381 -97.433605) (xy 70.319623 -97.435542) (xy 70.374557 -97.445594)
			(xy 70.427439 -97.463547) (xy 70.47714 -97.489017) (xy 70.522596 -97.52146) (xy 70.562837 -97.560183)
			(xy 70.597004 -97.604359) (xy 70.624366 -97.653043) (xy 70.644339 -97.705196) (xy 70.656496 -97.759703)
			(xy 70.660578 -97.8154) (xy 70.656496 -97.871097) (xy 70.644339 -97.925604) (xy 70.624366 -97.977757)
			(xy 70.597004 -98.026441) (xy 70.562837 -98.070617) (xy 70.522596 -98.10934) (xy 70.47714 -98.141783)
			(xy 70.427439 -98.167253) (xy 70.374557 -98.185206) (xy 70.319623 -98.195258) (xy 70.26381 -98.197195)
			(xy 70.208311 -98.190975) (xy 70.154311 -98.176732) (xy 70.102965 -98.154768) (xy 70.055369 -98.125555)
			(xy 70.033642 -98.108008) (xy 70.016372 -98.094197) (xy 69.978048 -98.072146) (xy 69.936483 -98.057065)
			(xy 69.892936 -98.049408) (xy 69.84872 -98.049408) (xy 69.805173 -98.057065) (xy 69.763608 -98.072146)
			(xy 69.725284 -98.094197) (xy 69.708014 -98.108008) (xy 69.687191 -98.12481) (xy 69.641763 -98.153078)
			(xy 69.592828 -98.174713) (xy 69.541348 -98.189289) (xy 69.488334 -98.196521) (xy 69.43483 -98.196265)
			(xy 69.408294 -98.192844) (xy 69.387281 -98.190298) (xy 69.344969 -98.191278) (xy 69.303405 -98.199255)
			(xy 69.263737 -98.214008) (xy 69.227061 -98.235129) (xy 69.194392 -98.262036) (xy 69.166632 -98.293982)
			(xy 69.144549 -98.330087) (xy 69.13626 -98.349562) (xy 69.125573 -98.374951) (xy 69.097903 -98.422585)
			(xy 69.063669 -98.465743) (xy 69.023584 -98.503528) (xy 68.978481 -98.535154) (xy 68.929297 -98.559964)
			(xy 68.877057 -98.577442) (xy 68.822845 -98.587223) (xy 68.767791 -98.589105) (xy 68.713038 -98.583049)
			(xy 68.659726 -98.56918) (xy 68.608963 -98.547788) (xy 68.561804 -98.519315) (xy 68.519232 -98.484356)
			(xy 68.482131 -98.443637) (xy 68.451272 -98.398005) (xy 68.427298 -98.348409) (xy 68.410708 -98.29588)
			(xy 68.401845 -98.241511) (xy 68.400895 -98.186432) (xy 66.709803 -98.186432) (xy 66.709548 -98.191841)
			(xy 66.714952 -98.220774) (xy 66.726859 -98.247692) (xy 66.735452 -98.259646) (xy 66.751309 -98.281383)
			(xy 66.777407 -98.328434) (xy 66.796634 -98.378686) (xy 66.808608 -98.431141) (xy 66.813092 -98.484758)
			(xy 66.809997 -98.538473) (xy 66.803752 -98.569513) (xy 67.406741 -98.569513) (xy 67.414326 -98.514393)
			(xy 67.429838 -98.460958) (xy 67.452947 -98.410344) (xy 67.483163 -98.363623) (xy 67.519844 -98.321787)
			(xy 67.562213 -98.285722) (xy 67.609372 -98.256194) (xy 67.660319 -98.233829) (xy 67.713975 -98.219102)
			(xy 67.769201 -98.212324) (xy 67.824825 -98.213641) (xy 67.879669 -98.223022) (xy 67.932568 -98.240271)
			(xy 67.982401 -98.26502) (xy 68.02811 -98.296746) (xy 68.068726 -98.334774) (xy 68.103388 -98.378299)
			(xy 68.13136 -98.426396) (xy 68.152049 -98.478047) (xy 68.165016 -98.532155) (xy 68.169986 -98.587573)
			(xy 68.166854 -98.643125) (xy 68.155686 -98.697633) (xy 68.146676 -98.723958) (xy 68.141596 -98.739308)
			(xy 68.138553 -98.771489) (xy 68.143705 -98.8034) (xy 68.156721 -98.832988) (xy 68.176764 -98.858348)
			(xy 68.202544 -98.877848) (xy 68.217288 -98.884486) (xy 68.242742 -98.895713) (xy 68.29041 -98.924388)
			(xy 68.333408 -98.959682) (xy 68.370824 -99.000848) (xy 68.401864 -99.047012) (xy 68.425869 -99.097194)
			(xy 68.442331 -99.150332) (xy 68.450901 -99.205296) (xy 68.451321 -99.252532) (xy 69.59422 -99.252532)
			(xy 69.598291 -99.19691) (xy 69.610417 -99.142473) (xy 69.63034 -99.090382) (xy 69.657636 -99.041747)
			(xy 69.691722 -98.997604) (xy 69.731871 -98.958895) (xy 69.777229 -98.926444) (xy 69.826829 -98.900943)
			(xy 69.879613 -98.882936) (xy 69.934456 -98.872806) (xy 69.99019 -98.870769) (xy 70.045627 -98.876869)
			(xy 70.099584 -98.890975) (xy 70.150913 -98.912787) (xy 70.198519 -98.941841) (xy 70.241387 -98.977516)
			(xy 70.278604 -99.019053) (xy 70.309377 -99.065566) (xy 70.333049 -99.116063) (xy 70.349117 -99.16947)
			(xy 70.357237 -99.224646) (xy 70.357746 -99.252532) (xy 70.357237 -99.280418) (xy 70.349117 -99.335594)
			(xy 70.333049 -99.389001) (xy 70.309377 -99.439498) (xy 70.278604 -99.486011) (xy 70.241387 -99.527548)
			(xy 70.198519 -99.563223) (xy 70.150913 -99.592277) (xy 70.099584 -99.614089) (xy 70.045627 -99.628195)
			(xy 69.99019 -99.634295) (xy 69.934456 -99.632258) (xy 69.879613 -99.622128) (xy 69.826829 -99.604121)
			(xy 69.777229 -99.57862) (xy 69.731871 -99.546169) (xy 69.691722 -99.50746) (xy 69.657636 -99.463317)
			(xy 69.63034 -99.414682) (xy 69.610417 -99.362591) (xy 69.598291 -99.308154) (xy 69.59422 -99.252532)
			(xy 68.451321 -99.252532) (xy 68.451396 -99.260923) (xy 68.443806 -99.316031) (xy 68.428292 -99.369453)
			(xy 68.405184 -99.420055) (xy 68.374971 -99.466764) (xy 68.338294 -99.508589) (xy 68.295931 -99.544643)
			(xy 68.24878 -99.574162) (xy 68.197842 -99.59652) (xy 68.144197 -99.611241) (xy 68.088982 -99.618015)
			(xy 68.033369 -99.616697) (xy 67.978537 -99.607316) (xy 67.925649 -99.59007) (xy 67.875827 -99.565325)
			(xy 67.830128 -99.533606) (xy 67.78952 -99.495585) (xy 67.754865 -99.45207) (xy 67.726898 -99.403983)
			(xy 67.706212 -99.352343) (xy 67.693246 -99.298246) (xy 67.688275 -99.24284) (xy 67.691405 -99.1873)
			(xy 67.702568 -99.132803) (xy 67.711574 -99.106482) (xy 67.716638 -99.091126) (xy 67.719692 -99.058946)
			(xy 67.714546 -99.027034) (xy 67.701533 -98.997446) (xy 67.681489 -98.972086) (xy 67.655707 -98.952589)
			(xy 67.640962 -98.945954) (xy 67.615484 -98.934769) (xy 67.567802 -98.906096) (xy 67.524789 -98.8708)
			(xy 67.48736 -98.829631) (xy 67.456308 -98.783462) (xy 67.432291 -98.733272) (xy 67.415819 -98.680126)
			(xy 67.407242 -98.625151) (xy 67.406741 -98.569513) (xy 66.803752 -98.569513) (xy 66.799384 -98.591221)
			(xy 66.781464 -98.641953) (xy 66.756593 -98.689664) (xy 66.725263 -98.733406) (xy 66.707004 -98.753168)
			(xy 66.696211 -98.765182) (xy 66.68052 -98.793399) (xy 66.672428 -98.824655) (xy 66.671952 -98.840798)
			(xy 66.671952 -100.06203) (xy 66.776854 -100.166932) (xy 70.205092 -100.166932)
		)
		(stroke
			(width 0)
			(type solid)
		)
		(fill yes)
		(layer "In2.Cu")
		(net "P3V3_SUS_NODE1")
	)
	(gr_poly
		(pts
			(xy 40.31742 -114.735864) (xy 40.31742 -111.293148) (xy 40.287448 -111.262922) (xy 40.287448 -103.830628)
			(xy 40.30726 -103.810562) (xy 40.30726 -102.497382) (xy 41.53154 -101.273102) (xy 41.53154 -98.774758)
			(xy 40.641524 -97.884742) (xy 40.627554 -97.87636) (xy 40.606707 -97.863704) (xy 40.568105 -97.833896)
			(xy 40.533618 -97.799411) (xy 40.503808 -97.760812) (xy 40.491156 -97.739962) (xy 40.482774 -97.725738)
			(xy 40.450516 -97.69348) (xy 40.450516 -97.641918) (xy 40.44696 -97.625408) (xy 40.445436 -97.61728)
			(xy 40.441457 -97.594107) (xy 40.438565 -97.547176) (xy 40.441463 -97.500246) (xy 40.445436 -97.477072)
			(xy 40.44696 -97.468944) (xy 40.450516 -97.452434) (xy 40.450516 -95.843598) (xy 40.449921 -95.825347)
			(xy 40.439588 -95.790338) (xy 40.419769 -95.759685) (xy 40.40632 -95.747332) (xy 40.385826 -95.729125)
			(xy 40.349757 -95.687845) (xy 40.319969 -95.641826) (xy 40.297074 -95.592018) (xy 40.281545 -95.539445)
			(xy 40.273701 -95.485191) (xy 40.273703 -95.430373) (xy 40.281553 -95.376119) (xy 40.297087 -95.323548)
			(xy 40.319986 -95.273742) (xy 40.349779 -95.227726) (xy 40.385852 -95.186449) (xy 40.40632 -95.168212)
			(xy 40.419763 -95.155858) (xy 40.439564 -95.125199) (xy 40.449891 -95.090194) (xy 40.450516 -95.071946)
			(xy 40.450516 -94.703646) (xy 40.54602 -94.703646) (xy 44.738798 -90.510868) (xy 44.749424 -90.499632)
			(xy 44.765387 -90.473154) (xy 44.774502 -90.443611) (xy 44.776232 -90.412742) (xy 44.770475 -90.382365)
			(xy 44.764452 -90.36812) (xy 44.753129 -90.342053) (xy 44.737458 -90.287425) (xy 44.730058 -90.231077)
			(xy 44.731091 -90.174255) (xy 44.740536 -90.118214) (xy 44.758183 -90.064193) (xy 44.783642 -90.013383)
			(xy 44.816352 -89.966909) (xy 44.835572 -89.945972) (xy 44.845788 -89.934653) (xy 44.861034 -89.908258)
			(xy 44.869573 -89.878997) (xy 44.870916 -89.848545) (xy 44.864985 -89.818646) (xy 44.852121 -89.791011)
			(xy 44.842938 -89.77884) (xy 44.82639 -89.757383) (xy 44.798881 -89.710701) (xy 44.778254 -89.660596)
			(xy 44.764923 -89.608076) (xy 44.759159 -89.554199) (xy 44.761075 -89.500048) (xy 44.770634 -89.446713)
			(xy 44.787644 -89.395268) (xy 44.811762 -89.346746) (xy 44.842502 -89.302125) (xy 44.879247 -89.262303)
			(xy 44.921257 -89.228081) (xy 44.967686 -89.200147) (xy 45.017601 -89.179063) (xy 45.069997 -89.165255)
			(xy 45.123819 -89.158998) (xy 45.177985 -89.160421) (xy 45.231405 -89.169493) (xy 45.283004 -89.186033)
			(xy 45.331743 -89.209707) (xy 45.376643 -89.240039) (xy 45.416799 -89.276419) (xy 45.451403 -89.318115)
			(xy 45.466 -89.340944) (xy 45.478422 -89.360239) (xy 45.50906 -89.394397) (xy 45.545335 -89.422497)
			(xy 45.586066 -89.443626) (xy 45.629929 -89.457098) (xy 45.675498 -89.462473) (xy 45.721292 -89.459577)
			(xy 45.765821 -89.448504) (xy 45.807638 -89.429614) (xy 45.845382 -89.403522) (xy 45.861986 -89.38768)
			(xy 47.289974 -87.959692) (xy 47.306189 -87.942745) (xy 47.332739 -87.904088) (xy 47.351748 -87.861216)
			(xy 47.36257 -87.815585) (xy 47.364839 -87.768743) (xy 47.358477 -87.72228) (xy 47.343701 -87.677772)
			(xy 47.321011 -87.636729) (xy 47.306484 -87.618316) (xy 47.28895 -87.596285) (xy 47.259877 -87.548067)
			(xy 47.238208 -87.496099) (xy 47.224416 -87.44151) (xy 47.218799 -87.385486) (xy 47.22148 -87.329245)
			(xy 47.2324 -87.274009) (xy 47.251322 -87.220979) (xy 47.277835 -87.171308) (xy 47.311363 -87.126074)
			(xy 47.351176 -87.08626) (xy 47.39641 -87.052733) (xy 47.446082 -87.026221) (xy 47.499112 -87.007299)
			(xy 47.554348 -86.996379) (xy 47.610589 -86.993699) (xy 47.666613 -86.999316) (xy 47.721202 -87.013109)
			(xy 47.77317 -87.034778) (xy 47.821388 -87.063852) (xy 47.84344 -87.08136) (xy 47.861878 -87.095844)
			(xy 47.90292 -87.118502) (xy 47.947418 -87.133255) (xy 47.993867 -87.139605) (xy 48.040693 -87.137336)
			(xy 48.08631 -87.126524) (xy 48.129173 -87.107536) (xy 48.167831 -87.081015) (xy 48.184816 -87.06485)
			(xy 48.44669 -86.802976) (xy 48.458552 -86.790336) (xy 48.475612 -86.760178) (xy 48.483917 -86.726539)
			(xy 48.482852 -86.691907) (xy 48.478186 -86.675214) (xy 48.470486 -86.648992) (xy 48.461799 -86.595037)
			(xy 48.460893 -86.540395) (xy 48.467789 -86.486182) (xy 48.482344 -86.433506) (xy 48.504262 -86.383444)
			(xy 48.533094 -86.337018) (xy 48.550322 -86.315804) (xy 48.58004 -86.280498) (xy 48.58004 -85.975444)
			(xy 48.546258 -85.938868) (xy 48.527301 -85.91759) (xy 48.495264 -85.870465) (xy 48.470591 -85.819099)
			(xy 48.453831 -85.764634) (xy 48.445358 -85.708283) (xy 48.445359 -85.651299) (xy 48.453835 -85.594948)
			(xy 48.470597 -85.540485) (xy 48.495273 -85.48912) (xy 48.527312 -85.441996) (xy 48.546258 -85.420708)
			(xy 48.58004 -85.384132) (xy 48.58004 -85.098636) (xy 48.55591 -85.047328) (xy 48.534066 -85.029294)
			(xy 48.512929 -85.011075) (xy 48.475689 -84.969518) (xy 48.444897 -84.922981) (xy 48.421209 -84.872457)
			(xy 48.405131 -84.819023) (xy 48.397003 -84.763816) (xy 48.397001 -84.708015) (xy 48.405124 -84.652807)
			(xy 48.421198 -84.599371) (xy 48.444882 -84.548845) (xy 48.475671 -84.502306) (xy 48.512907 -84.460746)
			(xy 48.534066 -84.442554) (xy 48.55591 -84.42452) (xy 48.58004 -84.373212) (xy 48.58004 -83.35899)
			(xy 48.579536 -83.335929) (xy 48.571213 -83.290563) (xy 48.554841 -83.247444) (xy 48.530959 -83.207987)
			(xy 48.500349 -83.173486) (xy 48.464016 -83.145074) (xy 48.423154 -83.123683) (xy 48.379103 -83.110016)
			(xy 48.356266 -83.106768) (xy 48.329117 -83.103063) (xy 48.276194 -83.088875) (xy 48.225845 -83.067261)
			(xy 48.179107 -83.038665) (xy 48.136941 -83.003676) (xy 48.100216 -82.963013) (xy 48.069687 -82.917514)
			(xy 48.045983 -82.868115) (xy 48.02959 -82.815832) (xy 48.020848 -82.761742) (xy 48.019934 -82.706957)
			(xy 48.026869 -82.652605) (xy 48.04151 -82.599805) (xy 48.063555 -82.549644) (xy 48.092551 -82.503152)
			(xy 48.1279 -82.461288) (xy 48.168876 -82.424913) (xy 48.214635 -82.394775) (xy 48.264236 -82.371495)
			(xy 48.316657 -82.355551) (xy 48.37082 -82.347272) (xy 48.425611 -82.346829) (xy 48.479901 -82.354229)
			(xy 48.50638 -82.361278) (xy 48.523398 -82.366104) (xy 48.621442 -82.366104) (xy 49.678082 -81.309464)
			(xy 50.674524 -81.309464) (xy 50.699162 -81.298542) (xy 50.723587 -81.288224) (xy 50.774573 -81.273678)
			(xy 50.827083 -81.266334) (xy 50.880105 -81.266334) (xy 50.932615 -81.273678) (xy 50.983601 -81.288224)
			(xy 51.008026 -81.298542) (xy 51.032664 -81.309464) (xy 51.82362 -81.309464) (xy 52.06238 -81.070704)
			(xy 52.06238 -80.991456) (xy 52.110132 -80.943704) (xy 53.634132 -80.943704) (xy 53.642289 -80.917686)
			(xy 53.664956 -80.868097) (xy 53.694447 -80.822236) (xy 53.730163 -80.781039) (xy 53.771377 -80.745341)
			(xy 53.817251 -80.715871) (xy 53.866851 -80.693227) (xy 53.919168 -80.67787) (xy 53.973138 -80.670113)
			(xy 54.027662 -80.670113) (xy 54.081632 -80.67787) (xy 54.133949 -80.693227) (xy 54.183549 -80.715871)
			(xy 54.229423 -80.745341) (xy 54.270637 -80.781039) (xy 54.306353 -80.822236) (xy 54.335844 -80.868097)
			(xy 54.358511 -80.917686) (xy 54.366668 -80.943704) (xy 54.64048 -80.943704) (xy 56.014874 -79.56931)
			(xy 56.033162 -79.508096) (xy 56.02605 -79.47279) (xy 56.02478 -79.466186) (xy 56.020565 -79.439687)
			(xy 56.018737 -79.386061) (xy 56.024446 -79.332709) (xy 56.03758 -79.280684) (xy 56.057879 -79.231015)
			(xy 56.071008 -79.207614) (xy 56.08828 -79.177896) (xy 56.08828 -79.043022) (xy 56.087864 -79.02803)
			(xy 56.080865 -78.998876) (xy 56.067247 -78.972164) (xy 56.047766 -78.949372) (xy 56.023499 -78.931762)
			(xy 56.009794 -78.925674) (xy 55.94223 -78.897734) (xy 55.927237 -78.892036) (xy 55.895487 -78.887561)
			(xy 55.863624 -78.891145) (xy 55.833661 -78.902562) (xy 55.82031 -78.91145) (xy 55.797691 -78.92683)
			(xy 55.74895 -78.951653) (xy 55.697164 -78.96926) (xy 55.643395 -78.979291) (xy 55.588744 -78.98154)
			(xy 55.534332 -78.975962) (xy 55.481274 -78.962669) (xy 55.430658 -78.941936) (xy 55.383523 -78.914187)
			(xy 55.340833 -78.879991) (xy 55.303465 -78.840048) (xy 55.272184 -78.795178) (xy 55.247631 -78.746301)
			(xy 55.230311 -78.694419) (xy 55.220577 -78.640594) (xy 55.21863 -78.585932) (xy 55.22451 -78.531551)
			(xy 55.238095 -78.478568) (xy 55.259108 -78.428068) (xy 55.287117 -78.381086) (xy 55.303928 -78.359508)
			(xy 55.317195 -78.342435) (xy 55.338323 -78.304714) (xy 55.352759 -78.26396) (xy 55.360085 -78.22135)
			(xy 55.360091 -78.178115) (xy 55.352775 -78.135503) (xy 55.33835 -78.094746) (xy 55.317232 -78.057019)
			(xy 55.303928 -78.039976) (xy 55.286607 -78.017822) (xy 55.257982 -77.96942) (xy 55.236773 -77.917339)
			(xy 55.22344 -77.862709) (xy 55.218272 -77.806714) (xy 55.221381 -77.750566) (xy 55.232699 -77.695484)
			(xy 55.251981 -77.642659) (xy 55.27881 -77.593238) (xy 55.312603 -77.548292) (xy 55.352629 -77.508793)
			(xy 55.39802 -77.475599) (xy 55.447793 -77.449428) (xy 55.500868 -77.430849) (xy 55.556096 -77.420262)
			(xy 55.61228 -77.417899) (xy 55.668202 -77.423809) (xy 55.72265 -77.437866) (xy 55.774445 -77.459764)
			(xy 55.822464 -77.489028) (xy 55.84444 -77.506576) (xy 55.912004 -77.514196) (xy 56.009794 -77.47381)
			(xy 56.023483 -77.467693) (xy 56.047739 -77.450082) (xy 56.067214 -77.427296) (xy 56.080834 -77.400593)
			(xy 56.087844 -77.371449) (xy 56.08828 -77.356462) (xy 56.08828 -77.221588) (xy 56.071008 -77.19187)
			(xy 56.057211 -77.167205) (xy 56.036246 -77.114724) (xy 56.023251 -77.059725) (xy 56.01851 -77.00341)
			(xy 56.022127 -76.947012) (xy 56.034023 -76.891765) (xy 56.053937 -76.838876) (xy 56.067198 -76.813918)
			(xy 56.0832 -76.785216) (xy 56.0832 -76.72578) (xy 56.082654 -76.709133) (xy 56.074033 -76.676976)
			(xy 56.057383 -76.648144) (xy 56.03384 -76.624604) (xy 56.005006 -76.607959) (xy 55.972847 -76.599343)
			(xy 55.9562 -76.59878) (xy 55.917338 -76.59878) (xy 55.88508 -76.620624) (xy 55.857969 -76.638341)
			(xy 55.800144 -76.667508) (xy 55.739082 -76.689093) (xy 55.675773 -76.702745) (xy 55.611242 -76.708244)
			(xy 55.546535 -76.7055) (xy 55.482701 -76.694557) (xy 55.420775 -76.675594) (xy 55.361759 -76.648918)
			(xy 55.306611 -76.61496) (xy 55.256224 -76.574271) (xy 55.211414 -76.527511) (xy 55.172907 -76.475436)
			(xy 55.141328 -76.418892) (xy 55.117189 -76.358794) (xy 55.10088 -76.296116) (xy 55.092666 -76.231875)
			(xy 55.092092 -76.199492) (xy 55.092092 -75.796902) (xy 55.853076 -75.035664) (xy 55.9562 -75.035664)
			(xy 55.972853 -75.035169) (xy 56.005024 -75.026548) (xy 56.033866 -75.009892) (xy 56.057414 -74.986337)
			(xy 56.074061 -74.95749) (xy 56.082674 -74.925317) (xy 56.0832 -74.908664) (xy 56.0832 -74.013568)
			(xy 56.067198 -73.984866) (xy 56.054142 -73.960414) (xy 56.034453 -73.908598) (xy 56.022473 -73.854477)
			(xy 56.018451 -73.799193) (xy 56.022475 -73.743909) (xy 56.034457 -73.689789) (xy 56.054148 -73.637974)
			(xy 56.067198 -73.613518) (xy 56.0832 -73.584816) (xy 56.0832 -73.407016) (xy 55.507636 -72.831452)
			(xy 54.629812 -72.831452) (xy 54.607026 -72.831968) (xy 54.562186 -72.840106) (xy 54.519515 -72.856106)
			(xy 54.480379 -72.879455) (xy 54.44603 -72.909406) (xy 54.417571 -72.944999) (xy 54.39591 -72.985094)
			(xy 54.381743 -73.028409) (xy 54.378098 -73.050908) (xy 54.374151 -73.076611) (xy 54.360191 -73.126704)
			(xy 54.339548 -73.174432) (xy 54.312604 -73.218908) (xy 54.296564 -73.239376) (xy 54.283304 -73.256449)
			(xy 54.262191 -73.294168) (xy 54.247769 -73.334917) (xy 54.240456 -73.37752) (xy 54.240461 -73.420746)
			(xy 54.247786 -73.463346) (xy 54.262218 -73.504092) (xy 54.283341 -73.541805) (xy 54.296564 -73.558908)
			(xy 54.30139 -73.56475) (xy 54.312022 -73.577178) (xy 54.33831 -73.596619) (xy 54.368679 -73.608729)
			(xy 54.401131 -73.612713) (xy 54.433528 -73.608307) (xy 54.463737 -73.595801) (xy 54.489769 -73.576019)
			(xy 54.500272 -73.56348) (xy 54.517533 -73.542277) (xy 54.557108 -73.504554) (xy 54.601664 -73.472867)
			(xy 54.650286 -73.447865) (xy 54.70198 -73.430062) (xy 54.755686 -73.419821) (xy 54.810304 -73.417352)
			(xy 54.864715 -73.422706) (xy 54.917805 -73.435773) (xy 54.968485 -73.456285) (xy 55.015717 -73.483823)
			(xy 55.058534 -73.517822) (xy 55.096059 -73.557585) (xy 55.127522 -73.602299) (xy 55.15228 -73.651046)
			(xy 55.169825 -73.702828) (xy 55.179797 -73.756585) (xy 55.181993 -73.811214) (xy 55.176367 -73.865598)
			(xy 55.163034 -73.918621) (xy 55.142268 -73.969198) (xy 55.114495 -74.016292) (xy 55.080282 -74.058939)
			(xy 55.040331 -74.096264) (xy 54.995461 -74.127503) (xy 54.946591 -74.152017) (xy 54.894722 -74.169302)
			(xy 54.840916 -74.179006) (xy 54.786276 -74.180928) (xy 54.731921 -74.17503) (xy 54.678965 -74.161432)
			(xy 54.628493 -74.140414) (xy 54.581538 -74.112405) (xy 54.559962 -74.09561) (xy 54.542888 -74.082348)
			(xy 54.505168 -74.061229) (xy 54.464417 -74.046802) (xy 54.421811 -74.039483) (xy 54.378581 -74.039483)
			(xy 54.335975 -74.046802) (xy 54.295224 -74.061229) (xy 54.257504 -74.082348) (xy 54.24043 -74.09561)
			(xy 54.234588 -74.100436) (xy 54.222158 -74.111071) (xy 54.202713 -74.137365) (xy 54.190597 -74.16774)
			(xy 54.186606 -74.200197) (xy 54.191003 -74.232603) (xy 54.203498 -74.262824) (xy 54.22327 -74.288872)
			(xy 54.235858 -74.299318) (xy 54.257066 -74.316582) (xy 54.294797 -74.356166) (xy 54.326491 -74.400731)
			(xy 54.351497 -74.449364) (xy 54.369304 -74.501069) (xy 54.379546 -74.554787) (xy 54.382014 -74.609416)
			(xy 54.376658 -74.663839) (xy 54.363586 -74.716939) (xy 54.343067 -74.767629) (xy 54.315521 -74.81487)
			(xy 54.281513 -74.857694) (xy 54.241739 -74.895225) (xy 54.197014 -74.926692) (xy 54.148255 -74.951452)
			(xy 54.096461 -74.968996) (xy 54.042692 -74.978967) (xy 53.98805 -74.981158) (xy 53.933656 -74.975526)
			(xy 53.880622 -74.962186) (xy 53.830037 -74.94141) (xy 53.782936 -74.913626) (xy 53.740284 -74.879401)
			(xy 53.702956 -74.839437) (xy 53.671715 -74.794554) (xy 53.647203 -74.74567) (xy 53.62992 -74.693787)
			(xy 53.620223 -74.639969) (xy 53.618308 -74.585317) (xy 53.624215 -74.530951) (xy 53.637824 -74.477986)
			(xy 53.658855 -74.427507) (xy 53.686878 -74.380547) (xy 53.703728 -74.359008) (xy 53.716995 -74.341935)
			(xy 53.738123 -74.304214) (xy 53.752559 -74.26346) (xy 53.759885 -74.22085) (xy 53.759891 -74.177615)
			(xy 53.752575 -74.135003) (xy 53.73815 -74.094246) (xy 53.717032 -74.056519) (xy 53.703728 -74.039476)
			(xy 53.698902 -74.033634) (xy 53.688264 -74.021253) (xy 53.661993 -74.001896) (xy 53.631671 -73.989839)
			(xy 53.599281 -73.985873) (xy 53.566945 -73.990255) (xy 53.536779 -74.0027) (xy 53.51076 -74.022393)
			(xy 53.500274 -74.034904) (xy 53.484131 -74.054765) (xy 53.447399 -74.090407) (xy 53.406231 -74.120817)
			(xy 53.361367 -74.145449) (xy 53.313612 -74.163862) (xy 53.263824 -74.175724) (xy 53.2384 -74.178668)
			(xy 53.215206 -74.181532) (xy 53.170351 -74.194625) (xy 53.128644 -74.215696) (xy 53.091492 -74.244036)
			(xy 53.060146 -74.27869) (xy 53.035663 -74.31849) (xy 53.018867 -74.362094) (xy 53.010325 -74.408034)
			(xy 53.0098 -74.431398) (xy 53.0098 -75.390248) (xy 51.926236 -76.473812) (xy 51.703224 -76.473812)
			(xy 51.675538 -76.488036) (xy 51.648329 -76.501691) (xy 51.591354 -76.523143) (xy 51.532226 -76.53764)
			(xy 51.471789 -76.544973) (xy 51.44135 -76.54544) (xy 50.91938 -76.54544) (xy 50.847752 -76.473812)
			(xy 50.106834 -76.473812) (xy 50.084104 -76.474313) (xy 50.039369 -76.482398) (xy 49.996787 -76.498316)
			(xy 49.957717 -76.521559) (xy 49.923409 -76.551384) (xy 49.894956 -76.586838) (xy 49.873268 -76.626791)
			(xy 49.859037 -76.669966) (xy 49.852717 -76.714985) (xy 49.853088 -76.737718) (xy 49.853683 -76.765352)
			(xy 49.847862 -76.820318) (xy 49.834171 -76.873869) (xy 49.812898 -76.924884) (xy 49.784486 -76.972295)
			(xy 49.749532 -77.015112) (xy 49.708765 -77.052437) (xy 49.66304 -77.08349) (xy 49.613312 -77.107621)
			(xy 49.560624 -77.124325) (xy 49.506077 -77.133252) (xy 49.450812 -77.134216) (xy 49.395987 -77.127196)
			(xy 49.342748 -77.112339) (xy 49.292209 -77.089957) (xy 49.245429 -77.060517) (xy 49.203386 -77.024635)
			(xy 49.184814 -77.004164) (xy 49.173464 -76.992021) (xy 49.145857 -76.973535) (xy 49.114408 -76.962817)
			(xy 49.081258 -76.960598) (xy 49.048661 -76.967029) (xy 49.018837 -76.981672) (xy 49.005998 -76.992226)
			(xy 48.98568 -77.009356) (xy 48.941183 -77.038413) (xy 48.893082 -77.061009) (xy 48.84231 -77.076706)
			(xy 48.789849 -77.085201) (xy 48.736717 -77.086329) (xy 48.683944 -77.080068) (xy 48.632551 -77.066539)
			(xy 48.583534 -77.046005) (xy 48.537844 -77.018863) (xy 48.516794 -77.00264) (xy 48.499685 -76.989526)
			(xy 48.461974 -76.968652) (xy 48.421281 -76.954441) (xy 48.378774 -76.947299) (xy 48.335671 -76.947431)
			(xy 48.293208 -76.954833) (xy 48.252603 -76.969294) (xy 48.215021 -76.990399) (xy 48.198024 -77.003656)
			(xy 48.175768 -77.021053) (xy 48.127129 -77.049782) (xy 48.074787 -77.071024) (xy 48.019884 -77.084315)
			(xy 47.963621 -77.089364) (xy 47.907228 -77.086061) (xy 47.85194 -77.074478) (xy 47.798964 -77.054869)
			(xy 47.749459 -77.027661) (xy 47.704507 -76.993451) (xy 47.665092 -76.952985) (xy 47.632075 -76.90715)
			(xy 47.606178 -76.856947) (xy 47.587968 -76.803473) (xy 47.577843 -76.747899) (xy 47.576486 -76.719684)
			(xy 47.575354 -76.697969) (xy 47.566602 -76.655381) (xy 47.550725 -76.614904) (xy 47.528187 -76.577723)
			(xy 47.499647 -76.544922) (xy 47.465938 -76.51746) (xy 47.428046 -76.496139) (xy 47.387076 -76.481582)
			(xy 47.344226 -76.474215) (xy 47.322486 -76.473812) (xy 47.321724 -76.473812) (xy 47.305068 -76.474304)
			(xy 47.272889 -76.482921) (xy 47.244038 -76.499575) (xy 47.220482 -76.523129) (xy 47.203826 -76.551978)
			(xy 47.195205 -76.584156) (xy 47.194724 -76.600812) (xy 47.194724 -76.646278) (xy 47.223172 -76.681076)
			(xy 47.240359 -76.702958) (xy 47.268877 -76.750736) (xy 47.290151 -76.802149) (xy 47.30373 -76.856108)
			(xy 47.309326 -76.911467) (xy 47.306819 -76.967051) (xy 47.296265 -77.021682) (xy 47.277885 -77.0742)
			(xy 47.25207 -77.12349) (xy 47.219369 -77.168507) (xy 47.180474 -77.208296) (xy 47.136212 -77.242011)
			(xy 47.08752 -77.268939) (xy 47.035434 -77.288507) (xy 46.981057 -77.3003) (xy 46.925544 -77.304069)
			(xy 46.870072 -77.299732) (xy 46.815819 -77.287382) (xy 46.763935 -77.267282) (xy 46.715522 -77.239857)
			(xy 46.671608 -77.205689) (xy 46.633122 -77.165504) (xy 46.61662 -77.143102) (xy 46.602776 -77.124539)
			(xy 46.569535 -77.092306) (xy 46.53101 -77.06662) (xy 46.488473 -77.04833) (xy 46.443329 -77.038039)
			(xy 46.397067 -77.036087) (xy 46.351216 -77.042538) (xy 46.329092 -77.049376) (xy 46.303986 -77.057325)
			(xy 46.252228 -77.067034) (xy 46.199627 -77.069527) (xy 46.147183 -77.064757) (xy 46.095894 -77.052814)
			(xy 46.046737 -77.033926) (xy 46.000648 -77.008453) (xy 45.979334 -76.992988) (xy 45.960322 -76.979392)
			(xy 45.918439 -76.95866) (xy 45.873471 -76.945934) (xy 45.826934 -76.941644) (xy 45.780397 -76.945934)
			(xy 45.735429 -76.95866) (xy 45.693546 -76.979392) (xy 45.674534 -76.992988) (xy 45.652443 -77.00895)
			(xy 45.604612 -77.035073) (xy 45.553549 -77.054122) (xy 45.500295 -77.065708) (xy 45.445934 -77.069597)
			(xy 45.391573 -77.065708) (xy 45.338319 -77.054122) (xy 45.287256 -77.035073) (xy 45.239425 -77.00895)
			(xy 45.217334 -76.992988) (xy 45.198322 -76.979392) (xy 45.156439 -76.95866) (xy 45.111471 -76.945934)
			(xy 45.064934 -76.941644) (xy 45.018397 -76.945934) (xy 44.973429 -76.95866) (xy 44.931546 -76.979392)
			(xy 44.912534 -76.992988) (xy 44.890356 -77.009004) (xy 44.84233 -77.035198) (xy 44.791055 -77.054264)
			(xy 44.737582 -77.06581) (xy 44.683008 -77.0696) (xy 44.628453 -77.065556) (xy 44.575035 -77.05376)
			(xy 44.523849 -77.034455) (xy 44.475946 -77.008037) (xy 44.432308 -76.975047) (xy 44.393829 -76.936163)
			(xy 44.361299 -76.89218) (xy 44.335385 -76.844003) (xy 44.316618 -76.792617) (xy 44.305384 -76.739078)
			(xy 44.303188 -76.71181) (xy 44.301129 -76.687938) (xy 44.289208 -76.641535) (xy 44.268803 -76.598188)
			(xy 44.240639 -76.559431) (xy 44.205711 -76.526638) (xy 44.165258 -76.50097) (xy 44.120712 -76.483336)
			(xy 44.073651 -76.47436) (xy 44.049696 -76.473812) (xy 41.776904 -76.473812) (xy 41.754028 -76.474298)
			(xy 41.709015 -76.482491) (xy 41.666197 -76.498614) (xy 41.626959 -76.522144) (xy 41.59257 -76.55232)
			(xy 41.564141 -76.588168) (xy 41.542591 -76.628528) (xy 41.528619 -76.672094) (xy 41.522674 -76.717459)
			(xy 41.52495 -76.763155) (xy 41.535374 -76.807704) (xy 41.543986 -76.828904) (xy 41.554702 -76.854792)
			(xy 41.569285 -76.908888) (xy 41.575802 -76.964535) (xy 41.574114 -77.020537) (xy 41.564256 -77.075691)
			(xy 41.54644 -77.12881) (xy 41.52105 -77.178754) (xy 41.48863 -77.224449) (xy 41.449878 -77.264913)
			(xy 41.405627 -77.299277) (xy 41.356827 -77.326802) (xy 41.304527 -77.346896) (xy 41.249851 -77.359128)
			(xy 41.193974 -77.363235) (xy 41.138097 -77.359128) (xy 41.083421 -77.346896) (xy 41.031121 -77.326802)
			(xy 40.982321 -77.299277) (xy 40.93807 -77.264913) (xy 40.899318 -77.224449) (xy 40.866898 -77.178754)
			(xy 40.841508 -77.12881) (xy 40.823692 -77.075691) (xy 40.813834 -77.020537) (xy 40.812146 -76.964535)
			(xy 40.818663 -76.908888) (xy 40.833246 -76.854792) (xy 40.843962 -76.828904) (xy 40.852621 -76.807723)
			(xy 40.863022 -76.763168) (xy 40.865281 -76.71747) (xy 40.859324 -76.672105) (xy 40.845344 -76.62854)
			(xy 40.823792 -76.58818) (xy 40.795363 -76.552329) (xy 40.760977 -76.522146) (xy 40.721744 -76.498605)
			(xy 40.678931 -76.482467) (xy 40.633921 -76.474252) (xy 40.611044 -76.473812) (xy 38.42258 -76.473812)
			(xy 36.85032 -74.901552) (xy 36.85032 -74.043286) (xy 36.526724 -73.71969) (xy 35.66541 -73.71969)
			(xy 35.642033 -73.720221) (xy 35.596068 -73.728774) (xy 35.552444 -73.745592) (xy 35.512633 -73.770108)
			(xy 35.47798 -73.801494) (xy 35.449654 -73.838691) (xy 35.428612 -73.880442) (xy 35.415565 -73.925338)
			(xy 35.41268 -73.948544) (xy 35.409397 -73.976485) (xy 35.395669 -74.031041) (xy 35.374077 -74.082989)
			(xy 35.345089 -74.131202) (xy 35.309334 -74.174635) (xy 35.267587 -74.212346) (xy 35.220755 -74.243516)
			(xy 35.169852 -74.267469) (xy 35.115984 -74.283686) (xy 35.060317 -74.291816) (xy 35.032188 -74.292206)
			(xy 35.009978 -74.292621) (xy 34.966221 -74.300259) (xy 34.924459 -74.315389) (xy 34.885963 -74.337549)
			(xy 34.851907 -74.366065) (xy 34.823326 -74.400068) (xy 34.801093 -74.438521) (xy 34.785884 -74.480255)
			(xy 34.778162 -74.523997) (xy 34.77768 -74.546206) (xy 34.77768 -74.735436) (xy 34.778173 -74.758014)
			(xy 34.786156 -74.80246) (xy 34.801864 -74.844797) (xy 34.824804 -74.883693) (xy 34.854254 -74.917926)
			(xy 34.889288 -74.946418) (xy 34.928804 -74.968273) (xy 34.971559 -74.982805) (xy 35.016208 -74.989556)
			(xy 35.038792 -74.989436) (xy 35.066527 -74.989155) (xy 35.121611 -74.995645) (xy 35.175174 -75.010045)
			(xy 35.226087 -75.032051) (xy 35.273275 -75.061199) (xy 35.315743 -75.096874) (xy 35.352597 -75.138325)
			(xy 35.383058 -75.184676) (xy 35.406485 -75.234951) (xy 35.422383 -75.288088) (xy 35.430416 -75.342968)
			(xy 35.430416 -75.398433) (xy 35.422383 -75.453312) (xy 35.406485 -75.50645) (xy 35.383058 -75.556725)
			(xy 35.352597 -75.603076) (xy 35.315743 -75.644526) (xy 35.273274 -75.680202) (xy 35.226086 -75.70935)
			(xy 35.175174 -75.731355) (xy 35.121611 -75.745755) (xy 35.066527 -75.752245) (xy 35.038792 -75.751944)
			(xy 35.016202 -75.751795) (xy 34.971534 -75.75852) (xy 34.928759 -75.773036) (xy 34.889225 -75.794886)
			(xy 34.854176 -75.823382) (xy 34.824719 -75.857626) (xy 34.80178 -75.896539) (xy 34.786082 -75.938895)
			(xy 34.778121 -75.983358) (xy 34.77768 -76.005944) (xy 34.77768 -76.201778) (xy 34.837878 -76.272898)
			(xy 34.883852 -76.280518) (xy 34.911626 -76.285666) (xy 34.965364 -76.303067) (xy 35.01595 -76.328201)
			(xy 35.062278 -76.360517) (xy 35.103336 -76.39931) (xy 35.138226 -76.443731) (xy 35.166186 -76.492811)
			(xy 35.186606 -76.545476) (xy 35.199038 -76.600577) (xy 35.203212 -76.656908) (xy 35.199036 -76.713238)
			(xy 35.186601 -76.768338) (xy 35.16618 -76.821003) (xy 35.138217 -76.870081) (xy 35.103325 -76.914502)
			(xy 35.062266 -76.953293) (xy 35.015937 -76.985607) (xy 34.96535 -77.010738) (xy 34.911612 -77.028138)
			(xy 34.883852 -77.033374) (xy 34.837878 -77.040994) (xy 34.797674 -77.088492) (xy 37.469062 -77.088492)
			(xy 37.473133 -77.03287) (xy 37.485259 -76.978433) (xy 37.505182 -76.926342) (xy 37.532478 -76.877707)
			(xy 37.566564 -76.833564) (xy 37.606713 -76.794855) (xy 37.652071 -76.762404) (xy 37.701671 -76.736903)
			(xy 37.754455 -76.718896) (xy 37.809298 -76.708766) (xy 37.865032 -76.706729) (xy 37.920469 -76.712829)
			(xy 37.974426 -76.726935) (xy 38.025755 -76.748747) (xy 38.073361 -76.777801) (xy 38.116229 -76.813476)
			(xy 38.153446 -76.855013) (xy 38.184219 -76.901526) (xy 38.207891 -76.952023) (xy 38.223959 -77.00543)
			(xy 38.232079 -77.060606) (xy 38.232588 -77.088492) (xy 38.232079 -77.116378) (xy 38.223959 -77.171554)
			(xy 38.207891 -77.224961) (xy 38.184219 -77.275458) (xy 38.153446 -77.321971) (xy 38.116229 -77.363508)
			(xy 38.073361 -77.399183) (xy 38.025755 -77.428237) (xy 37.974426 -77.450049) (xy 37.920469 -77.464155)
			(xy 37.865032 -77.470255) (xy 37.809298 -77.468218) (xy 37.754455 -77.458088) (xy 37.701671 -77.440081)
			(xy 37.652071 -77.41458) (xy 37.606713 -77.382129) (xy 37.566564 -77.34342) (xy 37.532478 -77.299277)
			(xy 37.505182 -77.250642) (xy 37.485259 -77.198551) (xy 37.473133 -77.144114) (xy 37.469062 -77.088492)
			(xy 34.797674 -77.088492) (xy 34.77768 -77.112114) (xy 34.77768 -77.27188) (xy 34.801302 -77.322426)
			(xy 34.822892 -77.340714) (xy 34.84376 -77.358941) (xy 34.880528 -77.400391) (xy 34.910915 -77.446721)
			(xy 34.934284 -77.496959) (xy 34.950142 -77.550047) (xy 34.958158 -77.604871) (xy 34.958162 -77.660278)
			(xy 34.950154 -77.715102) (xy 34.934302 -77.768193) (xy 34.92452 -77.78923) (xy 52.018003 -77.78923)
			(xy 52.023542 -77.734043) (xy 52.037012 -77.680239) (xy 52.05813 -77.628953) (xy 52.086451 -77.581264)
			(xy 52.103528 -77.559408) (xy 52.116751 -77.542305) (xy 52.137875 -77.504592) (xy 52.152308 -77.463847)
			(xy 52.159633 -77.421246) (xy 52.159638 -77.37802) (xy 52.152324 -77.335417) (xy 52.137902 -77.294668)
			(xy 52.116788 -77.256949) (xy 52.103528 -77.239876) (xy 52.086451 -77.21802) (xy 52.05813 -77.170331)
			(xy 52.037012 -77.119045) (xy 52.023542 -77.065241) (xy 52.018003 -77.010054) (xy 52.020512 -76.954647)
			(xy 52.031017 -76.900186) (xy 52.049296 -76.847821) (xy 52.074964 -76.798653) (xy 52.107479 -76.75372)
			(xy 52.146158 -76.713967) (xy 52.190184 -76.680234) (xy 52.23863 -76.653229) (xy 52.290476 -76.633523)
			(xy 52.344628 -76.621531) (xy 52.399946 -76.617506) (xy 52.455264 -76.621531) (xy 52.509416 -76.633523)
			(xy 52.561262 -76.653229) (xy 52.609708 -76.680234) (xy 52.653734 -76.713967) (xy 52.692413 -76.75372)
			(xy 52.724928 -76.798653) (xy 52.750596 -76.847821) (xy 52.768875 -76.900186) (xy 52.77938 -76.954647)
			(xy 52.78146 -77.000587) (xy 53.617995 -77.000587) (xy 53.622249 -76.942731) (xy 53.635213 -76.886185)
			(xy 53.656588 -76.832254) (xy 53.68588 -76.78218) (xy 53.703728 -76.759308) (xy 53.716951 -76.742205)
			(xy 53.738075 -76.704492) (xy 53.752508 -76.663747) (xy 53.759833 -76.621146) (xy 53.759838 -76.57792)
			(xy 53.752524 -76.535317) (xy 53.738102 -76.494568) (xy 53.716988 -76.456849) (xy 53.703728 -76.439776)
			(xy 53.686651 -76.41792) (xy 53.65833 -76.370231) (xy 53.637212 -76.318945) (xy 53.623742 -76.265141)
			(xy 53.618203 -76.209954) (xy 53.620712 -76.154547) (xy 53.631217 -76.100086) (xy 53.649496 -76.047721)
			(xy 53.675164 -75.998553) (xy 53.707679 -75.95362) (xy 53.746358 -75.913867) (xy 53.790384 -75.880134)
			(xy 53.83883 -75.853129) (xy 53.890676 -75.833423) (xy 53.944828 -75.821431) (xy 54.000146 -75.817406)
			(xy 54.055464 -75.821431) (xy 54.109616 -75.833423) (xy 54.161462 -75.853129) (xy 54.209908 -75.880134)
			(xy 54.253934 -75.913867) (xy 54.292613 -75.95362) (xy 54.325128 -75.998553) (xy 54.350796 -76.047721)
			(xy 54.369075 -76.100086) (xy 54.37958 -76.154547) (xy 54.382089 -76.209954) (xy 54.37655 -76.265141)
			(xy 54.36308 -76.318945) (xy 54.341962 -76.370231) (xy 54.313641 -76.41792) (xy 54.296564 -76.439776)
			(xy 54.283261 -76.45682) (xy 54.262143 -76.494546) (xy 54.247718 -76.535304) (xy 54.240403 -76.577915)
			(xy 54.240409 -76.62115) (xy 54.247735 -76.66376) (xy 54.26217 -76.704513) (xy 54.283297 -76.742235)
			(xy 54.296564 -76.759308) (xy 54.314288 -76.782089) (xy 54.343487 -76.831874) (xy 54.364853 -76.88549)
			(xy 54.377898 -76.941712) (xy 54.382325 -76.999258) (xy 54.378031 -77.056814) (xy 54.365116 -77.113067)
			(xy 54.343875 -77.166732) (xy 54.314791 -77.216584) (xy 54.297072 -77.239368) (xy 54.28381 -77.256518)
			(xy 54.262702 -77.294381) (xy 54.248327 -77.335278) (xy 54.241103 -77.378022) (xy 54.241239 -77.421371)
			(xy 54.248732 -77.464068) (xy 54.263363 -77.504874) (xy 54.284708 -77.542604) (xy 54.298088 -77.559662)
			(xy 54.31532 -77.581428) (xy 54.34391 -77.629016) (xy 54.365302 -77.680245) (xy 54.379047 -77.734032)
			(xy 54.384853 -77.789244) (xy 54.382598 -77.844714) (xy 54.37233 -77.899272) (xy 54.354266 -77.951766)
			(xy 54.328787 -78.00109) (xy 54.29643 -78.046201) (xy 54.257878 -78.086148) (xy 54.213945 -78.120088)
			(xy 54.165559 -78.147304) (xy 54.113739 -78.167222) (xy 54.059581 -78.179423) (xy 54.004226 -78.183647)
			(xy 53.948843 -78.179807) (xy 53.894601 -78.167983) (xy 53.842645 -78.148424) (xy 53.79407 -78.121544)
			(xy 53.749903 -78.08791) (xy 53.711075 -78.048231) (xy 53.678406 -78.003346) (xy 53.652585 -77.9542)
			(xy 53.634157 -77.901832) (xy 53.623511 -77.847347) (xy 53.620871 -77.791894) (xy 53.626294 -77.736644)
			(xy 53.639665 -77.682762) (xy 53.660702 -77.631387) (xy 53.68896 -77.583601) (xy 53.706014 -77.561694)
			(xy 53.719313 -77.544571) (xy 53.74042 -77.506702) (xy 53.754792 -77.4658) (xy 53.762012 -77.423051)
			(xy 53.761871 -77.379697) (xy 53.754373 -77.336997) (xy 53.739734 -77.296189) (xy 53.718381 -77.258458)
			(xy 53.704998 -77.2414) (xy 53.687008 -77.218641) (xy 53.657457 -77.168719) (xy 53.635804 -77.114899)
			(xy 53.622548 -77.058421) (xy 53.617995 -77.000587) (xy 52.78146 -77.000587) (xy 52.781889 -77.010054)
			(xy 52.77635 -77.065241) (xy 52.76288 -77.119045) (xy 52.741762 -77.170331) (xy 52.713441 -77.21802)
			(xy 52.696364 -77.239876) (xy 52.683061 -77.25692) (xy 52.661943 -77.294646) (xy 52.647518 -77.335404)
			(xy 52.640203 -77.378015) (xy 52.640209 -77.42125) (xy 52.647535 -77.46386) (xy 52.66197 -77.504613)
			(xy 52.683097 -77.542335) (xy 52.696364 -77.559408) (xy 52.713441 -77.581264) (xy 52.741762 -77.628953)
			(xy 52.76288 -77.680239) (xy 52.77635 -77.734043) (xy 52.781889 -77.78923) (xy 52.77938 -77.844637)
			(xy 52.768875 -77.899098) (xy 52.750596 -77.951463) (xy 52.724928 -78.000631) (xy 52.692413 -78.045564)
			(xy 52.653734 -78.085317) (xy 52.609708 -78.11905) (xy 52.561262 -78.146055) (xy 52.509416 -78.165761)
			(xy 52.455264 -78.177753) (xy 52.399946 -78.181778) (xy 52.344628 -78.177753) (xy 52.290476 -78.165761)
			(xy 52.23863 -78.146055) (xy 52.190184 -78.11905) (xy 52.146158 -78.085317) (xy 52.107479 -78.045564)
			(xy 52.074964 -78.000631) (xy 52.049296 -77.951463) (xy 52.031017 -77.899098) (xy 52.020512 -77.844637)
			(xy 52.018003 -77.78923) (xy 34.92452 -77.78923) (xy 34.91094 -77.818434) (xy 34.880559 -77.864768)
			(xy 34.843797 -77.906223) (xy 34.822892 -77.924406) (xy 34.822638 -77.92466) (xy 34.808952 -77.937033)
			(xy 34.788764 -77.967896) (xy 34.778258 -78.003247) (xy 34.77768 -78.021688) (xy 34.77768 -78.426818)
			(xy 38.881556 -78.426818) (xy 38.885627 -78.371196) (xy 38.897753 -78.316759) (xy 38.917676 -78.264668)
			(xy 38.944972 -78.216033) (xy 38.979058 -78.17189) (xy 39.019207 -78.133181) (xy 39.064565 -78.10073)
			(xy 39.114165 -78.075229) (xy 39.166949 -78.057222) (xy 39.221792 -78.047092) (xy 39.277526 -78.045055)
			(xy 39.332963 -78.051155) (xy 39.38692 -78.065261) (xy 39.438249 -78.087073) (xy 39.485855 -78.116127)
			(xy 39.528723 -78.151802) (xy 39.56594 -78.193339) (xy 39.596713 -78.239852) (xy 39.620385 -78.290349)
			(xy 39.636453 -78.343756) (xy 39.644573 -78.398932) (xy 39.645082 -78.426818) (xy 39.644573 -78.454704)
			(xy 39.636453 -78.50988) (xy 39.620385 -78.563287) (xy 39.596713 -78.613784) (xy 39.56594 -78.660297)
			(xy 39.528723 -78.701834) (xy 39.485855 -78.737509) (xy 39.438249 -78.766563) (xy 39.38692 -78.788375)
			(xy 39.332963 -78.802481) (xy 39.277526 -78.808581) (xy 39.221792 -78.806544) (xy 39.166949 -78.796414)
			(xy 39.114165 -78.778407) (xy 39.064565 -78.752906) (xy 39.019207 -78.720455) (xy 38.979058 -78.681746)
			(xy 38.944972 -78.637603) (xy 38.917676 -78.588968) (xy 38.897753 -78.536877) (xy 38.885627 -78.48244)
			(xy 38.881556 -78.426818) (xy 34.77768 -78.426818) (xy 34.77768 -78.780132) (xy 35.076892 -79.079344)
			(xy 36.630862 -79.079344) (xy 36.634933 -79.023722) (xy 36.647059 -78.969285) (xy 36.666982 -78.917194)
			(xy 36.694278 -78.868559) (xy 36.728364 -78.824416) (xy 36.768513 -78.785707) (xy 36.813871 -78.753256)
			(xy 36.863471 -78.727755) (xy 36.916255 -78.709748) (xy 36.971098 -78.699618) (xy 37.026832 -78.697581)
			(xy 37.082269 -78.703681) (xy 37.136226 -78.717787) (xy 37.187555 -78.739599) (xy 37.235161 -78.768653)
			(xy 37.278029 -78.804328) (xy 37.301183 -78.83017) (xy 40.68648 -78.83017) (xy 40.690551 -78.774548)
			(xy 40.702677 -78.720111) (xy 40.7226 -78.66802) (xy 40.749896 -78.619385) (xy 40.783982 -78.575242)
			(xy 40.824131 -78.536533) (xy 40.869489 -78.504082) (xy 40.919089 -78.478581) (xy 40.971873 -78.460574)
			(xy 41.026716 -78.450444) (xy 41.08245 -78.448407) (xy 41.137887 -78.454507) (xy 41.191844 -78.468613)
			(xy 41.243173 -78.490425) (xy 41.290779 -78.519479) (xy 41.333647 -78.555154) (xy 41.370864 -78.596691)
			(xy 41.401637 -78.643204) (xy 41.425309 -78.693701) (xy 41.427394 -78.70063) (xy 44.33138 -78.70063)
			(xy 44.335451 -78.645008) (xy 44.347577 -78.590571) (xy 44.3675 -78.53848) (xy 44.394796 -78.489845)
			(xy 44.428882 -78.445702) (xy 44.469031 -78.406993) (xy 44.514389 -78.374542) (xy 44.563989 -78.349041)
			(xy 44.616773 -78.331034) (xy 44.671616 -78.320904) (xy 44.72735 -78.318867) (xy 44.782787 -78.324967)
			(xy 44.836744 -78.339073) (xy 44.888073 -78.360885) (xy 44.935679 -78.389939) (xy 44.978547 -78.425614)
			(xy 45.015764 -78.467151) (xy 45.046537 -78.513664) (xy 45.070209 -78.564161) (xy 45.086277 -78.617568)
			(xy 45.094397 -78.672744) (xy 45.094906 -78.70063) (xy 45.094397 -78.728516) (xy 45.086277 -78.783692)
			(xy 45.070209 -78.837099) (xy 45.046537 -78.887596) (xy 45.032774 -78.908399) (xy 45.402575 -78.908399)
			(xy 45.406464 -78.854042) (xy 45.418048 -78.800792) (xy 45.437094 -78.749733) (xy 45.463213 -78.701904)
			(xy 45.495873 -78.658279) (xy 45.534409 -78.619747) (xy 45.578037 -78.587091) (xy 45.625868 -78.560978)
			(xy 45.67693 -78.541937) (xy 45.730181 -78.530358) (xy 45.784538 -78.526475) (xy 45.838895 -78.530369)
			(xy 45.892144 -78.541959) (xy 45.943201 -78.561009) (xy 45.991028 -78.587133) (xy 46.013116 -78.603094)
			(xy 46.032128 -78.61669) (xy 46.074011 -78.637422) (xy 46.118979 -78.650148) (xy 46.165516 -78.654438)
			(xy 46.212053 -78.650148) (xy 46.257021 -78.637422) (xy 46.298904 -78.61669) (xy 46.317916 -78.603094)
			(xy 46.340007 -78.587132) (xy 46.387838 -78.561009) (xy 46.438901 -78.54196) (xy 46.492155 -78.530374)
			(xy 46.546516 -78.526485) (xy 46.600877 -78.530374) (xy 46.654131 -78.54196) (xy 46.705194 -78.561009)
			(xy 46.753025 -78.587132) (xy 46.775116 -78.603094) (xy 46.794128 -78.61669) (xy 46.836011 -78.637422)
			(xy 46.880979 -78.650148) (xy 46.927516 -78.654438) (xy 46.974053 -78.650148) (xy 47.019021 -78.637422)
			(xy 47.060904 -78.61669) (xy 47.079916 -78.603094) (xy 47.104112 -78.585672) (xy 47.156814 -78.557793)
			(xy 47.213214 -78.538461) (xy 47.242476 -78.532736) (xy 47.259315 -78.529211) (xy 47.290355 -78.514402)
			(xy 47.316322 -78.491853) (xy 47.335337 -78.463196) (xy 47.346023 -78.430507) (xy 47.347378 -78.413356)
			(xy 47.349132 -78.385758) (xy 47.359654 -78.33147) (xy 47.377905 -78.279269) (xy 47.403501 -78.230251)
			(xy 47.435907 -78.185442) (xy 47.474444 -78.145783) (xy 47.518303 -78.112103) (xy 47.566566 -78.085109)
			(xy 47.618221 -78.065367) (xy 47.672185 -78.053291) (xy 47.727328 -78.049133) (xy 47.782493 -78.052981)
			(xy 47.836524 -78.064755) (xy 47.888289 -78.084206) (xy 47.936702 -78.110928) (xy 47.98075 -78.144361)
			(xy 48.019509 -78.183804) (xy 48.052166 -78.22843) (xy 48.078038 -78.277304) (xy 48.096581 -78.329401)
			(xy 48.107407 -78.38363) (xy 48.108676 -78.407932) (xy 48.84681 -78.407932) (xy 48.848156 -78.352257)
			(xy 48.857584 -78.297369) (xy 48.874894 -78.244436) (xy 48.899717 -78.194582) (xy 48.931527 -78.148869)
			(xy 48.969646 -78.108267) (xy 49.013264 -78.07364) (xy 49.061454 -78.045725) (xy 49.113191 -78.025114)
			(xy 49.167376 -78.012246) (xy 49.222856 -78.007394) (xy 49.278451 -78.010662) (xy 49.332981 -78.021981)
			(xy 49.385285 -78.041108) (xy 49.434251 -78.067639) (xy 49.456848 -78.083918) (xy 49.47586 -78.097514)
			(xy 49.517743 -78.118246) (xy 49.562711 -78.130972) (xy 49.609248 -78.135262) (xy 49.655785 -78.130972)
			(xy 49.700753 -78.118246) (xy 49.742636 -78.097514) (xy 49.761648 -78.083918) (xy 49.784032 -78.067727)
			(xy 49.832554 -78.041317) (xy 49.884378 -78.022183) (xy 49.938421 -78.010726) (xy 49.993551 -78.007186)
			(xy 50.048615 -78.011635) (xy 50.102461 -78.023982) (xy 50.153963 -78.043969) (xy 50.202042 -78.071175)
			(xy 50.245694 -78.105034) (xy 50.284004 -78.144836) (xy 50.316172 -78.189748) (xy 50.341524 -78.238831)
			(xy 50.359529 -78.291058) (xy 50.365152 -78.318106) (xy 50.368413 -78.332939) (xy 50.380976 -78.360581)
			(xy 50.399721 -78.384467) (xy 50.423583 -78.403242) (xy 50.451209 -78.415839) (xy 50.481031 -78.421545)
			(xy 50.496216 -78.42123) (xy 50.523739 -78.420424) (xy 50.578553 -78.425576) (xy 50.632058 -78.438554)
			(xy 50.683141 -78.45909) (xy 50.730742 -78.486756) (xy 50.77387 -78.520978) (xy 50.81163 -78.561045)
			(xy 50.843238 -78.606124) (xy 50.868036 -78.65528) (xy 50.885511 -78.707489) (xy 50.895297 -78.761669)
			(xy 50.897193 -78.816693) (xy 50.891159 -78.871417) (xy 50.87732 -78.924706) (xy 50.855964 -78.975451)
			(xy 50.827534 -79.022599) (xy 50.792621 -79.065171) (xy 50.751951 -79.10228) (xy 50.706368 -79.133157)
			(xy 50.656819 -79.15716) (xy 50.604335 -79.173791) (xy 50.550004 -79.182703) (xy 50.494957 -79.183712)
			(xy 50.440337 -79.176796) (xy 50.387278 -79.1621) (xy 50.336884 -79.139929) (xy 50.2902 -79.110743)
			(xy 50.268886 -79.093314) (xy 50.250912 -79.078819) (xy 50.210879 -79.055822) (xy 50.167349 -79.040439)
			(xy 50.121756 -79.033176) (xy 50.075601 -79.034274) (xy 50.030405 -79.043694) (xy 49.987655 -79.061129)
			(xy 49.94876 -79.086002) (xy 49.915001 -79.117495) (xy 49.90084 -79.135732) (xy 49.884222 -79.157242)
			(xy 49.845965 -79.195849) (xy 49.802614 -79.228634) (xy 49.755049 -79.254933) (xy 49.704232 -79.274214)
			(xy 49.651193 -79.286087) (xy 49.597005 -79.29031) (xy 49.542767 -79.286798) (xy 49.489576 -79.275622)
			(xy 49.43851 -79.257009) (xy 49.390604 -79.231336) (xy 49.346827 -79.199122) (xy 49.308067 -79.161021)
			(xy 49.275107 -79.117803) (xy 49.248616 -79.070343) (xy 49.229131 -79.019605) (xy 49.217045 -78.966613)
			(xy 49.212604 -78.912443) (xy 49.21377 -78.885288) (xy 49.214293 -78.868132) (xy 49.20712 -78.834577)
			(xy 49.191268 -78.804144) (xy 49.167883 -78.779033) (xy 49.138654 -78.761057) (xy 49.12233 -78.755748)
			(xy 49.095729 -78.747499) (xy 49.045048 -78.724412) (xy 48.998263 -78.694201) (xy 48.956369 -78.657507)
			(xy 48.920256 -78.615111) (xy 48.890693 -78.567914) (xy 48.868307 -78.516919) (xy 48.853575 -78.463211)
			(xy 48.84681 -78.407932) (xy 48.108676 -78.407932) (xy 48.11029 -78.438853) (xy 48.105168 -78.493915)
			(xy 48.092149 -78.547659) (xy 48.071507 -78.598961) (xy 48.043673 -78.646744) (xy 48.009232 -78.690008)
			(xy 47.968904 -78.727845) (xy 47.923535 -78.759463) (xy 47.874077 -78.784198) (xy 47.821565 -78.801532)
			(xy 47.794418 -78.806802) (xy 47.777569 -78.81029) (xy 47.746526 -78.825106) (xy 47.720558 -78.847664)
			(xy 47.701546 -78.876329) (xy 47.690866 -78.909027) (xy 47.689516 -78.926182) (xy 47.687714 -78.953688)
			(xy 47.677245 -79.007806) (xy 47.659094 -79.059852) (xy 47.633641 -79.108744) (xy 47.601414 -79.153462)
			(xy 47.563086 -79.193076) (xy 47.519454 -79.226759) (xy 47.471428 -79.253811) (xy 47.420008 -79.273667)
			(xy 47.366265 -79.285915) (xy 47.311319 -79.290298) (xy 47.256315 -79.286726) (xy 47.202397 -79.275274)
			(xy 47.150689 -79.256179) (xy 47.102269 -79.229839) (xy 47.079916 -79.21371) (xy 47.060904 -79.200114)
			(xy 47.019021 -79.179382) (xy 46.974053 -79.166656) (xy 46.927516 -79.162366) (xy 46.880979 -79.166656)
			(xy 46.836011 -79.179382) (xy 46.794128 -79.200114) (xy 46.775116 -79.21371) (xy 46.753025 -79.229672)
			(xy 46.705194 -79.255795) (xy 46.654131 -79.274844) (xy 46.600877 -79.28643) (xy 46.546516 -79.290319)
			(xy 46.492155 -79.28643) (xy 46.438901 -79.274844) (xy 46.387838 -79.255795) (xy 46.340007 -79.229672)
			(xy 46.317916 -79.21371) (xy 46.298904 -79.200114) (xy 46.257021 -79.179382) (xy 46.212053 -79.166656)
			(xy 46.165516 -79.162366) (xy 46.118979 -79.166656) (xy 46.074011 -79.179382) (xy 46.032128 -79.200114)
			(xy 46.013116 -79.21371) (xy 45.991026 -79.229669) (xy 45.943199 -79.255792) (xy 45.892142 -79.274842)
			(xy 45.838892 -79.286431) (xy 45.784536 -79.290325) (xy 45.730179 -79.286442) (xy 45.676927 -79.274862)
			(xy 45.625866 -79.255821) (xy 45.578035 -79.229707) (xy 45.534407 -79.197052) (xy 45.495871 -79.158519)
			(xy 45.463211 -79.114894) (xy 45.437093 -79.067065) (xy 45.418048 -79.016006) (xy 45.406463 -78.962756)
			(xy 45.402575 -78.908399) (xy 45.032774 -78.908399) (xy 45.015764 -78.934109) (xy 44.978547 -78.975646)
			(xy 44.935679 -79.011321) (xy 44.888073 -79.040375) (xy 44.836744 -79.062187) (xy 44.782787 -79.076293)
			(xy 44.72735 -79.082393) (xy 44.671616 -79.080356) (xy 44.616773 -79.070226) (xy 44.563989 -79.052219)
			(xy 44.514389 -79.026718) (xy 44.469031 -78.994267) (xy 44.428882 -78.955558) (xy 44.394796 -78.911415)
			(xy 44.3675 -78.86278) (xy 44.347577 -78.810689) (xy 44.335451 -78.756252) (xy 44.33138 -78.70063)
			(xy 41.427394 -78.70063) (xy 41.441377 -78.747108) (xy 41.449497 -78.802284) (xy 41.450006 -78.83017)
			(xy 41.449497 -78.858056) (xy 41.441377 -78.913232) (xy 41.425309 -78.966639) (xy 41.401637 -79.017136)
			(xy 41.370864 -79.063649) (xy 41.333647 -79.105186) (xy 41.290779 -79.140861) (xy 41.243173 -79.169915)
			(xy 41.191844 -79.191727) (xy 41.137887 -79.205833) (xy 41.08245 -79.211933) (xy 41.026716 -79.209896)
			(xy 40.971873 -79.199766) (xy 40.919089 -79.181759) (xy 40.869489 -79.156258) (xy 40.824131 -79.123807)
			(xy 40.783982 -79.085098) (xy 40.749896 -79.040955) (xy 40.7226 -78.99232) (xy 40.702677 -78.940229)
			(xy 40.690551 -78.885792) (xy 40.68648 -78.83017) (xy 37.301183 -78.83017) (xy 37.315246 -78.845865)
			(xy 37.346019 -78.892378) (xy 37.369691 -78.942875) (xy 37.385759 -78.996282) (xy 37.393879 -79.051458)
			(xy 37.394388 -79.079344) (xy 37.393879 -79.10723) (xy 37.385759 -79.162406) (xy 37.369691 -79.215813)
			(xy 37.346019 -79.26631) (xy 37.315246 -79.312823) (xy 37.278029 -79.35436) (xy 37.235161 -79.390035)
			(xy 37.187555 -79.419089) (xy 37.136226 -79.440901) (xy 37.082269 -79.455007) (xy 37.026832 -79.461107)
			(xy 36.971098 -79.45907) (xy 36.916255 -79.44894) (xy 36.863471 -79.430933) (xy 36.813871 -79.405432)
			(xy 36.768513 -79.372981) (xy 36.728364 -79.334272) (xy 36.694278 -79.290129) (xy 36.666982 -79.241494)
			(xy 36.647059 -79.189403) (xy 36.634933 -79.134966) (xy 36.630862 -79.079344) (xy 35.076892 -79.079344)
			(xy 35.2171 -79.219552) (xy 35.2171 -80.476344) (xy 36.595302 -80.476344) (xy 36.599373 -80.420722)
			(xy 36.611499 -80.366285) (xy 36.631422 -80.314194) (xy 36.658718 -80.265559) (xy 36.692804 -80.221416)
			(xy 36.732953 -80.182707) (xy 36.778311 -80.150256) (xy 36.827911 -80.124755) (xy 36.880695 -80.106748)
			(xy 36.935538 -80.096618) (xy 36.991272 -80.094581) (xy 37.046709 -80.100681) (xy 37.100666 -80.114787)
			(xy 37.151995 -80.136599) (xy 37.199601 -80.165653) (xy 37.242469 -80.201328) (xy 37.279686 -80.242865)
			(xy 37.310459 -80.289378) (xy 37.334131 -80.339875) (xy 37.350199 -80.393282) (xy 37.358319 -80.448458)
			(xy 37.358828 -80.476344) (xy 37.358319 -80.50423) (xy 37.350199 -80.559406) (xy 37.334131 -80.612813)
			(xy 37.310459 -80.66331) (xy 37.279686 -80.709823) (xy 37.242469 -80.75136) (xy 37.199601 -80.787035)
			(xy 37.168467 -80.806036) (xy 37.951154 -80.806036) (xy 37.955225 -80.750414) (xy 37.967351 -80.695977)
			(xy 37.987274 -80.643886) (xy 38.01457 -80.595251) (xy 38.048656 -80.551108) (xy 38.088805 -80.512399)
			(xy 38.134163 -80.479948) (xy 38.183763 -80.454447) (xy 38.236547 -80.43644) (xy 38.29139 -80.42631)
			(xy 38.347124 -80.424273) (xy 38.402561 -80.430373) (xy 38.456518 -80.444479) (xy 38.507847 -80.466291)
			(xy 38.555453 -80.495345) (xy 38.598321 -80.53102) (xy 38.6192 -80.554322) (xy 40.642284 -80.554322)
			(xy 40.646355 -80.4987) (xy 40.658481 -80.444263) (xy 40.678404 -80.392172) (xy 40.7057 -80.343537)
			(xy 40.739786 -80.299394) (xy 40.779935 -80.260685) (xy 40.825293 -80.228234) (xy 40.874893 -80.202733)
			(xy 40.927677 -80.184726) (xy 40.98252 -80.174596) (xy 41.038254 -80.172559) (xy 41.093691 -80.178659)
			(xy 41.147648 -80.192765) (xy 41.198977 -80.214577) (xy 41.246583 -80.243631) (xy 41.289451 -80.279306)
			(xy 41.326668 -80.320843) (xy 41.357441 -80.367356) (xy 41.37025 -80.39468) (xy 45.42509 -80.39468)
			(xy 45.427492 -80.338802) (xy 45.438027 -80.283874) (xy 45.456471 -80.231073) (xy 45.482427 -80.181531)
			(xy 45.515339 -80.136311) (xy 45.554502 -80.096381) (xy 45.599075 -80.062598) (xy 45.648104 -80.035686)
			(xy 45.700537 -80.016221) (xy 45.755251 -80.004623) (xy 45.811072 -80.001137) (xy 45.866803 -80.005841)
			(xy 45.92125 -80.018632) (xy 45.973246 -80.039237) (xy 46.021675 -80.067213) (xy 46.0655 -80.101962)
			(xy 46.084998 -80.122014) (xy 46.100952 -80.138315) (xy 46.13758 -80.165491) (xy 46.178467 -80.185697)
			(xy 46.222304 -80.198287) (xy 46.267682 -80.202855) (xy 46.313148 -80.199256) (xy 46.357243 -80.187605)
			(xy 46.378114 -80.178402) (xy 46.402997 -80.167313) (xy 46.455107 -80.151444) (xy 46.508945 -80.143152)
			(xy 46.563416 -80.142605) (xy 46.617409 -80.149816) (xy 46.669828 -80.164637) (xy 46.719603 -80.186767)
			(xy 46.765723 -80.215754) (xy 46.7868 -80.233012) (xy 46.803434 -80.246517) (xy 46.840271 -80.268388)
			(xy 46.880257 -80.283765) (xy 46.922257 -80.29221) (xy 46.965079 -80.293483) (xy 47.007507 -80.28755)
			(xy 47.048336 -80.274577) (xy 47.086408 -80.254933) (xy 47.103792 -80.24241) (xy 47.126229 -80.226266)
			(xy 47.174754 -80.199802) (xy 47.226589 -80.180618) (xy 47.280651 -80.169116) (xy 47.335807 -80.165537)
			(xy 47.390901 -80.169955) (xy 47.444782 -80.182279) (xy 47.496319 -80.202249) (xy 47.544436 -80.229448)
			(xy 47.588122 -80.263307) (xy 47.626465 -80.303116) (xy 47.658662 -80.348042) (xy 47.684037 -80.397145)
			(xy 47.702061 -80.449395) (xy 47.712354 -80.5037) (xy 47.714243 -80.548114) (xy 48.17248 -80.548114)
			(xy 48.178531 -80.492475) (xy 48.192644 -80.438316) (xy 48.214516 -80.386799) (xy 48.243677 -80.33903)
			(xy 48.279503 -80.296031) (xy 48.321226 -80.258727) (xy 48.367949 -80.227917) (xy 48.418671 -80.204261)
			(xy 48.472305 -80.188268) (xy 48.527699 -80.18028) (xy 48.583666 -80.180468) (xy 48.639006 -80.188829)
			(xy 48.69253 -80.205183) (xy 48.743092 -80.22918) (xy 48.789607 -80.260304) (xy 48.810672 -80.278732)
			(xy 48.823168 -80.289361) (xy 48.852298 -80.304424) (xy 48.884308 -80.311557) (xy 48.917078 -80.310288)
			(xy 48.94844 -80.3007) (xy 48.976318 -80.283429) (xy 48.987964 -80.271874) (xy 49.007851 -80.251682)
			(xy 49.052474 -80.216747) (xy 49.101772 -80.188795) (xy 49.154662 -80.16844) (xy 49.20998 -80.156131)
			(xy 49.26651 -80.152138) (xy 49.32301 -80.156548) (xy 49.378236 -80.169265) (xy 49.430974 -80.19001)
			(xy 49.480065 -80.218325) (xy 49.502568 -80.235552) (xy 49.516483 -80.245868) (xy 49.548353 -80.259392)
			(xy 49.582688 -80.263833) (xy 49.61695 -80.25886) (xy 49.648606 -80.244843) (xy 49.662334 -80.234282)
			(xy 49.684077 -80.217071) (xy 49.731524 -80.188376) (xy 49.782626 -80.166852) (xy 49.836304 -80.15295)
			(xy 49.89143 -80.146965) (xy 49.946842 -80.149022) (xy 49.951777 -80.149932) (xy 51.194898 -80.149932)
			(xy 51.200483 -80.094655) (xy 51.214027 -80.040773) (xy 51.235242 -79.989424) (xy 51.26368 -79.941696)
			(xy 51.280822 -79.91983) (xy 51.29533 -79.901298) (xy 51.317849 -79.859974) (xy 51.332366 -79.815208)
			(xy 51.338384 -79.768532) (xy 51.335696 -79.721548) (xy 51.324394 -79.675864) (xy 51.304866 -79.633045)
			(xy 51.291744 -79.613506) (xy 51.27644 -79.590849) (xy 51.251782 -79.542051) (xy 51.234342 -79.490232)
			(xy 51.224478 -79.436454) (xy 51.222392 -79.381819) (xy 51.228127 -79.327446) (xy 51.241565 -79.274448)
			(xy 51.262431 -79.223912) (xy 51.290298 -79.176872) (xy 51.324594 -79.134291) (xy 51.364617 -79.097042)
			(xy 51.409548 -79.065889) (xy 51.458466 -79.041468) (xy 51.510369 -79.024281) (xy 51.564194 -79.014679)
			(xy 51.618838 -79.012859) (xy 51.673183 -79.018858) (xy 51.726115 -79.032554) (xy 51.776549 -79.053666)
			(xy 51.823453 -79.081761) (xy 51.844956 -79.098648) (xy 51.861916 -79.111848) (xy 51.899333 -79.132982)
			(xy 51.939771 -79.147522) (xy 51.982079 -79.155055) (xy 52.025051 -79.155366) (xy 52.067463 -79.148446)
			(xy 52.108107 -79.134492) (xy 52.145826 -79.113902) (xy 52.162964 -79.100934) (xy 52.185729 -79.083509)
			(xy 52.235466 -79.055001) (xy 52.288909 -79.034259) (xy 52.344855 -79.021748) (xy 52.402043 -79.017752)
			(xy 52.459186 -79.02236) (xy 52.514994 -79.035468) (xy 52.568213 -79.056782) (xy 52.617642 -79.08582)
			(xy 52.64023 -79.103474) (xy 52.657304 -79.116736) (xy 52.695024 -79.137855) (xy 52.735775 -79.152282)
			(xy 52.778381 -79.159601) (xy 52.821611 -79.159601) (xy 52.864217 -79.152282) (xy 52.904968 -79.137855)
			(xy 52.942688 -79.116736) (xy 52.959762 -79.103474) (xy 52.981332 -79.086659) (xy 53.028302 -79.058645)
			(xy 53.07879 -79.037625) (xy 53.131762 -79.024029) (xy 53.186134 -79.018137) (xy 53.240789 -79.020069)
			(xy 53.294608 -79.029786) (xy 53.346488 -79.047088) (xy 53.395367 -79.071621) (xy 53.440241 -79.102882)
			(xy 53.480191 -79.14023) (xy 53.514399 -79.182901) (xy 53.542163 -79.230018) (xy 53.562915 -79.280618)
			(xy 53.576228 -79.333662) (xy 53.581831 -79.388063) (xy 53.579609 -79.442708) (xy 53.569606 -79.496475)
			(xy 53.552028 -79.548262) (xy 53.527236 -79.597009) (xy 53.495737 -79.641716) (xy 53.458176 -79.681468)
			(xy 53.415325 -79.715448) (xy 53.36806 -79.742961) (xy 53.317351 -79.763444) (xy 53.264237 -79.776475)
			(xy 53.209806 -79.781789) (xy 53.155175 -79.779276) (xy 53.101462 -79.768987) (xy 53.049768 -79.751135)
			(xy 53.001154 -79.726083) (xy 52.956615 -79.694347) (xy 52.917064 -79.656576) (xy 52.899818 -79.63535)
			(xy 52.889256 -79.622751) (xy 52.863014 -79.602964) (xy 52.832587 -79.590541) (xy 52.799996 -79.586306)
			(xy 52.767405 -79.590541) (xy 52.736978 -79.602964) (xy 52.710736 -79.622751) (xy 52.700174 -79.63535)
			(xy 52.696364 -79.640176) (xy 52.683061 -79.65722) (xy 52.661943 -79.694946) (xy 52.647518 -79.735704)
			(xy 52.640203 -79.778315) (xy 52.640209 -79.82155) (xy 52.647535 -79.86416) (xy 52.66197 -79.904913)
			(xy 52.683097 -79.942635) (xy 52.696364 -79.959708) (xy 52.713238 -79.981205) (xy 52.741281 -80.028111)
			(xy 52.762346 -80.078538) (xy 52.775999 -80.131455) (xy 52.781963 -80.185778) (xy 52.780115 -80.240396)
			(xy 52.770493 -80.294192) (xy 52.753293 -80.346065) (xy 52.728868 -80.394953) (xy 52.697717 -80.439855)
			(xy 52.660479 -80.479854) (xy 52.617914 -80.51413) (xy 52.570894 -80.541982) (xy 52.520381 -80.56284)
			(xy 52.467409 -80.576277) (xy 52.413062 -80.582019) (xy 52.358452 -80.579948) (xy 52.304696 -80.570105)
			(xy 52.252894 -80.552694) (xy 52.204106 -80.528069) (xy 52.159331 -80.496736) (xy 52.139088 -80.478376)
			(xy 52.122436 -80.463335) (xy 52.084848 -80.438832) (xy 52.043539 -80.421315) (xy 51.999794 -80.411332)
			(xy 51.954975 -80.409191) (xy 51.910478 -80.414961) (xy 51.867687 -80.42846) (xy 51.827935 -80.44927)
			(xy 51.809904 -80.462628) (xy 51.787619 -80.47922) (xy 51.739178 -80.506427) (xy 51.687303 -80.526321)
			(xy 51.633092 -80.538481) (xy 51.57769 -80.54265) (xy 51.522269 -80.538739) (xy 51.468002 -80.526832)
			(xy 51.416035 -80.50718) (xy 51.367468 -80.480198) (xy 51.323328 -80.446458) (xy 51.284548 -80.406673)
			(xy 51.251949 -80.361684) (xy 51.226219 -80.312442) (xy 51.207903 -80.259989) (xy 51.197389 -80.205435)
			(xy 51.194898 -80.149932) (xy 49.951777 -80.149932) (xy 50.001372 -80.159078) (xy 50.053872 -80.17692)
			(xy 50.103237 -80.202175) (xy 50.148427 -80.234308) (xy 50.188489 -80.272644) (xy 50.222581 -80.316375)
			(xy 50.249984 -80.36458) (xy 50.270121 -80.416244) (xy 50.282568 -80.470279) (xy 50.287062 -80.525546)
			(xy 50.28351 -80.580882) (xy 50.271985 -80.635121) (xy 50.252731 -80.68712) (xy 50.226153 -80.735785)
			(xy 50.192811 -80.780091) (xy 50.153407 -80.819103) (xy 50.108771 -80.852002) (xy 50.059844 -80.878093)
			(xy 50.007655 -80.896827) (xy 49.953304 -80.90781) (xy 49.897935 -80.910811) (xy 49.842716 -80.905765)
			(xy 49.788808 -80.89278) (xy 49.737347 -80.872129) (xy 49.689418 -80.844246) (xy 49.667414 -80.827372)
			(xy 49.653511 -80.817038) (xy 49.621637 -80.803513) (xy 49.587298 -80.799075) (xy 49.553033 -80.804053)
			(xy 49.521376 -80.818077) (xy 49.507648 -80.828642) (xy 49.486373 -80.845612) (xy 49.439896 -80.873923)
			(xy 49.389866 -80.89534) (xy 49.337299 -80.909426) (xy 49.283264 -80.915896) (xy 49.228858 -80.914619)
			(xy 49.175186 -80.90562) (xy 49.123339 -80.889083) (xy 49.074369 -80.865342) (xy 49.029272 -80.834881)
			(xy 49.008792 -80.816958) (xy 48.996325 -80.806293) (xy 48.967185 -80.791234) (xy 48.935168 -80.784107)
			(xy 48.902392 -80.785383) (xy 48.871026 -80.794978) (xy 48.843146 -80.812257) (xy 48.8315 -80.823816)
			(xy 48.811943 -80.843836) (xy 48.767943 -80.878424) (xy 48.719363 -80.906216) (xy 48.667245 -80.926613)
			(xy 48.612707 -80.93918) (xy 48.556918 -80.943646) (xy 48.501075 -80.939915) (xy 48.446376 -80.928069)
			(xy 48.393994 -80.908359) (xy 48.345052 -80.881211) (xy 48.3006 -80.847205) (xy 48.261592 -80.807071)
			(xy 48.228864 -80.76167) (xy 48.203119 -80.711976) (xy 48.184907 -80.659055) (xy 48.174621 -80.604041)
			(xy 48.17248 -80.548114) (xy 47.714243 -80.548114) (xy 47.714703 -80.558921) (xy 47.709058 -80.613904)
			(xy 47.695536 -80.667496) (xy 47.674422 -80.718576) (xy 47.646157 -80.766074) (xy 47.611332 -80.808995)
			(xy 47.570678 -80.846441) (xy 47.525046 -80.877628) (xy 47.47539 -80.901902) (xy 47.42275 -80.918756)
			(xy 47.36823 -80.927837) (xy 47.312969 -80.928954) (xy 47.258126 -80.922084) (xy 47.204849 -80.907371)
			(xy 47.154253 -80.885123) (xy 47.107397 -80.855806) (xy 47.086012 -80.838294) (xy 47.069369 -80.8248)
			(xy 47.032534 -80.802928) (xy 46.99255 -80.78755) (xy 46.950551 -80.779103) (xy 46.907731 -80.777828)
			(xy 46.865304 -80.78376) (xy 46.824475 -80.796732) (xy 46.786404 -80.816374) (xy 46.76902 -80.828896)
			(xy 46.746397 -80.845202) (xy 46.697409 -80.871839) (xy 46.645064 -80.891062) (xy 46.590478 -80.902459)
			(xy 46.534815 -80.905788) (xy 46.47926 -80.900978) (xy 46.424997 -80.888132) (xy 46.373183 -80.867523)
			(xy 46.32492 -80.839591) (xy 46.281238 -80.804931) (xy 46.261782 -80.784954) (xy 46.245835 -80.768644)
			(xy 46.209208 -80.741464) (xy 46.168319 -80.721255) (xy 46.124481 -80.708665) (xy 46.0791 -80.704098)
			(xy 46.033632 -80.707701) (xy 45.989536 -80.719359) (xy 45.968666 -80.728566) (xy 45.943127 -80.739969)
			(xy 45.889555 -80.756036) (xy 45.834211 -80.764108) (xy 45.778282 -80.764012) (xy 45.722966 -80.75575)
			(xy 45.669449 -80.739499) (xy 45.61888 -80.715607) (xy 45.572341 -80.684588) (xy 45.53083 -80.647105)
			(xy 45.495238 -80.603962) (xy 45.466328 -80.556084) (xy 45.444719 -80.504498) (xy 45.430874 -80.450309)
			(xy 45.42509 -80.39468) (xy 41.37025 -80.39468) (xy 41.381113 -80.417853) (xy 41.397181 -80.47126)
			(xy 41.405301 -80.526436) (xy 41.40581 -80.554322) (xy 41.405301 -80.582208) (xy 41.397181 -80.637384)
			(xy 41.381113 -80.690791) (xy 41.357441 -80.741288) (xy 41.326668 -80.787801) (xy 41.289451 -80.829338)
			(xy 41.246583 -80.865013) (xy 41.198977 -80.894067) (xy 41.156287 -80.912208) (xy 44.151802 -80.912208)
			(xy 44.155873 -80.856586) (xy 44.167999 -80.802149) (xy 44.187922 -80.750058) (xy 44.215218 -80.701423)
			(xy 44.249304 -80.65728) (xy 44.289453 -80.618571) (xy 44.334811 -80.58612) (xy 44.384411 -80.560619)
			(xy 44.437195 -80.542612) (xy 44.492038 -80.532482) (xy 44.547772 -80.530445) (xy 44.603209 -80.536545)
			(xy 44.657166 -80.550651) (xy 44.708495 -80.572463) (xy 44.756101 -80.601517) (xy 44.798969 -80.637192)
			(xy 44.836186 -80.678729) (xy 44.866959 -80.725242) (xy 44.890631 -80.775739) (xy 44.906699 -80.829146)
			(xy 44.914819 -80.884322) (xy 44.915328 -80.912208) (xy 44.914819 -80.940094) (xy 44.906699 -80.99527)
			(xy 44.890631 -81.048677) (xy 44.866959 -81.099174) (xy 44.836186 -81.145687) (xy 44.798969 -81.187224)
			(xy 44.756101 -81.222899) (xy 44.708495 -81.251953) (xy 44.657166 -81.273765) (xy 44.603209 -81.287871)
			(xy 44.547772 -81.293971) (xy 44.492038 -81.291934) (xy 44.437195 -81.281804) (xy 44.384411 -81.263797)
			(xy 44.334811 -81.238296) (xy 44.289453 -81.205845) (xy 44.249304 -81.167136) (xy 44.215218 -81.122993)
			(xy 44.187922 -81.074358) (xy 44.167999 -81.022267) (xy 44.155873 -80.96783) (xy 44.151802 -80.912208)
			(xy 41.156287 -80.912208) (xy 41.147648 -80.915879) (xy 41.093691 -80.929985) (xy 41.038254 -80.936085)
			(xy 40.98252 -80.934048) (xy 40.927677 -80.923918) (xy 40.874893 -80.905911) (xy 40.825293 -80.88041)
			(xy 40.779935 -80.847959) (xy 40.739786 -80.80925) (xy 40.7057 -80.765107) (xy 40.678404 -80.716472)
			(xy 40.658481 -80.664381) (xy 40.646355 -80.609944) (xy 40.642284 -80.554322) (xy 38.6192 -80.554322)
			(xy 38.635538 -80.572557) (xy 38.666311 -80.61907) (xy 38.689983 -80.669567) (xy 38.706051 -80.722974)
			(xy 38.714171 -80.77815) (xy 38.71468 -80.806036) (xy 38.714171 -80.833922) (xy 38.706051 -80.889098)
			(xy 38.689983 -80.942505) (xy 38.666311 -80.993002) (xy 38.635538 -81.039515) (xy 38.598321 -81.081052)
			(xy 38.555453 -81.116727) (xy 38.507847 -81.145781) (xy 38.456518 -81.167593) (xy 38.402561 -81.181699)
			(xy 38.347124 -81.187799) (xy 38.29139 -81.185762) (xy 38.236547 -81.175632) (xy 38.183763 -81.157625)
			(xy 38.134163 -81.132124) (xy 38.088805 -81.099673) (xy 38.048656 -81.060964) (xy 38.01457 -81.016821)
			(xy 37.987274 -80.968186) (xy 37.967351 -80.916095) (xy 37.955225 -80.861658) (xy 37.951154 -80.806036)
			(xy 37.168467 -80.806036) (xy 37.151995 -80.816089) (xy 37.100666 -80.837901) (xy 37.046709 -80.852007)
			(xy 36.991272 -80.858107) (xy 36.935538 -80.85607) (xy 36.880695 -80.84594) (xy 36.827911 -80.827933)
			(xy 36.778311 -80.802432) (xy 36.732953 -80.769981) (xy 36.692804 -80.731272) (xy 36.658718 -80.687129)
			(xy 36.631422 -80.638494) (xy 36.611499 -80.586403) (xy 36.599373 -80.531966) (xy 36.595302 -80.476344)
			(xy 35.2171 -80.476344) (xy 35.2171 -82.179922) (xy 36.727382 -82.179922) (xy 36.731453 -82.1243)
			(xy 36.743579 -82.069863) (xy 36.763502 -82.017772) (xy 36.790798 -81.969137) (xy 36.824884 -81.924994)
			(xy 36.865033 -81.886285) (xy 36.910391 -81.853834) (xy 36.959991 -81.828333) (xy 37.012775 -81.810326)
			(xy 37.067618 -81.800196) (xy 37.123352 -81.798159) (xy 37.178789 -81.804259) (xy 37.232746 -81.818365)
			(xy 37.284075 -81.840177) (xy 37.331681 -81.869231) (xy 37.374549 -81.904906) (xy 37.411766 -81.946443)
			(xy 37.442539 -81.992956) (xy 37.466211 -82.043453) (xy 37.482279 -82.09686) (xy 37.490399 -82.152036)
			(xy 37.490908 -82.179922) (xy 37.490399 -82.207808) (xy 37.482279 -82.262984) (xy 37.466211 -82.316391)
			(xy 37.442539 -82.366888) (xy 37.411766 -82.413401) (xy 37.374549 -82.454938) (xy 37.331681 -82.490613)
			(xy 37.284075 -82.519667) (xy 37.232746 -82.541479) (xy 37.178789 -82.555585) (xy 37.123352 -82.561685)
			(xy 37.067618 -82.559648) (xy 37.012775 -82.549518) (xy 36.959991 -82.531511) (xy 36.910391 -82.50601)
			(xy 36.865033 -82.473559) (xy 36.824884 -82.43485) (xy 36.790798 -82.390707) (xy 36.763502 -82.342072)
			(xy 36.743579 -82.289981) (xy 36.731453 -82.235544) (xy 36.727382 -82.179922) (xy 35.2171 -82.179922)
			(xy 35.2171 -83.326519) (xy 40.147525 -83.326519) (xy 40.149904 -83.271295) (xy 40.160229 -83.216992)
			(xy 40.178284 -83.164748) (xy 40.203692 -83.115657) (xy 40.235919 -83.070748) (xy 40.274291 -83.030961)
			(xy 40.318005 -82.99713) (xy 40.366144 -82.969963) (xy 40.4177 -82.950028) (xy 40.471594 -82.937745)
			(xy 40.526696 -82.933369) (xy 40.581853 -82.936993) (xy 40.635909 -82.948541) (xy 40.687732 -82.96777)
			(xy 40.736237 -82.994278) (xy 40.758618 -83.010502) (xy 40.77267 -83.020342) (xy 40.804583 -83.032892)
			(xy 40.838683 -83.03651) (xy 40.872519 -83.030935) (xy 40.903655 -83.016567) (xy 40.917114 -83.00593)
			(xy 40.932611 -82.993122) (xy 40.965824 -82.970465) (xy 40.983408 -82.960718) (xy 40.996767 -82.953034)
			(xy 41.019599 -82.932343) (xy 41.036807 -82.906785) (xy 41.047389 -82.877847) (xy 41.050729 -82.847217)
			(xy 41.046631 -82.816679) (xy 41.035334 -82.788013) (xy 41.017497 -82.762889) (xy 40.99416 -82.742771)
			(xy 40.980614 -82.73542) (xy 40.956403 -82.722632) (xy 40.911544 -82.691241) (xy 40.871634 -82.653758)
			(xy 40.837494 -82.610954) (xy 40.809824 -82.563709) (xy 40.789193 -82.512993) (xy 40.776026 -82.459848)
			(xy 40.770592 -82.405367) (xy 40.773004 -82.350668) (xy 40.783212 -82.296877) (xy 40.801006 -82.245097)
			(xy 40.82602 -82.196394) (xy 40.857741 -82.151767) (xy 40.895517 -82.112134) (xy 40.938571 -82.07831)
			(xy 40.986019 -82.050989) (xy 41.036886 -82.030732) (xy 41.090126 -82.017957) (xy 41.144646 -82.012925)
			(xy 41.199325 -82.01574) (xy 41.25304 -82.026343) (xy 41.304687 -82.044518) (xy 41.353205 -82.069891)
			(xy 41.397597 -82.101939) (xy 41.43695 -82.140006) (xy 41.470456 -82.183308) (xy 41.497427 -82.230956)
			(xy 41.517309 -82.28197) (xy 41.529692 -82.335303) (xy 41.53194 -82.361786) (xy 45.03623 -82.361786)
			(xy 45.040301 -82.306164) (xy 45.052427 -82.251727) (xy 45.07235 -82.199636) (xy 45.099646 -82.151001)
			(xy 45.133732 -82.106858) (xy 45.173881 -82.068149) (xy 45.219239 -82.035698) (xy 45.268839 -82.010197)
			(xy 45.321623 -81.99219) (xy 45.376466 -81.98206) (xy 45.4322 -81.980023) (xy 45.487637 -81.986123)
			(xy 45.541594 -82.000229) (xy 45.592923 -82.022041) (xy 45.640529 -82.051095) (xy 45.683397 -82.08677)
			(xy 45.720614 -82.128307) (xy 45.751387 -82.17482) (xy 45.775059 -82.225317) (xy 45.791127 -82.278724)
			(xy 45.799247 -82.3339) (xy 45.799756 -82.361786) (xy 45.799247 -82.389672) (xy 45.791127 -82.444848)
			(xy 45.775059 -82.498255) (xy 45.751387 -82.548752) (xy 45.720614 -82.595265) (xy 45.683397 -82.636802)
			(xy 45.640529 -82.672477) (xy 45.592923 -82.701531) (xy 45.541594 -82.723343) (xy 45.487637 -82.737449)
			(xy 45.4322 -82.743549) (xy 45.376466 -82.741512) (xy 45.321623 -82.731382) (xy 45.268839 -82.713375)
			(xy 45.219239 -82.687874) (xy 45.173881 -82.655423) (xy 45.133732 -82.616714) (xy 45.099646 -82.572571)
			(xy 45.07235 -82.523936) (xy 45.052427 -82.471845) (xy 45.040301 -82.417408) (xy 45.03623 -82.361786)
			(xy 41.53194 -82.361786) (xy 41.534322 -82.389859) (xy 41.531104 -82.444516) (xy 41.520105 -82.498151)
			(xy 41.501551 -82.549663) (xy 41.475821 -82.597993) (xy 41.443447 -82.642147) (xy 41.424606 -82.662014)
			(xy 41.409395 -82.67829) (xy 41.384234 -82.715046) (xy 41.365861 -82.755623) (xy 41.354837 -82.79878)
			(xy 41.3515 -82.843197) (xy 41.355951 -82.887517) (xy 41.358618 -82.896964) (xy 46.937166 -82.896964)
			(xy 46.941237 -82.841342) (xy 46.953363 -82.786905) (xy 46.973286 -82.734814) (xy 47.000582 -82.686179)
			(xy 47.034668 -82.642036) (xy 47.074817 -82.603327) (xy 47.120175 -82.570876) (xy 47.169775 -82.545375)
			(xy 47.222559 -82.527368) (xy 47.277402 -82.517238) (xy 47.333136 -82.515201) (xy 47.388573 -82.521301)
			(xy 47.44253 -82.535407) (xy 47.493859 -82.557219) (xy 47.541465 -82.586273) (xy 47.584333 -82.621948)
			(xy 47.62155 -82.663485) (xy 47.652323 -82.709998) (xy 47.675995 -82.760495) (xy 47.692063 -82.813902)
			(xy 47.700183 -82.869078) (xy 47.700692 -82.896964) (xy 47.700183 -82.92485) (xy 47.692063 -82.980026)
			(xy 47.675995 -83.033433) (xy 47.652323 -83.08393) (xy 47.62155 -83.130443) (xy 47.584333 -83.17198)
			(xy 47.541465 -83.207655) (xy 47.493859 -83.236709) (xy 47.44253 -83.258521) (xy 47.388573 -83.272627)
			(xy 47.333136 -83.278727) (xy 47.277402 -83.27669) (xy 47.222559 -83.26656) (xy 47.169775 -83.248553)
			(xy 47.120175 -83.223052) (xy 47.074817 -83.190601) (xy 47.034668 -83.151892) (xy 47.000582 -83.107749)
			(xy 46.973286 -83.059114) (xy 46.953363 -83.007023) (xy 46.941237 -82.952586) (xy 46.937166 -82.896964)
			(xy 41.358618 -82.896964) (xy 41.368055 -82.930384) (xy 41.387441 -82.970487) (xy 41.413516 -83.006599)
			(xy 41.429178 -83.02244) (xy 41.448572 -83.04184) (xy 41.48214 -83.085224) (xy 41.509148 -83.132968)
			(xy 41.529039 -83.184089) (xy 41.541404 -83.237531) (xy 41.545988 -83.292194) (xy 41.542695 -83.346949)
			(xy 41.531594 -83.400668) (xy 41.512914 -83.452244) (xy 41.48704 -83.500612) (xy 41.454505 -83.544776)
			(xy 41.41598 -83.583825) (xy 41.37226 -83.616954) (xy 41.324246 -83.64348) (xy 41.272927 -83.662856)
			(xy 41.219363 -83.674681) (xy 41.164657 -83.678714) (xy 41.109938 -83.67487) (xy 41.056333 -83.663228)
			(xy 41.004948 -83.644029) (xy 40.956843 -83.617669) (xy 40.93464 -83.60156) (xy 40.920612 -83.591683)
			(xy 40.88869 -83.579143) (xy 40.854583 -83.575534) (xy 40.820743 -83.581118) (xy 40.789604 -83.595491)
			(xy 40.776144 -83.606132) (xy 40.754732 -83.623615) (xy 40.707868 -83.652926) (xy 40.657263 -83.675166)
			(xy 40.603978 -83.689868) (xy 40.549129 -83.696725) (xy 40.493865 -83.695592) (xy 40.439343 -83.686495)
			(xy 40.386705 -83.669623) (xy 40.337054 -83.645329) (xy 40.291429 -83.614123) (xy 40.250787 -83.576658)
			(xy 40.215978 -83.533719) (xy 40.187731 -83.486206) (xy 40.166639 -83.435112) (xy 40.153143 -83.381509)
			(xy 40.147525 -83.326519) (xy 35.2171 -83.326519) (xy 35.2171 -83.861656) (xy 38.030402 -83.861656)
			(xy 38.034473 -83.806034) (xy 38.046599 -83.751597) (xy 38.066522 -83.699506) (xy 38.093818 -83.650871)
			(xy 38.127904 -83.606728) (xy 38.168053 -83.568019) (xy 38.213411 -83.535568) (xy 38.263011 -83.510067)
			(xy 38.315795 -83.49206) (xy 38.370638 -83.48193) (xy 38.426372 -83.479893) (xy 38.481809 -83.485993)
			(xy 38.535766 -83.500099) (xy 38.587095 -83.521911) (xy 38.634701 -83.550965) (xy 38.677569 -83.58664)
			(xy 38.714786 -83.628177) (xy 38.745559 -83.67469) (xy 38.769231 -83.725187) (xy 38.785299 -83.778594)
			(xy 38.793419 -83.83377) (xy 38.793928 -83.861656) (xy 38.793419 -83.889542) (xy 38.785299 -83.944718)
			(xy 38.769231 -83.998125) (xy 38.745559 -84.048622) (xy 38.714786 -84.095135) (xy 38.677569 -84.136672)
			(xy 38.634701 -84.172347) (xy 38.587095 -84.201401) (xy 38.535766 -84.223213) (xy 38.481809 -84.237319)
			(xy 38.426372 -84.243419) (xy 38.370638 -84.241382) (xy 38.315795 -84.231252) (xy 38.263011 -84.213245)
			(xy 38.213411 -84.187744) (xy 38.168053 -84.155293) (xy 38.127904 -84.116584) (xy 38.093818 -84.072441)
			(xy 38.066522 -84.023806) (xy 38.046599 -83.971715) (xy 38.034473 -83.917278) (xy 38.030402 -83.861656)
			(xy 35.2171 -83.861656) (xy 35.2171 -84.468462) (xy 44.667168 -84.468462) (xy 44.671239 -84.41284)
			(xy 44.683365 -84.358403) (xy 44.703288 -84.306312) (xy 44.730584 -84.257677) (xy 44.76467 -84.213534)
			(xy 44.804819 -84.174825) (xy 44.850177 -84.142374) (xy 44.899777 -84.116873) (xy 44.952561 -84.098866)
			(xy 45.007404 -84.088736) (xy 45.063138 -84.086699) (xy 45.118575 -84.092799) (xy 45.172532 -84.106905)
			(xy 45.223861 -84.128717) (xy 45.271467 -84.157771) (xy 45.314335 -84.193446) (xy 45.351552 -84.234983)
			(xy 45.382325 -84.281496) (xy 45.405997 -84.331993) (xy 45.422065 -84.3854) (xy 45.430185 -84.440576)
			(xy 45.430694 -84.468462) (xy 45.430185 -84.496348) (xy 45.423112 -84.544408) (xy 46.657512 -84.544408)
			(xy 46.661583 -84.488786) (xy 46.673709 -84.434349) (xy 46.693632 -84.382258) (xy 46.720928 -84.333623)
			(xy 46.755014 -84.28948) (xy 46.795163 -84.250771) (xy 46.840521 -84.21832) (xy 46.890121 -84.192819)
			(xy 46.942905 -84.174812) (xy 46.997748 -84.164682) (xy 47.053482 -84.162645) (xy 47.108919 -84.168745)
			(xy 47.162876 -84.182851) (xy 47.214205 -84.204663) (xy 47.261811 -84.233717) (xy 47.304679 -84.269392)
			(xy 47.341896 -84.310929) (xy 47.372669 -84.357442) (xy 47.396341 -84.407939) (xy 47.412409 -84.461346)
			(xy 47.420529 -84.516522) (xy 47.421038 -84.544408) (xy 47.420529 -84.572294) (xy 47.412409 -84.62747)
			(xy 47.396341 -84.680877) (xy 47.372669 -84.731374) (xy 47.341896 -84.777887) (xy 47.304679 -84.819424)
			(xy 47.261811 -84.855099) (xy 47.214205 -84.884153) (xy 47.162876 -84.905965) (xy 47.108919 -84.920071)
			(xy 47.053482 -84.926171) (xy 46.997748 -84.924134) (xy 46.942905 -84.914004) (xy 46.890121 -84.895997)
			(xy 46.840521 -84.870496) (xy 46.795163 -84.838045) (xy 46.755014 -84.799336) (xy 46.720928 -84.755193)
			(xy 46.693632 -84.706558) (xy 46.673709 -84.654467) (xy 46.661583 -84.60003) (xy 46.657512 -84.544408)
			(xy 45.423112 -84.544408) (xy 45.422065 -84.551524) (xy 45.405997 -84.604931) (xy 45.382325 -84.655428)
			(xy 45.351552 -84.701941) (xy 45.314335 -84.743478) (xy 45.271467 -84.779153) (xy 45.223861 -84.808207)
			(xy 45.172532 -84.830019) (xy 45.118575 -84.844125) (xy 45.063138 -84.850225) (xy 45.007404 -84.848188)
			(xy 44.952561 -84.838058) (xy 44.899777 -84.820051) (xy 44.850177 -84.79455) (xy 44.804819 -84.762099)
			(xy 44.76467 -84.72339) (xy 44.730584 -84.679247) (xy 44.703288 -84.630612) (xy 44.683365 -84.578521)
			(xy 44.671239 -84.524084) (xy 44.667168 -84.468462) (xy 35.2171 -84.468462) (xy 35.2171 -85.421724)
			(xy 37.847522 -85.421724) (xy 37.851593 -85.366102) (xy 37.863719 -85.311665) (xy 37.883642 -85.259574)
			(xy 37.910938 -85.210939) (xy 37.945024 -85.166796) (xy 37.985173 -85.128087) (xy 38.030531 -85.095636)
			(xy 38.080131 -85.070135) (xy 38.132915 -85.052128) (xy 38.187758 -85.041998) (xy 38.243492 -85.039961)
			(xy 38.298929 -85.046061) (xy 38.352886 -85.060167) (xy 38.404215 -85.081979) (xy 38.451821 -85.111033)
			(xy 38.494689 -85.146708) (xy 38.531906 -85.188245) (xy 38.562679 -85.234758) (xy 38.586351 -85.285255)
			(xy 38.602419 -85.338662) (xy 38.610539 -85.393838) (xy 38.611048 -85.421724) (xy 38.610539 -85.44961)
			(xy 38.602419 -85.504786) (xy 38.594637 -85.530652) (xy 39.356763 -85.530652) (xy 39.356893 -85.475168)
			(xy 39.365059 -85.420289) (xy 39.381089 -85.367171) (xy 39.404645 -85.316936) (xy 39.435231 -85.270644)
			(xy 39.4722 -85.229271) (xy 39.514772 -85.19369) (xy 39.56205 -85.164651) (xy 39.613036 -85.142768)
			(xy 39.666655 -85.128502) (xy 39.721774 -85.122155) (xy 39.777232 -85.123859) (xy 39.831857 -85.13358)
			(xy 39.884498 -85.151111) (xy 39.909496 -85.163152) (xy 39.929502 -85.172665) (xy 39.971924 -85.18541)
			(xy 40.015913 -85.190611) (xy 40.060137 -85.188109) (xy 40.103259 -85.177981) (xy 40.143973 -85.160534)
			(xy 40.181048 -85.136295) (xy 40.197532 -85.121496) (xy 40.218427 -85.102672) (xy 40.264682 -85.070685)
			(xy 40.31513 -85.045833) (xy 40.368681 -85.028656) (xy 40.424172 -85.019525) (xy 40.480402 -85.018637)
			(xy 40.536154 -85.026013) (xy 40.59022 -85.041492) (xy 40.641427 -85.064739) (xy 40.688668 -85.095251)
			(xy 40.730919 -85.132366) (xy 40.749474 -85.1535) (xy 40.75734 -85.16239) (xy 41.829988 -85.16239)
			(xy 41.834059 -85.106768) (xy 41.846185 -85.052331) (xy 41.866108 -85.00024) (xy 41.893404 -84.951605)
			(xy 41.92749 -84.907462) (xy 41.967639 -84.868753) (xy 42.012997 -84.836302) (xy 42.062597 -84.810801)
			(xy 42.115381 -84.792794) (xy 42.170224 -84.782664) (xy 42.225958 -84.780627) (xy 42.281395 -84.786727)
			(xy 42.335352 -84.800833) (xy 42.386681 -84.822645) (xy 42.434287 -84.851699) (xy 42.477155 -84.887374)
			(xy 42.514372 -84.928911) (xy 42.545145 -84.975424) (xy 42.568817 -85.025921) (xy 42.584885 -85.079328)
			(xy 42.593005 -85.134504) (xy 42.593514 -85.16239) (xy 42.593005 -85.190276) (xy 42.584885 -85.245452)
			(xy 42.568817 -85.298859) (xy 42.545145 -85.349356) (xy 42.514372 -85.395869) (xy 42.477155 -85.437406)
			(xy 42.434287 -85.473081) (xy 42.417304 -85.483446) (xy 44.036486 -85.483446) (xy 44.040557 -85.427824)
			(xy 44.052683 -85.373387) (xy 44.072606 -85.321296) (xy 44.099902 -85.272661) (xy 44.133988 -85.228518)
			(xy 44.174137 -85.189809) (xy 44.219495 -85.157358) (xy 44.269095 -85.131857) (xy 44.321879 -85.11385)
			(xy 44.376722 -85.10372) (xy 44.432456 -85.101683) (xy 44.487893 -85.107783) (xy 44.54185 -85.121889)
			(xy 44.593179 -85.143701) (xy 44.640785 -85.172755) (xy 44.683653 -85.20843) (xy 44.72087 -85.249967)
			(xy 44.751643 -85.29648) (xy 44.775315 -85.346977) (xy 44.791383 -85.400384) (xy 44.799503 -85.45556)
			(xy 44.800012 -85.483446) (xy 44.799503 -85.511332) (xy 44.791383 -85.566508) (xy 44.775315 -85.619915)
			(xy 44.751643 -85.670412) (xy 44.72087 -85.716925) (xy 44.683653 -85.758462) (xy 44.640785 -85.794137)
			(xy 44.632542 -85.799168) (xy 46.4472 -85.799168) (xy 46.451271 -85.743546) (xy 46.463397 -85.689109)
			(xy 46.48332 -85.637018) (xy 46.510616 -85.588383) (xy 46.544702 -85.54424) (xy 46.584851 -85.505531)
			(xy 46.630209 -85.47308) (xy 46.679809 -85.447579) (xy 46.732593 -85.429572) (xy 46.787436 -85.419442)
			(xy 46.84317 -85.417405) (xy 46.898607 -85.423505) (xy 46.952564 -85.437611) (xy 47.003893 -85.459423)
			(xy 47.051499 -85.488477) (xy 47.094367 -85.524152) (xy 47.131584 -85.565689) (xy 47.162357 -85.612202)
			(xy 47.186029 -85.662699) (xy 47.202097 -85.716106) (xy 47.210217 -85.771282) (xy 47.210726 -85.799168)
			(xy 47.210217 -85.827054) (xy 47.202097 -85.88223) (xy 47.186029 -85.935637) (xy 47.162357 -85.986134)
			(xy 47.131584 -86.032647) (xy 47.094367 -86.074184) (xy 47.051499 -86.109859) (xy 47.003893 -86.138913)
			(xy 46.952564 -86.160725) (xy 46.898607 -86.174831) (xy 46.84317 -86.180931) (xy 46.787436 -86.178894)
			(xy 46.732593 -86.168764) (xy 46.679809 -86.150757) (xy 46.630209 -86.125256) (xy 46.584851 -86.092805)
			(xy 46.544702 -86.054096) (xy 46.510616 -86.009953) (xy 46.48332 -85.961318) (xy 46.463397 -85.909227)
			(xy 46.451271 -85.85479) (xy 46.4472 -85.799168) (xy 44.632542 -85.799168) (xy 44.593179 -85.823191)
			(xy 44.54185 -85.845003) (xy 44.487893 -85.859109) (xy 44.432456 -85.865209) (xy 44.376722 -85.863172)
			(xy 44.321879 -85.853042) (xy 44.269095 -85.835035) (xy 44.219495 -85.809534) (xy 44.174137 -85.777083)
			(xy 44.133988 -85.738374) (xy 44.099902 -85.694231) (xy 44.072606 -85.645596) (xy 44.052683 -85.593505)
			(xy 44.040557 -85.539068) (xy 44.036486 -85.483446) (xy 42.417304 -85.483446) (xy 42.386681 -85.502135)
			(xy 42.335352 -85.523947) (xy 42.281395 -85.538053) (xy 42.225958 -85.544153) (xy 42.170224 -85.542116)
			(xy 42.115381 -85.531986) (xy 42.062597 -85.513979) (xy 42.012997 -85.488478) (xy 41.967639 -85.456027)
			(xy 41.92749 -85.417318) (xy 41.893404 -85.373175) (xy 41.866108 -85.32454) (xy 41.846185 -85.272449)
			(xy 41.834059 -85.218012) (xy 41.829988 -85.16239) (xy 40.75734 -85.16239) (xy 40.764234 -85.170182)
			(xy 40.798507 -85.198626) (xy 40.837212 -85.220661) (xy 40.879167 -85.235612) (xy 40.923085 -85.24302)
			(xy 40.967622 -85.24266) (xy 41.011414 -85.234541) (xy 41.03243 -85.22716) (xy 41.058614 -85.217878)
			(xy 41.11292 -85.206176) (xy 41.16835 -85.202477) (xy 41.22373 -85.206858) (xy 41.277888 -85.219227)
			(xy 41.329679 -85.239321) (xy 41.378008 -85.266716) (xy 41.421851 -85.300832) (xy 41.460281 -85.340947)
			(xy 41.492485 -85.386213) (xy 41.517782 -85.435672) (xy 41.535636 -85.488278) (xy 41.54567 -85.542917)
			(xy 41.547672 -85.598434) (xy 41.541599 -85.653653) (xy 41.527579 -85.707408) (xy 41.50591 -85.75856)
			(xy 41.477049 -85.806028) (xy 41.441608 -85.848807) (xy 41.400335 -85.885992) (xy 41.354105 -85.916796)
			(xy 41.303896 -85.940568) (xy 41.250768 -85.956804) (xy 41.195848 -85.965162) (xy 41.140296 -85.965464)
			(xy 41.085288 -85.957704) (xy 41.031987 -85.942047) (xy 40.981522 -85.918822) (xy 40.934959 -85.888523)
			(xy 40.893285 -85.851789) (xy 40.87495 -85.830918) (xy 40.860168 -85.814256) (xy 40.825901 -85.785809)
			(xy 40.787199 -85.763772) (xy 40.745249 -85.748818) (xy 40.701334 -85.741406) (xy 40.656799 -85.741764)
			(xy 40.613009 -85.749879) (xy 40.591994 -85.757258) (xy 40.567262 -85.765996) (xy 40.516072 -85.777431)
			(xy 40.463798 -85.781753) (xy 40.411424 -85.778881) (xy 40.359937 -85.768869) (xy 40.310304 -85.751905)
			(xy 40.286686 -85.740494) (xy 40.266691 -85.730955) (xy 40.224266 -85.718209) (xy 40.180273 -85.71301)
			(xy 40.136046 -85.715515) (xy 40.092922 -85.725647) (xy 40.052207 -85.743101) (xy 40.015133 -85.767347)
			(xy 39.99865 -85.78215) (xy 39.978066 -85.800755) (xy 39.932512 -85.832429) (xy 39.882849 -85.85717)
			(xy 39.830127 -85.874456) (xy 39.775457 -85.883921) (xy 39.719992 -85.885366) (xy 39.664902 -85.878761)
			(xy 39.611351 -85.864245) (xy 39.560468 -85.842124) (xy 39.513326 -85.812865) (xy 39.47092 -85.777086)
			(xy 39.434145 -85.73554) (xy 39.403776 -85.689105) (xy 39.380455 -85.638761) (xy 39.364673 -85.585569)
			(xy 39.356763 -85.530652) (xy 38.594637 -85.530652) (xy 38.586351 -85.558193) (xy 38.562679 -85.60869)
			(xy 38.531906 -85.655203) (xy 38.494689 -85.69674) (xy 38.451821 -85.732415) (xy 38.404215 -85.761469)
			(xy 38.352886 -85.783281) (xy 38.298929 -85.797387) (xy 38.243492 -85.803487) (xy 38.187758 -85.80145)
			(xy 38.132915 -85.79132) (xy 38.080131 -85.773313) (xy 38.030531 -85.747812) (xy 37.985173 -85.715361)
			(xy 37.945024 -85.676652) (xy 37.910938 -85.632509) (xy 37.883642 -85.583874) (xy 37.863719 -85.531783)
			(xy 37.851593 -85.477346) (xy 37.847522 -85.421724) (xy 35.2171 -85.421724) (xy 35.2171 -86.691724)
			(xy 42.133264 -86.691724) (xy 42.137335 -86.636102) (xy 42.149461 -86.581665) (xy 42.169384 -86.529574)
			(xy 42.19668 -86.480939) (xy 42.230766 -86.436796) (xy 42.270915 -86.398087) (xy 42.316273 -86.365636)
			(xy 42.365873 -86.340135) (xy 42.418657 -86.322128) (xy 42.4735 -86.311998) (xy 42.529234 -86.309961)
			(xy 42.584671 -86.316061) (xy 42.638628 -86.330167) (xy 42.689957 -86.351979) (xy 42.737563 -86.381033)
			(xy 42.780431 -86.416708) (xy 42.817648 -86.458245) (xy 42.848421 -86.504758) (xy 42.872093 -86.555255)
			(xy 42.888161 -86.608662) (xy 42.896281 -86.663838) (xy 42.89679 -86.691724) (xy 42.896281 -86.71961)
			(xy 42.888161 -86.774786) (xy 42.872093 -86.828193) (xy 42.848421 -86.87869) (xy 42.817648 -86.925203)
			(xy 42.780431 -86.96674) (xy 42.737563 -87.002415) (xy 42.689957 -87.031469) (xy 42.638628 -87.053281)
			(xy 42.584671 -87.067387) (xy 42.529234 -87.073487) (xy 42.4735 -87.07145) (xy 42.418657 -87.06132)
			(xy 42.365873 -87.043313) (xy 42.316273 -87.017812) (xy 42.270915 -86.985361) (xy 42.230766 -86.946652)
			(xy 42.19668 -86.902509) (xy 42.169384 -86.853874) (xy 42.149461 -86.801783) (xy 42.137335 -86.747346)
			(xy 42.133264 -86.691724) (xy 35.2171 -86.691724) (xy 35.2171 -88.439498) (xy 41.380154 -88.439498)
			(xy 41.384225 -88.383876) (xy 41.396351 -88.329439) (xy 41.416274 -88.277348) (xy 41.44357 -88.228713)
			(xy 41.477656 -88.18457) (xy 41.517805 -88.145861) (xy 41.563163 -88.11341) (xy 41.612763 -88.087909)
			(xy 41.665547 -88.069902) (xy 41.72039 -88.059772) (xy 41.776124 -88.057735) (xy 41.831561 -88.063835)
			(xy 41.885518 -88.077941) (xy 41.936847 -88.099753) (xy 41.984453 -88.128807) (xy 42.027321 -88.164482)
			(xy 42.064538 -88.206019) (xy 42.095311 -88.252532) (xy 42.118983 -88.303029) (xy 42.131308 -88.343994)
			(xy 44.583348 -88.343994) (xy 44.587419 -88.288372) (xy 44.599545 -88.233935) (xy 44.619468 -88.181844)
			(xy 44.646764 -88.133209) (xy 44.68085 -88.089066) (xy 44.720999 -88.050357) (xy 44.766357 -88.017906)
			(xy 44.815957 -87.992405) (xy 44.868741 -87.974398) (xy 44.923584 -87.964268) (xy 44.979318 -87.962231)
			(xy 45.034755 -87.968331) (xy 45.088712 -87.982437) (xy 45.140041 -88.004249) (xy 45.187647 -88.033303)
			(xy 45.230515 -88.068978) (xy 45.267732 -88.110515) (xy 45.298505 -88.157028) (xy 45.322177 -88.207525)
			(xy 45.338245 -88.260932) (xy 45.346365 -88.316108) (xy 45.346874 -88.343994) (xy 45.346365 -88.37188)
			(xy 45.338245 -88.427056) (xy 45.322177 -88.480463) (xy 45.298505 -88.53096) (xy 45.267732 -88.577473)
			(xy 45.230515 -88.61901) (xy 45.187647 -88.654685) (xy 45.140041 -88.683739) (xy 45.088712 -88.705551)
			(xy 45.034755 -88.719657) (xy 44.979318 -88.725757) (xy 44.923584 -88.72372) (xy 44.868741 -88.71359)
			(xy 44.815957 -88.695583) (xy 44.766357 -88.670082) (xy 44.720999 -88.637631) (xy 44.68085 -88.598922)
			(xy 44.646764 -88.554779) (xy 44.619468 -88.506144) (xy 44.599545 -88.454053) (xy 44.587419 -88.399616)
			(xy 44.583348 -88.343994) (xy 42.131308 -88.343994) (xy 42.135051 -88.356436) (xy 42.143171 -88.411612)
			(xy 42.14368 -88.439498) (xy 42.143171 -88.467384) (xy 42.135051 -88.52256) (xy 42.118983 -88.575967)
			(xy 42.095311 -88.626464) (xy 42.064538 -88.672977) (xy 42.027321 -88.714514) (xy 41.984453 -88.750189)
			(xy 41.936847 -88.779243) (xy 41.885518 -88.801055) (xy 41.831561 -88.815161) (xy 41.776124 -88.821261)
			(xy 41.72039 -88.819224) (xy 41.665547 -88.809094) (xy 41.612763 -88.791087) (xy 41.563163 -88.765586)
			(xy 41.517805 -88.733135) (xy 41.477656 -88.694426) (xy 41.44357 -88.650283) (xy 41.416274 -88.601648)
			(xy 41.396351 -88.549557) (xy 41.384225 -88.49512) (xy 41.380154 -88.439498) (xy 35.2171 -88.439498)
			(xy 35.2171 -89.063068) (xy 42.317922 -89.063068) (xy 42.321993 -89.007446) (xy 42.334119 -88.953009)
			(xy 42.354042 -88.900918) (xy 42.381338 -88.852283) (xy 42.415424 -88.80814) (xy 42.455573 -88.769431)
			(xy 42.500931 -88.73698) (xy 42.550531 -88.711479) (xy 42.603315 -88.693472) (xy 42.658158 -88.683342)
			(xy 42.713892 -88.681305) (xy 42.769329 -88.687405) (xy 42.823286 -88.701511) (xy 42.874615 -88.723323)
			(xy 42.922221 -88.752377) (xy 42.965089 -88.788052) (xy 43.002306 -88.829589) (xy 43.033079 -88.876102)
			(xy 43.056751 -88.926599) (xy 43.072819 -88.980006) (xy 43.080939 -89.035182) (xy 43.081448 -89.063068)
			(xy 43.080939 -89.090954) (xy 43.072819 -89.14613) (xy 43.056751 -89.199537) (xy 43.033079 -89.250034)
			(xy 43.002306 -89.296547) (xy 42.965089 -89.338084) (xy 42.922221 -89.373759) (xy 42.874615 -89.402813)
			(xy 42.823286 -89.424625) (xy 42.769329 -89.438731) (xy 42.713892 -89.444831) (xy 42.658158 -89.442794)
			(xy 42.603315 -89.432664) (xy 42.550531 -89.414657) (xy 42.500931 -89.389156) (xy 42.455573 -89.356705)
			(xy 42.415424 -89.317996) (xy 42.381338 -89.273853) (xy 42.354042 -89.225218) (xy 42.334119 -89.173127)
			(xy 42.321993 -89.11869) (xy 42.317922 -89.063068) (xy 35.2171 -89.063068) (xy 35.2171 -95.51035)
			(xy 36.208714 -95.51035) (xy 36.212785 -95.454728) (xy 36.224911 -95.400291) (xy 36.244834 -95.3482)
			(xy 36.27213 -95.299565) (xy 36.306216 -95.255422) (xy 36.346365 -95.216713) (xy 36.391723 -95.184262)
			(xy 36.441323 -95.158761) (xy 36.494107 -95.140754) (xy 36.54895 -95.130624) (xy 36.604684 -95.128587)
			(xy 36.660121 -95.134687) (xy 36.714078 -95.148793) (xy 36.765407 -95.170605) (xy 36.813013 -95.199659)
			(xy 36.855881 -95.235334) (xy 36.893098 -95.276871) (xy 36.923871 -95.323384) (xy 36.947543 -95.373881)
			(xy 36.963611 -95.427288) (xy 36.971731 -95.482464) (xy 36.97224 -95.51035) (xy 36.971731 -95.538236)
			(xy 36.963611 -95.593412) (xy 36.947543 -95.646819) (xy 36.923871 -95.697316) (xy 36.893098 -95.743829)
			(xy 36.855881 -95.785366) (xy 36.813013 -95.821041) (xy 36.765407 -95.850095) (xy 36.714078 -95.871907)
			(xy 36.660121 -95.886013) (xy 36.604684 -95.892113) (xy 36.54895 -95.890076) (xy 36.494107 -95.879946)
			(xy 36.441323 -95.861939) (xy 36.391723 -95.836438) (xy 36.346365 -95.803987) (xy 36.306216 -95.765278)
			(xy 36.27213 -95.721135) (xy 36.244834 -95.6725) (xy 36.224911 -95.620409) (xy 36.212785 -95.565972)
			(xy 36.208714 -95.51035) (xy 35.2171 -95.51035) (xy 35.2171 -97.234929) (xy 37.851077 -97.234929)
			(xy 37.854857 -97.179659) (xy 37.866589 -97.125517) (xy 37.886027 -97.073639) (xy 37.912761 -97.025118)
			(xy 37.94623 -96.980972) (xy 37.965634 -96.961198) (xy 37.980534 -96.94587) (xy 38.005594 -96.911245)
			(xy 38.0245 -96.872912) (xy 38.036718 -96.831954) (xy 38.041904 -96.789528) (xy 38.03991 -96.746832)
			(xy 38.030793 -96.705074) (xy 38.014811 -96.665433) (xy 38.003988 -96.647) (xy 37.989902 -96.623179)
			(xy 37.968047 -96.572337) (xy 37.953768 -96.51887) (xy 37.947365 -96.463902) (xy 37.948971 -96.408584)
			(xy 37.958553 -96.35408) (xy 37.97591 -96.301532) (xy 38.000677 -96.252043) (xy 38.032336 -96.206652)
			(xy 38.07022 -96.166312) (xy 38.113536 -96.13187) (xy 38.161374 -96.104047) (xy 38.186868 -96.09328)
			(xy 38.207579 -96.084455) (xy 38.245725 -96.060554) (xy 38.279066 -96.030308) (xy 38.306559 -95.994663)
			(xy 38.327344 -95.954734) (xy 38.340773 -95.911767) (xy 38.346424 -95.867108) (xy 38.344121 -95.822151)
			(xy 38.333937 -95.778302) (xy 38.31619 -95.736933) (xy 38.304216 -95.717868) (xy 38.289498 -95.694544)
			(xy 38.266126 -95.644593) (xy 38.25019 -95.591796) (xy 38.242022 -95.537256) (xy 38.241793 -95.482107)
			(xy 38.249508 -95.427501) (xy 38.265005 -95.374574) (xy 38.287962 -95.32443) (xy 38.3179 -95.278115)
			(xy 38.354195 -95.236593) (xy 38.396091 -95.200731) (xy 38.442715 -95.171274) (xy 38.493094 -95.148839)
			(xy 38.546178 -95.133892) (xy 38.600862 -95.126744) (xy 38.656005 -95.127545) (xy 38.710458 -95.136278)
			(xy 38.763086 -95.152761) (xy 38.812793 -95.17665) (xy 38.858541 -95.207448) (xy 38.899377 -95.244512)
			(xy 38.934451 -95.287071) (xy 38.963032 -95.334236) (xy 38.984522 -95.385025) (xy 38.998476 -95.43838)
			(xy 39.004601 -95.493188) (xy 39.002771 -95.548306) (xy 38.993022 -95.602587) (xy 38.975559 -95.654898)
			(xy 38.950746 -95.704149) (xy 38.919099 -95.749314) (xy 38.881278 -95.789452) (xy 38.838073 -95.823725)
			(xy 38.790382 -95.851419) (xy 38.764972 -95.86214) (xy 38.744255 -95.870953) (xy 38.706104 -95.894852)
			(xy 38.672759 -95.925098) (xy 38.645263 -95.960744) (xy 38.624476 -96.000676) (xy 38.611048 -96.043645)
			(xy 38.605398 -96.088308) (xy 38.607704 -96.133267) (xy 38.617893 -96.177118) (xy 38.635646 -96.218488)
			(xy 38.647624 -96.237552) (xy 38.661764 -96.25969) (xy 38.684382 -96.307102) (xy 38.700279 -96.35717)
			(xy 38.709153 -96.408946) (xy 38.710836 -96.46145) (xy 38.705296 -96.513688) (xy 38.692638 -96.564671)
			(xy 38.673102 -96.613435) (xy 38.647057 -96.659054) (xy 38.614997 -96.700668) (xy 38.59657 -96.71939)
			(xy 38.581594 -96.734648) (xy 38.556537 -96.769286) (xy 38.537637 -96.807632) (xy 38.525426 -96.848603)
			(xy 38.520251 -96.89104) (xy 38.522257 -96.933744) (xy 38.531388 -96.975509) (xy 38.547385 -97.015154)
			(xy 38.558216 -97.033588) (xy 38.573015 -97.058638) (xy 38.59561 -97.112253) (xy 38.60979 -97.168679)
			(xy 38.615228 -97.226605) (xy 38.611795 -97.284685) (xy 38.606222 -97.313242) (xy 38.601746 -97.336491)
			(xy 38.600598 -97.383818) (xy 38.608232 -97.43054) (xy 38.624384 -97.47504) (xy 38.648496 -97.515781)
			(xy 38.679733 -97.551354) (xy 38.717016 -97.580529) (xy 38.737794 -97.59188) (xy 38.761911 -97.604844)
			(xy 38.806432 -97.636717) (xy 38.845942 -97.674625) (xy 38.879627 -97.717791) (xy 38.906798 -97.765328)
			(xy 38.926896 -97.816261) (xy 38.939509 -97.869543) (xy 38.944377 -97.92408) (xy 38.941401 -97.978754)
			(xy 38.930642 -98.032441) (xy 38.91232 -98.084039) (xy 38.886812 -98.132488) (xy 38.854642 -98.176795)
			(xy 38.81647 -98.21605) (xy 38.773079 -98.249446) (xy 38.725361 -98.276298) (xy 38.674295 -98.296055)
			(xy 38.62093 -98.30831) (xy 38.566361 -98.312813) (xy 38.511709 -98.309471) (xy 38.458095 -98.298352)
			(xy 38.406621 -98.279686) (xy 38.358343 -98.253854) (xy 38.314253 -98.221388) (xy 38.275255 -98.182953)
			(xy 38.24215 -98.13934) (xy 38.215618 -98.091443) (xy 38.196204 -98.040246) (xy 38.184306 -97.9868)
			(xy 38.180168 -97.932202) (xy 38.183876 -97.877574) (xy 38.189154 -97.850706) (xy 38.193542 -97.827444)
			(xy 38.194697 -97.780126) (xy 38.187073 -97.733413) (xy 38.170935 -97.688918) (xy 38.146839 -97.648179)
			(xy 38.115618 -97.612604) (xy 38.078352 -97.583423) (xy 38.057582 -97.572068) (xy 38.033203 -97.55891)
			(xy 37.988223 -97.52657) (xy 37.948392 -97.488066) (xy 37.914548 -97.444207) (xy 37.8874 -97.395915)
			(xy 37.867521 -97.344205) (xy 37.855328 -97.290165) (xy 37.851077 -97.234929) (xy 35.2171 -97.234929)
			(xy 35.2171 -99.977956) (xy 35.217589 -99.994615) (xy 35.226203 -100.026799) (xy 35.242855 -100.055656)
			(xy 35.266409 -100.079218) (xy 35.295261 -100.09588) (xy 35.327442 -100.104505) (xy 35.3441 -100.104956)
			(xy 37.62121 -100.104956) (xy 39.089584 -101.57333) (xy 39.089584 -104.387142) (xy 38.715188 -104.761284)
			(xy 37.39642 -104.761284) (xy 37.379763 -104.761776) (xy 37.347582 -104.770394) (xy 37.318729 -104.787047)
			(xy 37.295169 -104.8106) (xy 37.278507 -104.839449) (xy 37.269881 -104.871627) (xy 37.26942 -104.888284)
			(xy 37.26942 -111.764064) (xy 37.26991 -111.780721) (xy 37.278526 -111.812901) (xy 37.295179 -111.841754)
			(xy 37.318733 -111.865312) (xy 37.347584 -111.881968) (xy 37.379763 -111.890588) (xy 37.39642 -111.891064)
			(xy 37.417248 -111.891064) (xy 37.443767 -111.882061) (xy 37.498673 -111.871037) (xy 37.554601 -111.868161)
			(xy 37.610349 -111.873494) (xy 37.664717 -111.886922) (xy 37.716538 -111.908157) (xy 37.764696 -111.936741)
			(xy 37.808156 -111.97206) (xy 37.845984 -112.013355) (xy 37.877367 -112.059737) (xy 37.90163 -112.11021)
			(xy 37.918251 -112.163689) (xy 37.926873 -112.219024) (xy 37.927311 -112.275024) (xy 37.919555 -112.330486)
			(xy 37.903771 -112.384218) (xy 37.8803 -112.435065) (xy 37.849646 -112.481932) (xy 37.812467 -112.523813)
			(xy 37.769564 -112.559807) (xy 37.721859 -112.58914) (xy 37.670377 -112.611181) (xy 37.616225 -112.625457)
			(xy 37.560567 -112.631661) (xy 37.532564 -112.63122) (xy 37.509879 -112.630909) (xy 37.464978 -112.637363)
			(xy 37.421936 -112.651684) (xy 37.382118 -112.673417) (xy 37.346791 -112.701873) (xy 37.317075 -112.736147)
			(xy 37.293914 -112.775151) (xy 37.278044 -112.817647) (xy 37.269969 -112.862285) (xy 37.26942 -112.884966)
			(xy 37.26942 -113.828576) (xy 37.19449 -113.903252) (xy 37.183037 -113.915389) (xy 37.16634 -113.944269)
			(xy 37.157693 -113.976488) (xy 37.157152 -113.993168) (xy 37.157152 -114.683032) (xy 37.41166 -114.93754)
			(xy 40.115744 -114.93754)
		)
		(stroke
			(width 0)
			(type solid)
		)
		(fill yes)
		(layer "In2.Cu")
		(net "P1V5_NODE1")
	)
	(gr_poly
		(pts
			(xy 86.571582 -143.998188) (xy 86.585806 -143.919956) (xy 86.5759 -143.898112) (xy 86.563776 -143.87311)
			(xy 86.546085 -143.820438) (xy 86.536217 -143.765757) (xy 86.534382 -143.710223) (xy 86.540618 -143.65501)
			(xy 86.554793 -143.601285) (xy 86.576608 -143.550183) (xy 86.605602 -143.502783) (xy 86.641162 -143.460088)
			(xy 86.682536 -143.423) (xy 86.72885 -143.392302) (xy 86.779126 -143.368644) (xy 86.832301 -143.352525)
			(xy 86.88725 -143.344286) (xy 86.942814 -143.344101) (xy 86.997817 -143.351975) (xy 87.051098 -143.367739)
			(xy 87.10153 -143.391063) (xy 87.125048 -143.40586) (xy 87.149432 -143.420592) (xy 87.61476 -142.95501)
			(xy 87.61476 -138.089132) (xy 87.614269 -138.072476) (xy 87.605653 -138.040299) (xy 87.588999 -138.01145)
			(xy 87.565444 -137.987896) (xy 87.536594 -137.971244) (xy 87.504416 -137.96263) (xy 87.48776 -137.962132)
			(xy 86.666832 -137.962132) (xy 86.634066 -137.981182) (xy 86.625684 -137.9855) (xy 86.601552 -137.998052)
			(xy 86.550546 -138.016947) (xy 86.497372 -138.0284) (xy 86.44311 -138.032178) (xy 86.388862 -138.028204)
			(xy 86.335729 -138.016559) (xy 86.284792 -137.997479) (xy 86.237084 -137.971353) (xy 86.193574 -137.93871)
			(xy 86.155146 -137.900214) (xy 86.12258 -137.856646) (xy 86.096539 -137.808892) (xy 86.07755 -137.757921)
			(xy 86.065999 -137.704768) (xy 86.062122 -137.650512) (xy 86.065996 -137.596257) (xy 86.077543 -137.543103)
			(xy 86.096529 -137.492131) (xy 86.122567 -137.444375) (xy 86.15513 -137.400805) (xy 86.193555 -137.362306)
			(xy 86.237063 -137.32966) (xy 86.284769 -137.303531) (xy 86.335705 -137.284448) (xy 86.388837 -137.2728)
			(xy 86.443085 -137.268822) (xy 86.497347 -137.272597) (xy 86.550522 -137.284046) (xy 86.60153 -137.302938)
			(xy 86.625684 -137.315448) (xy 86.634066 -137.319766) (xy 86.666832 -137.338816) (xy 87.48776 -137.338816)
			(xy 87.504419 -137.338326) (xy 87.536604 -137.329712) (xy 87.565462 -137.313061) (xy 87.589026 -137.289507)
			(xy 87.605691 -137.260656) (xy 87.614319 -137.228475) (xy 87.61476 -137.211816) (xy 87.61476 -133.26872)
			(xy 88.974168 -131.909312) (xy 88.989346 -131.893476) (xy 89.01457 -131.857595) (xy 89.033259 -131.817915)
			(xy 89.044859 -131.775617) (xy 89.049024 -131.731955) (xy 89.045633 -131.688226) (xy 89.034784 -131.645728)
			(xy 89.016801 -131.605724) (xy 88.992217 -131.569401) (xy 88.961762 -131.537838) (xy 88.926341 -131.511972)
			(xy 88.906858 -131.501896) (xy 88.881986 -131.489122) (xy 88.835947 -131.457394) (xy 88.795032 -131.419286)
			(xy 88.760117 -131.375615) (xy 88.73195 -131.327315) (xy 88.711133 -131.275422) (xy 88.698113 -131.221046)
			(xy 88.693168 -131.165353) (xy 88.696405 -131.109534) (xy 88.707753 -131.054785) (xy 88.72697 -131.002278)
			(xy 88.753645 -130.953139) (xy 88.787206 -130.908418) (xy 88.826934 -130.869075) (xy 88.8492 -130.852164)
			(xy 88.86697 -130.838509) (xy 88.897856 -130.806043) (xy 88.922567 -130.768661) (xy 88.940336 -130.727524)
			(xy 88.950612 -130.683907) (xy 88.953076 -130.639164) (xy 88.947652 -130.594683) (xy 88.934508 -130.551843)
			(xy 88.914051 -130.511974) (xy 88.886917 -130.476313) (xy 88.87079 -130.46075) (xy 88.850405 -130.441302)
			(xy 88.815015 -130.397465) (xy 88.786458 -130.3489) (xy 88.765356 -130.296663) (xy 88.752166 -130.24189)
			(xy 88.747178 -130.185772) (xy 88.750498 -130.129531) (xy 88.762054 -130.074391) (xy 88.781597 -130.02155)
			(xy 88.808699 -129.972158) (xy 88.842771 -129.92729) (xy 88.883073 -129.887922) (xy 88.928728 -129.854911)
			(xy 88.978741 -129.828974) (xy 89.032026 -129.810677) (xy 89.087423 -129.800416) (xy 89.143726 -129.798416)
			(xy 89.199711 -129.804719) (xy 89.25416 -129.819189) (xy 89.305888 -129.84151) (xy 89.35377 -129.871198)
			(xy 89.396764 -129.907607) (xy 89.433935 -129.949943) (xy 89.449656 -129.973324) (xy 89.462352 -129.99212)
			(xy 89.493285 -130.025287) (xy 89.529616 -130.052433) (xy 89.570191 -130.072696) (xy 89.613719 -130.085431)
			(xy 89.658817 -130.090235) (xy 89.704051 -130.086953) (xy 89.747983 -130.07569) (xy 89.789217 -130.056805)
			(xy 89.826441 -130.030898) (xy 89.842848 -130.015234) (xy 90.18778 -129.670302) (xy 90.18778 -126.648464)
			(xy 87.195152 -123.655836) (xy 85.808566 -123.655836) (xy 84.593176 -122.440446) (xy 84.593176 -118.323868)
			(xy 84.146136 -116.795296) (xy 84.146136 -114.939572) (xy 84.555076 -114.530632) (xy 84.555076 -114.335052)
			(xy 84.4804 -114.26063) (xy 84.4804 -113.698528) (xy 83.857084 -113.075212) (xy 82.584544 -113.075212)
			(xy 81.84896 -113.81105) (xy 81.3562 -113.81105) (xy 81.35493 -113.81232) (xy 78.722728 -113.81232)
			(xy 78.721458 -113.81105) (xy 78.098904 -113.81105) (xy 74.553064 -110.26521) (xy 74.448416 -110.26521)
			(xy 74.42708 -110.286546) (xy 74.42708 -110.273846) (xy 74.352912 -110.199678) (xy 68.09486 -110.199678)
			(xy 62.75578 -104.860598) (xy 61.80074 -104.860598) (xy 58.691526 -101.751384) (xy 57.29859 -101.751384)
			(xy 57.275819 -101.751893) (xy 57.231008 -101.760014) (xy 57.188362 -101.775993) (xy 57.149248 -101.799319)
			(xy 57.114919 -101.829244) (xy 57.086476 -101.86481) (xy 57.064828 -101.904878) (xy 57.05067 -101.948162)
			(xy 57.044455 -101.993277) (xy 57.044844 -102.016052) (xy 57.045545 -102.044047) (xy 57.039728 -102.099743)
			(xy 57.025834 -102.153991) (xy 57.004161 -102.205626) (xy 56.975174 -102.253538) (xy 56.939496 -102.2967)
			(xy 56.897893 -102.334185) (xy 56.851258 -102.365186) (xy 56.800594 -102.38904) (xy 56.746987 -102.405232)
			(xy 56.691589 -102.413416) (xy 56.635591 -102.413416) (xy 56.580193 -102.405232) (xy 56.526586 -102.38904)
			(xy 56.475922 -102.365186) (xy 56.429287 -102.334185) (xy 56.387684 -102.2967) (xy 56.352006 -102.253538)
			(xy 56.323019 -102.205626) (xy 56.301346 -102.153991) (xy 56.287452 -102.099743) (xy 56.281635 -102.044047)
			(xy 56.282336 -102.016052) (xy 56.282784 -101.993277) (xy 56.276554 -101.948159) (xy 56.262384 -101.904873)
			(xy 56.240727 -101.864804) (xy 56.212276 -101.829236) (xy 56.177943 -101.799308) (xy 56.138826 -101.775976)
			(xy 56.096178 -101.759988) (xy 56.051363 -101.751856) (xy 56.02859 -101.751384) (xy 55.049674 -101.751384)
			(xy 54.907688 -101.893624) (xy 54.64048 -101.893624) (xy 54.611246 -101.893042) (xy 54.553467 -101.88408)
			(xy 54.497731 -101.866413) (xy 54.445339 -101.840455) (xy 54.397518 -101.806813) (xy 54.376066 -101.786944)
			(xy 54.364017 -101.776012) (xy 54.335655 -101.760093) (xy 54.30419 -101.751863) (xy 54.287928 -101.751384)
			(xy 52.76596 -101.751384) (xy 52.4764 -101.461824) (xy 52.4764 -94.327726) (xy 54.06898 -92.735146)
			(xy 54.083908 -92.719571) (xy 54.108819 -92.684352) (xy 54.127425 -92.645433) (xy 54.139191 -92.603931)
			(xy 54.143781 -92.561038) (xy 54.141062 -92.517986) (xy 54.131112 -92.476011) (xy 54.114216 -92.43632)
			(xy 54.090861 -92.400051) (xy 54.0766 -92.383864) (xy 54.057808 -92.362595) (xy 54.026077 -92.31554)
			(xy 54.001664 -92.264304) (xy 53.985109 -92.210018) (xy 53.976777 -92.153879) (xy 53.976851 -92.097125)
			(xy 53.98533 -92.041008) (xy 54.002027 -91.986766) (xy 54.026573 -91.935594) (xy 54.058427 -91.888622)
			(xy 54.096887 -91.846887) (xy 54.141104 -91.811307) (xy 54.190103 -91.782669) (xy 54.242803 -91.761604)
			(xy 54.298041 -91.748576) (xy 54.3546 -91.743873) (xy 54.411232 -91.747598) (xy 54.439058 -91.753182)
			(xy 54.461336 -91.75753) (xy 54.506693 -91.759175) (xy 54.55162 -91.752738) (xy 54.59469 -91.738424)
			(xy 54.634533 -91.716688) (xy 54.669882 -91.688222) (xy 54.699614 -91.65393) (xy 54.722783 -91.614903)
			(xy 54.738652 -91.572381) (xy 54.746717 -91.527717) (xy 54.74716 -91.505024) (xy 54.74716 -91.110816)
			(xy 54.74671 -91.089298) (xy 54.739461 -91.046877) (xy 54.72517 -91.006283) (xy 54.704243 -90.968677)
			(xy 54.677279 -90.935135) (xy 54.64505 -90.906615) (xy 54.608476 -90.883933) (xy 54.568604 -90.867738)
			(xy 54.526573 -90.858491) (xy 54.505098 -90.85707) (xy 54.47754 -90.855293) (xy 54.423327 -90.84479)
			(xy 54.371194 -90.826579) (xy 54.322232 -90.801043) (xy 54.277463 -90.768714) (xy 54.237823 -90.730267)
			(xy 54.204141 -90.686507) (xy 54.17712 -90.638348) (xy 54.157325 -90.586796) (xy 54.14517 -90.532929)
			(xy 54.140909 -90.477872) (xy 54.14463 -90.422776) (xy 54.156257 -90.368792) (xy 54.175545 -90.317049)
			(xy 54.202093 -90.268627) (xy 54.235345 -90.224539) (xy 54.254654 -90.204798) (xy 54.270609 -90.188326)
			(xy 54.296898 -90.150755) (xy 54.316026 -90.10908) (xy 54.327371 -90.064651) (xy 54.330566 -90.018907)
			(xy 54.325509 -89.973332) (xy 54.312362 -89.929402) (xy 54.291552 -89.888542) (xy 54.278022 -89.870026)
			(xy 54.261238 -89.847134) (xy 54.233911 -89.797384) (xy 54.21426 -89.744133) (xy 54.202719 -89.688557)
			(xy 54.199541 -89.631885) (xy 54.204798 -89.575367) (xy 54.218373 -89.520253) (xy 54.239967 -89.46776)
			(xy 54.269102 -89.419047) (xy 54.305135 -89.375189) (xy 54.347271 -89.337157) (xy 54.394577 -89.305789)
			(xy 54.446011 -89.281779) (xy 54.500434 -89.265657) (xy 54.528466 -89.261188) (xy 54.550923 -89.257521)
			(xy 54.594129 -89.24327) (xy 54.634109 -89.221555) (xy 54.669586 -89.19307) (xy 54.699425 -89.158726)
			(xy 54.722675 -89.119618) (xy 54.738592 -89.076997) (xy 54.746668 -89.032223) (xy 54.74716 -89.009474)
			(xy 54.74716 -86.499192) (xy 54.770782 -86.47557) (xy 54.787038 -86.404196) (xy 54.774846 -86.369652)
			(xy 54.765607 -86.341548) (xy 54.754931 -86.283364) (xy 54.753364 -86.224228) (xy 54.760942 -86.16556)
			(xy 54.777484 -86.108764) (xy 54.802594 -86.055201) (xy 54.83567 -86.006156) (xy 54.855364 -85.98408)
			(xy 54.870749 -85.966733) (xy 54.895589 -85.927587) (xy 54.912924 -85.884588) (xy 54.922182 -85.839159)
			(xy 54.923056 -85.792806) (xy 54.915516 -85.747061) (xy 54.899814 -85.703439) (xy 54.876467 -85.663384)
			(xy 54.861714 -85.645498) (xy 54.843372 -85.623414) (xy 54.812844 -85.574798) (xy 54.789949 -85.522156)
			(xy 54.775203 -85.466677) (xy 54.76894 -85.409614) (xy 54.771302 -85.352257) (xy 54.782234 -85.295901)
			(xy 54.801491 -85.241822) (xy 54.828636 -85.19124) (xy 54.845458 -85.167978) (xy 54.859054 -85.148967)
			(xy 54.879786 -85.107085) (xy 54.89251 -85.062118) (xy 54.896797 -85.015582) (xy 54.892503 -84.969048)
			(xy 54.879773 -84.924082) (xy 54.859035 -84.882203) (xy 54.845458 -84.863178) (xy 54.829498 -84.84109)
			(xy 54.803377 -84.793264) (xy 54.784329 -84.742208) (xy 54.772741 -84.688961) (xy 54.768849 -84.634606)
			(xy 54.772733 -84.580251) (xy 54.784313 -84.527002) (xy 54.803354 -84.475943) (xy 54.829468 -84.428113)
			(xy 54.862123 -84.384487) (xy 54.900654 -84.345953) (xy 54.944278 -84.313295) (xy 54.992105 -84.287178)
			(xy 55.043163 -84.268133) (xy 55.096411 -84.256549) (xy 55.150766 -84.252661) (xy 55.205121 -84.256549)
			(xy 55.258369 -84.268133) (xy 55.309427 -84.287178) (xy 55.357254 -84.313295) (xy 55.400878 -84.345953)
			(xy 55.439409 -84.384487) (xy 55.472064 -84.428113) (xy 55.498178 -84.475943) (xy 55.517219 -84.527002)
			(xy 55.528799 -84.580251) (xy 55.532683 -84.634606) (xy 55.528791 -84.688961) (xy 55.517203 -84.742208)
			(xy 55.498155 -84.793264) (xy 55.472034 -84.84109) (xy 55.456074 -84.863178) (xy 55.442478 -84.882191)
			(xy 55.421743 -84.924075) (xy 55.409015 -84.969044) (xy 55.404722 -85.015582) (xy 55.409009 -85.062121)
			(xy 55.421731 -85.107092) (xy 55.442459 -85.148979) (xy 55.456074 -85.167978) (xy 55.469835 -85.186863)
			(xy 55.493147 -85.227361) (xy 55.502556 -85.24875) (xy 55.511768 -85.269424) (xy 55.536395 -85.307393)
			(xy 55.56736 -85.340398) (xy 55.603682 -85.367395) (xy 55.644212 -85.38753) (xy 55.687668 -85.400166)
			(xy 55.732676 -85.404903) (xy 55.777811 -85.401592) (xy 55.821645 -85.390337) (xy 55.862792 -85.371493)
			(xy 55.899949 -85.345659) (xy 55.916322 -85.33003) (xy 56.273192 -84.97316) (xy 56.284733 -84.960851)
			(xy 56.30147 -84.931564) (xy 56.309955 -84.898917) (xy 56.309596 -84.865188) (xy 56.300418 -84.832729)
			(xy 56.292242 -84.817966) (xy 56.27818 -84.793587) (xy 56.256594 -84.741612) (xy 56.242874 -84.687031)
			(xy 56.237318 -84.631027) (xy 56.240047 -84.574815) (xy 56.251 -84.519612) (xy 56.269941 -84.466616)
			(xy 56.29646 -84.416977) (xy 56.32998 -84.37177) (xy 56.369776 -84.331975) (xy 56.414984 -84.298455)
			(xy 56.464624 -84.271938) (xy 56.51762 -84.252998) (xy 56.572823 -84.242046) (xy 56.629036 -84.239318)
			(xy 56.685039 -84.244876) (xy 56.73962 -84.258597) (xy 56.791594 -84.280184) (xy 56.81599 -84.294218)
			(xy 56.853328 -84.316824) (xy 56.939942 -84.30641) (xy 57.377838 -83.868514) (xy 57.377838 -80.098392)
			(xy 57.190132 -79.910686) (xy 56.627014 -79.910686) (xy 55.09768 -81.44002) (xy 52.54371 -81.44002)
			(xy 51.219354 -82.764376) (xy 51.207891 -82.776508) (xy 51.191177 -82.805386) (xy 51.182524 -82.837611)
			(xy 51.182523 -82.870978) (xy 51.191173 -82.903203) (xy 51.207884 -82.932083) (xy 51.219354 -82.944208)
			(xy 51.238325 -82.963797) (xy 51.271044 -83.007422) (xy 51.297217 -83.055262) (xy 51.316311 -83.106341)
			(xy 51.327936 -83.159619) (xy 51.331856 -83.21401) (xy 51.327991 -83.268404) (xy 51.316418 -83.321693)
			(xy 51.297375 -83.372792) (xy 51.27125 -83.420657) (xy 51.238575 -83.464315) (xy 51.200015 -83.502874)
			(xy 51.156357 -83.53555) (xy 51.108492 -83.561675) (xy 51.057393 -83.580718) (xy 51.004104 -83.59229)
			(xy 50.94971 -83.596156) (xy 50.895319 -83.592236) (xy 50.842041 -83.580611) (xy 50.790962 -83.561517)
			(xy 50.743122 -83.535344) (xy 50.699497 -83.502625) (xy 50.679858 -83.483704) (xy 50.667726 -83.472243)
			(xy 50.638847 -83.455534) (xy 50.606624 -83.446883) (xy 50.57326 -83.446883) (xy 50.541037 -83.455534)
			(xy 50.512158 -83.472243) (xy 50.500026 -83.483704) (xy 50.415444 -83.568286) (xy 50.415444 -83.837625)
			(xy 52.274889 -83.837625) (xy 52.282041 -83.781525) (xy 52.297391 -83.727094) (xy 52.320602 -83.675523)
			(xy 52.351166 -83.62794) (xy 52.388415 -83.585385) (xy 52.431533 -83.548791) (xy 52.479578 -83.518957)
			(xy 52.531498 -83.496537) (xy 52.558696 -83.488784) (xy 52.573073 -83.484385) (xy 52.598619 -83.46856)
			(xy 52.618483 -83.446011) (xy 52.630962 -83.418674) (xy 52.634984 -83.388894) (xy 52.633118 -83.373976)
			(xy 52.628868 -83.344557) (xy 52.628441 -83.28512) (xy 52.637239 -83.226336) (xy 52.655049 -83.169629)
			(xy 52.681439 -83.11637) (xy 52.698142 -83.091782) (xy 52.706217 -83.07955) (xy 52.715665 -83.051817)
			(xy 52.716873 -83.022544) (xy 52.709743 -82.994126) (xy 52.694859 -82.968891) (xy 52.673438 -82.948902)
			(xy 52.66055 -82.941922) (xy 52.636669 -82.929397) (xy 52.592385 -82.898626) (xy 52.552873 -82.861929)
			(xy 52.518918 -82.820036) (xy 52.491196 -82.773782) (xy 52.47026 -82.724088) (xy 52.456525 -82.671941)
			(xy 52.450265 -82.618381) (xy 52.451605 -82.564472) (xy 52.460517 -82.511289) (xy 52.476826 -82.459889)
			(xy 52.500205 -82.411296) (xy 52.530191 -82.366476) (xy 52.566185 -82.326323) (xy 52.607471 -82.291634)
			(xy 52.653229 -82.2631) (xy 52.702546 -82.24129) (xy 52.728368 -82.233516) (xy 52.741336 -82.229427)
			(xy 52.764596 -82.215355) (xy 52.783337 -82.195662) (xy 52.796239 -82.171734) (xy 52.802394 -82.145255)
			(xy 52.80137 -82.118089) (xy 52.79771 -82.104992) (xy 52.789958 -82.078684) (xy 52.781267 -82.024532)
			(xy 52.780416 -81.969694) (xy 52.787424 -81.915299) (xy 52.802144 -81.862466) (xy 52.824275 -81.812285)
			(xy 52.853361 -81.765788) (xy 52.888803 -81.723932) (xy 52.92987 -81.687581) (xy 52.975718 -81.657482)
			(xy 53.025402 -81.634255) (xy 53.077899 -81.618379) (xy 53.132127 -81.61018) (xy 53.186971 -81.609827)
			(xy 53.241301 -81.617328) (xy 53.293997 -81.632528) (xy 53.343976 -81.655115) (xy 53.390207 -81.684622)
			(xy 53.431738 -81.720442) (xy 53.467715 -81.761838) (xy 53.497396 -81.807957) (xy 53.520171 -81.85785)
			(xy 53.53557 -81.910489) (xy 53.543276 -81.96479) (xy 53.54313 -82.019634) (xy 53.535136 -82.073894)
			(xy 53.519458 -82.12645) (xy 53.496419 -82.176221) (xy 53.466493 -82.222182) (xy 53.430297 -82.263386)
			(xy 53.388576 -82.298986) (xy 53.342189 -82.328247) (xy 53.292091 -82.350567) (xy 53.265832 -82.358484)
			(xy 53.252864 -82.362573) (xy 53.229604 -82.376645) (xy 53.210863 -82.396338) (xy 53.197961 -82.420266)
			(xy 53.191806 -82.446745) (xy 53.19283 -82.473911) (xy 53.19649 -82.487008) (xy 53.204675 -82.515052)
			(xy 53.213343 -82.572825) (xy 53.213108 -82.631243) (xy 53.203976 -82.688944) (xy 53.198877 -82.704867)
			(xy 54.250085 -82.704867) (xy 54.255384 -82.650644) (xy 54.268346 -82.597726) (xy 54.288707 -82.547192)
			(xy 54.316053 -82.50007) (xy 54.349826 -82.45732) (xy 54.38934 -82.419811) (xy 54.43379 -82.388307)
			(xy 54.482271 -82.36345) (xy 54.533796 -82.345746) (xy 54.56047 -82.340196) (xy 54.533733 -82.33441)
			(xy 54.482172 -82.316129) (xy 54.433748 -82.290678) (xy 54.389451 -82.258577) (xy 54.350188 -82.220483)
			(xy 54.316764 -82.177177) (xy 54.289861 -82.129543) (xy 54.270031 -82.078559) (xy 54.257679 -82.025266)
			(xy 54.253059 -81.970756) (xy 54.256265 -81.916144) (xy 54.267231 -81.862549) (xy 54.285733 -81.811068)
			(xy 54.311392 -81.762753) (xy 54.343683 -81.718595) (xy 54.381945 -81.679496) (xy 54.425395 -81.646258)
			(xy 54.473144 -81.61956) (xy 54.524213 -81.599949) (xy 54.577559 -81.587827) (xy 54.632088 -81.583441)
			(xy 54.686685 -81.586882) (xy 54.740232 -81.598078) (xy 54.791634 -81.616801) (xy 54.839838 -81.642668)
			(xy 54.883857 -81.675148) (xy 54.922791 -81.713578) (xy 54.955842 -81.757171) (xy 54.982334 -81.805033)
			(xy 55.001725 -81.856187) (xy 55.013618 -81.909584) (xy 55.01777 -81.964132) (xy 55.0164 -81.991454)
			(xy 55.042098 -81.982295) (xy 55.09538 -81.970575) (xy 55.149788 -81.966564) (xy 55.204213 -81.970344)
			(xy 55.257544 -81.981837) (xy 55.308694 -82.000809) (xy 55.356621 -82.026874) (xy 55.400346 -82.0595)
			(xy 55.438978 -82.098021) (xy 55.47173 -82.141651) (xy 55.497933 -82.189503) (xy 55.517053 -82.240598)
			(xy 55.5287 -82.293896) (xy 55.532637 -82.348309) (xy 55.528783 -82.402728) (xy 55.517217 -82.456044)
			(xy 55.498175 -82.507168) (xy 55.472045 -82.555059) (xy 55.456074 -82.577178) (xy 55.4425 -82.596204)
			(xy 55.421768 -82.638085) (xy 55.409041 -82.683049) (xy 55.404748 -82.729582) (xy 55.409035 -82.776116)
			(xy 55.421755 -82.821082) (xy 55.442482 -82.862965) (xy 55.456074 -82.881978) (xy 55.471923 -82.904073)
			(xy 55.498008 -82.951778) (xy 55.517055 -83.002703) (xy 55.528678 -83.055817) (xy 55.532641 -83.110044)
			(xy 55.528864 -83.164283) (xy 55.517424 -83.217437) (xy 55.498552 -83.268428) (xy 55.472631 -83.316222)
			(xy 55.440187 -83.359852) (xy 55.401876 -83.398432) (xy 55.358475 -83.431182) (xy 55.310863 -83.457437)
			(xy 55.260006 -83.476666) (xy 55.206934 -83.488479) (xy 55.152722 -83.492636) (xy 55.09847 -83.489053)
			(xy 55.045275 -83.477803) (xy 54.994217 -83.459114) (xy 54.946331 -83.433364) (xy 54.902585 -83.401076)
			(xy 54.863868 -83.362903) (xy 54.830963 -83.31962) (xy 54.804538 -83.272102) (xy 54.785127 -83.221314)
			(xy 54.778656 -83.194906) (xy 54.774952 -83.1806) (xy 54.762025 -83.15404) (xy 54.74333 -83.13117)
			(xy 54.71987 -83.11322) (xy 54.692907 -83.101155) (xy 54.66389 -83.095623) (xy 54.649116 -83.095846)
			(xy 54.621877 -83.096516) (xy 54.567654 -83.091218) (xy 54.514736 -83.078257) (xy 54.464201 -83.057898)
			(xy 54.417078 -83.030553) (xy 54.374327 -82.996781) (xy 54.336817 -82.957267) (xy 54.305312 -82.912818)
			(xy 54.280454 -82.864338) (xy 54.262749 -82.812813) (xy 54.252556 -82.759293) (xy 54.250085 -82.704867)
			(xy 53.198877 -82.704867) (xy 53.18616 -82.74458) (xy 53.160076 -82.796853) (xy 53.143658 -82.821018)
			(xy 53.135583 -82.83325) (xy 53.126135 -82.860983) (xy 53.124927 -82.890256) (xy 53.132057 -82.918674)
			(xy 53.146941 -82.943909) (xy 53.168362 -82.963898) (xy 53.18125 -82.970878) (xy 53.205343 -82.983405)
			(xy 53.249927 -83.01441) (xy 53.289668 -83.051419) (xy 53.323765 -83.093685) (xy 53.351529 -83.140356)
			(xy 53.372402 -83.190489) (xy 53.385961 -83.243074) (xy 53.391932 -83.29705) (xy 53.390197 -83.351327)
			(xy 53.380789 -83.404811) (xy 53.363898 -83.456422) (xy 53.339865 -83.505119) (xy 53.309176 -83.549921)
			(xy 53.272448 -83.589922) (xy 53.230424 -83.624316) (xy 53.18395 -83.65241) (xy 53.133965 -83.673635)
			(xy 53.107844 -83.681062) (xy 53.093439 -83.68538) (xy 53.067892 -83.701228) (xy 53.048032 -83.723797)
			(xy 53.035561 -83.751152) (xy 53.031549 -83.780946) (xy 53.033422 -83.79587) (xy 53.037025 -83.820427)
			(xy 53.038634 -83.870034) (xy 53.033804 -83.919431) (xy 53.028596 -83.943698) (xy 53.025783 -83.958068)
			(xy 53.027537 -83.987286) (xy 53.037479 -84.014816) (xy 53.054799 -84.038412) (xy 53.078083 -84.056149)
			(xy 53.091588 -84.061808) (xy 53.116937 -84.071931) (xy 53.164627 -84.098487) (xy 53.208048 -84.131566)
			(xy 53.246314 -84.170492) (xy 53.278645 -84.214472) (xy 53.304382 -84.262608) (xy 53.322999 -84.31392)
			(xy 53.334118 -84.367361) (xy 53.337511 -84.421841) (xy 53.333109 -84.476248) (xy 53.321003 -84.529474)
			(xy 53.301438 -84.580432) (xy 53.274813 -84.628084) (xy 53.241673 -84.671457) (xy 53.202692 -84.709668)
			(xy 53.158666 -84.741936) (xy 53.110492 -84.767604) (xy 53.059154 -84.786148) (xy 53.005697 -84.797191)
			(xy 52.951213 -84.800506) (xy 52.896812 -84.796026) (xy 52.843604 -84.783843) (xy 52.792673 -84.764205)
			(xy 52.74506 -84.737513) (xy 52.701734 -84.704311) (xy 52.663579 -84.665275) (xy 52.631374 -84.621203)
			(xy 52.605774 -84.572993) (xy 52.587304 -84.521628) (xy 52.576338 -84.468156) (xy 52.5731 -84.413666)
			(xy 52.577658 -84.359272) (xy 52.583334 -84.332572) (xy 52.586222 -84.318212) (xy 52.58446 -84.288981)
			(xy 52.574503 -84.261443) (xy 52.557163 -84.237845) (xy 52.533857 -84.220114) (xy 52.520342 -84.214462)
			(xy 52.494123 -84.203857) (xy 52.444855 -84.17609) (xy 52.400222 -84.141359) (xy 52.3612 -84.100425)
			(xy 52.328644 -84.054182) (xy 52.303264 -84.003642) (xy 52.285618 -83.949912) (xy 52.27609 -83.894166)
			(xy 52.274889 -83.837625) (xy 50.415444 -83.837625) (xy 50.415444 -84.25561) (xy 50.415944 -84.278633)
			(xy 50.424239 -84.323926) (xy 50.440557 -84.366984) (xy 50.464363 -84.406398) (xy 50.49488 -84.440881)
			(xy 50.531107 -84.469302) (xy 50.571862 -84.490734) (xy 50.61581 -84.504475) (xy 50.661515 -84.510075)
			(xy 50.70748 -84.507351) (xy 50.752203 -84.496393) (xy 50.794221 -84.477559) (xy 50.813462 -84.464906)
			(xy 50.836556 -84.449599) (xy 50.886248 -84.425098) (xy 50.938962 -84.408043) (xy 50.993588 -84.398792)
			(xy 51.048978 -84.397539) (xy 51.103966 -84.40431) (xy 51.157397 -84.418965) (xy 51.208147 -84.441193)
			(xy 51.255147 -84.470528) (xy 51.297411 -84.506353) (xy 51.334048 -84.547914) (xy 51.364288 -84.594337)
			(xy 51.387496 -84.644646) (xy 51.403183 -84.697783) (xy 51.41102 -84.75263) (xy 51.410841 -84.808033)
			(xy 51.40265 -84.862829) (xy 51.38662 -84.915863) (xy 51.37531 -84.941156) (xy 51.368549 -84.956928)
			(xy 51.362811 -84.990746) (xy 51.366284 -85.024871) (xy 51.378718 -85.05684) (xy 51.399214 -85.084344)
			(xy 51.412394 -85.095334) (xy 51.433043 -85.11196) (xy 51.46999 -85.149977) (xy 51.501315 -85.192746)
			(xy 51.526413 -85.239442) (xy 51.544801 -85.289164) (xy 51.556123 -85.340954) (xy 51.560162 -85.393813)
			(xy 51.55684 -85.446722) (xy 51.54622 -85.498661) (xy 51.528508 -85.548627) (xy 51.504046 -85.595659)
			(xy 51.489102 -85.617558) (xy 51.476464 -85.63614) (xy 51.457248 -85.676759) (xy 51.445473 -85.720123)
			(xy 51.441504 -85.764882) (xy 51.445466 -85.809642) (xy 51.457236 -85.853008) (xy 51.476446 -85.893629)
			(xy 51.489102 -85.912198) (xy 51.504819 -85.935184) (xy 51.530136 -85.984776) (xy 51.547973 -86.037523)
			(xy 51.557952 -86.092303) (xy 51.55986 -86.147952) (xy 51.553656 -86.203286) (xy 51.539473 -86.257131)
			(xy 51.517611 -86.308341) (xy 51.488536 -86.355828) (xy 51.452866 -86.398583) (xy 51.411357 -86.435698)
			(xy 51.364894 -86.466383) (xy 51.314463 -86.489986) (xy 51.261136 -86.506006) (xy 51.206047 -86.514101)
			(xy 51.150365 -86.514101) (xy 51.095276 -86.506006) (xy 51.041949 -86.489986) (xy 50.991518 -86.466383)
			(xy 50.945055 -86.435698) (xy 50.903546 -86.398583) (xy 50.867876 -86.355828) (xy 50.838801 -86.308341)
			(xy 50.816939 -86.257131) (xy 50.802756 -86.203286) (xy 50.796552 -86.147952) (xy 50.79846 -86.092303)
			(xy 50.808439 -86.037523) (xy 50.826276 -85.984776) (xy 50.851593 -85.935184) (xy 50.86731 -85.912198)
			(xy 50.879944 -85.893616) (xy 50.899151 -85.852998) (xy 50.910919 -85.809637) (xy 50.91488 -85.764882)
			(xy 50.910912 -85.720128) (xy 50.899138 -85.676768) (xy 50.879925 -85.636153) (xy 50.86731 -85.617558)
			(xy 50.851032 -85.593784) (xy 50.82506 -85.542353) (xy 50.807126 -85.4876) (xy 50.797637 -85.43077)
			(xy 50.796809 -85.37316) (xy 50.804663 -85.316081) (xy 50.821018 -85.260835) (xy 50.832766 -85.234526)
			(xy 50.839521 -85.218753) (xy 50.845251 -85.184937) (xy 50.841776 -85.150815) (xy 50.829346 -85.118848)
			(xy 50.808857 -85.091342) (xy 50.795682 -85.080348) (xy 50.772623 -85.061716) (xy 50.732005 -85.018538)
			(xy 50.698552 -84.969598) (xy 50.673067 -84.916075) (xy 50.66411 -84.887816) (xy 50.658894 -84.872182)
			(xy 50.641688 -84.844085) (xy 50.617862 -84.82133) (xy 50.589002 -84.805436) (xy 50.557035 -84.797462)
			(xy 50.524092 -84.79794) (xy 50.49237 -84.806839) (xy 50.463984 -84.823564) (xy 50.440828 -84.847)
			(xy 50.424446 -84.875585) (xy 50.415929 -84.907412) (xy 50.415444 -84.923884) (xy 50.415444 -87.29091)
			(xy 50.431954 -87.319866) (xy 50.445321 -87.344531) (xy 50.46547 -87.396886) (xy 50.477738 -87.451628)
			(xy 50.481859 -87.507576) (xy 50.477745 -87.563524) (xy 50.465484 -87.618267) (xy 50.445342 -87.670625)
			(xy 50.431954 -87.695278) (xy 50.415444 -87.724234) (xy 50.415444 -89.18829) (xy 50.415938 -89.204944)
			(xy 50.424558 -89.237116) (xy 50.441213 -89.265959) (xy 50.464768 -89.289508) (xy 50.493616 -89.306155)
			(xy 50.52579 -89.314767) (xy 50.542444 -89.31529) (xy 50.569709 -89.315736) (xy 50.623688 -89.323463)
			(xy 50.676017 -89.338797) (xy 50.725629 -89.361425) (xy 50.771515 -89.390886) (xy 50.812738 -89.42658)
			(xy 50.84846 -89.46778) (xy 50.877952 -89.513646) (xy 50.900613 -89.563243) (xy 50.915982 -89.615562)
			(xy 50.923746 -89.669535) (xy 50.923746 -89.724065) (xy 50.915982 -89.778038) (xy 50.900613 -89.830357)
			(xy 50.877952 -89.879954) (xy 50.84846 -89.92582) (xy 50.812738 -89.96702) (xy 50.771515 -90.002714)
			(xy 50.725629 -90.032175) (xy 50.676017 -90.054803) (xy 50.623688 -90.070137) (xy 50.569709 -90.077864)
			(xy 50.542444 -90.078306) (xy 50.525786 -90.078795) (xy 50.493602 -90.087409) (xy 50.464746 -90.104061)
			(xy 50.441184 -90.127616) (xy 50.424524 -90.156467) (xy 50.4159 -90.188648) (xy 50.415444 -90.205306)
			(xy 50.415444 -90.472542) (xy 52.10942 -90.472542) (xy 52.110494 -90.419136) (xy 52.119006 -90.366401)
			(xy 52.134789 -90.315369) (xy 52.157537 -90.267038) (xy 52.186802 -90.222351) (xy 52.222015 -90.182183)
			(xy 52.241958 -90.164412) (xy 52.259719 -90.148476) (xy 52.289463 -90.111167) (xy 52.311718 -90.068961)
			(xy 52.325703 -90.023343) (xy 52.330925 -89.975915) (xy 52.327202 -89.928347) (xy 52.314664 -89.88231)
			(xy 52.304696 -89.860628) (xy 52.293118 -89.835765) (xy 52.276397 -89.783532) (xy 52.26733 -89.729442)
			(xy 52.266102 -89.674612) (xy 52.27274 -89.62017) (xy 52.287106 -89.567241) (xy 52.308904 -89.516915)
			(xy 52.337685 -89.470229) (xy 52.372855 -89.428146) (xy 52.41369 -89.391534) (xy 52.459347 -89.361148)
			(xy 52.508885 -89.337613) (xy 52.561283 -89.321416) (xy 52.615461 -89.31289) (xy 52.670301 -89.31221)
			(xy 52.724673 -89.319392) (xy 52.777456 -89.334286) (xy 52.827562 -89.356586) (xy 52.873958 -89.385832)
			(xy 52.915687 -89.421422) (xy 52.951889 -89.46262) (xy 52.981818 -89.508579) (xy 53.004856 -89.55835)
			(xy 53.020529 -89.610907) (xy 53.028513 -89.665167) (xy 53.028644 -89.720011) (xy 53.020919 -89.774309)
			(xy 53.005498 -89.826941) (xy 52.982698 -89.876821) (xy 52.952989 -89.922922) (xy 52.916985 -89.964293)
			(xy 52.896516 -89.982548) (xy 52.878783 -89.998513) (xy 52.849041 -90.035817) (xy 52.826785 -90.078017)
			(xy 52.812797 -90.12363) (xy 52.807569 -90.171052) (xy 52.811285 -90.218616) (xy 52.823815 -90.264651)
			(xy 52.833778 -90.286332) (xy 52.845446 -90.311359) (xy 52.86224 -90.36396) (xy 52.871272 -90.418434)
			(xy 52.872354 -90.473641) (xy 52.865463 -90.528426) (xy 52.850743 -90.581646) (xy 52.828502 -90.632186)
			(xy 52.799205 -90.67899) (xy 52.781708 -90.700352) (xy 52.77169 -90.712985) (xy 52.757717 -90.742028)
			(xy 52.751465 -90.773646) (xy 52.753331 -90.805821) (xy 52.763198 -90.836503) (xy 52.780436 -90.863736)
			(xy 52.791868 -90.875104) (xy 52.811312 -90.893958) (xy 52.845297 -90.936124) (xy 52.872976 -90.982673)
			(xy 52.893793 -91.03267) (xy 52.907328 -91.085108) (xy 52.91331 -91.138934) (xy 52.911619 -91.193065)
			(xy 52.902287 -91.246412) (xy 52.885504 -91.297902) (xy 52.861606 -91.346502) (xy 52.846732 -91.369134)
			(xy 52.833847 -91.388923) (xy 52.814904 -91.432175) (xy 52.80427 -91.478179) (xy 52.802309 -91.525356)
			(xy 52.809089 -91.572085) (xy 52.824378 -91.616759) (xy 52.847649 -91.657844) (xy 52.86248 -91.67622)
			(xy 52.879796 -91.697402) (xy 52.908794 -91.743797) (xy 52.930868 -91.793858) (xy 52.945567 -91.846558)
			(xy 52.952588 -91.900817) (xy 52.951789 -91.955522) (xy 52.943184 -92.009553) (xy 52.926952 -92.061801)
			(xy 52.903424 -92.111195) (xy 52.873084 -92.156723) (xy 52.836552 -92.197451) (xy 52.794578 -92.232544)
			(xy 52.748022 -92.261283) (xy 52.69784 -92.283078) (xy 52.645059 -92.297484) (xy 52.590762 -92.304203)
			(xy 52.536061 -92.3031) (xy 52.482079 -92.294195) (xy 52.429922 -92.277673) (xy 52.38066 -92.253871)
			(xy 52.335302 -92.223277) (xy 52.294777 -92.186519) (xy 52.259918 -92.144351) (xy 52.231439 -92.097636)
			(xy 52.209922 -92.047333) (xy 52.195811 -91.994473) (xy 52.189393 -91.940139) (xy 52.190801 -91.885446)
			(xy 52.200006 -91.831514) (xy 52.216818 -91.77945) (xy 52.240894 -91.730321) (xy 52.255928 -91.707462)
			(xy 52.268811 -91.687672) (xy 52.287749 -91.64442) (xy 52.29838 -91.598416) (xy 52.300339 -91.551241)
			(xy 52.29356 -91.504513) (xy 52.278275 -91.45984) (xy 52.255008 -91.418754) (xy 52.24018 -91.400376)
			(xy 52.223249 -91.37956) (xy 52.19469 -91.334137) (xy 52.172777 -91.285162) (xy 52.15794 -91.233599)
			(xy 52.150474 -91.180467) (xy 52.150525 -91.126812) (xy 52.158091 -91.073694) (xy 52.173025 -91.022159)
			(xy 52.195032 -90.973225) (xy 52.223676 -90.927857) (xy 52.240688 -90.907108) (xy 52.250747 -90.894506)
			(xy 52.264717 -90.865453) (xy 52.270964 -90.833827) (xy 52.269089 -90.801645) (xy 52.259213 -90.770958)
			(xy 52.241965 -90.743724) (xy 52.230528 -90.732356) (xy 52.211326 -90.713786) (xy 52.177757 -90.672235)
			(xy 52.150311 -90.626408) (xy 52.129525 -90.577201) (xy 52.115805 -90.525576) (xy 52.10942 -90.472542)
			(xy 50.415444 -90.472542) (xy 50.415444 -92.182442) (xy 48.83404 -93.763846) (xy 48.83404 -94.577172)
			(xy 49.254917 -94.577172) (xy 49.261017 -94.521735) (xy 49.275123 -94.467778) (xy 49.296935 -94.416449)
			(xy 49.325989 -94.368843) (xy 49.361664 -94.325975) (xy 49.403201 -94.288758) (xy 49.449714 -94.257985)
			(xy 49.500211 -94.234313) (xy 49.553618 -94.218245) (xy 49.608794 -94.210125) (xy 49.63668 -94.209616)
			(xy 49.664566 -94.210125) (xy 49.719742 -94.218245) (xy 49.773149 -94.234313) (xy 49.823646 -94.257985)
			(xy 49.870159 -94.288758) (xy 49.911696 -94.325975) (xy 49.947371 -94.368843) (xy 49.976425 -94.416449)
			(xy 49.998237 -94.467778) (xy 50.012343 -94.521735) (xy 50.018443 -94.577172) (xy 50.016406 -94.632906)
			(xy 50.006276 -94.687749) (xy 49.988269 -94.740533) (xy 49.962768 -94.790133) (xy 49.930317 -94.835491)
			(xy 49.891608 -94.87564) (xy 49.847465 -94.909726) (xy 49.79883 -94.937022) (xy 49.746739 -94.956945)
			(xy 49.692302 -94.969071) (xy 49.63668 -94.973142) (xy 49.581058 -94.969071) (xy 49.526621 -94.956945)
			(xy 49.47453 -94.937022) (xy 49.425895 -94.909726) (xy 49.381752 -94.87564) (xy 49.343043 -94.835491)
			(xy 49.310592 -94.790133) (xy 49.285091 -94.740533) (xy 49.267084 -94.687749) (xy 49.256954 -94.632906)
			(xy 49.254917 -94.577172) (xy 48.83404 -94.577172) (xy 48.83404 -95.390716) (xy 48.834564 -95.406923)
			(xy 48.842804 -95.438274) (xy 48.858672 -95.466542) (xy 48.881145 -95.489903) (xy 48.908777 -95.506853)
			(xy 48.939786 -95.516301) (xy 48.95596 -95.517462) (xy 48.983757 -95.519058) (xy 49.038483 -95.529305)
			(xy 49.091139 -95.547396) (xy 49.140606 -95.572949) (xy 49.185833 -95.605421) (xy 49.225861 -95.644121)
			(xy 49.259838 -95.688229) (xy 49.268197 -95.703154) (xy 49.894489 -95.703154) (xy 49.900589 -95.647717)
			(xy 49.914695 -95.59376) (xy 49.936507 -95.542431) (xy 49.965561 -95.494825) (xy 50.001236 -95.451957)
			(xy 50.042773 -95.41474) (xy 50.089286 -95.383967) (xy 50.139783 -95.360295) (xy 50.19319 -95.344227)
			(xy 50.248366 -95.336107) (xy 50.276252 -95.335598) (xy 50.304138 -95.336107) (xy 50.359314 -95.344227)
			(xy 50.412721 -95.360295) (xy 50.463218 -95.383967) (xy 50.509731 -95.41474) (xy 50.551268 -95.451957)
			(xy 50.586943 -95.494825) (xy 50.615997 -95.542431) (xy 50.637809 -95.59376) (xy 50.651915 -95.647717)
			(xy 50.658015 -95.703154) (xy 50.657244 -95.724236) (xy 51.135279 -95.724236) (xy 51.141379 -95.668799)
			(xy 51.155485 -95.614842) (xy 51.177297 -95.563513) (xy 51.206351 -95.515907) (xy 51.242026 -95.473039)
			(xy 51.283563 -95.435822) (xy 51.330076 -95.405049) (xy 51.380573 -95.381377) (xy 51.43398 -95.365309)
			(xy 51.489156 -95.357189) (xy 51.517042 -95.35668) (xy 51.544928 -95.357189) (xy 51.600104 -95.365309)
			(xy 51.653511 -95.381377) (xy 51.704008 -95.405049) (xy 51.750521 -95.435822) (xy 51.792058 -95.473039)
			(xy 51.827733 -95.515907) (xy 51.856787 -95.563513) (xy 51.878599 -95.614842) (xy 51.892705 -95.668799)
			(xy 51.898805 -95.724236) (xy 51.896768 -95.77997) (xy 51.886638 -95.834813) (xy 51.868631 -95.887597)
			(xy 51.84313 -95.937197) (xy 51.810679 -95.982555) (xy 51.77197 -96.022704) (xy 51.727827 -96.05679)
			(xy 51.679192 -96.084086) (xy 51.627101 -96.104009) (xy 51.572664 -96.116135) (xy 51.517042 -96.120206)
			(xy 51.46142 -96.116135) (xy 51.406983 -96.104009) (xy 51.354892 -96.084086) (xy 51.306257 -96.05679)
			(xy 51.262114 -96.022704) (xy 51.223405 -95.982555) (xy 51.190954 -95.937197) (xy 51.165453 -95.887597)
			(xy 51.147446 -95.834813) (xy 51.137316 -95.77997) (xy 51.135279 -95.724236) (xy 50.657244 -95.724236)
			(xy 50.655978 -95.758888) (xy 50.645848 -95.813731) (xy 50.627841 -95.866515) (xy 50.60234 -95.916115)
			(xy 50.569889 -95.961473) (xy 50.53118 -96.001622) (xy 50.487037 -96.035708) (xy 50.438402 -96.063004)
			(xy 50.386311 -96.082927) (xy 50.331874 -96.095053) (xy 50.276252 -96.099124) (xy 50.22063 -96.095053)
			(xy 50.166193 -96.082927) (xy 50.114102 -96.063004) (xy 50.065467 -96.035708) (xy 50.021324 -96.001622)
			(xy 49.982615 -95.961473) (xy 49.950164 -95.916115) (xy 49.924663 -95.866515) (xy 49.906656 -95.813731)
			(xy 49.896526 -95.758888) (xy 49.894489 -95.703154) (xy 49.268197 -95.703154) (xy 49.287044 -95.736806)
			(xy 49.3069 -95.788822) (xy 49.318985 -95.843172) (xy 49.323042 -95.898701) (xy 49.318985 -95.95423)
			(xy 49.3069 -96.008579) (xy 49.287043 -96.060595) (xy 49.259838 -96.109172) (xy 49.22586 -96.15328)
			(xy 49.185832 -96.19198) (xy 49.140605 -96.224451) (xy 49.091138 -96.250004) (xy 49.038482 -96.268096)
			(xy 48.983756 -96.278342) (xy 48.95596 -96.27997) (xy 48.939778 -96.281101) (xy 48.90875 -96.290523)
			(xy 48.881102 -96.307468) (xy 48.858624 -96.330841) (xy 48.842771 -96.35913) (xy 48.834568 -96.390503)
			(xy 48.83404 -96.406716) (xy 48.83404 -96.749362) (xy 48.834474 -96.771005) (xy 48.841808 -96.813666)
			(xy 48.856269 -96.854465) (xy 48.87744 -96.892221) (xy 48.904706 -96.92584) (xy 48.937277 -96.954349)
			(xy 48.974212 -96.976922) (xy 49.014439 -96.992905) (xy 49.056794 -97.001836) (xy 49.10005 -97.003455)
			(xy 49.121568 -97.001076) (xy 49.148482 -96.997973) (xy 49.202656 -96.998494) (xy 49.256211 -97.006673)
			(xy 49.308071 -97.022346) (xy 49.357193 -97.045196) (xy 49.402589 -97.074765) (xy 49.443345 -97.110457)
			(xy 49.478644 -97.151556) (xy 49.507774 -97.197234) (xy 49.53015 -97.246574) (xy 49.545322 -97.298583)
			(xy 49.552984 -97.352214) (xy 49.552984 -97.406391) (xy 49.545321 -97.460022) (xy 49.530148 -97.51203)
			(xy 49.507771 -97.56137) (xy 49.478641 -97.607048) (xy 49.443342 -97.648146) (xy 49.402585 -97.683838)
			(xy 49.357189 -97.713406) (xy 49.308067 -97.736256) (xy 49.256207 -97.751928) (xy 49.202651 -97.760106)
			(xy 49.148477 -97.760627) (xy 49.121568 -97.757488) (xy 49.100059 -97.75507) (xy 49.056811 -97.756719)
			(xy 49.014468 -97.765672) (xy 48.974254 -97.781671) (xy 48.937332 -97.804251) (xy 48.90477 -97.832761)
			(xy 48.894734 -97.845136) (xy 51.403757 -97.845136) (xy 51.409857 -97.789699) (xy 51.423963 -97.735742)
			(xy 51.445775 -97.684413) (xy 51.474829 -97.636807) (xy 51.510504 -97.593939) (xy 51.552041 -97.556722)
			(xy 51.598554 -97.525949) (xy 51.649051 -97.502277) (xy 51.702458 -97.486209) (xy 51.757634 -97.478089)
			(xy 51.78552 -97.47758) (xy 51.813406 -97.478089) (xy 51.868582 -97.486209) (xy 51.921989 -97.502277)
			(xy 51.972486 -97.525949) (xy 52.018999 -97.556722) (xy 52.060536 -97.593939) (xy 52.096211 -97.636807)
			(xy 52.125265 -97.684413) (xy 52.147077 -97.735742) (xy 52.161183 -97.789699) (xy 52.167283 -97.845136)
			(xy 52.165246 -97.90087) (xy 52.155116 -97.955713) (xy 52.137109 -98.008497) (xy 52.111608 -98.058097)
			(xy 52.079157 -98.103455) (xy 52.040448 -98.143604) (xy 51.996305 -98.17769) (xy 51.94767 -98.204986)
			(xy 51.895579 -98.224909) (xy 51.841142 -98.237035) (xy 51.78552 -98.241106) (xy 51.729898 -98.237035)
			(xy 51.675461 -98.224909) (xy 51.62337 -98.204986) (xy 51.574735 -98.17769) (xy 51.530592 -98.143604)
			(xy 51.491883 -98.103455) (xy 51.459432 -98.058097) (xy 51.433931 -98.008497) (xy 51.415924 -97.955713)
			(xy 51.405794 -97.90087) (xy 51.403757 -97.845136) (xy 48.894734 -97.845136) (xy 48.877509 -97.866375)
			(xy 48.856338 -97.904123) (xy 48.841868 -97.944912) (xy 48.834519 -97.987562) (xy 48.83404 -98.009202)
			(xy 48.83404 -98.542094) (xy 48.834553 -98.564841) (xy 48.842667 -98.609605) (xy 48.858619 -98.652211)
			(xy 48.8819 -98.691296) (xy 48.911766 -98.725614) (xy 48.947264 -98.754068) (xy 48.987259 -98.775749)
			(xy 49.030475 -98.789966) (xy 49.075531 -98.796263) (xy 49.120988 -98.79444) (xy 49.165395 -98.784556)
			(xy 49.186592 -98.776282) (xy 49.212442 -98.765939) (xy 49.266346 -98.75201) (xy 49.321703 -98.746065)
			(xy 49.377335 -98.748231) (xy 49.432062 -98.758462) (xy 49.484721 -98.776539) (xy 49.534191 -98.80208)
			(xy 49.579424 -98.834542) (xy 49.619456 -98.873234) (xy 49.653439 -98.917335) (xy 49.680649 -98.965907)
			(xy 49.700509 -99.017919) (xy 49.712597 -99.072266) (xy 49.7138 -99.08872) (xy 50.529743 -99.08872)
			(xy 50.535843 -99.033283) (xy 50.549949 -98.979326) (xy 50.571761 -98.927997) (xy 50.600815 -98.880391)
			(xy 50.63649 -98.837523) (xy 50.678027 -98.800306) (xy 50.72454 -98.769533) (xy 50.775037 -98.745861)
			(xy 50.828444 -98.729793) (xy 50.88362 -98.721673) (xy 50.911506 -98.721164) (xy 50.939392 -98.721673)
			(xy 50.994568 -98.729793) (xy 51.047975 -98.745861) (xy 51.098472 -98.769533) (xy 51.144985 -98.800306)
			(xy 51.186522 -98.837523) (xy 51.222197 -98.880391) (xy 51.251251 -98.927997) (xy 51.273063 -98.979326)
			(xy 51.287169 -99.033283) (xy 51.293269 -99.08872) (xy 51.291232 -99.144454) (xy 51.281102 -99.199297)
			(xy 51.263095 -99.252081) (xy 51.237594 -99.301681) (xy 51.205143 -99.347039) (xy 51.166434 -99.387188)
			(xy 51.122291 -99.421274) (xy 51.073656 -99.44857) (xy 51.021565 -99.468493) (xy 50.967128 -99.480619)
			(xy 50.911506 -99.48469) (xy 50.855884 -99.480619) (xy 50.801447 -99.468493) (xy 50.749356 -99.44857)
			(xy 50.700721 -99.421274) (xy 50.656578 -99.387188) (xy 50.617869 -99.347039) (xy 50.585418 -99.301681)
			(xy 50.559917 -99.252081) (xy 50.54191 -99.199297) (xy 50.53178 -99.144454) (xy 50.529743 -99.08872)
			(xy 49.7138 -99.08872) (xy 49.716656 -99.127793) (xy 49.712599 -99.18332) (xy 49.700513 -99.237667)
			(xy 49.680655 -99.28968) (xy 49.653447 -99.338254) (xy 49.619466 -99.382356) (xy 49.579434 -99.421049)
			(xy 49.534203 -99.453512) (xy 49.484734 -99.479055) (xy 49.432076 -99.497135) (xy 49.377349 -99.507367)
			(xy 49.321717 -99.509535) (xy 49.26636 -99.503592) (xy 49.212455 -99.489665) (xy 49.186592 -99.479354)
			(xy 49.165423 -99.470986) (xy 49.121001 -99.461071) (xy 49.075524 -99.459228) (xy 49.030445 -99.465516)
			(xy 48.987208 -99.479734) (xy 48.947195 -99.501426) (xy 48.911686 -99.5299) (xy 48.881818 -99.564243)
			(xy 48.858545 -99.603358) (xy 48.842612 -99.645993) (xy 48.834529 -99.690784) (xy 48.83404 -99.713542)
			(xy 48.83404 -100.117402) (xy 48.834561 -100.140663) (xy 48.843026 -100.186408) (xy 48.859674 -100.229849)
			(xy 48.883949 -100.269536) (xy 48.915039 -100.304144) (xy 48.951908 -100.332516) (xy 48.993323 -100.353706)
			(xy 49.037904 -100.367007) (xy 49.08416 -100.371974) (xy 49.130547 -100.368441) (xy 49.175518 -100.356526)
			(xy 49.196752 -100.347018) (xy 49.221754 -100.335725) (xy 49.274198 -100.319623) (xy 49.328408 -100.3112)
			(xy 49.383265 -100.31063) (xy 49.437639 -100.317923) (xy 49.490407 -100.33293) (xy 49.540481 -100.355341)
			(xy 49.586828 -100.384693) (xy 49.628493 -100.420382) (xy 49.664616 -100.461672) (xy 49.694451 -100.507709)
			(xy 49.717385 -100.557546) (xy 49.732942 -100.610154) (xy 49.740804 -100.664449) (xy 49.740805 -100.677998)
			(xy 50.542189 -100.677998) (xy 50.548289 -100.622561) (xy 50.562395 -100.568604) (xy 50.584207 -100.517275)
			(xy 50.613261 -100.469669) (xy 50.648936 -100.426801) (xy 50.690473 -100.389584) (xy 50.736986 -100.358811)
			(xy 50.787483 -100.335139) (xy 50.84089 -100.319071) (xy 50.896066 -100.310951) (xy 50.923952 -100.310442)
			(xy 50.951838 -100.310951) (xy 51.007014 -100.319071) (xy 51.060421 -100.335139) (xy 51.110918 -100.358811)
			(xy 51.157431 -100.389584) (xy 51.198968 -100.426801) (xy 51.234643 -100.469669) (xy 51.263697 -100.517275)
			(xy 51.285509 -100.568604) (xy 51.299615 -100.622561) (xy 51.305715 -100.677998) (xy 51.303678 -100.733732)
			(xy 51.293548 -100.788575) (xy 51.275541 -100.841359) (xy 51.25004 -100.890959) (xy 51.217589 -100.936317)
			(xy 51.17888 -100.976466) (xy 51.134737 -101.010552) (xy 51.086102 -101.037848) (xy 51.034011 -101.057771)
			(xy 50.979574 -101.069897) (xy 50.923952 -101.073968) (xy 50.86833 -101.069897) (xy 50.813893 -101.057771)
			(xy 50.761802 -101.037848) (xy 50.713167 -101.010552) (xy 50.669024 -100.976466) (xy 50.630315 -100.936317)
			(xy 50.597864 -100.890959) (xy 50.572363 -100.841359) (xy 50.554356 -100.788575) (xy 50.544226 -100.733732)
			(xy 50.542189 -100.677998) (xy 49.740805 -100.677998) (xy 49.740807 -100.719309) (xy 49.732952 -100.773604)
			(xy 49.7174 -100.826214) (xy 49.694472 -100.876053) (xy 49.664641 -100.922094) (xy 49.628523 -100.963388)
			(xy 49.586862 -100.999081) (xy 49.540518 -101.028439) (xy 49.490447 -101.050855) (xy 49.437681 -101.065868)
			(xy 49.383308 -101.073168) (xy 49.328451 -101.072603) (xy 49.27424 -101.064186) (xy 49.221794 -101.048091)
			(xy 49.196752 -101.036882) (xy 49.175505 -101.027392) (xy 49.130534 -101.015456) (xy 49.084141 -101.011906)
			(xy 49.037877 -101.016861) (xy 48.993289 -101.030155) (xy 48.951865 -101.051343) (xy 48.914991 -101.079719)
			(xy 48.883898 -101.114333) (xy 48.859626 -101.154029) (xy 48.842986 -101.197479) (xy 48.834533 -101.243234)
			(xy 48.83404 -101.266498) (xy 48.83404 -101.844094) (xy 48.834515 -101.860297) (xy 48.84267 -101.89166)
			(xy 48.85848 -101.919947) (xy 48.880919 -101.943327) (xy 48.908534 -101.960283) (xy 48.939535 -101.969719)
			(xy 48.955706 -101.97084) (xy 48.981579 -101.972356) (xy 49.032591 -101.981512) (xy 49.081893 -101.997493)
			(xy 49.128575 -102.020006) (xy 49.171778 -102.048634) (xy 49.210705 -102.08285) (xy 49.227994 -102.102158)
			(xy 49.243238 -102.118987) (xy 49.278588 -102.147475) (xy 49.318435 -102.169235) (xy 49.361512 -102.183575)
			(xy 49.406451 -102.190038) (xy 49.451823 -102.188421) (xy 49.496188 -102.178774) (xy 49.538135 -102.161404)
			(xy 49.576331 -102.136862) (xy 49.593246 -102.121716) (xy 49.613663 -102.103338) (xy 49.6588 -102.072032)
			(xy 49.70796 -102.047522) (xy 49.760127 -102.030317) (xy 49.814222 -102.02077) (xy 49.869128 -102.01908)
			(xy 49.923708 -102.025281) (xy 49.976834 -102.039245) (xy 50.027409 -102.060684) (xy 50.074387 -102.089155)
			(xy 50.116796 -102.124068) (xy 50.153759 -102.164702) (xy 50.184513 -102.210217) (xy 50.208422 -102.259672)
			(xy 50.224992 -102.312045) (xy 50.233879 -102.366253) (xy 50.234901 -102.421174) (xy 50.234706 -102.422724)
			(xy 50.740055 -102.422724) (xy 50.746155 -102.367287) (xy 50.760261 -102.31333) (xy 50.782073 -102.262001)
			(xy 50.811127 -102.214395) (xy 50.846802 -102.171527) (xy 50.888339 -102.13431) (xy 50.934852 -102.103537)
			(xy 50.985349 -102.079865) (xy 51.038756 -102.063797) (xy 51.093932 -102.055677) (xy 51.121818 -102.055168)
			(xy 51.149704 -102.055677) (xy 51.20488 -102.063797) (xy 51.258287 -102.079865) (xy 51.308784 -102.103537)
			(xy 51.355297 -102.13431) (xy 51.396834 -102.171527) (xy 51.432509 -102.214395) (xy 51.461563 -102.262001)
			(xy 51.483375 -102.31333) (xy 51.497481 -102.367287) (xy 51.503581 -102.422724) (xy 51.501544 -102.478458)
			(xy 51.491414 -102.533301) (xy 51.473407 -102.586085) (xy 51.447906 -102.635685) (xy 51.415455 -102.681043)
			(xy 51.376746 -102.721192) (xy 51.332603 -102.755278) (xy 51.283968 -102.782574) (xy 51.231877 -102.802497)
			(xy 51.17744 -102.814623) (xy 51.121818 -102.818694) (xy 51.066196 -102.814623) (xy 51.011759 -102.802497)
			(xy 50.959668 -102.782574) (xy 50.911033 -102.755278) (xy 50.86689 -102.721192) (xy 50.828181 -102.681043)
			(xy 50.79573 -102.635685) (xy 50.770229 -102.586085) (xy 50.752222 -102.533301) (xy 50.742092 -102.478458)
			(xy 50.740055 -102.422724) (xy 50.234706 -102.422724) (xy 50.228035 -102.475675) (xy 50.213425 -102.528628)
			(xy 50.191372 -102.578938) (xy 50.162331 -102.625565) (xy 50.126904 -102.667545) (xy 50.085823 -102.704012)
			(xy 50.039937 -102.734209) (xy 49.990194 -102.757514) (xy 49.937624 -102.773445) (xy 49.883312 -102.781671)
			(xy 49.828382 -102.782024) (xy 49.773969 -102.774496) (xy 49.721198 -102.759242) (xy 49.67116 -102.736578)
			(xy 49.62489 -102.706972) (xy 49.583344 -102.671036) (xy 49.565052 -102.650544) (xy 49.549809 -102.63372)
			(xy 49.514459 -102.60524) (xy 49.474615 -102.583489) (xy 49.431542 -102.569158) (xy 49.386609 -102.562702)
			(xy 49.341244 -102.564326) (xy 49.296888 -102.573978) (xy 49.25495 -102.591352) (xy 49.216763 -102.615896)
			(xy 49.1998 -102.630986) (xy 49.179709 -102.649092) (xy 49.13536 -102.680045) (xy 49.08709 -102.704436)
			(xy 49.035863 -102.721777) (xy 48.982702 -102.731722) (xy 48.955706 -102.733348) (xy 48.939558 -102.73453)
			(xy 48.908611 -102.74402) (xy 48.881048 -102.760991) (xy 48.858641 -102.784351) (xy 48.842832 -102.812596)
			(xy 48.834638 -102.843911) (xy 48.83404 -102.860094) (xy 48.83404 -103.247698) (xy 51.019964 -105.433622)
			(xy 57.510172 -105.433622) (xy 57.539636 -105.463086) (xy 57.555856 -105.478639) (xy 57.592714 -105.504339)
			(xy 57.633521 -105.523148) (xy 57.677002 -105.534477) (xy 57.721799 -105.537973) (xy 57.766512 -105.533526)
			(xy 57.809743 -105.521276) (xy 57.850142 -105.501605) (xy 57.868566 -105.48874) (xy 57.890678 -105.473233)
			(xy 57.938393 -105.447937) (xy 57.989197 -105.429619) (xy 58.042077 -105.418645) (xy 58.095975 -105.415234)
			(xy 58.149816 -105.419455) (xy 58.202524 -105.431223) (xy 58.253047 -105.450304) (xy 58.300376 -105.476315)
			(xy 58.343566 -105.508738) (xy 58.381755 -105.546926) (xy 58.414179 -105.590115) (xy 58.440192 -105.637443)
			(xy 58.459274 -105.687966) (xy 58.471043 -105.740674) (xy 58.475266 -105.794515) (xy 58.471857 -105.848413)
			(xy 58.460884 -105.901293) (xy 58.442568 -105.952098) (xy 58.417272 -105.999813) (xy 58.401712 -106.021886)
			(xy 58.388893 -106.040331) (xy 58.369274 -106.080733) (xy 58.357061 -106.123954) (xy 58.352634 -106.168648)
			(xy 58.356129 -106.213425) (xy 58.367439 -106.256891) (xy 58.386212 -106.297693) (xy 58.411863 -106.334562)
			(xy 58.427366 -106.350816) (xy 58.640128 -106.563578) (xy 61.644239 -106.563578) (xy 61.650892 -106.507904)
			(xy 61.665625 -106.453805) (xy 61.688119 -106.402446) (xy 61.71789 -106.354933) (xy 61.735716 -106.33329)
			(xy 61.745107 -106.321591) (xy 61.758741 -106.294881) (xy 61.765755 -106.265725) (xy 61.765762 -106.235736)
			(xy 61.758762 -106.206576) (xy 61.745141 -106.179859) (xy 61.735716 -106.16819) (xy 61.71789 -106.146547)
			(xy 61.688119 -106.099034) (xy 61.665625 -106.047675) (xy 61.650892 -105.993576) (xy 61.644239 -105.937902)
			(xy 61.645808 -105.881855) (xy 61.655566 -105.826641) (xy 61.673303 -105.773451) (xy 61.698636 -105.723431)
			(xy 61.731019 -105.677659) (xy 61.769754 -105.63712) (xy 61.814007 -105.60269) (xy 61.862824 -105.57511)
			(xy 61.915153 -105.554974) (xy 61.969866 -105.542716) (xy 62.025784 -105.5386) (xy 62.081702 -105.542716)
			(xy 62.136415 -105.554974) (xy 62.188744 -105.57511) (xy 62.237561 -105.60269) (xy 62.281814 -105.63712)
			(xy 62.320549 -105.677659) (xy 62.352932 -105.723431) (xy 62.378265 -105.773451) (xy 62.396002 -105.826641)
			(xy 62.40576 -105.881855) (xy 62.407329 -105.937902) (xy 62.400676 -105.993576) (xy 62.385943 -106.047675)
			(xy 62.363449 -106.099034) (xy 62.333678 -106.146547) (xy 62.315852 -106.16819) (xy 62.306386 -106.179831)
			(xy 62.292763 -106.206559) (xy 62.285762 -106.235731) (xy 62.285769 -106.26573) (xy 62.292784 -106.294898)
			(xy 62.30642 -106.321619) (xy 62.315852 -106.33329) (xy 62.333678 -106.354933) (xy 62.363449 -106.402446)
			(xy 62.385943 -106.453805) (xy 62.400676 -106.507904) (xy 62.407329 -106.563578) (xy 62.40576 -106.619625)
			(xy 62.396002 -106.674839) (xy 62.378265 -106.728029) (xy 62.352932 -106.778049) (xy 62.320549 -106.823821)
			(xy 62.281814 -106.86436) (xy 62.237561 -106.89879) (xy 62.188744 -106.92637) (xy 62.136415 -106.946506)
			(xy 62.081702 -106.958764) (xy 62.025784 -106.96288) (xy 61.969866 -106.958764) (xy 61.915153 -106.946506)
			(xy 61.862824 -106.92637) (xy 61.814007 -106.89879) (xy 61.769754 -106.86436) (xy 61.731019 -106.823821)
			(xy 61.698636 -106.778049) (xy 61.673303 -106.728029) (xy 61.655566 -106.674839) (xy 61.645808 -106.619625)
			(xy 61.644239 -106.563578) (xy 58.640128 -106.563578) (xy 60.672128 -108.595578) (xy 61.644239 -108.595578)
			(xy 61.650892 -108.539904) (xy 61.665625 -108.485805) (xy 61.688119 -108.434446) (xy 61.71789 -108.386933)
			(xy 61.735716 -108.36529) (xy 61.745107 -108.353591) (xy 61.758741 -108.326881) (xy 61.765755 -108.297725)
			(xy 61.765762 -108.267736) (xy 61.758762 -108.238576) (xy 61.745141 -108.211859) (xy 61.735716 -108.20019)
			(xy 61.71789 -108.178547) (xy 61.688119 -108.131034) (xy 61.665625 -108.079675) (xy 61.650892 -108.025576)
			(xy 61.644239 -107.969902) (xy 61.645808 -107.913855) (xy 61.655566 -107.858641) (xy 61.673303 -107.805451)
			(xy 61.698636 -107.755431) (xy 61.731019 -107.709659) (xy 61.769754 -107.66912) (xy 61.814007 -107.63469)
			(xy 61.862824 -107.60711) (xy 61.915153 -107.586974) (xy 61.969866 -107.574716) (xy 62.025784 -107.5706)
			(xy 62.081702 -107.574716) (xy 62.136415 -107.586974) (xy 62.188744 -107.60711) (xy 62.237561 -107.63469)
			(xy 62.281814 -107.66912) (xy 62.320549 -107.709659) (xy 62.352932 -107.755431) (xy 62.378265 -107.805451)
			(xy 62.396002 -107.858641) (xy 62.40576 -107.913855) (xy 62.407329 -107.969902) (xy 62.400676 -108.025576)
			(xy 62.385943 -108.079675) (xy 62.363449 -108.131034) (xy 62.333678 -108.178547) (xy 62.315852 -108.20019)
			(xy 62.306386 -108.211831) (xy 62.292763 -108.238559) (xy 62.285762 -108.267731) (xy 62.285769 -108.29773)
			(xy 62.292784 -108.326898) (xy 62.30642 -108.353619) (xy 62.315852 -108.36529) (xy 62.333678 -108.386933)
			(xy 62.363449 -108.434446) (xy 62.369657 -108.44862) (xy 64.340739 -108.44862) (xy 64.346839 -108.393183)
			(xy 64.360945 -108.339226) (xy 64.382757 -108.287897) (xy 64.411811 -108.240291) (xy 64.447486 -108.197423)
			(xy 64.489023 -108.160206) (xy 64.535536 -108.129433) (xy 64.586033 -108.105761) (xy 64.63944 -108.089693)
			(xy 64.694616 -108.081573) (xy 64.722502 -108.081064) (xy 64.750388 -108.081573) (xy 64.805564 -108.089693)
			(xy 64.858971 -108.105761) (xy 64.909468 -108.129433) (xy 64.955981 -108.160206) (xy 64.997518 -108.197423)
			(xy 65.033193 -108.240291) (xy 65.062247 -108.287897) (xy 65.084059 -108.339226) (xy 65.098165 -108.393183)
			(xy 65.104265 -108.44862) (xy 65.102228 -108.504354) (xy 65.092098 -108.559197) (xy 65.074091 -108.611981)
			(xy 65.04859 -108.661581) (xy 65.016139 -108.706939) (xy 64.97743 -108.747088) (xy 64.933287 -108.781174)
			(xy 64.884652 -108.80847) (xy 64.832561 -108.828393) (xy 64.778124 -108.840519) (xy 64.722502 -108.84459)
			(xy 64.66688 -108.840519) (xy 64.612443 -108.828393) (xy 64.560352 -108.80847) (xy 64.511717 -108.781174)
			(xy 64.467574 -108.747088) (xy 64.428865 -108.706939) (xy 64.396414 -108.661581) (xy 64.370913 -108.611981)
			(xy 64.352906 -108.559197) (xy 64.342776 -108.504354) (xy 64.340739 -108.44862) (xy 62.369657 -108.44862)
			(xy 62.385943 -108.485805) (xy 62.400676 -108.539904) (xy 62.407329 -108.595578) (xy 62.40576 -108.651625)
			(xy 62.396002 -108.706839) (xy 62.378265 -108.760029) (xy 62.352932 -108.810049) (xy 62.320549 -108.855821)
			(xy 62.281814 -108.89636) (xy 62.237561 -108.93079) (xy 62.188744 -108.95837) (xy 62.136415 -108.978506)
			(xy 62.081702 -108.990764) (xy 62.025784 -108.99488) (xy 61.969866 -108.990764) (xy 61.915153 -108.978506)
			(xy 61.862824 -108.95837) (xy 61.814007 -108.93079) (xy 61.769754 -108.89636) (xy 61.731019 -108.855821)
			(xy 61.698636 -108.810049) (xy 61.673303 -108.760029) (xy 61.655566 -108.706839) (xy 61.645808 -108.651625)
			(xy 61.644239 -108.595578) (xy 60.672128 -108.595578) (xy 61.70041 -109.62386) (xy 61.712151 -109.634898)
			(xy 61.739936 -109.651204) (xy 61.77092 -109.66003) (xy 61.803126 -109.660813) (xy 61.834502 -109.653504)
			(xy 61.849 -109.646466) (xy 61.874455 -109.633746) (xy 61.928237 -109.615156) (xy 61.984183 -109.604761)
			(xy 62.041052 -109.602792) (xy 62.097583 -109.609292) (xy 62.152521 -109.624118) (xy 62.204648 -109.646939)
			(xy 62.252806 -109.677251) (xy 62.295927 -109.71438) (xy 62.333055 -109.757502) (xy 62.363365 -109.805661)
			(xy 62.386186 -109.857788) (xy 62.40101 -109.912727) (xy 62.407509 -109.969258) (xy 62.405538 -110.026128)
			(xy 62.395142 -110.082073) (xy 62.37655 -110.135854) (xy 62.363858 -110.161324) (xy 62.344554 -110.198408)
			(xy 62.357 -110.28045) (xy 64.660036 -112.583486) (xy 67.391025 -112.583486) (xy 67.397125 -112.528049)
			(xy 67.411231 -112.474092) (xy 67.433043 -112.422763) (xy 67.462097 -112.375157) (xy 67.497772 -112.332289)
			(xy 67.539309 -112.295072) (xy 67.585822 -112.264299) (xy 67.636319 -112.240627) (xy 67.689726 -112.224559)
			(xy 67.744902 -112.216439) (xy 67.772788 -112.21593) (xy 67.800674 -112.216439) (xy 67.85585 -112.224559)
			(xy 67.909257 -112.240627) (xy 67.959754 -112.264299) (xy 68.006267 -112.295072) (xy 68.047804 -112.332289)
			(xy 68.083479 -112.375157) (xy 68.112533 -112.422763) (xy 68.134345 -112.474092) (xy 68.148451 -112.528049)
			(xy 68.154551 -112.583486) (xy 68.152514 -112.63922) (xy 68.142384 -112.694063) (xy 68.124377 -112.746847)
			(xy 68.098876 -112.796447) (xy 68.066425 -112.841805) (xy 68.027716 -112.881954) (xy 67.983573 -112.91604)
			(xy 67.934938 -112.943336) (xy 67.882847 -112.963259) (xy 67.82841 -112.975385) (xy 67.772788 -112.979456)
			(xy 67.717166 -112.975385) (xy 67.662729 -112.963259) (xy 67.610638 -112.943336) (xy 67.562003 -112.91604)
			(xy 67.51786 -112.881954) (xy 67.479151 -112.841805) (xy 67.4467 -112.796447) (xy 67.421199 -112.746847)
			(xy 67.403192 -112.694063) (xy 67.393062 -112.63922) (xy 67.391025 -112.583486) (xy 64.660036 -112.583486)
			(xy 65.02654 -112.94999) (xy 65.02654 -113.36401) (xy 66.3702 -114.70767) (xy 73.851008 -114.70767)
			(xy 73.869296 -114.689636) (xy 74.81062 -115.63096) (xy 75.787758 -115.63096) (xy 76.146932 -115.990134)
			(xy 81.242915 -115.990134) (xy 81.249015 -115.934697) (xy 81.263121 -115.88074) (xy 81.284933 -115.829411)
			(xy 81.313987 -115.781805) (xy 81.349662 -115.738937) (xy 81.391199 -115.70172) (xy 81.437712 -115.670947)
			(xy 81.488209 -115.647275) (xy 81.541616 -115.631207) (xy 81.596792 -115.623087) (xy 81.624678 -115.622578)
			(xy 81.652564 -115.623087) (xy 81.70774 -115.631207) (xy 81.761147 -115.647275) (xy 81.811644 -115.670947)
			(xy 81.858157 -115.70172) (xy 81.899694 -115.738937) (xy 81.935369 -115.781805) (xy 81.964423 -115.829411)
			(xy 81.986235 -115.88074) (xy 82.000341 -115.934697) (xy 82.006441 -115.990134) (xy 82.004404 -116.045868)
			(xy 81.994274 -116.100711) (xy 81.976267 -116.153495) (xy 81.950766 -116.203095) (xy 81.918315 -116.248453)
			(xy 81.879606 -116.288602) (xy 81.835463 -116.322688) (xy 81.786828 -116.349984) (xy 81.734737 -116.369907)
			(xy 81.6803 -116.382033) (xy 81.624678 -116.386104) (xy 81.569056 -116.382033) (xy 81.514619 -116.369907)
			(xy 81.462528 -116.349984) (xy 81.413893 -116.322688) (xy 81.36975 -116.288602) (xy 81.331041 -116.248453)
			(xy 81.29859 -116.203095) (xy 81.273089 -116.153495) (xy 81.255082 -116.100711) (xy 81.244952 -116.045868)
			(xy 81.242915 -115.990134) (xy 76.146932 -115.990134) (xy 76.56957 -116.412772) (xy 76.591376 -116.435235)
			(xy 76.629897 -116.484586) (xy 76.662066 -116.538294) (xy 76.687397 -116.595546) (xy 76.705504 -116.655475)
			(xy 76.716115 -116.717175) (xy 76.719068 -116.77971) (xy 76.714319 -116.842135) (xy 76.70194 -116.903504)
			(xy 76.682118 -116.962889) (xy 76.655154 -117.019389) (xy 76.621455 -117.072151) (xy 76.601828 -117.09654)
			(xy 76.587264 -117.114954) (xy 76.564452 -117.155979) (xy 76.549564 -117.200496) (xy 76.543106 -117.246991)
			(xy 76.545299 -117.293881) (xy 76.556067 -117.33957) (xy 76.575045 -117.382504) (xy 76.601587 -117.421221)
			(xy 76.61783 -117.43817) (xy 77.738986 -118.559326) (xy 77.75096 -118.570615) (xy 77.779371 -118.5872)
			(xy 77.811083 -118.59595) (xy 77.843978 -118.596281) (xy 77.875859 -118.588171) (xy 77.904598 -118.572161)
			(xy 77.916786 -118.561104) (xy 77.936434 -118.542844) (xy 77.979924 -118.51145) (xy 78.027383 -118.486458)
			(xy 78.077876 -118.468359) (xy 78.130405 -118.457512) (xy 78.183936 -118.454129) (xy 78.237413 -118.458278)
			(xy 78.289781 -118.469877) (xy 78.340009 -118.488697) (xy 78.387105 -118.514367) (xy 78.430142 -118.54638)
			(xy 78.468269 -118.584107) (xy 78.500737 -118.626802) (xy 78.514194 -118.650004) (xy 78.52283 -118.665244)
			(xy 78.627979 -118.770418) (xy 80.126839 -118.770418) (xy 80.132939 -118.714981) (xy 80.147045 -118.661024)
			(xy 80.168857 -118.609695) (xy 80.197911 -118.562089) (xy 80.233586 -118.519221) (xy 80.275123 -118.482004)
			(xy 80.321636 -118.451231) (xy 80.372133 -118.427559) (xy 80.42554 -118.411491) (xy 80.480716 -118.403371)
			(xy 80.508602 -118.402862) (xy 80.536488 -118.403371) (xy 80.591664 -118.411491) (xy 80.645071 -118.427559)
			(xy 80.695568 -118.451231) (xy 80.742081 -118.482004) (xy 80.783618 -118.519221) (xy 80.819293 -118.562089)
			(xy 80.848347 -118.609695) (xy 80.857712 -118.631734) (xy 81.656681 -118.631734) (xy 81.662781 -118.576297)
			(xy 81.676887 -118.52234) (xy 81.698699 -118.471011) (xy 81.727753 -118.423405) (xy 81.763428 -118.380537)
			(xy 81.804965 -118.34332) (xy 81.851478 -118.312547) (xy 81.901975 -118.288875) (xy 81.955382 -118.272807)
			(xy 82.010558 -118.264687) (xy 82.038444 -118.264178) (xy 82.06633 -118.264687) (xy 82.121506 -118.272807)
			(xy 82.174913 -118.288875) (xy 82.22541 -118.312547) (xy 82.271923 -118.34332) (xy 82.31346 -118.380537)
			(xy 82.349135 -118.423405) (xy 82.378189 -118.471011) (xy 82.400001 -118.52234) (xy 82.414107 -118.576297)
			(xy 82.420207 -118.631734) (xy 82.41817 -118.687468) (xy 82.40804 -118.742311) (xy 82.390033 -118.795095)
			(xy 82.364532 -118.844695) (xy 82.332081 -118.890053) (xy 82.293372 -118.930202) (xy 82.249229 -118.964288)
			(xy 82.200594 -118.991584) (xy 82.148503 -119.011507) (xy 82.094066 -119.023633) (xy 82.038444 -119.027704)
			(xy 81.982822 -119.023633) (xy 81.928385 -119.011507) (xy 81.876294 -118.991584) (xy 81.827659 -118.964288)
			(xy 81.783516 -118.930202) (xy 81.744807 -118.890053) (xy 81.712356 -118.844695) (xy 81.686855 -118.795095)
			(xy 81.668848 -118.742311) (xy 81.658718 -118.687468) (xy 81.656681 -118.631734) (xy 80.857712 -118.631734)
			(xy 80.870159 -118.661024) (xy 80.884265 -118.714981) (xy 80.890365 -118.770418) (xy 80.888328 -118.826152)
			(xy 80.878198 -118.880995) (xy 80.860191 -118.933779) (xy 80.83469 -118.983379) (xy 80.802239 -119.028737)
			(xy 80.76353 -119.068886) (xy 80.719387 -119.102972) (xy 80.670752 -119.130268) (xy 80.618661 -119.150191)
			(xy 80.564224 -119.162317) (xy 80.508602 -119.166388) (xy 80.45298 -119.162317) (xy 80.398543 -119.150191)
			(xy 80.346452 -119.130268) (xy 80.297817 -119.102972) (xy 80.253674 -119.068886) (xy 80.214965 -119.028737)
			(xy 80.182514 -118.983379) (xy 80.157013 -118.933779) (xy 80.139006 -118.880995) (xy 80.128876 -118.826152)
			(xy 80.126839 -118.770418) (xy 78.627979 -118.770418) (xy 79.57312 -119.715788) (xy 79.588761 -119.730837)
			(xy 79.624194 -119.755899) (xy 79.663372 -119.774572) (xy 79.705155 -119.786311) (xy 79.748326 -119.790774)
			(xy 79.791626 -119.787833) (xy 79.833796 -119.777571) (xy 79.873608 -119.760288) (xy 79.9099 -119.736488)
			(xy 79.941617 -119.706863) (xy 79.955136 -119.68988) (xy 79.972431 -119.667917) (xy 80.012379 -119.628813)
			(xy 80.057605 -119.595957) (xy 80.107143 -119.570054) (xy 80.159931 -119.551658) (xy 80.214839 -119.541164)
			(xy 80.27069 -119.538797) (xy 80.326289 -119.544606) (xy 80.380445 -119.558468) (xy 80.431997 -119.580085)
			(xy 80.479842 -119.608996) (xy 80.522956 -119.64458) (xy 80.560414 -119.686075) (xy 80.591415 -119.732593)
			(xy 80.615294 -119.783137) (xy 80.631541 -119.836626) (xy 80.639807 -119.891913) (xy 80.639915 -119.947814)
			(xy 80.631863 -120.003133) (xy 80.61963 -120.043974) (xy 81.214721 -120.043974) (xy 81.220821 -119.988537)
			(xy 81.234927 -119.93458) (xy 81.256739 -119.883251) (xy 81.285793 -119.835645) (xy 81.321468 -119.792777)
			(xy 81.363005 -119.75556) (xy 81.409518 -119.724787) (xy 81.460015 -119.701115) (xy 81.513422 -119.685047)
			(xy 81.568598 -119.676927) (xy 81.596484 -119.676418) (xy 81.62437 -119.676927) (xy 81.679546 -119.685047)
			(xy 81.732953 -119.701115) (xy 81.78345 -119.724787) (xy 81.829963 -119.75556) (xy 81.8715 -119.792777)
			(xy 81.907175 -119.835645) (xy 81.936229 -119.883251) (xy 81.958041 -119.93458) (xy 81.972147 -119.988537)
			(xy 81.978247 -120.043974) (xy 81.97621 -120.099708) (xy 81.96608 -120.154551) (xy 81.948073 -120.207335)
			(xy 81.922572 -120.256935) (xy 81.890121 -120.302293) (xy 81.851412 -120.342442) (xy 81.807269 -120.376528)
			(xy 81.758634 -120.403824) (xy 81.706543 -120.423747) (xy 81.652106 -120.435873) (xy 81.596484 -120.439944)
			(xy 81.540862 -120.435873) (xy 81.486425 -120.423747) (xy 81.434334 -120.403824) (xy 81.385699 -120.376528)
			(xy 81.341556 -120.342442) (xy 81.302847 -120.302293) (xy 81.270396 -120.256935) (xy 81.244895 -120.207335)
			(xy 81.226888 -120.154551) (xy 81.216758 -120.099708) (xy 81.214721 -120.043974) (xy 80.61963 -120.043974)
			(xy 80.615823 -120.056683) (xy 80.592139 -120.10732) (xy 80.561319 -120.153957) (xy 80.524021 -120.195597)
			(xy 80.481046 -120.231348) (xy 80.433313 -120.260443) (xy 80.381844 -120.282259) (xy 80.354932 -120.289828)
			(xy 80.321658 -120.298464) (xy 80.227424 -120.392444) (xy 80.227424 -120.988582) (xy 80.227928 -121.011325)
			(xy 80.236025 -121.056084) (xy 80.251964 -121.098685) (xy 80.275235 -121.137767) (xy 80.305093 -121.17208)
			(xy 80.340585 -121.200527) (xy 80.380576 -121.222199) (xy 80.423787 -121.236402) (xy 80.468837 -121.242684)
			(xy 80.491584 -121.242328) (xy 80.519532 -121.241702) (xy 80.575116 -121.247646) (xy 80.629238 -121.261637)
			(xy 80.680739 -121.283374) (xy 80.728518 -121.312393) (xy 80.771551 -121.348073) (xy 80.808918 -121.389649)
			(xy 80.83982 -121.436233) (xy 80.863593 -121.486827) (xy 80.879731 -121.540348) (xy 80.887887 -121.59565)
			(xy 80.887887 -121.651551) (xy 80.879731 -121.706854) (xy 80.863593 -121.760375) (xy 80.839819 -121.810968)
			(xy 80.808917 -121.857552) (xy 80.77155 -121.899128) (xy 80.728517 -121.934808) (xy 80.721921 -121.938814)
			(xy 82.178397 -121.938814) (xy 82.184497 -121.883377) (xy 82.198603 -121.82942) (xy 82.220415 -121.778091)
			(xy 82.249469 -121.730485) (xy 82.285144 -121.687617) (xy 82.326681 -121.6504) (xy 82.373194 -121.619627)
			(xy 82.423691 -121.595955) (xy 82.477098 -121.579887) (xy 82.532274 -121.571767) (xy 82.56016 -121.571258)
			(xy 82.588046 -121.571767) (xy 82.643222 -121.579887) (xy 82.696629 -121.595955) (xy 82.747126 -121.619627)
			(xy 82.793639 -121.6504) (xy 82.835176 -121.687617) (xy 82.870851 -121.730485) (xy 82.899905 -121.778091)
			(xy 82.921717 -121.82942) (xy 82.935823 -121.883377) (xy 82.941923 -121.938814) (xy 82.939886 -121.994548)
			(xy 82.929756 -122.049391) (xy 82.911749 -122.102175) (xy 82.886248 -122.151775) (xy 82.853797 -122.197133)
			(xy 82.815088 -122.237282) (xy 82.770945 -122.271368) (xy 82.72231 -122.298664) (xy 82.670219 -122.318587)
			(xy 82.615782 -122.330713) (xy 82.56016 -122.334784) (xy 82.504538 -122.330713) (xy 82.450101 -122.318587)
			(xy 82.39801 -122.298664) (xy 82.349375 -122.271368) (xy 82.305232 -122.237282) (xy 82.266523 -122.197133)
			(xy 82.234072 -122.151775) (xy 82.208571 -122.102175) (xy 82.190564 -122.049391) (xy 82.180434 -121.994548)
			(xy 82.178397 -121.938814) (xy 80.721921 -121.938814) (xy 80.680738 -121.963827) (xy 80.629236 -121.985564)
			(xy 80.575114 -121.999554) (xy 80.51953 -122.005498) (xy 80.491584 -122.004836) (xy 80.468841 -122.004437)
			(xy 80.4238 -122.010747) (xy 80.3806 -122.024972) (xy 80.340621 -122.046656) (xy 80.305138 -122.075108)
			(xy 80.275284 -122.10942) (xy 80.252012 -122.148496) (xy 80.236064 -122.19109) (xy 80.227951 -122.235842)
			(xy 80.227424 -122.258582) (xy 80.227424 -123.041918) (xy 80.246982 -123.088654) (xy 80.247744 -123.089416)
			(xy 80.247744 -124.52301) (xy 83.467447 -124.52301) (xy 83.473547 -124.467573) (xy 83.487653 -124.413616)
			(xy 83.509465 -124.362287) (xy 83.538519 -124.314681) (xy 83.574194 -124.271813) (xy 83.615731 -124.234596)
			(xy 83.662244 -124.203823) (xy 83.712741 -124.180151) (xy 83.766148 -124.164083) (xy 83.821324 -124.155963)
			(xy 83.84921 -124.155454) (xy 83.877096 -124.155963) (xy 83.932272 -124.164083) (xy 83.985679 -124.180151)
			(xy 84.036176 -124.203823) (xy 84.082689 -124.234596) (xy 84.124226 -124.271813) (xy 84.159901 -124.314681)
			(xy 84.188955 -124.362287) (xy 84.210767 -124.413616) (xy 84.224873 -124.467573) (xy 84.230973 -124.52301)
			(xy 84.228936 -124.578744) (xy 84.218806 -124.633587) (xy 84.200799 -124.686371) (xy 84.175298 -124.735971)
			(xy 84.142847 -124.781329) (xy 84.104138 -124.821478) (xy 84.059995 -124.855564) (xy 84.01136 -124.88286)
			(xy 83.959269 -124.902783) (xy 83.904832 -124.914909) (xy 83.84921 -124.91898) (xy 83.793588 -124.914909)
			(xy 83.739151 -124.902783) (xy 83.68706 -124.88286) (xy 83.638425 -124.855564) (xy 83.594282 -124.821478)
			(xy 83.555573 -124.781329) (xy 83.523122 -124.735971) (xy 83.497621 -124.686371) (xy 83.479614 -124.633587)
			(xy 83.469484 -124.578744) (xy 83.467447 -124.52301) (xy 80.247744 -124.52301) (xy 80.247744 -125.90985)
			(xy 82.610197 -125.90985) (xy 82.616297 -125.854413) (xy 82.630403 -125.800456) (xy 82.652215 -125.749127)
			(xy 82.681269 -125.701521) (xy 82.716944 -125.658653) (xy 82.758481 -125.621436) (xy 82.804994 -125.590663)
			(xy 82.855491 -125.566991) (xy 82.908898 -125.550923) (xy 82.964074 -125.542803) (xy 82.99196 -125.542294)
			(xy 83.019846 -125.542803) (xy 83.075022 -125.550923) (xy 83.128429 -125.566991) (xy 83.178926 -125.590663)
			(xy 83.225439 -125.621436) (xy 83.266976 -125.658653) (xy 83.302651 -125.701521) (xy 83.331705 -125.749127)
			(xy 83.353517 -125.800456) (xy 83.367623 -125.854413) (xy 83.373723 -125.90985) (xy 83.371686 -125.965584)
			(xy 83.361556 -126.020427) (xy 83.343549 -126.073211) (xy 83.318048 -126.122811) (xy 83.285597 -126.168169)
			(xy 83.246888 -126.208318) (xy 83.202745 -126.242404) (xy 83.15411 -126.2697) (xy 83.102019 -126.289623)
			(xy 83.047582 -126.301749) (xy 82.99196 -126.30582) (xy 82.936338 -126.301749) (xy 82.881901 -126.289623)
			(xy 82.82981 -126.2697) (xy 82.781175 -126.242404) (xy 82.737032 -126.208318) (xy 82.698323 -126.168169)
			(xy 82.665872 -126.122811) (xy 82.640371 -126.073211) (xy 82.622364 -126.020427) (xy 82.612234 -125.965584)
			(xy 82.610197 -125.90985) (xy 80.247744 -125.90985) (xy 80.247744 -126.469412) (xy 86.846917 -126.469412)
			(xy 86.853017 -126.413975) (xy 86.867123 -126.360018) (xy 86.888935 -126.308689) (xy 86.917989 -126.261083)
			(xy 86.953664 -126.218215) (xy 86.995201 -126.180998) (xy 87.041714 -126.150225) (xy 87.092211 -126.126553)
			(xy 87.145618 -126.110485) (xy 87.200794 -126.102365) (xy 87.22868 -126.101856) (xy 87.256566 -126.102365)
			(xy 87.311742 -126.110485) (xy 87.365149 -126.126553) (xy 87.415646 -126.150225) (xy 87.462159 -126.180998)
			(xy 87.503696 -126.218215) (xy 87.539371 -126.261083) (xy 87.568425 -126.308689) (xy 87.590237 -126.360018)
			(xy 87.604343 -126.413975) (xy 87.610443 -126.469412) (xy 87.608406 -126.525146) (xy 87.598276 -126.579989)
			(xy 87.580269 -126.632773) (xy 87.554768 -126.682373) (xy 87.522317 -126.727731) (xy 87.483608 -126.76788)
			(xy 87.439465 -126.801966) (xy 87.39083 -126.829262) (xy 87.338739 -126.849185) (xy 87.284302 -126.861311)
			(xy 87.22868 -126.865382) (xy 87.173058 -126.861311) (xy 87.118621 -126.849185) (xy 87.06653 -126.829262)
			(xy 87.017895 -126.801966) (xy 86.973752 -126.76788) (xy 86.935043 -126.727731) (xy 86.902592 -126.682373)
			(xy 86.877091 -126.632773) (xy 86.859084 -126.579989) (xy 86.848954 -126.525146) (xy 86.846917 -126.469412)
			(xy 80.247744 -126.469412) (xy 80.247744 -127.508526) (xy 83.354925 -127.508526) (xy 83.361025 -127.453089)
			(xy 83.375131 -127.399132) (xy 83.396943 -127.347803) (xy 83.425997 -127.300197) (xy 83.461672 -127.257329)
			(xy 83.503209 -127.220112) (xy 83.549722 -127.189339) (xy 83.600219 -127.165667) (xy 83.653626 -127.149599)
			(xy 83.708802 -127.141479) (xy 83.736688 -127.14097) (xy 83.764574 -127.141479) (xy 83.81975 -127.149599)
			(xy 83.873157 -127.165667) (xy 83.923654 -127.189339) (xy 83.970167 -127.220112) (xy 84.011704 -127.257329)
			(xy 84.047379 -127.300197) (xy 84.076433 -127.347803) (xy 84.098245 -127.399132) (xy 84.112351 -127.453089)
			(xy 84.118451 -127.508526) (xy 84.116414 -127.56426) (xy 84.106284 -127.619103) (xy 84.088277 -127.671887)
			(xy 84.076413 -127.694962) (xy 84.749385 -127.694962) (xy 84.755485 -127.639525) (xy 84.769591 -127.585568)
			(xy 84.791403 -127.534239) (xy 84.820457 -127.486633) (xy 84.856132 -127.443765) (xy 84.897669 -127.406548)
			(xy 84.944182 -127.375775) (xy 84.994679 -127.352103) (xy 85.048086 -127.336035) (xy 85.103262 -127.327915)
			(xy 85.131148 -127.327406) (xy 85.159034 -127.327915) (xy 85.21421 -127.336035) (xy 85.267617 -127.352103)
			(xy 85.318114 -127.375775) (xy 85.332181 -127.385082) (xy 88.231217 -127.385082) (xy 88.237317 -127.329645)
			(xy 88.251423 -127.275688) (xy 88.273235 -127.224359) (xy 88.302289 -127.176753) (xy 88.337964 -127.133885)
			(xy 88.379501 -127.096668) (xy 88.426014 -127.065895) (xy 88.476511 -127.042223) (xy 88.529918 -127.026155)
			(xy 88.585094 -127.018035) (xy 88.61298 -127.017526) (xy 88.640866 -127.018035) (xy 88.696042 -127.026155)
			(xy 88.749449 -127.042223) (xy 88.799946 -127.065895) (xy 88.846459 -127.096668) (xy 88.887996 -127.133885)
			(xy 88.923671 -127.176753) (xy 88.952725 -127.224359) (xy 88.974537 -127.275688) (xy 88.988643 -127.329645)
			(xy 88.994743 -127.385082) (xy 88.992706 -127.440816) (xy 88.982576 -127.495659) (xy 88.964569 -127.548443)
			(xy 88.939068 -127.598043) (xy 88.906617 -127.643401) (xy 88.867908 -127.68355) (xy 88.823765 -127.717636)
			(xy 88.77513 -127.744932) (xy 88.723039 -127.764855) (xy 88.668602 -127.776981) (xy 88.61298 -127.781052)
			(xy 88.557358 -127.776981) (xy 88.502921 -127.764855) (xy 88.45083 -127.744932) (xy 88.402195 -127.717636)
			(xy 88.358052 -127.68355) (xy 88.319343 -127.643401) (xy 88.286892 -127.598043) (xy 88.261391 -127.548443)
			(xy 88.243384 -127.495659) (xy 88.233254 -127.440816) (xy 88.231217 -127.385082) (xy 85.332181 -127.385082)
			(xy 85.364627 -127.406548) (xy 85.406164 -127.443765) (xy 85.441839 -127.486633) (xy 85.470893 -127.534239)
			(xy 85.492705 -127.585568) (xy 85.506811 -127.639525) (xy 85.512911 -127.694962) (xy 85.510874 -127.750696)
			(xy 85.500744 -127.805539) (xy 85.482737 -127.858323) (xy 85.457236 -127.907923) (xy 85.436779 -127.936516)
			(xy 86.207345 -127.936516) (xy 86.213445 -127.881079) (xy 86.227551 -127.827122) (xy 86.249363 -127.775793)
			(xy 86.278417 -127.728187) (xy 86.314092 -127.685319) (xy 86.355629 -127.648102) (xy 86.402142 -127.617329)
			(xy 86.452639 -127.593657) (xy 86.506046 -127.577589) (xy 86.561222 -127.569469) (xy 86.589108 -127.56896)
			(xy 86.616994 -127.569469) (xy 86.67217 -127.577589) (xy 86.725577 -127.593657) (xy 86.776074 -127.617329)
			(xy 86.822587 -127.648102) (xy 86.864124 -127.685319) (xy 86.899799 -127.728187) (xy 86.928853 -127.775793)
			(xy 86.950665 -127.827122) (xy 86.964771 -127.881079) (xy 86.970871 -127.936516) (xy 86.968834 -127.99225)
			(xy 86.958704 -128.047093) (xy 86.940697 -128.099877) (xy 86.915196 -128.149477) (xy 86.882745 -128.194835)
			(xy 86.844036 -128.234984) (xy 86.799893 -128.26907) (xy 86.751258 -128.296366) (xy 86.699167 -128.316289)
			(xy 86.64473 -128.328415) (xy 86.589108 -128.332486) (xy 86.533486 -128.328415) (xy 86.479049 -128.316289)
			(xy 86.426958 -128.296366) (xy 86.378323 -128.26907) (xy 86.33418 -128.234984) (xy 86.295471 -128.194835)
			(xy 86.26302 -128.149477) (xy 86.237519 -128.099877) (xy 86.219512 -128.047093) (xy 86.209382 -127.99225)
			(xy 86.207345 -127.936516) (xy 85.436779 -127.936516) (xy 85.424785 -127.953281) (xy 85.386076 -127.99343)
			(xy 85.341933 -128.027516) (xy 85.293298 -128.054812) (xy 85.241207 -128.074735) (xy 85.18677 -128.086861)
			(xy 85.131148 -128.090932) (xy 85.075526 -128.086861) (xy 85.021089 -128.074735) (xy 84.968998 -128.054812)
			(xy 84.920363 -128.027516) (xy 84.87622 -127.99343) (xy 84.837511 -127.953281) (xy 84.80506 -127.907923)
			(xy 84.779559 -127.858323) (xy 84.761552 -127.805539) (xy 84.751422 -127.750696) (xy 84.749385 -127.694962)
			(xy 84.076413 -127.694962) (xy 84.062776 -127.721487) (xy 84.030325 -127.766845) (xy 83.991616 -127.806994)
			(xy 83.947473 -127.84108) (xy 83.898838 -127.868376) (xy 83.846747 -127.888299) (xy 83.79231 -127.900425)
			(xy 83.736688 -127.904496) (xy 83.681066 -127.900425) (xy 83.626629 -127.888299) (xy 83.574538 -127.868376)
			(xy 83.525903 -127.84108) (xy 83.48176 -127.806994) (xy 83.443051 -127.766845) (xy 83.4106 -127.721487)
			(xy 83.385099 -127.671887) (xy 83.367092 -127.619103) (xy 83.356962 -127.56426) (xy 83.354925 -127.508526)
			(xy 80.247744 -127.508526) (xy 80.247744 -130.086354) (xy 80.268572 -130.107182) (xy 80.268572 -130.220992)
			(xy 80.918557 -130.220992) (xy 80.924657 -130.165555) (xy 80.938763 -130.111598) (xy 80.960575 -130.060269)
			(xy 80.989629 -130.012663) (xy 81.025304 -129.969795) (xy 81.066841 -129.932578) (xy 81.113354 -129.901805)
			(xy 81.163851 -129.878133) (xy 81.217258 -129.862065) (xy 81.272434 -129.853945) (xy 81.30032 -129.853436)
			(xy 81.328206 -129.853945) (xy 81.383382 -129.862065) (xy 81.436789 -129.878133) (xy 81.487286 -129.901805)
			(xy 81.533799 -129.932578) (xy 81.575336 -129.969795) (xy 81.611011 -130.012663) (xy 81.640065 -130.060269)
			(xy 81.661877 -130.111598) (xy 81.67009 -130.143014) (xy 86.362285 -130.143014) (xy 86.368385 -130.087577)
			(xy 86.382491 -130.03362) (xy 86.404303 -129.982291) (xy 86.433357 -129.934685) (xy 86.469032 -129.891817)
			(xy 86.510569 -129.8546) (xy 86.557082 -129.823827) (xy 86.607579 -129.800155) (xy 86.660986 -129.784087)
			(xy 86.716162 -129.775967) (xy 86.744048 -129.775458) (xy 86.771934 -129.775967) (xy 86.82711 -129.784087)
			(xy 86.880517 -129.800155) (xy 86.931014 -129.823827) (xy 86.977527 -129.8546) (xy 87.019064 -129.891817)
			(xy 87.054739 -129.934685) (xy 87.083793 -129.982291) (xy 87.105605 -130.03362) (xy 87.119711 -130.087577)
			(xy 87.125811 -130.143014) (xy 87.123774 -130.198748) (xy 87.113644 -130.253591) (xy 87.095637 -130.306375)
			(xy 87.070136 -130.355975) (xy 87.037685 -130.401333) (xy 86.998976 -130.441482) (xy 86.954833 -130.475568)
			(xy 86.906198 -130.502864) (xy 86.854107 -130.522787) (xy 86.79967 -130.534913) (xy 86.744048 -130.538984)
			(xy 86.688426 -130.534913) (xy 86.633989 -130.522787) (xy 86.581898 -130.502864) (xy 86.533263 -130.475568)
			(xy 86.48912 -130.441482) (xy 86.450411 -130.401333) (xy 86.41796 -130.355975) (xy 86.392459 -130.306375)
			(xy 86.374452 -130.253591) (xy 86.364322 -130.198748) (xy 86.362285 -130.143014) (xy 81.67009 -130.143014)
			(xy 81.675983 -130.165555) (xy 81.682083 -130.220992) (xy 81.680046 -130.276726) (xy 81.669916 -130.331569)
			(xy 81.651909 -130.384353) (xy 81.626408 -130.433953) (xy 81.593957 -130.479311) (xy 81.555248 -130.51946)
			(xy 81.511105 -130.553546) (xy 81.46247 -130.580842) (xy 81.410379 -130.600765) (xy 81.355942 -130.612891)
			(xy 81.30032 -130.616962) (xy 81.244698 -130.612891) (xy 81.190261 -130.600765) (xy 81.13817 -130.580842)
			(xy 81.089535 -130.553546) (xy 81.045392 -130.51946) (xy 81.006683 -130.479311) (xy 80.974232 -130.433953)
			(xy 80.948731 -130.384353) (xy 80.930724 -130.331569) (xy 80.920594 -130.276726) (xy 80.918557 -130.220992)
			(xy 80.268572 -130.220992) (xy 80.268572 -131.173492) (xy 84.926677 -131.173492) (xy 84.932777 -131.118055)
			(xy 84.946883 -131.064098) (xy 84.968695 -131.012769) (xy 84.997749 -130.965163) (xy 85.033424 -130.922295)
			(xy 85.074961 -130.885078) (xy 85.121474 -130.854305) (xy 85.171971 -130.830633) (xy 85.225378 -130.814565)
			(xy 85.280554 -130.806445) (xy 85.30844 -130.805936) (xy 85.336326 -130.806445) (xy 85.391502 -130.814565)
			(xy 85.444909 -130.830633) (xy 85.495406 -130.854305) (xy 85.541919 -130.885078) (xy 85.583456 -130.922295)
			(xy 85.619131 -130.965163) (xy 85.648185 -131.012769) (xy 85.669997 -131.064098) (xy 85.684103 -131.118055)
			(xy 85.690203 -131.173492) (xy 85.688166 -131.229226) (xy 85.678036 -131.284069) (xy 85.660029 -131.336853)
			(xy 85.639546 -131.376692) (xy 87.591137 -131.376692) (xy 87.597237 -131.321255) (xy 87.611343 -131.267298)
			(xy 87.633155 -131.215969) (xy 87.662209 -131.168363) (xy 87.697884 -131.125495) (xy 87.739421 -131.088278)
			(xy 87.785934 -131.057505) (xy 87.836431 -131.033833) (xy 87.889838 -131.017765) (xy 87.945014 -131.009645)
			(xy 87.9729 -131.009136) (xy 88.000786 -131.009645) (xy 88.055962 -131.017765) (xy 88.109369 -131.033833)
			(xy 88.159866 -131.057505) (xy 88.206379 -131.088278) (xy 88.247916 -131.125495) (xy 88.283591 -131.168363)
			(xy 88.312645 -131.215969) (xy 88.334457 -131.267298) (xy 88.348563 -131.321255) (xy 88.354663 -131.376692)
			(xy 88.352626 -131.432426) (xy 88.342496 -131.487269) (xy 88.324489 -131.540053) (xy 88.298988 -131.589653)
			(xy 88.266537 -131.635011) (xy 88.227828 -131.67516) (xy 88.183685 -131.709246) (xy 88.13505 -131.736542)
			(xy 88.082959 -131.756465) (xy 88.028522 -131.768591) (xy 87.9729 -131.772662) (xy 87.917278 -131.768591)
			(xy 87.862841 -131.756465) (xy 87.81075 -131.736542) (xy 87.762115 -131.709246) (xy 87.717972 -131.67516)
			(xy 87.679263 -131.635011) (xy 87.646812 -131.589653) (xy 87.621311 -131.540053) (xy 87.603304 -131.487269)
			(xy 87.593174 -131.432426) (xy 87.591137 -131.376692) (xy 85.639546 -131.376692) (xy 85.634528 -131.386453)
			(xy 85.602077 -131.431811) (xy 85.563368 -131.47196) (xy 85.519225 -131.506046) (xy 85.47059 -131.533342)
			(xy 85.418499 -131.553265) (xy 85.364062 -131.565391) (xy 85.30844 -131.569462) (xy 85.252818 -131.565391)
			(xy 85.198381 -131.553265) (xy 85.14629 -131.533342) (xy 85.097655 -131.506046) (xy 85.053512 -131.47196)
			(xy 85.014803 -131.431811) (xy 84.982352 -131.386453) (xy 84.956851 -131.336853) (xy 84.938844 -131.284069)
			(xy 84.928714 -131.229226) (xy 84.926677 -131.173492) (xy 80.268572 -131.173492) (xy 80.268572 -131.656092)
			(xy 82.465417 -131.656092) (xy 82.471517 -131.600655) (xy 82.485623 -131.546698) (xy 82.507435 -131.495369)
			(xy 82.536489 -131.447763) (xy 82.572164 -131.404895) (xy 82.613701 -131.367678) (xy 82.660214 -131.336905)
			(xy 82.710711 -131.313233) (xy 82.764118 -131.297165) (xy 82.819294 -131.289045) (xy 82.84718 -131.288536)
			(xy 82.875066 -131.289045) (xy 82.930242 -131.297165) (xy 82.983649 -131.313233) (xy 83.034146 -131.336905)
			(xy 83.080659 -131.367678) (xy 83.122196 -131.404895) (xy 83.157871 -131.447763) (xy 83.186925 -131.495369)
			(xy 83.208737 -131.546698) (xy 83.222843 -131.600655) (xy 83.228943 -131.656092) (xy 83.226906 -131.711826)
			(xy 83.216776 -131.766669) (xy 83.198769 -131.819453) (xy 83.173268 -131.869053) (xy 83.140817 -131.914411)
			(xy 83.102108 -131.95456) (xy 83.057965 -131.988646) (xy 83.00933 -132.015942) (xy 82.957239 -132.035865)
			(xy 82.902802 -132.047991) (xy 82.84718 -132.052062) (xy 82.791558 -132.047991) (xy 82.737121 -132.035865)
			(xy 82.68503 -132.015942) (xy 82.636395 -131.988646) (xy 82.592252 -131.95456) (xy 82.553543 -131.914411)
			(xy 82.521092 -131.869053) (xy 82.495591 -131.819453) (xy 82.477584 -131.766669) (xy 82.467454 -131.711826)
			(xy 82.465417 -131.656092) (xy 80.268572 -131.656092) (xy 80.268572 -134.26694) (xy 80.1497 -134.385812)
			(xy 80.1497 -135.01194) (xy 84.964777 -135.01194) (xy 84.970877 -134.956503) (xy 84.984983 -134.902546)
			(xy 85.006795 -134.851217) (xy 85.035849 -134.803611) (xy 85.071524 -134.760743) (xy 85.113061 -134.723526)
			(xy 85.159574 -134.692753) (xy 85.210071 -134.669081) (xy 85.263478 -134.653013) (xy 85.318654 -134.644893)
			(xy 85.34654 -134.644384) (xy 85.374426 -134.644893) (xy 85.429602 -134.653013) (xy 85.483009 -134.669081)
			(xy 85.533506 -134.692753) (xy 85.580019 -134.723526) (xy 85.621556 -134.760743) (xy 85.657231 -134.803611)
			(xy 85.686285 -134.851217) (xy 85.708097 -134.902546) (xy 85.722203 -134.956503) (xy 85.728303 -135.01194)
			(xy 85.726548 -135.059946) (xy 86.024465 -135.059946) (xy 86.030565 -135.004509) (xy 86.044671 -134.950552)
			(xy 86.066483 -134.899223) (xy 86.095537 -134.851617) (xy 86.131212 -134.808749) (xy 86.172749 -134.771532)
			(xy 86.219262 -134.740759) (xy 86.269759 -134.717087) (xy 86.323166 -134.701019) (xy 86.378342 -134.692899)
			(xy 86.406228 -134.69239) (xy 86.434114 -134.692899) (xy 86.48929 -134.701019) (xy 86.542697 -134.717087)
			(xy 86.593194 -134.740759) (xy 86.639707 -134.771532) (xy 86.681244 -134.808749) (xy 86.716919 -134.851617)
			(xy 86.745973 -134.899223) (xy 86.767785 -134.950552) (xy 86.781891 -135.004509) (xy 86.787991 -135.059946)
			(xy 86.785954 -135.11568) (xy 86.775824 -135.170523) (xy 86.757817 -135.223307) (xy 86.732316 -135.272907)
			(xy 86.699865 -135.318265) (xy 86.661156 -135.358414) (xy 86.617013 -135.3925) (xy 86.568378 -135.419796)
			(xy 86.516287 -135.439719) (xy 86.46185 -135.451845) (xy 86.406228 -135.455916) (xy 86.350606 -135.451845)
			(xy 86.296169 -135.439719) (xy 86.244078 -135.419796) (xy 86.195443 -135.3925) (xy 86.1513 -135.358414)
			(xy 86.112591 -135.318265) (xy 86.08014 -135.272907) (xy 86.054639 -135.223307) (xy 86.036632 -135.170523)
			(xy 86.026502 -135.11568) (xy 86.024465 -135.059946) (xy 85.726548 -135.059946) (xy 85.726266 -135.067674)
			(xy 85.716136 -135.122517) (xy 85.698129 -135.175301) (xy 85.672628 -135.224901) (xy 85.640177 -135.270259)
			(xy 85.601468 -135.310408) (xy 85.557325 -135.344494) (xy 85.50869 -135.37179) (xy 85.456599 -135.391713)
			(xy 85.402162 -135.403839) (xy 85.34654 -135.40791) (xy 85.290918 -135.403839) (xy 85.236481 -135.391713)
			(xy 85.18439 -135.37179) (xy 85.135755 -135.344494) (xy 85.091612 -135.310408) (xy 85.052903 -135.270259)
			(xy 85.020452 -135.224901) (xy 84.994951 -135.175301) (xy 84.976944 -135.122517) (xy 84.966814 -135.067674)
			(xy 84.964777 -135.01194) (xy 80.1497 -135.01194) (xy 80.1497 -135.47041) (xy 83.272629 -135.47041)
			(xy 83.278729 -135.414973) (xy 83.292835 -135.361016) (xy 83.314647 -135.309687) (xy 83.343701 -135.262081)
			(xy 83.379376 -135.219213) (xy 83.420913 -135.181996) (xy 83.467426 -135.151223) (xy 83.517923 -135.127551)
			(xy 83.57133 -135.111483) (xy 83.626506 -135.103363) (xy 83.654392 -135.102854) (xy 83.682278 -135.103363)
			(xy 83.737454 -135.111483) (xy 83.790861 -135.127551) (xy 83.841358 -135.151223) (xy 83.887871 -135.181996)
			(xy 83.929408 -135.219213) (xy 83.965083 -135.262081) (xy 83.994137 -135.309687) (xy 84.015949 -135.361016)
			(xy 84.030055 -135.414973) (xy 84.036155 -135.47041) (xy 84.034118 -135.526144) (xy 84.023988 -135.580987)
			(xy 84.005981 -135.633771) (xy 83.98048 -135.683371) (xy 83.948029 -135.728729) (xy 83.90932 -135.768878)
			(xy 83.865177 -135.802964) (xy 83.816542 -135.83026) (xy 83.764451 -135.850183) (xy 83.710014 -135.862309)
			(xy 83.654392 -135.86638) (xy 83.59877 -135.862309) (xy 83.544333 -135.850183) (xy 83.492242 -135.83026)
			(xy 83.443607 -135.802964) (xy 83.399464 -135.768878) (xy 83.360755 -135.728729) (xy 83.328304 -135.683371)
			(xy 83.302803 -135.633771) (xy 83.284796 -135.580987) (xy 83.274666 -135.526144) (xy 83.272629 -135.47041)
			(xy 80.1497 -135.47041) (xy 80.1497 -136.143256) (xy 80.636109 -136.143256) (xy 80.642209 -136.087819)
			(xy 80.656315 -136.033862) (xy 80.678127 -135.982533) (xy 80.707181 -135.934927) (xy 80.742856 -135.892059)
			(xy 80.784393 -135.854842) (xy 80.830906 -135.824069) (xy 80.881403 -135.800397) (xy 80.93481 -135.784329)
			(xy 80.989986 -135.776209) (xy 81.017872 -135.7757) (xy 81.045758 -135.776209) (xy 81.100934 -135.784329)
			(xy 81.154341 -135.800397) (xy 81.204838 -135.824069) (xy 81.251351 -135.854842) (xy 81.292888 -135.892059)
			(xy 81.328563 -135.934927) (xy 81.357617 -135.982533) (xy 81.379429 -136.033862) (xy 81.393535 -136.087819)
			(xy 81.399635 -136.143256) (xy 81.397598 -136.19899) (xy 81.387468 -136.253833) (xy 81.369461 -136.306617)
			(xy 81.34396 -136.356217) (xy 81.311509 -136.401575) (xy 81.2728 -136.441724) (xy 81.228657 -136.47581)
			(xy 81.180022 -136.503106) (xy 81.127931 -136.523029) (xy 81.073494 -136.535155) (xy 81.017872 -136.539226)
			(xy 80.96225 -136.535155) (xy 80.907813 -136.523029) (xy 80.855722 -136.503106) (xy 80.807087 -136.47581)
			(xy 80.762944 -136.441724) (xy 80.724235 -136.401575) (xy 80.691784 -136.356217) (xy 80.666283 -136.306617)
			(xy 80.648276 -136.253833) (xy 80.638146 -136.19899) (xy 80.636109 -136.143256) (xy 80.1497 -136.143256)
			(xy 80.1497 -136.59436) (xy 86.235031 -136.59436) (xy 86.241131 -136.538923) (xy 86.255237 -136.484966)
			(xy 86.277049 -136.433637) (xy 86.306103 -136.386031) (xy 86.341778 -136.343163) (xy 86.383315 -136.305946)
			(xy 86.429828 -136.275173) (xy 86.480325 -136.251501) (xy 86.533732 -136.235433) (xy 86.588908 -136.227313)
			(xy 86.616794 -136.226804) (xy 86.64468 -136.227313) (xy 86.699856 -136.235433) (xy 86.753263 -136.251501)
			(xy 86.80376 -136.275173) (xy 86.850273 -136.305946) (xy 86.89181 -136.343163) (xy 86.927485 -136.386031)
			(xy 86.956539 -136.433637) (xy 86.978351 -136.484966) (xy 86.992457 -136.538923) (xy 86.998557 -136.59436)
			(xy 86.99652 -136.650094) (xy 86.98639 -136.704937) (xy 86.968383 -136.757721) (xy 86.942882 -136.807321)
			(xy 86.910431 -136.852679) (xy 86.871722 -136.892828) (xy 86.827579 -136.926914) (xy 86.778944 -136.95421)
			(xy 86.726853 -136.974133) (xy 86.672416 -136.986259) (xy 86.616794 -136.99033) (xy 86.561172 -136.986259)
			(xy 86.506735 -136.974133) (xy 86.454644 -136.95421) (xy 86.406009 -136.926914) (xy 86.361866 -136.892828)
			(xy 86.323157 -136.852679) (xy 86.290706 -136.807321) (xy 86.265205 -136.757721) (xy 86.247198 -136.704937)
			(xy 86.237068 -136.650094) (xy 86.235031 -136.59436) (xy 80.1497 -136.59436) (xy 80.1497 -137.431736)
			(xy 80.563066 -137.431736) (xy 80.563279 -137.37577) (xy 80.571665 -137.320435) (xy 80.588046 -137.266919)
			(xy 80.61207 -137.216371) (xy 80.64322 -137.169874) (xy 80.680829 -137.128428) (xy 80.72409 -137.09292)
			(xy 80.772074 -137.064114) (xy 80.823751 -137.042627) (xy 80.878013 -137.02892) (xy 80.933696 -137.023288)
			(xy 80.989604 -137.025851) (xy 81.044537 -137.036555) (xy 81.097318 -137.055169) (xy 81.146813 -137.081294)
			(xy 81.19196 -137.11437) (xy 81.23179 -137.153686) (xy 81.249012 -137.175748) (xy 81.262795 -137.193288)
			(xy 81.295407 -137.223717) (xy 81.332832 -137.247983) (xy 81.373919 -137.26534) (xy 81.417407 -137.275255)
			(xy 81.461958 -137.277423) (xy 81.506203 -137.271777) (xy 81.548781 -137.258491) (xy 81.568798 -137.248646)
			(xy 81.592894 -137.236699) (xy 81.643632 -137.218864) (xy 81.696373 -137.208339) (xy 81.75007 -137.205333)
			(xy 81.803657 -137.209905) (xy 81.856068 -137.221965) (xy 81.906263 -137.241274) (xy 81.953246 -137.267447)
			(xy 81.996082 -137.299966) (xy 82.01533 -137.31875) (xy 82.030896 -137.333838) (xy 82.066173 -137.359028)
			(xy 82.105214 -137.377862) (xy 82.146887 -137.389793) (xy 82.189981 -137.394474) (xy 82.233243 -137.391769)
			(xy 82.275418 -137.381757) (xy 82.315281 -137.364729) (xy 82.351673 -137.341179) (xy 82.383537 -137.311792)
			(xy 82.397092 -137.294874) (xy 82.414446 -137.273013) (xy 82.454583 -137.234224) (xy 82.499943 -137.201697)
			(xy 82.549559 -137.176126) (xy 82.602371 -137.158059) (xy 82.657252 -137.147879) (xy 82.71303 -137.145805)
			(xy 82.768516 -137.15188) (xy 82.822524 -137.165976) (xy 82.873902 -137.187791) (xy 82.89798 -137.20191)
			(xy 82.918358 -137.213677) (xy 82.962359 -137.230336) (xy 83.008674 -137.238621) (xy 83.055722 -137.238251)
			(xy 83.101901 -137.229237) (xy 83.145635 -137.211888) (xy 83.185434 -137.186794) (xy 83.203034 -137.171176)
			(xy 83.223389 -137.152965) (xy 83.268337 -137.121938) (xy 83.31725 -137.097639) (xy 83.369129 -137.080564)
			(xy 83.422913 -137.071063) (xy 83.477502 -137.069329) (xy 83.531781 -137.075399) (xy 83.584639 -137.089148)
			(xy 83.634995 -137.110295) (xy 83.681821 -137.138407) (xy 83.724159 -137.172911) (xy 83.761143 -137.2131)
			(xy 83.792017 -137.258153) (xy 83.816151 -137.307148) (xy 83.83305 -137.359085) (xy 83.842369 -137.4129)
			(xy 83.843917 -137.467495) (xy 83.837664 -137.521753) (xy 83.823736 -137.574564) (xy 83.802418 -137.624848)
			(xy 83.774147 -137.671579) (xy 83.739501 -137.713799) (xy 83.699187 -137.750647) (xy 83.654029 -137.781369)
			(xy 83.604952 -137.805336) (xy 83.552959 -137.822059) (xy 83.499112 -137.831196) (xy 83.444512 -137.832559)
			(xy 83.390276 -137.826122) (xy 83.337513 -137.812015) (xy 83.2873 -137.790527) (xy 83.26374 -137.776712)
			(xy 83.2434 -137.764878) (xy 83.199386 -137.748233) (xy 83.153064 -137.739961) (xy 83.106009 -137.740344)
			(xy 83.059827 -137.749368) (xy 83.01609 -137.766725) (xy 82.976288 -137.791826) (xy 82.958686 -137.807446)
			(xy 82.938792 -137.825217) (xy 82.894985 -137.855653) (xy 82.847367 -137.879692) (xy 82.796864 -137.896865)
			(xy 82.744463 -137.906838) (xy 82.691183 -137.909416) (xy 82.638063 -137.904549) (xy 82.586139 -137.892332)
			(xy 82.536422 -137.873003) (xy 82.489881 -137.846939) (xy 82.447423 -137.814648) (xy 82.428334 -137.796016)
			(xy 82.4128 -137.780894) (xy 82.377517 -137.755708) (xy 82.33847 -137.736879) (xy 82.296792 -137.724953)
			(xy 82.253695 -137.720276) (xy 82.21043 -137.722985) (xy 82.168253 -137.733) (xy 82.128388 -137.750031)
			(xy 82.091994 -137.773584) (xy 82.060128 -137.802973) (xy 82.046572 -137.819892) (xy 82.029731 -137.84102)
			(xy 81.991084 -137.878775) (xy 81.947496 -137.910699) (xy 81.899838 -137.936152) (xy 81.849066 -137.954625)
			(xy 81.796195 -137.965748) (xy 81.742284 -137.9693) (xy 81.68841 -137.965208) (xy 81.635654 -137.953554)
			(xy 81.585069 -137.934572) (xy 81.53767 -137.908642) (xy 81.494404 -137.876283) (xy 81.456138 -137.838141)
			(xy 81.439512 -137.816844) (xy 81.425691 -137.799335) (xy 81.39309 -137.768898) (xy 81.355673 -137.744624)
			(xy 81.314591 -137.72726) (xy 81.271107 -137.71734) (xy 81.226559 -137.715169) (xy 81.182317 -137.720814)
			(xy 81.139741 -137.7341) (xy 81.119726 -137.743946) (xy 81.094654 -137.756385) (xy 81.041734 -137.774597)
			(xy 80.986721 -137.784883) (xy 80.930795 -137.787021) (xy 80.875157 -137.780966) (xy 80.821 -137.766848)
			(xy 80.769487 -137.744968) (xy 80.721724 -137.715798) (xy 80.678734 -137.679963) (xy 80.641441 -137.638232)
			(xy 80.610645 -137.591501) (xy 80.587006 -137.540771) (xy 80.571032 -137.487133) (xy 80.563066 -137.431736)
			(xy 80.1497 -137.431736) (xy 80.1497 -138.670151) (xy 82.149889 -138.670151) (xy 82.156473 -138.614743)
			(xy 82.171058 -138.560886) (xy 82.193333 -138.509727) (xy 82.222824 -138.46236) (xy 82.2589 -138.419793)
			(xy 82.300792 -138.382936) (xy 82.347607 -138.352576) (xy 82.398344 -138.329358) (xy 82.451923 -138.31378)
			(xy 82.5072 -138.306173) (xy 82.562995 -138.3067) (xy 82.618118 -138.31535) (xy 82.671394 -138.331937)
			(xy 82.721684 -138.356108) (xy 82.745072 -138.371326) (xy 82.76326 -138.383179) (xy 82.802818 -138.401057)
			(xy 82.844841 -138.411947) (xy 82.888104 -138.415532) (xy 82.931346 -138.411708) (xy 82.973308 -138.400585)
			(xy 83.012767 -138.382488) (xy 83.048574 -138.357944) (xy 83.079685 -138.327668) (xy 83.092798 -138.310366)
			(xy 83.109608 -138.288096) (xy 83.148631 -138.248217) (xy 83.193048 -138.214449) (xy 83.241911 -138.187512)
			(xy 83.294176 -138.16798) (xy 83.348729 -138.156271) (xy 83.404406 -138.152634) (xy 83.460018 -138.157147)
			(xy 83.51438 -138.169713) (xy 83.557707 -138.186686) (xy 84.049869 -138.186686) (xy 84.055969 -138.131249)
			(xy 84.070075 -138.077292) (xy 84.091887 -138.025963) (xy 84.120941 -137.978357) (xy 84.156616 -137.935489)
			(xy 84.198153 -137.898272) (xy 84.244666 -137.867499) (xy 84.295163 -137.843827) (xy 84.34857 -137.827759)
			(xy 84.403746 -137.819639) (xy 84.431632 -137.81913) (xy 84.459518 -137.819639) (xy 84.514694 -137.827759)
			(xy 84.568101 -137.843827) (xy 84.618598 -137.867499) (xy 84.665111 -137.898272) (xy 84.706648 -137.935489)
			(xy 84.742323 -137.978357) (xy 84.771377 -138.025963) (xy 84.793189 -138.077292) (xy 84.807295 -138.131249)
			(xy 84.813395 -138.186686) (xy 84.811358 -138.24242) (xy 84.801228 -138.297263) (xy 84.783221 -138.350047)
			(xy 84.75772 -138.399647) (xy 84.725269 -138.445005) (xy 84.68656 -138.485154) (xy 84.642417 -138.51924)
			(xy 84.593782 -138.546536) (xy 84.541691 -138.566459) (xy 84.487254 -138.578585) (xy 84.431632 -138.582656)
			(xy 84.37601 -138.578585) (xy 84.321573 -138.566459) (xy 84.269482 -138.546536) (xy 84.220847 -138.51924)
			(xy 84.176704 -138.485154) (xy 84.137995 -138.445005) (xy 84.105544 -138.399647) (xy 84.080043 -138.350047)
			(xy 84.062036 -138.297263) (xy 84.051906 -138.24242) (xy 84.049869 -138.186686) (xy 83.557707 -138.186686)
			(xy 83.566332 -138.190065) (xy 83.614764 -138.217767) (xy 83.658644 -138.25223) (xy 83.697035 -138.292718)
			(xy 83.729119 -138.338366) (xy 83.75421 -138.388202) (xy 83.771773 -138.441161) (xy 83.781434 -138.496114)
			(xy 83.782987 -138.551888) (xy 83.776397 -138.607293) (xy 83.761807 -138.661147) (xy 83.739527 -138.712301)
			(xy 83.710032 -138.759663) (xy 83.673952 -138.802224) (xy 83.632057 -138.839074) (xy 83.585241 -138.869428)
			(xy 83.534502 -138.892638) (xy 83.480923 -138.908208) (xy 83.425647 -138.915808) (xy 83.369854 -138.915273)
			(xy 83.314735 -138.906616) (xy 83.261464 -138.890022) (xy 83.211179 -138.865845) (xy 83.187794 -138.850624)
			(xy 83.169568 -138.838832) (xy 83.130019 -138.820945) (xy 83.088003 -138.810045) (xy 83.044746 -138.806451)
			(xy 83.001508 -138.810267) (xy 82.959549 -138.821383) (xy 82.920093 -138.839474) (xy 82.884288 -138.864012)
			(xy 82.85318 -138.894284) (xy 82.840068 -138.911584) (xy 82.823323 -138.933903) (xy 82.7843 -138.973785)
			(xy 82.739883 -139.007557) (xy 82.691021 -139.034498) (xy 82.638755 -139.054034) (xy 82.584201 -139.065748)
			(xy 82.528522 -139.069389) (xy 82.472907 -139.06488) (xy 82.418542 -139.052317) (xy 82.366587 -139.031969)
			(xy 82.31815 -139.004269) (xy 82.274266 -138.969809) (xy 82.235869 -138.929323) (xy 82.20378 -138.883676)
			(xy 82.178684 -138.833841) (xy 82.161114 -138.780881) (xy 82.151448 -138.725927) (xy 82.149889 -138.670151)
			(xy 80.1497 -138.670151) (xy 80.1497 -139.485624) (xy 80.7085 -140.044424) (xy 80.7085 -142.636126)
			(xy 81.682652 -142.636126) (xy 81.684483 -142.581928) (xy 81.693966 -142.528534) (xy 81.71091 -142.47702)
			(xy 81.734974 -142.428423) (xy 81.765673 -142.38372) (xy 81.783682 -142.363444) (xy 81.793702 -142.351964)
			(xy 81.808404 -142.325281) (xy 81.816348 -142.29587) (xy 81.817081 -142.265414) (xy 81.810561 -142.235655)
			(xy 81.797159 -142.208296) (xy 81.787746 -142.196312) (xy 81.769652 -142.173618) (xy 81.739751 -142.123877)
			(xy 81.717722 -142.070183) (xy 81.704072 -142.013775) (xy 81.699116 -141.95595) (xy 81.702967 -141.898041)
			(xy 81.715538 -141.841382) (xy 81.736538 -141.787278) (xy 81.765484 -141.736975) (xy 81.783174 -141.713966)
			(xy 81.793415 -141.700207) (xy 81.806902 -141.668687) (xy 81.811512 -141.634714) (xy 81.80691 -141.60074)
			(xy 81.79343 -141.569217) (xy 81.783174 -141.55547) (xy 81.765724 -141.532796) (xy 81.737063 -141.48328)
			(xy 81.716118 -141.430038) (xy 81.70336 -141.374266) (xy 81.699074 -141.317214) (xy 81.703356 -141.260162)
			(xy 81.71611 -141.204388) (xy 81.737051 -141.151146) (xy 81.765708 -141.101627) (xy 81.783174 -141.078966)
			(xy 81.793415 -141.065207) (xy 81.806902 -141.033687) (xy 81.811512 -140.999714) (xy 81.80691 -140.96574)
			(xy 81.79343 -140.934217) (xy 81.783174 -140.92047) (xy 81.766293 -140.898573) (xy 81.738359 -140.850861)
			(xy 81.717605 -140.799617) (xy 81.704465 -140.745913) (xy 81.699216 -140.690875) (xy 81.701966 -140.635655)
			(xy 81.712659 -140.581411) (xy 81.73107 -140.529279) (xy 81.756813 -140.48035) (xy 81.789351 -140.43565)
			(xy 81.828 -140.396115) (xy 81.871951 -140.362573) (xy 81.920283 -140.335727) (xy 81.971985 -140.31614)
			(xy 82.025973 -140.304221) (xy 82.081116 -140.30022) (xy 82.136259 -140.304221) (xy 82.190247 -140.31614)
			(xy 82.241949 -140.335727) (xy 82.290281 -140.362573) (xy 82.334232 -140.396115) (xy 82.372881 -140.43565)
			(xy 82.405419 -140.48035) (xy 82.431162 -140.529279) (xy 82.449573 -140.581411) (xy 82.460266 -140.635655)
			(xy 82.463016 -140.690875) (xy 82.457767 -140.745913) (xy 82.444627 -140.799617) (xy 82.423873 -140.850861)
			(xy 82.395939 -140.898573) (xy 82.379058 -140.92047) (xy 82.368788 -140.934207) (xy 82.355312 -140.965736)
			(xy 82.350712 -140.999714) (xy 82.35532 -141.033691) (xy 82.368802 -141.065217) (xy 82.379058 -141.078966)
			(xy 82.396542 -141.101615) (xy 82.425198 -141.151137) (xy 82.446138 -141.204383) (xy 82.457479 -141.253978)
			(xy 85.355633 -141.253978) (xy 85.35992 -141.196922) (xy 85.37268 -141.141146) (xy 85.393626 -141.087901)
			(xy 85.422289 -141.038381) (xy 85.439758 -141.01572) (xy 85.450037 -141.001989) (xy 85.463509 -140.970457)
			(xy 85.468106 -140.936478) (xy 85.463497 -140.9025) (xy 85.450014 -140.870974) (xy 85.439758 -140.857224)
			(xy 85.422877 -140.835327) (xy 85.394943 -140.787615) (xy 85.374189 -140.736371) (xy 85.361049 -140.682667)
			(xy 85.3558 -140.627629) (xy 85.35855 -140.572409) (xy 85.369243 -140.518165) (xy 85.387654 -140.466033)
			(xy 85.413397 -140.417104) (xy 85.445935 -140.372404) (xy 85.484584 -140.332869) (xy 85.528535 -140.299327)
			(xy 85.576867 -140.272481) (xy 85.628569 -140.252894) (xy 85.682557 -140.240975) (xy 85.7377 -140.236974)
			(xy 85.792843 -140.240975) (xy 85.846831 -140.252894) (xy 85.898533 -140.272481) (xy 85.946865 -140.299327)
			(xy 85.990816 -140.332869) (xy 86.029465 -140.372404) (xy 86.062003 -140.417104) (xy 86.087746 -140.466033)
			(xy 86.106157 -140.518165) (xy 86.11685 -140.572409) (xy 86.1196 -140.627629) (xy 86.114351 -140.682667)
			(xy 86.101211 -140.736371) (xy 86.080457 -140.787615) (xy 86.052523 -140.835327) (xy 86.035642 -140.857224)
			(xy 86.025416 -140.870992) (xy 86.011936 -140.90251) (xy 86.007328 -140.936478) (xy 86.011925 -140.970448)
			(xy 86.025393 -141.001971) (xy 86.035642 -141.01572) (xy 86.053082 -141.038401) (xy 86.081742 -141.087916)
			(xy 86.102687 -141.141157) (xy 86.115445 -141.196927) (xy 86.119732 -141.253978) (xy 86.115452 -141.311029)
			(xy 86.102699 -141.366802) (xy 86.081761 -141.420044) (xy 86.053107 -141.469563) (xy 86.035642 -141.492224)
			(xy 86.025416 -141.505992) (xy 86.011936 -141.53751) (xy 86.007328 -141.571478) (xy 86.011925 -141.605448)
			(xy 86.025393 -141.636971) (xy 86.035642 -141.65072) (xy 86.052523 -141.672617) (xy 86.080457 -141.720329)
			(xy 86.101211 -141.771573) (xy 86.114351 -141.825277) (xy 86.1196 -141.880315) (xy 86.11685 -141.935535)
			(xy 86.106157 -141.989779) (xy 86.087746 -142.041911) (xy 86.062003 -142.09084) (xy 86.029465 -142.13554)
			(xy 85.990816 -142.175075) (xy 85.946865 -142.208617) (xy 85.898533 -142.235463) (xy 85.846831 -142.25505)
			(xy 85.792843 -142.266969) (xy 85.7377 -142.27097) (xy 85.682557 -142.266969) (xy 85.628569 -142.25505)
			(xy 85.576867 -142.235463) (xy 85.528535 -142.208617) (xy 85.484584 -142.175075) (xy 85.445935 -142.13554)
			(xy 85.413397 -142.09084) (xy 85.387654 -142.041911) (xy 85.369243 -141.989779) (xy 85.35855 -141.935535)
			(xy 85.3558 -141.880315) (xy 85.361049 -141.825277) (xy 85.374189 -141.771573) (xy 85.394943 -141.720329)
			(xy 85.422877 -141.672617) (xy 85.439758 -141.65072) (xy 85.450037 -141.636989) (xy 85.463509 -141.605457)
			(xy 85.468106 -141.571478) (xy 85.463497 -141.5375) (xy 85.450014 -141.505974) (xy 85.439758 -141.492224)
			(xy 85.422264 -141.469583) (xy 85.393607 -141.420059) (xy 85.372667 -141.366812) (xy 85.359914 -141.311035)
			(xy 85.355633 -141.253978) (xy 82.457479 -141.253978) (xy 82.458892 -141.260159) (xy 82.463174 -141.317214)
			(xy 82.458888 -141.374269) (xy 82.44613 -141.430044) (xy 82.425186 -141.483288) (xy 82.396526 -141.532808)
			(xy 82.379058 -141.55547) (xy 82.368788 -141.569207) (xy 82.355312 -141.600736) (xy 82.350712 -141.634714)
			(xy 82.35532 -141.668691) (xy 82.368802 -141.700217) (xy 82.379058 -141.713966) (xy 82.395571 -141.735416)
			(xy 82.423052 -141.782051) (xy 82.443667 -141.832103) (xy 82.457 -141.884565) (xy 82.462785 -141.938386)
			(xy 82.460905 -141.992484) (xy 82.451398 -142.045773) (xy 82.434455 -142.097183) (xy 82.410416 -142.145683)
			(xy 82.379764 -142.190298) (xy 82.361786 -142.210536) (xy 82.351787 -142.222032) (xy 82.337087 -142.248711)
			(xy 82.329142 -142.278117) (xy 82.328405 -142.308569) (xy 82.33492 -142.338325) (xy 82.348313 -142.365683)
			(xy 82.357722 -142.377668) (xy 82.375003 -142.399258) (xy 82.403864 -142.446426) (xy 82.425609 -142.497268)
			(xy 82.439782 -142.550719) (xy 82.446086 -142.605656) (xy 82.444389 -142.660927) (xy 82.434725 -142.715374)
			(xy 82.417298 -142.767854) (xy 82.392473 -142.817266) (xy 82.377026 -142.840202) (xy 82.364095 -142.85966)
			(xy 82.344796 -142.902201) (xy 82.333593 -142.947552) (xy 82.330861 -142.994186) (xy 82.336693 -143.040534)
			(xy 82.350892 -143.085038) (xy 82.372981 -143.1262) (xy 82.387186 -143.144748) (xy 82.403842 -143.166327)
			(xy 82.431588 -143.213247) (xy 82.452372 -143.263638) (xy 82.465771 -143.316475) (xy 82.471512 -143.370681)
			(xy 82.469477 -143.425153) (xy 82.45971 -143.47878) (xy 82.442407 -143.53047) (xy 82.417923 -143.579171)
			(xy 82.386755 -143.62389) (xy 82.349538 -143.663717) (xy 82.307031 -143.69784) (xy 82.260099 -143.725565)
			(xy 82.209698 -143.746326) (xy 82.156855 -143.759701) (xy 82.102646 -143.765418) (xy 82.048176 -143.763359)
			(xy 81.994553 -143.753567) (xy 81.942871 -143.736241) (xy 81.894181 -143.711734) (xy 81.849476 -143.680546)
			(xy 81.809666 -143.643312) (xy 81.775562 -143.600789) (xy 81.747858 -143.553844) (xy 81.72712 -143.503434)
			(xy 81.713769 -143.450585) (xy 81.708077 -143.396374) (xy 81.71016 -143.341905) (xy 81.719976 -143.288286)
			(xy 81.737325 -143.236612) (xy 81.761854 -143.187933) (xy 81.777078 -143.165322) (xy 81.789986 -143.145849)
			(xy 81.809286 -143.103312) (xy 81.820493 -143.057965) (xy 81.823228 -143.011334) (xy 81.8174 -142.964988)
			(xy 81.803205 -142.920485) (xy 81.781121 -142.879324) (xy 81.766918 -142.860776) (xy 81.75028 -142.839362)
			(xy 81.722667 -142.792689) (xy 81.701938 -142.742578) (xy 81.68851 -142.690038) (xy 81.682652 -142.636126)
			(xy 80.7085 -142.636126) (xy 80.7085 -144.405604) (xy 80.73644 -144.440402) (xy 80.751966 -144.460462)
			(xy 80.778139 -144.503914) (xy 80.798318 -144.550453) (xy 80.812149 -144.599256) (xy 80.816196 -144.624298)
			(xy 80.822292 -144.665954) (xy 81.82864 -145.672302) (xy 84.897468 -145.672302)
		)
		(stroke
			(width 0)
			(type solid)
		)
		(fill yes)
		(layer "In2.Cu")
		(net "P1V8_NODE1")
	)
	(gr_poly
		(pts
			(xy 130.904234 -151.59863) (xy 139.534392 -151.59863) (xy 140.834872 -150.29815) (xy 140.834872 -140.560298)
			(xy 142.451074 -138.944096) (xy 142.466806 -138.927632) (xy 142.492734 -138.890204) (xy 142.511582 -138.848757)
			(xy 142.522747 -138.804615) (xy 142.525871 -138.759191) (xy 142.520855 -138.713936) (xy 142.50786 -138.670298)
			(xy 142.487301 -138.629673) (xy 142.459834 -138.593358) (xy 142.426339 -138.562516) (xy 142.387887 -138.538133)
			(xy 142.367 -138.52906) (xy 142.340662 -138.517817) (xy 142.291415 -138.488594) (xy 142.247088 -138.452339)
			(xy 142.208676 -138.409868) (xy 142.177043 -138.362133) (xy 142.152897 -138.310207) (xy 142.136783 -138.255257)
			(xy 142.129061 -138.198515) (xy 142.129904 -138.141256) (xy 142.139295 -138.084766) (xy 142.157022 -138.030314)
			(xy 142.182687 -137.979122) (xy 142.215713 -137.93234) (xy 142.235174 -137.911332) (xy 142.250931 -137.894118)
			(xy 142.276515 -137.855096) (xy 142.294548 -137.812061) (xy 142.304423 -137.766456) (xy 142.30581 -137.719816)
			(xy 142.298662 -137.673706) (xy 142.283219 -137.629674) (xy 142.259999 -137.589201) (xy 142.229783 -137.553645)
			(xy 142.21206 -137.53846) (xy 142.191306 -137.520947) (xy 142.154479 -137.481041) (xy 142.12368 -137.436317)
			(xy 142.099532 -137.38768) (xy 142.082522 -137.33611) (xy 142.072994 -137.28265) (xy 142.07114 -137.228379)
			(xy 142.076997 -137.174393) (xy 142.090448 -137.121783) (xy 142.11122 -137.071611) (xy 142.138895 -137.024889)
			(xy 142.172912 -136.982562) (xy 142.212586 -136.945485) (xy 142.257115 -136.914406) (xy 142.3056 -136.889952)
			(xy 142.331186 -136.880854) (xy 142.353557 -136.872782) (xy 142.39504 -136.849532) (xy 142.431474 -136.818971)
			(xy 142.461586 -136.782166) (xy 142.484327 -136.740402) (xy 142.498902 -136.695137) (xy 142.504803 -136.64795)
			(xy 142.501823 -136.60049) (xy 142.490067 -136.554412) (xy 142.480538 -136.53262) (xy 142.469187 -136.507128)
			(xy 142.453225 -136.453659) (xy 142.445222 -136.398436) (xy 142.445348 -136.342635) (xy 142.453602 -136.287448)
			(xy 142.469807 -136.234052) (xy 142.493617 -136.183587) (xy 142.524525 -136.137128) (xy 142.561871 -136.095667)
			(xy 142.604858 -136.060088) (xy 142.652569 -136.031151) (xy 142.703987 -136.009473) (xy 142.758014 -135.995516)
			(xy 142.813498 -135.989578) (xy 142.869255 -135.991786) (xy 142.924095 -136.002093) (xy 142.97685 -136.020278)
			(xy 143.026392 -136.045954) (xy 143.071666 -136.078573) (xy 143.111705 -136.11744) (xy 143.145655 -136.161724)
			(xy 143.172792 -136.210482) (xy 143.192538 -136.262672) (xy 143.204469 -136.317182) (xy 143.208334 -136.372849)
			(xy 143.204047 -136.428485) (xy 143.191702 -136.482903) (xy 143.171562 -136.534942) (xy 143.144056 -136.583492)
			(xy 143.10977 -136.627518) (xy 143.069438 -136.666079) (xy 143.023918 -136.698354) (xy 142.974182 -136.723654)
			(xy 142.947898 -136.733026) (xy 142.925526 -136.741099) (xy 142.884044 -136.76435) (xy 142.84761 -136.794912)
			(xy 142.817496 -136.831717) (xy 142.794754 -136.873481) (xy 142.780177 -136.918746) (xy 142.774273 -136.965933)
			(xy 142.77725 -137.013395) (xy 142.789003 -137.059474) (xy 142.798546 -137.08126) (xy 142.808429 -137.103298)
			(xy 142.823199 -137.149285) (xy 142.82801 -137.172954) (xy 142.83155 -137.189336) (xy 142.845999 -137.219565)
			(xy 142.86782 -137.244991) (xy 142.895506 -137.26386) (xy 142.92715 -137.274872) (xy 142.960569 -137.277266)
			(xy 142.977108 -137.274554) (xy 143.005549 -137.269585) (xy 143.063237 -137.267266) (xy 143.120617 -137.273662)
			(xy 143.176378 -137.288626) (xy 143.229251 -137.311817) (xy 143.278027 -137.342706) (xy 143.321596 -137.380589)
			(xy 143.358962 -137.4246) (xy 143.389275 -137.473737) (xy 143.401034 -137.500106) (xy 143.410296 -137.520722)
			(xy 143.434998 -137.558566) (xy 143.466004 -137.591443) (xy 143.502337 -137.618317) (xy 143.54285 -137.638341)
			(xy 143.586267 -137.650882) (xy 143.631218 -137.655546) (xy 143.676284 -137.652185) (xy 143.720046 -137.640905)
			(xy 143.761122 -137.622062) (xy 143.798217 -137.596251) (xy 143.814546 -137.580624) (xy 146.37766 -135.01751)
			(xy 146.37766 -134.940294) (xy 151.41448 -129.903474) (xy 151.41448 -101.113082) (xy 151.031702 -100.730304)
			(xy 150.998174 -100.721668) (xy 150.971962 -100.71437) (xy 150.921771 -100.693364) (xy 150.875073 -100.665443)
			(xy 150.832814 -100.631172) (xy 150.795851 -100.591245) (xy 150.764934 -100.546474) (xy 150.74069 -100.497764)
			(xy 150.723611 -100.446106) (xy 150.714042 -100.392544) (xy 150.712178 -100.338167) (xy 150.718057 -100.284077)
			(xy 150.731559 -100.231369) (xy 150.752411 -100.181115) (xy 150.780189 -100.134331) (xy 150.814331 -100.091967)
			(xy 150.854145 -100.054883) (xy 150.898822 -100.023829) (xy 150.947456 -99.999437) (xy 150.999063 -99.982199)
			(xy 151.052595 -99.972467) (xy 151.106966 -99.970437) (xy 151.134064 -99.972876) (xy 151.157637 -99.974817)
			(xy 151.204773 -99.970953) (xy 151.250381 -99.958436) (xy 151.292886 -99.937696) (xy 151.33082 -99.909452)
			(xy 151.362874 -99.874676) (xy 151.38794 -99.834572) (xy 151.405155 -99.790521) (xy 151.413923 -99.744047)
			(xy 151.41448 -99.7204) (xy 151.41448 -99.673156) (xy 151.40305 -99.64801) (xy 151.392113 -99.622991)
			(xy 151.376702 -99.570609) (xy 151.368919 -99.516565) (xy 151.368924 -99.461963) (xy 151.376717 -99.40792)
			(xy 151.392138 -99.35554) (xy 151.40305 -99.33051) (xy 151.41448 -99.305364) (xy 151.41448 -98.560382)
			(xy 151.57958 -98.395282) (xy 151.57958 -96.793558) (xy 137.59307 -82.807048) (xy 129.557526 -82.807048)
			(xy 128.76276 -83.601814) (xy 128.76276 -90.494104) (xy 128.763272 -90.510887) (xy 128.772023 -90.543292)
			(xy 128.78892 -90.572294) (xy 128.812793 -90.595889) (xy 128.841992 -90.612445) (xy 128.874497 -90.620816)
			(xy 128.891284 -90.621104) (xy 128.933969 -90.621084) (xy 129.019036 -90.628218) (xy 129.103027 -90.643469)
			(xy 129.185172 -90.666696) (xy 129.264713 -90.697684) (xy 129.34092 -90.73615) (xy 129.413092 -90.78174)
			(xy 129.480565 -90.834034) (xy 129.542717 -90.89255) (xy 129.598979 -90.956752) (xy 129.648831 -91.026048)
			(xy 129.691815 -91.099801) (xy 129.727537 -91.177333) (xy 129.755667 -91.25793) (xy 129.775946 -91.340851)
			(xy 129.788189 -91.425333) (xy 129.792283 -91.5106) (xy 129.788189 -91.595867) (xy 129.775947 -91.680349)
			(xy 129.755667 -91.76327) (xy 129.727537 -91.843867) (xy 129.691815 -91.921399) (xy 129.648831 -91.995152)
			(xy 129.598979 -92.064448) (xy 129.542718 -92.128649) (xy 129.480565 -92.187166) (xy 129.413092 -92.23946)
			(xy 129.340921 -92.285049) (xy 129.264714 -92.323516) (xy 129.185172 -92.354504) (xy 129.103028 -92.377731)
			(xy 129.019036 -92.392981) (xy 128.93397 -92.400116) (xy 128.891284 -92.40012) (xy 128.874501 -92.400435)
			(xy 128.842005 -92.408805) (xy 128.812816 -92.425357) (xy 128.788952 -92.448948) (xy 128.772064 -92.477945)
			(xy 128.76332 -92.510342) (xy 128.76276 -92.52712) (xy 128.76276 -96.044258) (xy 138.929362 -96.044258)
			(xy 138.933433 -95.988636) (xy 138.945559 -95.934199) (xy 138.965482 -95.882108) (xy 138.992778 -95.833473)
			(xy 139.026864 -95.78933) (xy 139.067013 -95.750621) (xy 139.112371 -95.71817) (xy 139.161971 -95.692669)
			(xy 139.214755 -95.674662) (xy 139.269598 -95.664532) (xy 139.325332 -95.662495) (xy 139.380769 -95.668595)
			(xy 139.434726 -95.682701) (xy 139.486055 -95.704513) (xy 139.533661 -95.733567) (xy 139.576529 -95.769242)
			(xy 139.613746 -95.810779) (xy 139.644519 -95.857292) (xy 139.668191 -95.907789) (xy 139.684259 -95.961196)
			(xy 139.692379 -96.016372) (xy 139.692888 -96.044258) (xy 139.692379 -96.072144) (xy 139.684259 -96.12732)
			(xy 139.668191 -96.180727) (xy 139.644519 -96.231224) (xy 139.613746 -96.277737) (xy 139.576529 -96.319274)
			(xy 139.533661 -96.354949) (xy 139.486055 -96.384003) (xy 139.434726 -96.405815) (xy 139.380769 -96.419921)
			(xy 139.325332 -96.426021) (xy 139.269598 -96.423984) (xy 139.214755 -96.413854) (xy 139.161971 -96.395847)
			(xy 139.112371 -96.370346) (xy 139.067013 -96.337895) (xy 139.026864 -96.299186) (xy 138.992778 -96.255043)
			(xy 138.965482 -96.206408) (xy 138.945559 -96.154317) (xy 138.933433 -96.09988) (xy 138.929362 -96.044258)
			(xy 128.76276 -96.044258) (xy 128.76276 -96.592136) (xy 130.944162 -98.773538) (xy 139.84929 -98.773538)
			(xy 139.856194 -98.718909) (xy 139.870879 -98.665839) (xy 139.89304 -98.615432) (xy 139.922217 -98.568733)
			(xy 139.957804 -98.526714) (xy 139.999062 -98.490247) (xy 140.045133 -98.46009) (xy 140.095061 -98.436868)
			(xy 140.147808 -98.421065) (xy 140.202279 -98.413008) (xy 140.257343 -98.412865) (xy 140.311855 -98.420639)
			(xy 140.364684 -98.436168) (xy 140.414732 -98.459131) (xy 140.460959 -98.489049) (xy 140.502405 -98.525301)
			(xy 140.520674 -98.545904) (xy 140.535878 -98.562991) (xy 140.571367 -98.591838) (xy 140.611445 -98.613872)
			(xy 140.654817 -98.628383) (xy 140.700086 -98.634901) (xy 140.74579 -98.633217) (xy 140.790456 -98.623386)
			(xy 140.832643 -98.605723) (xy 140.87099 -98.5808) (xy 140.887958 -98.565462) (xy 140.908289 -98.546893)
			(xy 140.953374 -98.515282) (xy 141.002534 -98.49048) (xy 141.054748 -98.473002) (xy 141.108933 -98.463211)
			(xy 141.163963 -98.461311) (xy 141.218694 -98.467341) (xy 141.27199 -98.481175) (xy 141.322744 -98.502526)
			(xy 141.369902 -98.530952) (xy 141.412484 -98.565861) (xy 141.449605 -98.606529) (xy 141.480496 -98.65211)
			(xy 141.504513 -98.701658) (xy 141.521159 -98.754144) (xy 141.530087 -98.808478) (xy 141.531112 -98.86353)
			(xy 141.524214 -98.918159) (xy 141.509534 -98.971228) (xy 141.487378 -99.021636) (xy 141.458206 -99.068336)
			(xy 141.422625 -99.110358) (xy 141.381372 -99.146828) (xy 141.335306 -99.17699) (xy 141.285382 -99.200217)
			(xy 141.232638 -99.216026) (xy 141.178169 -99.224089) (xy 141.123107 -99.224239) (xy 141.068595 -99.216473)
			(xy 141.015766 -99.200951) (xy 140.965716 -99.177997) (xy 140.919486 -99.148087) (xy 140.878036 -99.111842)
			(xy 140.859764 -99.091242) (xy 140.844521 -99.074191) (xy 140.80904 -99.045339) (xy 140.76897 -99.023299)
			(xy 140.725603 -99.008784) (xy 140.680339 -99.00226) (xy 140.634639 -99.00394) (xy 140.589976 -99.013767)
			(xy 140.547791 -99.031427) (xy 140.509447 -99.056347) (xy 140.49248 -99.071684) (xy 140.472106 -99.090209)
			(xy 140.42702 -99.12182) (xy 140.377858 -99.146622) (xy 140.325642 -99.164099) (xy 140.271455 -99.173889)
			(xy 140.216424 -99.175788) (xy 140.161692 -99.169756) (xy 140.108395 -99.155919) (xy 140.05764 -99.134564)
			(xy 140.010483 -99.106136) (xy 139.967901 -99.071223) (xy 139.930781 -99.030552) (xy 139.899893 -98.984968)
			(xy 139.875878 -98.935417) (xy 139.859236 -98.882928) (xy 139.850311 -98.828592) (xy 139.84929 -98.773538)
			(xy 130.944162 -98.773538) (xy 134.22249 -102.051866) (xy 137.710418 -102.051866) (xy 138.949176 -103.290624)
			(xy 138.949176 -103.413945) (xy 139.257896 -103.413945) (xy 139.266011 -103.358764) (xy 139.282072 -103.305352)
			(xy 139.305737 -103.254847) (xy 139.336501 -103.208325) (xy 139.373711 -103.166777) (xy 139.416572 -103.131088)
			(xy 139.464172 -103.102019) (xy 139.515497 -103.080189) (xy 139.569452 -103.066062) (xy 139.62489 -103.05994)
			(xy 139.680628 -103.061954) (xy 139.735479 -103.07206) (xy 139.788274 -103.090043) (xy 139.83789 -103.11552)
			(xy 139.883268 -103.147948) (xy 139.903708 -103.166926) (xy 139.919599 -103.181596) (xy 139.955402 -103.205852)
			(xy 139.994795 -103.223697) (xy 140.03664 -103.234614) (xy 140.07973 -103.238288) (xy 140.12282 -103.234614)
			(xy 140.164665 -103.223697) (xy 140.204058 -103.205852) (xy 140.239861 -103.181596) (xy 140.255752 -103.166926)
			(xy 140.275825 -103.148255) (xy 140.320339 -103.11626) (xy 140.368974 -103.090964) (xy 140.420728 -103.072889)
			(xy 140.474536 -103.062407) (xy 140.52929 -103.059734) (xy 140.583864 -103.064923) (xy 140.637133 -103.07787)
			(xy 140.688001 -103.098306) (xy 140.73542 -103.125812) (xy 140.778415 -103.159822) (xy 140.8161 -103.199634)
			(xy 140.8477 -103.244429) (xy 140.872564 -103.293286) (xy 140.89018 -103.345198) (xy 140.900185 -103.399097)
			(xy 140.902374 -103.453873) (xy 140.896701 -103.508399) (xy 140.883283 -103.561551) (xy 140.862397 -103.612236)
			(xy 140.848842 -103.636064) (xy 140.838001 -103.655355) (xy 140.822459 -103.696781) (xy 140.81432 -103.740272)
			(xy 140.813831 -103.784516) (xy 140.821006 -103.828176) (xy 140.835628 -103.869937) (xy 140.857257 -103.908536)
			(xy 140.88524 -103.94281) (xy 140.901674 -103.957628) (xy 140.922489 -103.976256) (xy 140.95903 -104.018504)
			(xy 140.989021 -104.065627) (xy 141.011822 -104.116619) (xy 141.026947 -104.17039) (xy 141.034071 -104.225791)
			(xy 141.033043 -104.281639) (xy 141.023884 -104.336741) (xy 141.006791 -104.389919) (xy 140.982128 -104.440037)
			(xy 140.950423 -104.486024) (xy 140.912352 -104.526898) (xy 140.868729 -104.561785) (xy 140.820487 -104.589941)
			(xy 140.768655 -104.610763) (xy 140.714342 -104.623807) (xy 140.658708 -104.628793) (xy 140.60294 -104.625616)
			(xy 140.548232 -104.614344) (xy 140.495752 -104.595216) (xy 140.44662 -104.568643) (xy 140.401887 -104.535191)
			(xy 140.362509 -104.495575) (xy 140.329326 -104.450642) (xy 140.303048 -104.401352) (xy 140.284236 -104.348757)
			(xy 140.273293 -104.293982) (xy 140.270451 -104.238197) (xy 140.275772 -104.182594) (xy 140.289142 -104.12836)
			(xy 140.310275 -104.076654) (xy 140.324078 -104.05237) (xy 140.334879 -104.033058) (xy 140.350423 -103.991637)
			(xy 140.358565 -103.948151) (xy 140.359059 -103.903912) (xy 140.351889 -103.860255) (xy 140.337273 -103.818498)
			(xy 140.315651 -103.779899) (xy 140.287676 -103.745625) (xy 140.271246 -103.730806) (xy 140.255752 -103.716582)
			(xy 140.239861 -103.701912) (xy 140.204058 -103.677656) (xy 140.164665 -103.659811) (xy 140.12282 -103.648894)
			(xy 140.07973 -103.64522) (xy 140.03664 -103.648894) (xy 139.994795 -103.659811) (xy 139.955402 -103.677656)
			(xy 139.919599 -103.701912) (xy 139.903708 -103.716582) (xy 139.883317 -103.735611) (xy 139.837944 -103.768047)
			(xy 139.788333 -103.793532) (xy 139.73554 -103.811524) (xy 139.680691 -103.821639) (xy 139.624953 -103.823662)
			(xy 139.569515 -103.81755) (xy 139.515557 -103.803432) (xy 139.464229 -103.78161) (xy 139.416624 -103.752549)
			(xy 139.373757 -103.716867) (xy 139.33654 -103.675326) (xy 139.305768 -103.628809) (xy 139.282094 -103.578308)
			(xy 139.266025 -103.524899) (xy 139.257901 -103.469719) (xy 139.257896 -103.413945) (xy 138.949176 -103.413945)
			(xy 138.949176 -104.825009) (xy 143.206766 -104.825009) (xy 143.210891 -104.769911) (xy 143.222923 -104.715984)
			(xy 143.24261 -104.664357) (xy 143.26954 -104.616112) (xy 143.303149 -104.572256) (xy 143.342734 -104.533709)
			(xy 143.387467 -104.501277) (xy 143.436412 -104.475639) (xy 143.488543 -104.457331) (xy 143.542771 -104.446736)
			(xy 143.597959 -104.444077) (xy 143.652954 -104.449408) (xy 143.706605 -104.462619) (xy 143.757787 -104.483432)
			(xy 143.805432 -104.511413) (xy 143.84854 -104.545975) (xy 143.88621 -104.586396) (xy 143.917654 -104.631829)
			(xy 143.942214 -104.681323) (xy 143.959375 -104.733843) (xy 143.968779 -104.78829) (xy 143.969994 -104.815894)
			(xy 143.97098 -104.837275) (xy 143.979292 -104.87926) (xy 143.99452 -104.919259) (xy 144.016232 -104.956143)
			(xy 144.043817 -104.988868) (xy 144.076493 -105.01651) (xy 144.113339 -105.038287) (xy 144.153311 -105.053584)
			(xy 144.17421 -105.05821) (xy 144.201197 -105.064128) (xy 144.253236 -105.08268) (xy 144.302054 -105.108547)
			(xy 144.346629 -105.141187) (xy 144.386029 -105.179916) (xy 144.419428 -105.223925) (xy 144.446128 -105.272292)
			(xy 144.465571 -105.324006) (xy 144.477349 -105.377983) (xy 144.481216 -105.433095) (xy 144.47709 -105.488188)
			(xy 144.46506 -105.54211) (xy 144.445375 -105.593732) (xy 144.418448 -105.641973) (xy 144.384843 -105.685825)
			(xy 144.345262 -105.724369) (xy 144.300535 -105.756799) (xy 144.251596 -105.782437) (xy 144.199471 -105.800746)
			(xy 144.145249 -105.811342) (xy 144.090066 -105.814005) (xy 144.035076 -105.808678) (xy 143.98143 -105.795472)
			(xy 143.93025 -105.774665) (xy 143.882608 -105.746692) (xy 143.839501 -105.712137) (xy 143.80183 -105.671724)
			(xy 143.770384 -105.626299) (xy 143.745821 -105.576812) (xy 143.728655 -105.524299) (xy 143.719245 -105.469859)
			(xy 143.718026 -105.442258) (xy 143.716979 -105.420881) (xy 143.708676 -105.378899) (xy 143.693458 -105.338902)
			(xy 143.671754 -105.302019) (xy 143.644178 -105.269294) (xy 143.611509 -105.24165) (xy 143.574672 -105.21987)
			(xy 143.534706 -105.204569) (xy 143.51381 -105.199942) (xy 143.486825 -105.193998) (xy 143.43478 -105.175447)
			(xy 143.385956 -105.149581) (xy 143.341374 -105.11694) (xy 143.301969 -105.078209) (xy 143.268565 -105.034198)
			(xy 143.24186 -104.985827) (xy 143.222414 -104.934109) (xy 143.210634 -104.880127) (xy 143.206766 -104.825009)
			(xy 138.949176 -104.825009) (xy 138.949176 -106.498644) (xy 139.022328 -106.571796) (xy 139.022328 -107.57535)
			(xy 149.241762 -107.57535) (xy 149.245833 -107.519728) (xy 149.257959 -107.465291) (xy 149.277882 -107.4132)
			(xy 149.305178 -107.364565) (xy 149.339264 -107.320422) (xy 149.379413 -107.281713) (xy 149.424771 -107.249262)
			(xy 149.474371 -107.223761) (xy 149.527155 -107.205754) (xy 149.581998 -107.195624) (xy 149.637732 -107.193587)
			(xy 149.693169 -107.199687) (xy 149.747126 -107.213793) (xy 149.798455 -107.235605) (xy 149.846061 -107.264659)
			(xy 149.888929 -107.300334) (xy 149.926146 -107.341871) (xy 149.956919 -107.388384) (xy 149.980591 -107.438881)
			(xy 149.996659 -107.492288) (xy 150.004779 -107.547464) (xy 150.005288 -107.57535) (xy 150.004779 -107.603236)
			(xy 149.996659 -107.658412) (xy 149.980591 -107.711819) (xy 149.956919 -107.762316) (xy 149.926146 -107.808829)
			(xy 149.888929 -107.850366) (xy 149.846061 -107.886041) (xy 149.798455 -107.915095) (xy 149.747126 -107.936907)
			(xy 149.693169 -107.951013) (xy 149.637732 -107.957113) (xy 149.581998 -107.955076) (xy 149.527155 -107.944946)
			(xy 149.474371 -107.926939) (xy 149.424771 -107.901438) (xy 149.379413 -107.868987) (xy 149.339264 -107.830278)
			(xy 149.305178 -107.786135) (xy 149.277882 -107.7375) (xy 149.257959 -107.685409) (xy 149.245833 -107.630972)
			(xy 149.241762 -107.57535) (xy 139.022328 -107.57535) (xy 139.022328 -108.01731) (xy 144.45234 -113.447322)
			(xy 144.45234 -113.840768) (xy 146.640802 -113.840768) (xy 146.644873 -113.785146) (xy 146.656999 -113.730709)
			(xy 146.676922 -113.678618) (xy 146.704218 -113.629983) (xy 146.738304 -113.58584) (xy 146.778453 -113.547131)
			(xy 146.823811 -113.51468) (xy 146.873411 -113.489179) (xy 146.926195 -113.471172) (xy 146.981038 -113.461042)
			(xy 147.036772 -113.459005) (xy 147.092209 -113.465105) (xy 147.146166 -113.479211) (xy 147.197495 -113.501023)
			(xy 147.245101 -113.530077) (xy 147.287969 -113.565752) (xy 147.325186 -113.607289) (xy 147.355959 -113.653802)
			(xy 147.379631 -113.704299) (xy 147.395699 -113.757706) (xy 147.403819 -113.812882) (xy 147.404328 -113.840768)
			(xy 147.403819 -113.868654) (xy 147.395699 -113.92383) (xy 147.379631 -113.977237) (xy 147.355959 -114.027734)
			(xy 147.325186 -114.074247) (xy 147.287969 -114.115784) (xy 147.245101 -114.151459) (xy 147.197495 -114.180513)
			(xy 147.146166 -114.202325) (xy 147.092209 -114.216431) (xy 147.036772 -114.222531) (xy 146.981038 -114.220494)
			(xy 146.926195 -114.210364) (xy 146.873411 -114.192357) (xy 146.823811 -114.166856) (xy 146.778453 -114.134405)
			(xy 146.738304 -114.095696) (xy 146.704218 -114.051553) (xy 146.676922 -114.002918) (xy 146.656999 -113.950827)
			(xy 146.644873 -113.89639) (xy 146.640802 -113.840768) (xy 144.45234 -113.840768) (xy 144.45234 -114.332512)
			(xy 149.757382 -114.332512) (xy 149.761453 -114.27689) (xy 149.773579 -114.222453) (xy 149.793502 -114.170362)
			(xy 149.820798 -114.121727) (xy 149.854884 -114.077584) (xy 149.895033 -114.038875) (xy 149.940391 -114.006424)
			(xy 149.989991 -113.980923) (xy 150.042775 -113.962916) (xy 150.097618 -113.952786) (xy 150.153352 -113.950749)
			(xy 150.208789 -113.956849) (xy 150.262746 -113.970955) (xy 150.314075 -113.992767) (xy 150.361681 -114.021821)
			(xy 150.404549 -114.057496) (xy 150.441766 -114.099033) (xy 150.472539 -114.145546) (xy 150.496211 -114.196043)
			(xy 150.512279 -114.24945) (xy 150.520399 -114.304626) (xy 150.520908 -114.332512) (xy 150.520399 -114.360398)
			(xy 150.512279 -114.415574) (xy 150.496211 -114.468981) (xy 150.472539 -114.519478) (xy 150.441766 -114.565991)
			(xy 150.404549 -114.607528) (xy 150.361681 -114.643203) (xy 150.314075 -114.672257) (xy 150.262746 -114.694069)
			(xy 150.208789 -114.708175) (xy 150.153352 -114.714275) (xy 150.097618 -114.712238) (xy 150.042775 -114.702108)
			(xy 149.989991 -114.684101) (xy 149.940391 -114.6586) (xy 149.895033 -114.626149) (xy 149.854884 -114.58744)
			(xy 149.820798 -114.543297) (xy 149.793502 -114.494662) (xy 149.773579 -114.442571) (xy 149.761453 -114.388134)
			(xy 149.757382 -114.332512) (xy 144.45234 -114.332512) (xy 144.45234 -115.843304) (xy 149.660862 -115.843304)
			(xy 149.664933 -115.787682) (xy 149.677059 -115.733245) (xy 149.696982 -115.681154) (xy 149.724278 -115.632519)
			(xy 149.758364 -115.588376) (xy 149.798513 -115.549667) (xy 149.843871 -115.517216) (xy 149.893471 -115.491715)
			(xy 149.946255 -115.473708) (xy 150.001098 -115.463578) (xy 150.056832 -115.461541) (xy 150.112269 -115.467641)
			(xy 150.166226 -115.481747) (xy 150.217555 -115.503559) (xy 150.265161 -115.532613) (xy 150.308029 -115.568288)
			(xy 150.345246 -115.609825) (xy 150.376019 -115.656338) (xy 150.399691 -115.706835) (xy 150.415759 -115.760242)
			(xy 150.423879 -115.815418) (xy 150.424388 -115.843304) (xy 150.423879 -115.87119) (xy 150.415759 -115.926366)
			(xy 150.399691 -115.979773) (xy 150.376019 -116.03027) (xy 150.345246 -116.076783) (xy 150.308029 -116.11832)
			(xy 150.265161 -116.153995) (xy 150.217555 -116.183049) (xy 150.166226 -116.204861) (xy 150.112269 -116.218967)
			(xy 150.056832 -116.225067) (xy 150.001098 -116.22303) (xy 149.946255 -116.2129) (xy 149.893471 -116.194893)
			(xy 149.843871 -116.169392) (xy 149.798513 -116.136941) (xy 149.758364 -116.098232) (xy 149.724278 -116.054089)
			(xy 149.696982 -116.005454) (xy 149.677059 -115.953363) (xy 149.664933 -115.898926) (xy 149.660862 -115.843304)
			(xy 144.45234 -115.843304) (xy 144.45234 -116.738146) (xy 149.008844 -116.738146) (xy 149.012915 -116.682524)
			(xy 149.025041 -116.628087) (xy 149.044964 -116.575996) (xy 149.07226 -116.527361) (xy 149.106346 -116.483218)
			(xy 149.146495 -116.444509) (xy 149.191853 -116.412058) (xy 149.241453 -116.386557) (xy 149.294237 -116.36855)
			(xy 149.34908 -116.35842) (xy 149.404814 -116.356383) (xy 149.460251 -116.362483) (xy 149.514208 -116.376589)
			(xy 149.565537 -116.398401) (xy 149.613143 -116.427455) (xy 149.656011 -116.46313) (xy 149.693228 -116.504667)
			(xy 149.724001 -116.55118) (xy 149.747673 -116.601677) (xy 149.763741 -116.655084) (xy 149.771861 -116.71026)
			(xy 149.77237 -116.738146) (xy 149.771861 -116.766032) (xy 149.763741 -116.821208) (xy 149.747673 -116.874615)
			(xy 149.724001 -116.925112) (xy 149.693228 -116.971625) (xy 149.656011 -117.013162) (xy 149.613143 -117.048837)
			(xy 149.565537 -117.077891) (xy 149.514208 -117.099703) (xy 149.460251 -117.113809) (xy 149.404814 -117.119909)
			(xy 149.34908 -117.117872) (xy 149.294237 -117.107742) (xy 149.241453 -117.089735) (xy 149.191853 -117.064234)
			(xy 149.146495 -117.031783) (xy 149.106346 -116.993074) (xy 149.07226 -116.948931) (xy 149.044964 -116.900296)
			(xy 149.025041 -116.848205) (xy 149.012915 -116.793768) (xy 149.008844 -116.738146) (xy 144.45234 -116.738146)
			(xy 144.45234 -117.948354) (xy 145.017746 -117.948354) (xy 145.020305 -117.892913) (xy 145.030868 -117.838428)
			(xy 145.049213 -117.786048) (xy 145.074952 -117.736878) (xy 145.107544 -117.691956) (xy 145.146299 -117.652229)
			(xy 145.190401 -117.618535) (xy 145.238918 -117.591586) (xy 145.290828 -117.571951) (xy 145.345035 -117.560042)
			(xy 145.400396 -117.556112) (xy 145.455741 -117.560244) (xy 145.509905 -117.572349) (xy 145.561743 -117.592174)
			(xy 145.586196 -117.605302) (xy 145.605335 -117.615509) (xy 145.646229 -117.629962) (xy 145.688983 -117.637263)
			(xy 145.732356 -117.6372) (xy 145.775088 -117.629774) (xy 145.81594 -117.615202) (xy 145.853725 -117.593906)
			(xy 145.887346 -117.566505) (xy 145.901918 -117.550438) (xy 145.920568 -117.52988) (xy 145.962686 -117.493736)
			(xy 146.009597 -117.464074) (xy 146.06031 -117.441522) (xy 146.113755 -117.426555) (xy 146.168805 -117.419488)
			(xy 146.224298 -117.420472) (xy 146.279063 -117.429484) (xy 146.331944 -117.446335) (xy 146.381826 -117.47067)
			(xy 146.427657 -117.501975) (xy 146.468469 -117.539589) (xy 146.5034 -117.582719) (xy 146.531715 -117.630454)
			(xy 146.552816 -117.681788) (xy 146.566257 -117.735638) (xy 146.571755 -117.790866) (xy 146.569193 -117.846308)
			(xy 146.558626 -117.900795) (xy 146.540278 -117.953175) (xy 146.514534 -118.002345) (xy 146.481938 -118.047267)
			(xy 146.443178 -118.086992) (xy 146.399072 -118.120683) (xy 146.350551 -118.147628) (xy 146.298637 -118.16726)
			(xy 146.244427 -118.179164) (xy 146.189065 -118.183088) (xy 146.133718 -118.178951) (xy 146.079554 -118.166838)
			(xy 146.027717 -118.147007) (xy 146.003264 -118.133876) (xy 145.984154 -118.12361) (xy 145.943252 -118.109155)
			(xy 145.900491 -118.101856) (xy 145.857111 -118.101925) (xy 145.814372 -118.109358) (xy 145.773517 -118.123941)
			(xy 145.735731 -118.14525) (xy 145.702112 -118.172666) (xy 145.687542 -118.18874) (xy 145.668926 -118.209326)
			(xy 145.626808 -118.245468) (xy 145.579898 -118.275128) (xy 145.529187 -118.297679) (xy 145.475743 -118.312645)
			(xy 145.420695 -118.319711) (xy 145.365204 -118.318728) (xy 145.310441 -118.309717) (xy 145.257561 -118.292866)
			(xy 145.20768 -118.268533) (xy 145.16185 -118.237231) (xy 145.121039 -118.199619) (xy 145.086107 -118.156492)
			(xy 145.057791 -118.108759) (xy 145.03669 -118.057427) (xy 145.023247 -118.00358) (xy 145.017746 -117.948354)
			(xy 144.45234 -117.948354) (xy 144.45234 -119.21108) (xy 145.017885 -119.21108) (xy 145.021351 -119.156679)
			(xy 145.032526 -119.103326) (xy 145.051183 -119.052107) (xy 145.076942 -119.004065) (xy 145.109277 -118.96018)
			(xy 145.147531 -118.921346) (xy 145.190924 -118.888353) (xy 145.238572 -118.861873) (xy 145.289504 -118.842447)
			(xy 145.342683 -118.830469) (xy 145.397025 -118.826184) (xy 145.451424 -118.829679) (xy 145.504772 -118.840883)
			(xy 145.555981 -118.859567) (xy 145.604008 -118.885352) (xy 145.647876 -118.917711) (xy 145.68669 -118.955985)
			(xy 145.703544 -118.97741) (xy 145.717654 -118.995205) (xy 145.751133 -119.025887) (xy 145.789526 -119.05014)
			(xy 145.831614 -119.067194) (xy 145.876061 -119.076507) (xy 145.921455 -119.077785) (xy 145.966355 -119.070986)
			(xy 146.009335 -119.056327) (xy 146.029426 -119.045736) (xy 146.053437 -119.032823) (xy 146.104354 -119.013333)
			(xy 146.157527 -119.00129) (xy 146.211872 -118.99694) (xy 146.266284 -119.000371) (xy 146.319653 -119.011514)
			(xy 146.370892 -119.030141) (xy 146.418957 -119.055873) (xy 146.462869 -119.088186) (xy 146.501733 -119.126421)
			(xy 146.534758 -119.1698) (xy 146.561271 -119.217439) (xy 146.580732 -119.268367) (xy 146.592743 -119.321547)
			(xy 146.597062 -119.375895) (xy 146.593599 -119.430305) (xy 146.582425 -119.483667) (xy 146.563768 -119.534895)
			(xy 146.538008 -119.582945) (xy 146.50567 -119.626838) (xy 146.467411 -119.66568) (xy 146.424013 -119.69868)
			(xy 146.376359 -119.725165) (xy 146.32542 -119.744596) (xy 146.272233 -119.756577) (xy 146.217882 -119.760864)
			(xy 146.163474 -119.757369) (xy 146.110119 -119.746164) (xy 146.058902 -119.727477) (xy 146.010867 -119.701689)
			(xy 145.966992 -119.669325) (xy 145.928173 -119.631044) (xy 145.911316 -119.609616) (xy 145.897146 -119.591871)
			(xy 145.863678 -119.561187) (xy 145.825296 -119.53693) (xy 145.783218 -119.51987) (xy 145.73878 -119.51055)
			(xy 145.693394 -119.509264) (xy 145.6485 -119.516054) (xy 145.605523 -119.530704) (xy 145.585434 -119.54129)
			(xy 145.5614 -119.554153) (xy 145.510489 -119.573635) (xy 145.457323 -119.585669) (xy 145.402985 -119.590013)
			(xy 145.348582 -119.586576) (xy 145.295223 -119.57543) (xy 145.243994 -119.556801) (xy 145.195939 -119.531068)
			(xy 145.152036 -119.498756) (xy 145.113181 -119.460523) (xy 145.080165 -119.417148) (xy 145.05366 -119.369514)
			(xy 145.034206 -119.318593) (xy 145.0222 -119.26542) (xy 145.017885 -119.21108) (xy 144.45234 -119.21108)
			(xy 144.45234 -121.369582) (xy 143.181832 -122.64009) (xy 143.170236 -122.652387) (xy 143.153402 -122.681684)
			(xy 143.144854 -122.714373) (xy 143.145193 -122.74816) (xy 143.14932 -122.76455) (xy 143.159226 -122.799348)
			(xy 143.166592 -122.812556) (xy 143.179894 -122.83713) (xy 143.199954 -122.889281) (xy 143.212193 -122.943801)
			(xy 143.216349 -122.999523) (xy 143.212333 -123.055255) (xy 143.20023 -123.109805) (xy 143.180299 -123.162007)
			(xy 143.152968 -123.210743) (xy 143.11882 -123.254971) (xy 143.078586 -123.293745) (xy 143.033127 -123.326236)
			(xy 142.983414 -123.351748) (xy 142.930512 -123.369736) (xy 142.875552 -123.379816) (xy 142.819709 -123.381771)
			(xy 142.764179 -123.375559) (xy 142.710148 -123.361314) (xy 142.658774 -123.339341) (xy 142.634716 -123.325128)
			(xy 142.619936 -123.316683) (xy 142.58727 -123.307152) (xy 142.553248 -123.306572) (xy 142.520276 -123.314985)
			(xy 142.49069 -123.331795) (xy 142.478252 -123.343416) (xy 138.037316 -127.784352) (xy 133.55955 -127.784352)
			(xy 133.361284 -127.982618) (xy 142.266876 -127.982618) (xy 142.271543 -127.92712) (xy 142.28423 -127.872889)
			(xy 142.304666 -127.82108) (xy 142.332418 -127.772793) (xy 142.366895 -127.729053) (xy 142.407366 -127.690791)
			(xy 142.452969 -127.658819) (xy 142.502737 -127.633818) (xy 142.55561 -127.616318) (xy 142.610466 -127.606691)
			(xy 142.666139 -127.605142) (xy 142.721445 -127.611704) (xy 142.77521 -127.626237) (xy 142.826291 -127.648432)
			(xy 142.873601 -127.677819) (xy 142.916137 -127.713771) (xy 142.934944 -127.734314) (xy 142.945983 -127.746206)
			(xy 142.972874 -127.764351) (xy 143.003472 -127.775127) (xy 143.035799 -127.777836) (xy 143.067764 -127.772302)
			(xy 143.097299 -127.758884) (xy 143.110204 -127.749046) (xy 143.13222 -127.731995) (xy 143.180158 -127.703666)
			(xy 143.231706 -127.682608) (xy 143.285767 -127.669269) (xy 143.341193 -127.663931) (xy 143.396806 -127.666708)
			(xy 143.451425 -127.677541) (xy 143.503888 -127.6962) (xy 143.553081 -127.722288) (xy 143.597959 -127.755252)
			(xy 143.637567 -127.794389) (xy 143.671063 -127.83887) (xy 143.697737 -127.887748) (xy 143.717022 -127.939985)
			(xy 143.728506 -127.99447) (xy 143.731947 -128.050046) (xy 143.727272 -128.105532) (xy 143.714579 -128.159749)
			(xy 143.694138 -128.211544) (xy 143.666384 -128.259817) (xy 143.631906 -128.303541) (xy 143.591438 -128.341789)
			(xy 143.545839 -128.373747) (xy 143.496078 -128.398735) (xy 143.443213 -128.416223) (xy 143.388367 -128.425839)
			(xy 143.332706 -128.427379) (xy 143.277412 -128.42081) (xy 143.223661 -128.406272) (xy 143.172594 -128.384074)
			(xy 143.125298 -128.354686) (xy 143.082777 -128.318735) (xy 143.063976 -128.298194) (xy 143.052918 -128.286321)
			(xy 143.026033 -128.268173) (xy 142.995439 -128.257395) (xy 142.963116 -128.254683) (xy 142.931154 -128.260212)
			(xy 142.90162 -128.273626) (xy 142.888716 -128.283462) (xy 142.866783 -128.300626) (xy 142.818841 -128.32897)
			(xy 142.767287 -128.350042) (xy 142.713217 -128.363395) (xy 142.65778 -128.368744) (xy 142.602154 -128.365977)
			(xy 142.547522 -128.355151) (xy 142.495044 -128.336498) (xy 142.445836 -128.310413) (xy 142.400944 -128.277451)
			(xy 142.361321 -128.238312) (xy 142.327809 -128.193828) (xy 142.301121 -128.144944) (xy 142.281823 -128.0927)
			(xy 142.270327 -128.038205) (xy 142.266876 -127.982618) (xy 133.361284 -127.982618) (xy 132.075174 -129.268728)
			(xy 132.059107 -129.285535) (xy 132.03277 -129.323848) (xy 132.013846 -129.366313) (xy 132.002965 -129.411513)
			(xy 132.000493 -129.457939) (xy 132.00651 -129.504039) (xy 132.020817 -129.548274) (xy 132.042935 -129.589167)
			(xy 132.072125 -129.625352) (xy 132.080222 -129.632297) (xy 137.888473 -129.632297) (xy 137.888962 -129.5766)
			(xy 137.897542 -129.521565) (xy 137.914029 -129.468362) (xy 137.938074 -129.41812) (xy 137.969166 -129.371906)
			(xy 138.006644 -129.330702) (xy 138.049713 -129.295383) (xy 138.097459 -129.266698) (xy 138.148866 -129.245257)
			(xy 138.202843 -129.231515) (xy 138.258245 -129.225765) (xy 138.313894 -129.228127) (xy 138.368609 -129.238553)
			(xy 138.421228 -129.25682) (xy 138.470633 -129.282541) (xy 138.4935 -129.298446) (xy 138.512912 -129.311866)
			(xy 138.555597 -129.331985) (xy 138.601264 -129.34387) (xy 138.648341 -129.347112) (xy 138.695206 -129.3416)
			(xy 138.740246 -129.327524) (xy 138.781909 -129.305368) (xy 138.818762 -129.275896) (xy 138.849534 -129.240122)
			(xy 138.8618 -129.21996) (xy 138.876217 -129.196137) (xy 138.91084 -129.152528) (xy 138.951433 -129.114414)
			(xy 138.997134 -129.082604) (xy 139.046973 -129.057774) (xy 139.099891 -129.04045) (xy 139.154765 -129.031001)
			(xy 139.21043 -129.029627) (xy 139.265703 -129.036358) (xy 139.319412 -129.05105) (xy 139.370415 -129.073392)
			(xy 139.417629 -129.102909) (xy 139.460053 -129.138974) (xy 139.496785 -129.180822) (xy 139.527044 -129.227564)
			(xy 139.55019 -129.278207) (xy 139.56573 -129.331676) (xy 139.573334 -129.386836) (xy 139.57284 -129.442516)
			(xy 139.56426 -129.497533) (xy 139.547776 -129.550718) (xy 139.533152 -129.581272) (xy 142.101659 -129.581272)
			(xy 142.105148 -129.526692) (xy 142.116393 -129.47317) (xy 142.135162 -129.4218) (xy 142.161072 -129.373636)
			(xy 142.193592 -129.329664) (xy 142.232056 -129.290784) (xy 142.275675 -129.257793) (xy 142.323558 -129.231366)
			(xy 142.374722 -129.212045) (xy 142.42812 -129.200226) (xy 142.482659 -129.196149) (xy 142.537221 -129.1999)
			(xy 142.590689 -129.211401) (xy 142.641968 -129.230416) (xy 142.666212 -129.243074) (xy 142.686081 -129.253361)
			(xy 142.728518 -129.267528) (xy 142.77278 -129.274037) (xy 142.817499 -129.272688) (xy 142.861289 -129.263522)
			(xy 142.902794 -129.246822) (xy 142.94073 -129.223106) (xy 142.973921 -129.193108) (xy 143.001341 -129.157757)
			(xy 143.01216 -129.138172) (xy 143.025252 -129.114156) (xy 143.057347 -129.069863) (xy 143.095436 -129.030606)
			(xy 143.138739 -128.997187) (xy 143.186369 -128.970292) (xy 143.23735 -128.950472) (xy 143.290639 -128.938132)
			(xy 143.345143 -128.933525) (xy 143.399747 -128.936745) (xy 143.453332 -128.947727) (xy 143.5048 -128.966245)
			(xy 143.553098 -128.991921) (xy 143.597237 -129.024228) (xy 143.636311 -129.062505) (xy 143.669522 -129.105968)
			(xy 143.696188 -129.153726) (xy 143.715764 -129.204802) (xy 143.727848 -129.258149) (xy 143.732194 -129.312675)
			(xy 143.728712 -129.367263) (xy 143.723255 -129.393254) (xy 144.862769 -129.393254) (xy 144.866327 -129.338305)
			(xy 144.877747 -129.284439) (xy 144.896792 -129.232774) (xy 144.923066 -129.184383) (xy 144.956023 -129.140272)
			(xy 144.99498 -129.101357) (xy 145.039126 -129.068446) (xy 145.087545 -129.042224) (xy 145.13923 -129.023234)
			(xy 145.193108 -129.011871) (xy 145.248061 -129.008372) (xy 145.302945 -129.012809) (xy 145.356622 -129.025089)
			(xy 145.407975 -129.044959) (xy 145.455939 -129.072004) (xy 145.499517 -129.105663) (xy 145.537804 -129.145238)
			(xy 145.570004 -129.189905) (xy 145.595448 -129.238737) (xy 145.613608 -129.29072) (xy 145.624107 -129.344773)
			(xy 145.626727 -129.399774) (xy 145.62455 -129.427224) (xy 145.622793 -129.450584) (xy 145.62688 -129.497246)
			(xy 145.639449 -129.542368) (xy 145.660075 -129.584423) (xy 145.688059 -129.621986) (xy 145.722452 -129.653784)
			(xy 145.76209 -129.678741) (xy 145.805631 -129.696011) (xy 145.828512 -129.701036) (xy 145.855416 -129.706885)
			(xy 145.907367 -129.725106) (xy 145.956159 -129.750606) (xy 146.000778 -129.782856) (xy 146.040298 -129.821184)
			(xy 146.073897 -129.864796) (xy 146.100878 -129.912785) (xy 146.12068 -129.964154) (xy 146.132891 -130.017836)
			(xy 146.136766 -130.066519) (xy 146.643574 -130.066519) (xy 146.648768 -130.012) (xy 146.661704 -129.958785)
			(xy 146.682117 -129.907966) (xy 146.709586 -129.860587) (xy 146.743547 -129.817624) (xy 146.783302 -129.779957)
			(xy 146.805396 -129.763774) (xy 146.823896 -129.750051) (xy 146.856078 -129.717105) (xy 146.881802 -129.678903)
			(xy 146.900227 -129.636694) (xy 146.910752 -129.591857) (xy 146.913031 -129.545858) (xy 146.906992 -129.5002)
			(xy 146.89283 -129.456375) (xy 146.882358 -129.43586) (xy 146.869794 -129.411523) (xy 146.850993 -129.360081)
			(xy 146.839742 -129.30648) (xy 146.836271 -129.25182) (xy 146.840652 -129.197226) (xy 146.852793 -129.143819)
			(xy 146.872447 -129.092697) (xy 146.899209 -129.044911) (xy 146.932529 -129.001443) (xy 146.971722 -128.963186)
			(xy 147.015983 -128.930926) (xy 147.064402 -128.905327) (xy 147.115983 -128.886914) (xy 147.169668 -128.876066)
			(xy 147.224352 -128.873006) (xy 147.278912 -128.877797) (xy 147.332226 -128.89034) (xy 147.383198 -128.910377)
			(xy 147.430782 -128.937498) (xy 147.473998 -128.971144) (xy 147.51196 -129.010623) (xy 147.543886 -129.055125)
			(xy 147.569121 -129.103735) (xy 147.587145 -129.155454) (xy 147.597589 -129.209218) (xy 147.600238 -129.263924)
			(xy 147.595037 -129.318446) (xy 147.582093 -129.371664) (xy 147.561673 -129.422485) (xy 147.534196 -129.469863)
			(xy 147.500226 -129.512825) (xy 147.460462 -129.550489) (xy 147.438364 -129.56667) (xy 147.419826 -129.580342)
			(xy 147.387647 -129.613299) (xy 147.361927 -129.65151) (xy 147.343506 -129.693728) (xy 147.332987 -129.738572)
			(xy 147.330714 -129.784577) (xy 147.33676 -129.830239) (xy 147.350928 -129.874067) (xy 147.361402 -129.894584)
			(xy 147.374002 -129.918899) (xy 147.392799 -129.970338) (xy 147.404047 -130.023936) (xy 147.407516 -130.078591)
			(xy 147.403134 -130.133181) (xy 147.390992 -130.186583) (xy 147.371339 -130.237701) (xy 147.344579 -130.285483)
			(xy 147.311262 -130.328948) (xy 147.272072 -130.367202) (xy 147.227815 -130.39946) (xy 147.179401 -130.425058)
			(xy 147.127823 -130.443471) (xy 147.074143 -130.45432) (xy 147.019464 -130.457382) (xy 146.964908 -130.452594)
			(xy 146.911598 -130.440054) (xy 146.860628 -130.420021) (xy 146.813046 -130.392906) (xy 146.769831 -130.359265)
			(xy 146.731869 -130.319792) (xy 146.699942 -130.275296) (xy 146.674705 -130.226692) (xy 146.656677 -130.174979)
			(xy 146.646228 -130.12122) (xy 146.643574 -130.066519) (xy 146.136766 -130.066519) (xy 146.137259 -130.072716)
			(xy 146.133691 -130.127654) (xy 146.122264 -130.181508) (xy 146.103213 -130.233161) (xy 146.076934 -130.281538)
			(xy 146.043974 -130.325635) (xy 146.005017 -130.364535) (xy 145.960873 -130.397431) (xy 145.912458 -130.42364)
			(xy 145.860778 -130.442616) (xy 145.806908 -130.453966) (xy 145.751965 -130.457454) (xy 145.697091 -130.453007)
			(xy 145.643427 -130.440718) (xy 145.592086 -130.420842) (xy 145.544136 -130.393792) (xy 145.500573 -130.36013)
			(xy 145.462302 -130.320555) (xy 145.430117 -130.27589) (xy 145.404687 -130.227061) (xy 145.386541 -130.175084)
			(xy 145.376055 -130.121038) (xy 145.373448 -130.066046) (xy 145.37563 -130.038602) (xy 145.377378 -130.015241)
			(xy 145.373295 -129.968579) (xy 145.360728 -129.923456) (xy 145.340104 -129.8814) (xy 145.312122 -129.843837)
			(xy 145.277729 -129.812038) (xy 145.23809 -129.787082) (xy 145.194549 -129.769814) (xy 145.171668 -129.76479)
			(xy 145.144727 -129.759102) (xy 145.092764 -129.740887) (xy 145.043959 -129.71539) (xy 144.999326 -129.683143)
			(xy 144.959792 -129.644814) (xy 144.926179 -129.6012) (xy 144.899185 -129.553207) (xy 144.879371 -129.501833)
			(xy 144.867147 -129.448143) (xy 144.862769 -129.393254) (xy 143.723255 -129.393254) (xy 143.717473 -129.420794)
			(xy 143.698709 -129.472173) (xy 143.672802 -129.520348) (xy 143.640283 -129.564331) (xy 143.601819 -129.603221)
			(xy 143.558198 -129.636223) (xy 143.510313 -129.66266) (xy 143.459144 -129.681991) (xy 143.405739 -129.69382)
			(xy 143.351193 -129.697904) (xy 143.296623 -129.694161) (xy 143.243146 -129.682666) (xy 143.191857 -129.663655)
			(xy 143.167608 -129.650998) (xy 143.147741 -129.640704) (xy 143.105304 -129.62653) (xy 143.061039 -129.620015)
			(xy 143.016318 -129.621362) (xy 142.972525 -129.630528) (xy 142.931018 -129.64723) (xy 142.893082 -129.67095)
			(xy 142.859892 -129.700954) (xy 142.832476 -129.736312) (xy 142.82166 -129.7559) (xy 142.808474 -129.779862)
			(xy 142.776377 -129.824144) (xy 142.738288 -129.86339) (xy 142.694986 -129.896798) (xy 142.647359 -129.923682)
			(xy 142.596382 -129.943493) (xy 142.5431 -129.955824) (xy 142.488602 -129.960422) (xy 142.434007 -129.957195)
			(xy 142.380431 -129.946207) (xy 142.328972 -129.927684) (xy 142.280685 -129.902005) (xy 142.236557 -129.869696)
			(xy 142.197494 -129.831419) (xy 142.164294 -129.787958) (xy 142.137638 -129.740203) (xy 142.118072 -129.689131)
			(xy 142.105997 -129.63579) (xy 142.101659 -129.581272) (xy 139.533152 -129.581272) (xy 139.523737 -129.600944)
			(xy 139.492653 -129.647142) (xy 139.455186 -129.688332) (xy 139.41213 -129.72364) (xy 139.3644 -129.752316)
			(xy 139.313009 -129.773751) (xy 139.259049 -129.787489) (xy 139.203665 -129.793239) (xy 139.148033 -129.79088)
			(xy 139.093335 -129.78046) (xy 139.040732 -129.762201) (xy 138.991341 -129.736492) (xy 138.96848 -129.720594)
			(xy 138.949072 -129.707169) (xy 138.906385 -129.687059) (xy 138.860719 -129.67518) (xy 138.813643 -129.671941)
			(xy 138.76678 -129.677454) (xy 138.721741 -129.69153) (xy 138.680078 -129.713683) (xy 138.643225 -129.743152)
			(xy 138.612449 -129.778921) (xy 138.60018 -129.79908) (xy 138.585812 -129.822942) (xy 138.551189 -129.866573)
			(xy 138.510592 -129.904708) (xy 138.464883 -129.936538) (xy 138.415034 -129.961386) (xy 138.362102 -129.978725)
			(xy 138.307212 -129.988187) (xy 138.25153 -129.989571) (xy 138.196238 -129.982848) (xy 138.14251 -129.968159)
			(xy 138.091488 -129.945818) (xy 138.044254 -129.916298) (xy 138.001813 -129.880226) (xy 137.965065 -129.83837)
			(xy 137.93479 -129.791616) (xy 137.911633 -129.740959) (xy 137.896083 -129.687474) (xy 137.888473 -129.632297)
			(xy 132.080222 -129.632297) (xy 132.107414 -129.65562) (xy 132.127244 -129.667762) (xy 132.149262 -129.681078)
			(xy 132.189838 -129.712722) (xy 132.225793 -129.749533) (xy 132.256473 -129.790842) (xy 132.281322 -129.835901)
			(xy 132.299889 -129.883891) (xy 132.306314 -129.908808) (xy 132.312318 -129.931741) (xy 132.331659 -129.975017)
			(xy 132.35869 -130.013954) (xy 132.392474 -130.047203) (xy 132.431838 -130.073609) (xy 132.475417 -130.092257)
			(xy 132.521698 -130.102498) (xy 132.569076 -130.103979) (xy 132.592572 -130.100832) (xy 132.61995 -130.097048)
			(xy 132.675214 -130.09648) (xy 132.729981 -130.103891) (xy 132.783107 -130.119126) (xy 132.833479 -130.141867)
			(xy 132.880042 -130.171637) (xy 132.921824 -130.207814) (xy 132.957948 -130.24964) (xy 132.98766 -130.296241)
			(xy 133.010338 -130.346641) (xy 133.025507 -130.399786) (xy 133.032849 -130.454563) (xy 133.032212 -130.509826)
			(xy 133.023608 -130.564419) (xy 133.007217 -130.6172) (xy 132.983383 -130.667063) (xy 132.952604 -130.712966)
			(xy 132.915525 -130.753949) (xy 132.87292 -130.789152) (xy 132.825683 -130.817841) (xy 132.7748 -130.839414)
			(xy 132.721337 -130.853419) (xy 132.666413 -130.859565) (xy 132.611177 -130.857723) (xy 132.556784 -130.84793)
			(xy 132.504374 -130.830392) (xy 132.455042 -130.805476) (xy 132.409821 -130.773703) (xy 132.369658 -130.735738)
			(xy 132.335392 -130.692376) (xy 132.307741 -130.644523) (xy 132.287283 -130.593182) (xy 132.280406 -130.566414)
			(xy 132.274404 -130.543478) (xy 132.255066 -130.500197) (xy 132.228036 -130.461254) (xy 132.194252 -130.428)
			(xy 132.154887 -130.401588) (xy 132.111306 -130.382936) (xy 132.065022 -130.37269) (xy 132.01764 -130.371206)
			(xy 131.994148 -130.37439) (xy 131.965819 -130.378304) (xy 131.908632 -130.378608) (xy 131.85204 -130.370374)
			(xy 131.797311 -130.353787) (xy 131.745669 -130.329218) (xy 131.698273 -130.297218) (xy 131.656183 -130.258503)
			(xy 131.620342 -130.21394) (xy 131.605528 -130.189478) (xy 131.593381 -130.169666) (xy 131.563077 -130.134438)
			(xy 131.526878 -130.105301) (xy 131.485989 -130.083224) (xy 131.441771 -130.068941) (xy 131.395693 -130.062927)
			(xy 131.34929 -130.065383) (xy 131.304104 -130.076227) (xy 131.26164 -130.095098) (xy 131.22331 -130.121368)
			(xy 131.206494 -130.137408) (xy 130.462879 -130.881023) (xy 137.888056 -130.881023) (xy 137.891503 -130.826609)
			(xy 137.902662 -130.77324) (xy 137.921307 -130.722003) (xy 137.947056 -130.673943) (xy 137.979387 -130.63004)
			(xy 138.017639 -130.591186) (xy 138.061033 -130.558176) (xy 138.108686 -130.53168) (xy 138.159625 -130.512239)
			(xy 138.212814 -130.500249) (xy 138.267168 -130.495954) (xy 138.321579 -130.499442) (xy 138.37494 -130.510642)
			(xy 138.426162 -130.529325) (xy 138.474202 -130.555112) (xy 138.518081 -130.587475) (xy 138.556905 -130.625757)
			(xy 138.573764 -130.647186) (xy 138.587562 -130.664604) (xy 138.620173 -130.694785) (xy 138.657538 -130.718831)
			(xy 138.698517 -130.736008) (xy 138.741859 -130.745794) (xy 138.786243 -130.747889) (xy 138.830315 -130.74223)
			(xy 138.872729 -130.728988) (xy 138.912193 -130.708569) (xy 138.930126 -130.695446) (xy 138.952098 -130.679304)
			(xy 138.999708 -130.652743) (xy 139.050615 -130.633231) (xy 139.103782 -130.621166) (xy 139.158125 -130.616795)
			(xy 139.212537 -130.620205) (xy 139.265908 -130.631328) (xy 139.317152 -130.649937) (xy 139.365225 -130.675653)
			(xy 139.409146 -130.707952) (xy 139.448021 -130.746175) (xy 139.481057 -130.789544) (xy 139.507582 -130.837175)
			(xy 139.527054 -130.888097) (xy 139.539078 -130.941273) (xy 139.543408 -130.995619) (xy 139.539955 -131.050028)
			(xy 139.528791 -131.103391) (xy 139.510143 -131.154621) (xy 139.48439 -131.202674) (xy 139.452057 -131.24657)
			(xy 139.413804 -131.285415) (xy 139.37041 -131.318418) (xy 139.322759 -131.344906) (xy 139.271821 -131.36434)
			(xy 139.218636 -131.376322) (xy 139.164286 -131.38061) (xy 139.10988 -131.377116) (xy 139.056526 -131.36591)
			(xy 139.00531 -131.347222) (xy 138.957277 -131.321433) (xy 138.913406 -131.289066) (xy 138.87459 -131.250783)
			(xy 138.857736 -131.229354) (xy 138.843933 -131.211938) (xy 138.811325 -131.181754) (xy 138.773961 -131.157705)
			(xy 138.732983 -131.140525) (xy 138.68964 -131.130738) (xy 138.645255 -131.128643) (xy 138.601183 -131.134303)
			(xy 138.558769 -131.147547) (xy 138.519306 -131.16797) (xy 138.501374 -131.181094) (xy 138.479453 -131.197306)
			(xy 138.431841 -131.223875) (xy 138.380931 -131.243393) (xy 138.327761 -131.255464) (xy 138.273413 -131.259841)
			(xy 138.218997 -131.256436) (xy 138.165619 -131.245317) (xy 138.114368 -131.226712) (xy 138.066289 -131.200999)
			(xy 138.022361 -131.168702) (xy 137.983478 -131.130479) (xy 137.950435 -131.08711) (xy 137.923902 -131.039478)
			(xy 137.904423 -130.988553) (xy 137.892392 -130.935373) (xy 137.888056 -130.881023) (xy 130.462879 -130.881023)
			(xy 129.83718 -131.506722) (xy 128.570228 -131.506722) (xy 128.36144 -131.71551) (xy 128.36144 -132.202682)
			(xy 128.361846 -132.216942) (xy 128.368195 -132.244746) (xy 128.380558 -132.270446) (xy 128.398319 -132.292761)
			(xy 128.409192 -132.301996) (xy 128.409446 -132.30225) (xy 128.430915 -132.319992) (xy 128.468976 -132.360651)
			(xy 128.500721 -132.406411) (xy 128.525475 -132.456301) (xy 128.542712 -132.50926) (xy 128.552066 -132.564162)
			(xy 128.553338 -132.619841) (xy 128.5465 -132.675113) (xy 128.531698 -132.728804) (xy 128.509248 -132.779771)
			(xy 128.479624 -132.826933) (xy 128.443459 -132.869287) (xy 128.401519 -132.905932) (xy 128.354698 -132.936089)
			(xy 128.303988 -132.959118) (xy 128.25047 -132.97453) (xy 128.195279 -132.981995) (xy 128.139589 -132.981357)
			(xy 128.084584 -132.972628) (xy 128.031432 -132.955995) (xy 127.981264 -132.93181) (xy 127.935146 -132.900587)
			(xy 127.894057 -132.862991) (xy 127.876046 -132.841746) (xy 127.875792 -132.841492) (xy 127.866618 -132.830867)
			(xy 127.844518 -132.813568) (xy 127.81916 -132.801541) (xy 127.791781 -132.795372) (xy 127.777748 -132.79501)
			(xy 127.662432 -132.79501) (xy 126.094471 -134.362971) (xy 126.956418 -134.362971) (xy 126.958312 -134.308132)
			(xy 126.968044 -134.254129) (xy 126.985415 -134.202078) (xy 127.010064 -134.153054) (xy 127.041485 -134.108067)
			(xy 127.079027 -134.068047) (xy 127.121916 -134.03382) (xy 127.169267 -134.006092) (xy 127.220103 -133.985435)
			(xy 127.273375 -133.972275) (xy 127.327982 -133.966885) (xy 127.382798 -133.969376) (xy 127.436692 -133.979695)
			(xy 127.48855 -133.997631) (xy 127.537304 -134.022812) (xy 127.581946 -134.05472) (xy 127.621555 -134.092696)
			(xy 127.63881 -134.114032) (xy 127.648687 -134.125939) (xy 127.673038 -134.145005) (xy 127.701263 -134.157648)
			(xy 127.731701 -134.163125) (xy 127.762563 -134.161114) (xy 127.792033 -134.151732) (xy 127.805434 -134.144004)
			(xy 127.829061 -134.130049) (xy 127.879434 -134.108292) (xy 127.932406 -134.093978) (xy 127.986882 -134.087401)
			(xy 128.041738 -134.088699) (xy 128.095842 -134.097844) (xy 128.148078 -134.114647) (xy 128.197366 -134.138762)
			(xy 128.242691 -134.169691) (xy 128.283116 -134.206795) (xy 128.317806 -134.249309) (xy 128.346047 -134.296355)
			(xy 128.352348 -134.31139) (xy 130.455922 -134.31139) (xy 130.459993 -134.255768) (xy 130.472119 -134.201331)
			(xy 130.492042 -134.14924) (xy 130.519338 -134.100605) (xy 130.553424 -134.056462) (xy 130.593573 -134.017753)
			(xy 130.638931 -133.985302) (xy 130.688531 -133.959801) (xy 130.741315 -133.941794) (xy 130.796158 -133.931664)
			(xy 130.851892 -133.929627) (xy 130.907329 -133.935727) (xy 130.961286 -133.949833) (xy 131.012615 -133.971645)
			(xy 131.060221 -134.000699) (xy 131.103089 -134.036374) (xy 131.140306 -134.077911) (xy 131.171079 -134.124424)
			(xy 131.194751 -134.174921) (xy 131.210819 -134.228328) (xy 131.218939 -134.283504) (xy 131.218962 -134.284781)
			(xy 132.698507 -134.284781) (xy 132.704041 -134.230432) (xy 132.717271 -134.177429) (xy 132.737928 -134.126855)
			(xy 132.765588 -134.079745) (xy 132.799685 -134.037063) (xy 132.839523 -133.999682) (xy 132.884286 -133.968366)
			(xy 132.933059 -133.943757) (xy 132.984843 -133.926356) (xy 133.03858 -133.916521) (xy 133.09317 -133.914453)
			(xy 133.140628 -133.919468) (xy 139.297662 -133.919468) (xy 139.301733 -133.863846) (xy 139.313859 -133.809409)
			(xy 139.333782 -133.757318) (xy 139.361078 -133.708683) (xy 139.395164 -133.66454) (xy 139.435313 -133.625831)
			(xy 139.480671 -133.59338) (xy 139.530271 -133.567879) (xy 139.583055 -133.549872) (xy 139.637898 -133.539742)
			(xy 139.693632 -133.537705) (xy 139.749069 -133.543805) (xy 139.803026 -133.557911) (xy 139.854355 -133.579723)
			(xy 139.901961 -133.608777) (xy 139.944829 -133.644452) (xy 139.982046 -133.685989) (xy 140.012819 -133.732502)
			(xy 140.036491 -133.782999) (xy 140.052559 -133.836406) (xy 140.060679 -133.891582) (xy 140.061188 -133.919468)
			(xy 140.060679 -133.947354) (xy 140.052559 -134.00253) (xy 140.036491 -134.055937) (xy 140.012819 -134.106434)
			(xy 139.982046 -134.152947) (xy 139.944829 -134.194484) (xy 139.901961 -134.230159) (xy 139.854355 -134.259213)
			(xy 139.803026 -134.281025) (xy 139.749069 -134.295131) (xy 139.693632 -134.301231) (xy 139.637898 -134.299194)
			(xy 139.583055 -134.289064) (xy 139.530271 -134.271057) (xy 139.480671 -134.245556) (xy 139.435313 -134.213105)
			(xy 139.395164 -134.174396) (xy 139.361078 -134.130253) (xy 139.333782 -134.081618) (xy 139.313859 -134.029527)
			(xy 139.301733 -133.97509) (xy 139.297662 -133.919468) (xy 133.140628 -133.919468) (xy 133.147498 -133.920194)
			(xy 133.20045 -133.933626) (xy 133.250945 -133.954474) (xy 133.297949 -133.982313) (xy 133.340501 -134.016572)
			(xy 133.377731 -134.056552) (xy 133.393688 -134.078726) (xy 133.407136 -134.097231) (xy 133.439488 -134.129563)
			(xy 133.477105 -134.155583) (xy 133.518771 -134.17445) (xy 133.563142 -134.185555) (xy 133.608783 -134.188539)
			(xy 133.654222 -134.183306) (xy 133.69799 -134.170024) (xy 133.718554 -134.160006) (xy 133.744146 -134.147405)
			(xy 133.798196 -134.12917) (xy 133.854359 -134.119183) (xy 133.911382 -134.117667) (xy 133.967996 -134.124655)
			(xy 134.022939 -134.139992) (xy 134.074987 -134.163336) (xy 134.122981 -134.194167) (xy 134.144766 -134.212584)
			(xy 134.16228 -134.227287) (xy 134.201506 -134.250784) (xy 134.244303 -134.266883) (xy 134.28929 -134.275064)
			(xy 134.335014 -134.275064) (xy 134.380001 -134.266883) (xy 134.422798 -134.250784) (xy 134.462024 -134.227287)
			(xy 134.479538 -134.212584) (xy 134.500439 -134.194961) (xy 134.546251 -134.165129) (xy 134.595851 -134.142142)
			(xy 134.648224 -134.126468) (xy 134.702298 -134.118429) (xy 134.756966 -134.11819) (xy 134.811108 -134.125755)
			(xy 134.863617 -134.14097) (xy 134.913416 -134.163522) (xy 134.959487 -134.192952) (xy 135.000886 -134.228654)
			(xy 135.036767 -134.2699) (xy 135.066393 -134.315845) (xy 135.089159 -134.365547) (xy 135.104599 -134.41799)
			(xy 135.112397 -134.472099) (xy 135.112392 -134.526767) (xy 135.104585 -134.580875) (xy 135.089136 -134.633315)
			(xy 135.080688 -134.65175) (xy 137.829034 -134.65175) (xy 137.833105 -134.596128) (xy 137.845231 -134.541691)
			(xy 137.865154 -134.4896) (xy 137.89245 -134.440965) (xy 137.926536 -134.396822) (xy 137.966685 -134.358113)
			(xy 138.012043 -134.325662) (xy 138.061643 -134.300161) (xy 138.114427 -134.282154) (xy 138.16927 -134.272024)
			(xy 138.225004 -134.269987) (xy 138.280441 -134.276087) (xy 138.334398 -134.290193) (xy 138.385727 -134.312005)
			(xy 138.433333 -134.341059) (xy 138.476201 -134.376734) (xy 138.513418 -134.418271) (xy 138.544191 -134.464784)
			(xy 138.567863 -134.515281) (xy 138.583931 -134.568688) (xy 138.592051 -134.623864) (xy 138.59256 -134.65175)
			(xy 138.592051 -134.679636) (xy 138.583931 -134.734812) (xy 138.567863 -134.788219) (xy 138.544191 -134.838716)
			(xy 138.513418 -134.885229) (xy 138.476201 -134.926766) (xy 138.433333 -134.962441) (xy 138.385727 -134.991495)
			(xy 138.334398 -135.013307) (xy 138.280441 -135.027413) (xy 138.225004 -135.033513) (xy 138.16927 -135.031476)
			(xy 138.114427 -135.021346) (xy 138.061643 -135.003339) (xy 138.012043 -134.977838) (xy 137.966685 -134.945387)
			(xy 137.926536 -134.906678) (xy 137.89245 -134.862535) (xy 137.865154 -134.8139) (xy 137.845231 -134.761809)
			(xy 137.833105 -134.707372) (xy 137.829034 -134.65175) (xy 135.080688 -134.65175) (xy 135.066361 -134.683013)
			(xy 135.036727 -134.728952) (xy 135.00084 -134.770192) (xy 134.959434 -134.805888) (xy 134.913358 -134.835309)
			(xy 134.863555 -134.857853) (xy 134.811044 -134.873059) (xy 134.7569 -134.880615) (xy 134.702232 -134.880366)
			(xy 134.64816 -134.872318) (xy 134.595789 -134.856635) (xy 134.546193 -134.833639) (xy 134.500387 -134.803799)
			(xy 134.479538 -134.786116) (xy 134.462024 -134.771413) (xy 134.422798 -134.747916) (xy 134.380001 -134.731817)
			(xy 134.335014 -134.723636) (xy 134.28929 -134.723636) (xy 134.244303 -134.731817) (xy 134.201506 -134.747916)
			(xy 134.16228 -134.771413) (xy 134.144766 -134.786116) (xy 134.124288 -134.803395) (xy 134.079464 -134.832744)
			(xy 134.030974 -134.855534) (xy 133.979774 -134.871316) (xy 133.926869 -134.879782) (xy 133.8733 -134.880764)
			(xy 133.820121 -134.874243) (xy 133.768376 -134.860347) (xy 133.719084 -134.839349) (xy 133.673214 -134.811663)
			(xy 133.631668 -134.777833) (xy 133.595262 -134.738523) (xy 133.579616 -134.716774) (xy 133.566164 -134.698272)
			(xy 133.533812 -134.66594) (xy 133.496196 -134.63992) (xy 133.454531 -134.621053) (xy 133.410161 -134.609947)
			(xy 133.36452 -134.606963) (xy 133.319082 -134.612195) (xy 133.275314 -134.625476) (xy 133.25475 -134.635494)
			(xy 133.230216 -134.647514) (xy 133.178566 -134.665307) (xy 133.124905 -134.67555) (xy 133.070332 -134.678034)
			(xy 133.015963 -134.672706) (xy 132.962909 -134.659677) (xy 132.912258 -134.639213) (xy 132.865043 -134.611733)
			(xy 132.822232 -134.577797) (xy 132.784699 -134.538102) (xy 132.753214 -134.493459) (xy 132.728419 -134.44478)
			(xy 132.710822 -134.393062) (xy 132.700783 -134.339363) (xy 132.698507 -134.284781) (xy 131.218962 -134.284781)
			(xy 131.219448 -134.31139) (xy 131.218939 -134.339276) (xy 131.210819 -134.394452) (xy 131.194751 -134.447859)
			(xy 131.171079 -134.498356) (xy 131.140306 -134.544869) (xy 131.103089 -134.586406) (xy 131.060221 -134.622081)
			(xy 131.012615 -134.651135) (xy 130.961286 -134.672947) (xy 130.907329 -134.687053) (xy 130.851892 -134.693153)
			(xy 130.796158 -134.691116) (xy 130.741315 -134.680986) (xy 130.688531 -134.662979) (xy 130.638931 -134.637478)
			(xy 130.593573 -134.605027) (xy 130.553424 -134.566318) (xy 130.519338 -134.522175) (xy 130.492042 -134.47354)
			(xy 130.472119 -134.421449) (xy 130.459993 -134.367012) (xy 130.455922 -134.31139) (xy 128.352348 -134.31139)
			(xy 128.367255 -134.346963) (xy 128.380993 -134.400087) (xy 128.386976 -134.454631) (xy 128.385082 -134.50947)
			(xy 128.375349 -134.563471) (xy 128.357979 -134.615521) (xy 128.33333 -134.664545) (xy 128.30191 -134.70953)
			(xy 128.264369 -134.749549) (xy 128.22148 -134.783775) (xy 128.17413 -134.811503) (xy 128.123295 -134.83216)
			(xy 128.070024 -134.845319) (xy 128.015418 -134.850709) (xy 127.960603 -134.848219) (xy 127.906711 -134.837899)
			(xy 127.854853 -134.819964) (xy 127.8061 -134.794783) (xy 127.761459 -134.762876) (xy 127.721851 -134.724902)
			(xy 127.704596 -134.703566) (xy 127.694714 -134.691664) (xy 127.670364 -134.672598) (xy 127.64214 -134.659955)
			(xy 127.611703 -134.654477) (xy 127.580842 -134.656487) (xy 127.551373 -134.665867) (xy 127.537972 -134.673594)
			(xy 127.514347 -134.687554) (xy 127.463973 -134.709312) (xy 127.411001 -134.723627) (xy 127.356523 -134.730204)
			(xy 127.301666 -134.728907) (xy 127.247561 -134.719763) (xy 127.195324 -134.70296) (xy 127.146034 -134.678845)
			(xy 127.100709 -134.647916) (xy 127.060283 -134.610811) (xy 127.025591 -134.568297) (xy 126.997349 -134.52125)
			(xy 126.97614 -134.470642) (xy 126.962402 -134.417517) (xy 126.956418 -134.362971) (xy 126.094471 -134.362971)
			(xy 125.405388 -135.052054) (xy 140.552422 -135.052054) (xy 140.556493 -134.996432) (xy 140.568619 -134.941995)
			(xy 140.588542 -134.889904) (xy 140.615838 -134.841269) (xy 140.649924 -134.797126) (xy 140.690073 -134.758417)
			(xy 140.735431 -134.725966) (xy 140.785031 -134.700465) (xy 140.837815 -134.682458) (xy 140.892658 -134.672328)
			(xy 140.948392 -134.670291) (xy 141.003829 -134.676391) (xy 141.057786 -134.690497) (xy 141.109115 -134.712309)
			(xy 141.156721 -134.741363) (xy 141.199589 -134.777038) (xy 141.236806 -134.818575) (xy 141.267579 -134.865088)
			(xy 141.291251 -134.915585) (xy 141.307319 -134.968992) (xy 141.315439 -135.024168) (xy 141.315948 -135.052054)
			(xy 141.315439 -135.07994) (xy 141.307319 -135.135116) (xy 141.295685 -135.173784) (xy 143.761274 -135.173784)
			(xy 143.766943 -135.118654) (xy 143.780527 -135.064924) (xy 143.801742 -135.013724) (xy 143.83014 -134.966131)
			(xy 143.865124 -134.923147) (xy 143.905958 -134.885677) (xy 143.928592 -134.869682) (xy 143.947138 -134.856391)
			(xy 143.979682 -134.824422) (xy 144.005995 -134.787156) (xy 144.025232 -134.745791) (xy 144.036773 -134.701655)
			(xy 144.04025 -134.656169) (xy 144.035548 -134.610792) (xy 144.02282 -134.566984) (xy 144.002475 -134.526153)
			(xy 143.975167 -134.48961) (xy 143.958818 -134.473696) (xy 143.9393 -134.454872) (xy 143.905272 -134.412655)
			(xy 143.877562 -134.366046) (xy 143.85673 -134.315983) (xy 143.843195 -134.263476) (xy 143.837229 -134.209581)
			(xy 143.838953 -134.155385) (xy 143.848332 -134.101978) (xy 143.865177 -134.050437) (xy 143.889149 -134.0018)
			(xy 143.919765 -133.957046) (xy 143.937736 -133.93674) (xy 143.953382 -133.919001) (xy 143.978382 -133.878851)
			(xy 143.995521 -133.834768) (xy 144.004205 -133.788275) (xy 144.004135 -133.740978) (xy 143.995314 -133.69451)
			(xy 143.978046 -133.650478) (xy 143.96593 -133.630162) (xy 143.951854 -133.606706) (xy 143.929745 -133.55667)
			(xy 143.91501 -133.50399) (xy 143.907951 -133.449745) (xy 143.908712 -133.395048) (xy 143.917279 -133.341021)
			(xy 143.933474 -133.288771) (xy 143.956967 -133.239371) (xy 143.987275 -133.193832) (xy 144.023777 -133.15309)
			(xy 144.065724 -133.117979) (xy 144.112256 -133.08922) (xy 144.162419 -133.067402) (xy 144.215184 -133.052974)
			(xy 144.269469 -133.046229) (xy 144.32416 -133.047308) (xy 144.378137 -133.056188) (xy 144.430292 -133.072687)
			(xy 144.479555 -133.096466) (xy 144.524917 -133.127038) (xy 144.565447 -133.163776) (xy 144.600313 -133.205926)
			(xy 144.628802 -133.252624) (xy 144.650328 -133.302913) (xy 144.66445 -133.35576) (xy 144.670879 -133.410083)
			(xy 144.669483 -133.464768) (xy 144.66029 -133.518692) (xy 144.643489 -133.57075) (xy 144.619424 -133.619875)
			(xy 144.588589 -133.665058) (xy 144.57045 -133.685534) (xy 144.554826 -133.703292) (xy 144.529826 -133.743438)
			(xy 144.512686 -133.787517) (xy 144.503999 -133.834006) (xy 144.504065 -133.8813) (xy 144.512881 -133.927765)
			(xy 144.530144 -133.971796) (xy 144.542256 -133.992112) (xy 144.556007 -134.014879) (xy 144.577706 -134.063439)
			(xy 144.592449 -134.114543) (xy 144.59995 -134.1672) (xy 144.600062 -134.220387) (xy 144.592785 -134.273075)
			(xy 144.578258 -134.324241) (xy 144.556765 -134.372893) (xy 144.528721 -134.418087) (xy 144.494671 -134.458947)
			(xy 144.455274 -134.49468) (xy 144.433544 -134.510018) (xy 144.414979 -134.523287) (xy 144.382427 -134.555258)
			(xy 144.356107 -134.592527) (xy 144.336866 -134.633898) (xy 144.325321 -134.678039) (xy 144.321844 -134.723532)
			(xy 144.326547 -134.768916) (xy 144.339278 -134.81273) (xy 144.359629 -134.853566) (xy 144.386944 -134.890112)
			(xy 144.403318 -134.906004) (xy 144.423252 -134.925259) (xy 144.45791 -134.968507) (xy 144.485947 -135.016313)
			(xy 144.506773 -135.067672) (xy 144.51995 -135.121504) (xy 144.525202 -135.176675) (xy 144.522417 -135.232027)
			(xy 144.511654 -135.286392) (xy 144.493139 -135.33863) (xy 144.467263 -135.387639) (xy 144.434569 -135.432389)
			(xy 144.395745 -135.471939) (xy 144.351608 -135.505457) (xy 144.303086 -135.532237) (xy 144.251201 -135.551716)
			(xy 144.197044 -135.563484) (xy 144.141754 -135.567294) (xy 144.086494 -135.563066) (xy 144.032428 -135.550888)
			(xy 143.980692 -135.531017) (xy 143.932374 -135.50387) (xy 143.888492 -135.470019) (xy 143.849969 -135.430177)
			(xy 143.817614 -135.38518) (xy 143.79211 -135.335977) (xy 143.773991 -135.283601) (xy 143.76364 -135.229155)
			(xy 143.761274 -135.173784) (xy 141.295685 -135.173784) (xy 141.291251 -135.188523) (xy 141.267579 -135.23902)
			(xy 141.236806 -135.285533) (xy 141.199589 -135.32707) (xy 141.156721 -135.362745) (xy 141.109115 -135.391799)
			(xy 141.057786 -135.413611) (xy 141.003829 -135.427717) (xy 140.948392 -135.433817) (xy 140.892658 -135.43178)
			(xy 140.837815 -135.42165) (xy 140.785031 -135.403643) (xy 140.735431 -135.378142) (xy 140.690073 -135.345691)
			(xy 140.649924 -135.306982) (xy 140.615838 -135.262839) (xy 140.588542 -135.214204) (xy 140.568619 -135.162113)
			(xy 140.556493 -135.107676) (xy 140.552422 -135.052054) (xy 125.405388 -135.052054) (xy 125.330712 -135.12673)
			(xy 125.330712 -137.966719) (xy 126.653129 -137.966719) (xy 126.658852 -137.912247) (xy 126.672304 -137.859154)
			(xy 126.693209 -137.808529) (xy 126.721138 -137.761414) (xy 126.755516 -137.718776) (xy 126.795638 -137.681492)
			(xy 126.840679 -137.650327) (xy 126.889712 -137.625923) (xy 126.941732 -137.608781) (xy 126.995668 -137.599252)
			(xy 127.050412 -137.597533) (xy 127.104839 -137.603659) (xy 127.157831 -137.617504) (xy 127.2083 -137.638784)
			(xy 127.255207 -137.667062) (xy 127.297588 -137.701755) (xy 127.334574 -137.742152) (xy 127.365404 -137.787423)
			(xy 127.389444 -137.836636) (xy 127.398272 -137.862564) (xy 127.405615 -137.88383) (xy 127.426711 -137.923563)
			(xy 127.454471 -137.958961) (xy 127.48803 -137.98892) (xy 127.526339 -138.012503) (xy 127.568201 -138.028973)
			(xy 127.612308 -138.037817) (xy 127.657284 -138.038758) (xy 127.701723 -138.031767) (xy 127.723138 -138.02487)
			(xy 127.746856 -138.017076) (xy 127.795769 -138.007073) (xy 127.84557 -138.003542) (xy 127.895405 -138.006543)
			(xy 127.919988 -138.0109) (xy 127.935747 -138.013408) (xy 127.967586 -138.011449) (xy 127.997942 -138.001647)
			(xy 128.024914 -137.984614) (xy 128.046811 -137.961418) (xy 128.062264 -137.933511) (xy 128.070305 -137.902642)
			(xy 128.070864 -137.886694) (xy 128.071372 -137.866628) (xy 128.072146 -137.844965) (xy 128.06719 -137.801905)
			(xy 128.054992 -137.760312) (xy 128.035906 -137.721395) (xy 128.010488 -137.686286) (xy 127.979475 -137.656005)
			(xy 127.94377 -137.631431) (xy 127.904409 -137.613279) (xy 127.862537 -137.602077) (xy 127.840994 -137.599674)
			(xy 127.813259 -137.596656) (xy 127.759035 -137.583532) (xy 127.7073 -137.562651) (xy 127.659158 -137.53446)
			(xy 127.615633 -137.499558) (xy 127.577655 -137.458691) (xy 127.546032 -137.41273) (xy 127.521439 -137.362653)
			(xy 127.5044 -137.309529) (xy 127.495278 -137.254491) (xy 127.494268 -137.19871) (xy 127.501391 -137.143377)
			(xy 127.516495 -137.089671) (xy 127.539259 -137.038737) (xy 127.569197 -136.991661) (xy 127.605671 -136.949445)
			(xy 127.647903 -136.912991) (xy 127.694993 -136.883075) (xy 127.745938 -136.860335) (xy 127.799651 -136.845255)
			(xy 127.854987 -136.838158) (xy 127.910767 -136.839194) (xy 127.965802 -136.848341) (xy 128.018918 -136.865405)
			(xy 128.068983 -136.890021) (xy 128.11493 -136.921666) (xy 128.155779 -136.959663) (xy 128.19066 -137.003204)
			(xy 128.218829 -137.05136) (xy 128.239686 -137.103104) (xy 128.252785 -137.157334) (xy 128.257849 -137.212893)
			(xy 128.256792 -137.240772) (xy 128.25596 -137.262435) (xy 128.260917 -137.305502) (xy 128.273119 -137.3471)
			(xy 128.29221 -137.386021) (xy 128.317636 -137.421133) (xy 128.348658 -137.451415) (xy 128.384372 -137.475986)
			(xy 128.423742 -137.494133) (xy 128.465623 -137.505328) (xy 128.48717 -137.507726) (xy 128.51452 -137.510633)
			(xy 128.568007 -137.523456) (xy 128.611376 -137.540746) (xy 130.041902 -137.540746) (xy 130.045973 -137.485124)
			(xy 130.058099 -137.430687) (xy 130.078022 -137.378596) (xy 130.105318 -137.329961) (xy 130.139404 -137.285818)
			(xy 130.179553 -137.247109) (xy 130.224911 -137.214658) (xy 130.274511 -137.189157) (xy 130.327295 -137.17115)
			(xy 130.382138 -137.16102) (xy 130.437872 -137.158983) (xy 130.493309 -137.165083) (xy 130.547266 -137.179189)
			(xy 130.598595 -137.201001) (xy 130.646201 -137.230055) (xy 130.682793 -137.260507) (xy 131.428318 -137.260507)
			(xy 131.433292 -137.206016) (xy 131.445998 -137.152795) (xy 131.466177 -137.101935) (xy 131.493415 -137.054479)
			(xy 131.527152 -137.011401) (xy 131.566697 -136.973584) (xy 131.611238 -136.941803) (xy 131.659863 -136.916711)
			(xy 131.711573 -136.898823) (xy 131.765308 -136.888505) (xy 131.819966 -136.885969) (xy 131.874426 -136.891267)
			(xy 131.927571 -136.90429) (xy 131.97831 -136.924771) (xy 132.025603 -136.95229) (xy 132.06848 -136.986283)
			(xy 132.106061 -137.026052) (xy 132.137576 -137.070782) (xy 132.162378 -137.119555) (xy 132.179958 -137.171371)
			(xy 132.183621 -137.191082) (xy 133.053925 -137.191082) (xy 133.058135 -137.13524) (xy 133.070465 -137.080613)
			(xy 133.090649 -137.028376) (xy 133.118255 -136.979652) (xy 133.152688 -136.935488) (xy 133.193208 -136.896832)
			(xy 133.238944 -136.864517) (xy 133.288914 -136.839237) (xy 133.342044 -136.821535) (xy 133.39719 -136.811791)
			(xy 133.453169 -136.810215) (xy 133.508777 -136.816841) (xy 133.562818 -136.831526) (xy 133.614131 -136.853955)
			(xy 133.661613 -136.883646) (xy 133.683248 -136.901428) (xy 133.696154 -136.911655) (xy 133.725841 -136.925866)
			(xy 133.758177 -136.932007) (xy 133.791006 -136.929666) (xy 133.822144 -136.919002) (xy 133.849515 -136.900723)
			(xy 133.860794 -136.888728) (xy 133.880441 -136.867192) (xy 133.925191 -136.829832) (xy 133.975103 -136.799714)
			(xy 134.029016 -136.777539) (xy 134.085674 -136.763822) (xy 134.143759 -136.758882) (xy 134.20192 -136.762836)
			(xy 134.258802 -136.77559) (xy 134.313083 -136.796848) (xy 134.338568 -136.811004) (xy 134.353934 -136.81918)
			(xy 134.387639 -136.82781) (xy 134.422422 -136.827032) (xy 134.455707 -136.816905) (xy 134.48503 -136.798179)
			(xy 134.497064 -136.785604) (xy 134.515898 -136.765192) (xy 134.558453 -136.729506) (xy 134.605733 -136.700367)
			(xy 134.656739 -136.678391) (xy 134.710391 -136.664043) (xy 134.765557 -136.657626) (xy 134.821071 -136.659275)
			(xy 134.875759 -136.668956) (xy 134.928465 -136.686463) (xy 134.978076 -136.711428) (xy 135.023543 -136.743322)
			(xy 135.063905 -136.781472) (xy 135.098309 -136.82507) (xy 135.126028 -136.873197) (xy 135.146476 -136.924833)
			(xy 135.159222 -136.978889) (xy 135.163995 -137.034222) (xy 135.160694 -137.089661) (xy 135.155312 -137.11555)
			(xy 135.416034 -137.11555) (xy 135.420105 -137.059928) (xy 135.432231 -137.005491) (xy 135.452154 -136.9534)
			(xy 135.47945 -136.904765) (xy 135.513536 -136.860622) (xy 135.553685 -136.821913) (xy 135.599043 -136.789462)
			(xy 135.648643 -136.763961) (xy 135.701427 -136.745954) (xy 135.75627 -136.735824) (xy 135.812004 -136.733787)
			(xy 135.867441 -136.739887) (xy 135.921398 -136.753993) (xy 135.972727 -136.775805) (xy 136.020333 -136.804859)
			(xy 136.063201 -136.840534) (xy 136.100418 -136.882071) (xy 136.131191 -136.928584) (xy 136.154863 -136.979081)
			(xy 136.170931 -137.032488) (xy 136.178329 -137.082757) (xy 137.092902 -137.082757) (xy 137.094312 -137.027428)
			(xy 137.103702 -136.972884) (xy 137.120876 -136.920269) (xy 137.145471 -136.870687) (xy 137.176974 -136.82518)
			(xy 137.214721 -136.784703) (xy 137.257921 -136.750105) (xy 137.305667 -136.722112) (xy 137.356957 -136.701313)
			(xy 137.410714 -136.688143) (xy 137.46581 -136.682879) (xy 137.521088 -136.685631) (xy 137.575389 -136.696342)
			(xy 137.627571 -136.714788) (xy 137.676541 -136.74058) (xy 137.72127 -136.773177) (xy 137.76082 -136.811896)
			(xy 137.777982 -136.83361) (xy 137.792115 -136.851399) (xy 137.825642 -136.882056) (xy 137.864086 -136.906263)
			(xy 137.906222 -136.923247) (xy 137.950707 -136.932467) (xy 137.996122 -136.93363) (xy 138.04102 -136.926698)
			(xy 138.08397 -136.911892) (xy 138.123602 -136.889684) (xy 138.158654 -136.860782) (xy 138.173714 -136.84377)
			(xy 138.191938 -136.82294) (xy 138.233408 -136.786287) (xy 138.279739 -136.756011) (xy 138.329959 -136.732747)
			(xy 138.383013 -136.716984) (xy 138.437788 -136.709053) (xy 138.493134 -136.70912) (xy 138.54789 -136.717184)
			(xy 138.600906 -136.733075) (xy 138.651069 -136.75646) (xy 138.697327 -136.786849) (xy 138.738708 -136.823602)
			(xy 138.774344 -136.865949) (xy 138.803487 -136.913001) (xy 138.825525 -136.963771) (xy 138.839995 -137.017192)
			(xy 138.846595 -137.072143) (xy 138.845185 -137.127471) (xy 138.835795 -137.182015) (xy 138.818622 -137.23463)
			(xy 138.794026 -137.284211) (xy 138.762524 -137.329717) (xy 138.724778 -137.370194) (xy 138.681578 -137.404792)
			(xy 138.633833 -137.432784) (xy 138.582543 -137.453584) (xy 138.528787 -137.466754) (xy 138.473692 -137.472018)
			(xy 138.418414 -137.469266) (xy 138.364114 -137.458555) (xy 138.311932 -137.44011) (xy 138.262962 -137.414319)
			(xy 138.218233 -137.381722) (xy 138.178684 -137.343004) (xy 138.161522 -137.32129) (xy 138.147384 -137.303505)
			(xy 138.113858 -137.272848) (xy 138.075415 -137.248641) (xy 138.03328 -137.231657) (xy 137.988796 -137.222436)
			(xy 137.943381 -137.221273) (xy 137.898483 -137.228204) (xy 137.855534 -137.24301) (xy 137.815902 -137.265217)
			(xy 137.78085 -137.294118) (xy 137.76579 -137.31113) (xy 137.747566 -137.33196) (xy 137.706095 -137.368614)
			(xy 137.659764 -137.398891) (xy 137.609544 -137.422155) (xy 137.556489 -137.437918) (xy 137.501714 -137.44585)
			(xy 137.446367 -137.445783) (xy 137.391611 -137.437719) (xy 137.338594 -137.421828) (xy 137.28843 -137.398443)
			(xy 137.242172 -137.368055) (xy 137.200791 -137.331301) (xy 137.165154 -137.288953) (xy 137.136011 -137.241901)
			(xy 137.113973 -137.191131) (xy 137.099502 -137.137709) (xy 137.092902 -137.082757) (xy 136.178329 -137.082757)
			(xy 136.179051 -137.087664) (xy 136.17956 -137.11555) (xy 136.179051 -137.143436) (xy 136.170931 -137.198612)
			(xy 136.154863 -137.252019) (xy 136.131191 -137.302516) (xy 136.100418 -137.349029) (xy 136.063201 -137.390566)
			(xy 136.020333 -137.426241) (xy 135.972727 -137.455295) (xy 135.921398 -137.477107) (xy 135.867441 -137.491213)
			(xy 135.812004 -137.497313) (xy 135.75627 -137.495276) (xy 135.701427 -137.485146) (xy 135.648643 -137.467139)
			(xy 135.599043 -137.441638) (xy 135.553685 -137.409187) (xy 135.513536 -137.370478) (xy 135.47945 -137.326335)
			(xy 135.452154 -137.2777) (xy 135.432231 -137.225609) (xy 135.420105 -137.171172) (xy 135.416034 -137.11555)
			(xy 135.155312 -137.11555) (xy 135.14939 -137.144037) (xy 135.130322 -137.196199) (xy 135.103892 -137.245045)
			(xy 135.070659 -137.289543) (xy 135.031326 -137.328752) (xy 134.986723 -137.361843) (xy 134.937793 -137.388118)
			(xy 134.885571 -137.407021) (xy 134.83116 -137.418152) (xy 134.77571 -137.421276) (xy 134.720393 -137.416328)
			(xy 134.666377 -137.403411) (xy 134.614806 -137.382799) (xy 134.590536 -137.369296) (xy 134.575168 -137.361124)
			(xy 134.541464 -137.352494) (xy 134.506682 -137.35327) (xy 134.473397 -137.363396) (xy 134.444075 -137.382121)
			(xy 134.43204 -137.394696) (xy 134.413775 -137.41441) (xy 134.372743 -137.449112) (xy 134.327249 -137.477715)
			(xy 134.278192 -137.499654) (xy 134.226542 -137.514494) (xy 134.173322 -137.521942) (xy 134.119583 -137.521851)
			(xy 134.066388 -137.514222) (xy 134.014789 -137.499206) (xy 133.965807 -137.477101) (xy 133.92041 -137.448344)
			(xy 133.899656 -137.431272) (xy 133.886747 -137.421049) (xy 133.857061 -137.406837) (xy 133.824726 -137.400697)
			(xy 133.791897 -137.403036) (xy 133.76076 -137.4137) (xy 133.733389 -137.431978) (xy 133.72211 -137.443972)
			(xy 133.70322 -137.464647) (xy 133.660453 -137.5008) (xy 133.61286 -137.530312) (xy 133.561462 -137.552548)
			(xy 133.507366 -137.56703) (xy 133.451734 -137.573447) (xy 133.395762 -137.571661) (xy 133.340652 -137.56171)
			(xy 133.28759 -137.543808) (xy 133.237715 -137.51834) (xy 133.1921 -137.485853) (xy 133.151726 -137.447046)
			(xy 133.117459 -137.402752) (xy 133.090037 -137.353925) (xy 133.07005 -137.301612) (xy 133.057925 -137.24694)
			(xy 133.053925 -137.191082) (xy 132.183621 -137.191082) (xy 132.189956 -137.225167) (xy 132.192167 -137.279839)
			(xy 132.186545 -137.334266) (xy 132.173206 -137.387332) (xy 132.152423 -137.437949) (xy 132.138928 -137.461752)
			(xy 132.131594 -137.475183) (xy 132.122844 -137.504497) (xy 132.121318 -137.53505) (xy 132.127102 -137.56509)
			(xy 132.139864 -137.592892) (xy 132.158873 -137.616861) (xy 132.170678 -137.626598) (xy 132.19201 -137.643735)
			(xy 132.230061 -137.683054) (xy 132.262105 -137.727406) (xy 132.287485 -137.77588) (xy 132.30568 -137.827482)
			(xy 132.316317 -137.881155) (xy 132.319178 -137.935796) (xy 132.314204 -137.990286) (xy 132.301497 -138.043507)
			(xy 132.281318 -138.094366) (xy 132.254081 -138.141821) (xy 132.220344 -138.184899) (xy 132.180799 -138.222716)
			(xy 132.136258 -138.254495) (xy 132.087633 -138.279586) (xy 132.035924 -138.297474) (xy 131.982189 -138.307792)
			(xy 131.927531 -138.310328) (xy 131.873072 -138.305029) (xy 131.819928 -138.292006) (xy 131.769189 -138.271525)
			(xy 131.721897 -138.244005) (xy 131.679021 -138.210013) (xy 131.64144 -138.170244) (xy 131.609926 -138.125514)
			(xy 131.585125 -138.076741) (xy 131.567545 -138.024926) (xy 131.557547 -137.971131) (xy 131.555337 -137.916459)
			(xy 131.560959 -137.862032) (xy 131.574298 -137.808967) (xy 131.595081 -137.758351) (xy 131.608576 -137.734548)
			(xy 131.615909 -137.721117) (xy 131.624658 -137.691803) (xy 131.626185 -137.66125) (xy 131.620401 -137.63121)
			(xy 131.607639 -137.603408) (xy 131.58863 -137.579439) (xy 131.576826 -137.569702) (xy 131.55549 -137.55257)
			(xy 131.517438 -137.51325) (xy 131.485394 -137.468899) (xy 131.460013 -137.420424) (xy 131.441817 -137.368822)
			(xy 131.43118 -137.315149) (xy 131.428318 -137.260507) (xy 130.682793 -137.260507) (xy 130.689069 -137.26573)
			(xy 130.726286 -137.307267) (xy 130.757059 -137.35378) (xy 130.780731 -137.404277) (xy 130.796799 -137.457684)
			(xy 130.804919 -137.51286) (xy 130.805428 -137.540746) (xy 130.804919 -137.568632) (xy 130.796799 -137.623808)
			(xy 130.780731 -137.677215) (xy 130.757059 -137.727712) (xy 130.726286 -137.774225) (xy 130.689069 -137.815762)
			(xy 130.646201 -137.851437) (xy 130.598595 -137.880491) (xy 130.547266 -137.902303) (xy 130.493309 -137.916409)
			(xy 130.437872 -137.922509) (xy 130.382138 -137.920472) (xy 130.327295 -137.910342) (xy 130.274511 -137.892335)
			(xy 130.224911 -137.866834) (xy 130.179553 -137.834383) (xy 130.139404 -137.795674) (xy 130.105318 -137.751531)
			(xy 130.078022 -137.702896) (xy 130.058099 -137.650805) (xy 130.045973 -137.596368) (xy 130.041902 -137.540746)
			(xy 128.611376 -137.540746) (xy 128.619099 -137.543825) (xy 128.666737 -137.571317) (xy 128.709936 -137.605364)
			(xy 128.747799 -137.645259) (xy 128.779543 -137.690176) (xy 128.804511 -137.739185) (xy 128.822184 -137.791271)
			(xy 128.832196 -137.845354) (xy 128.834342 -137.900315) (xy 128.828575 -137.955014) (xy 128.815015 -138.008319)
			(xy 128.793944 -138.059125) (xy 128.765797 -138.10638) (xy 128.731158 -138.149105) (xy 128.690745 -138.186414)
			(xy 128.645394 -138.217536) (xy 128.596045 -138.241825) (xy 128.543721 -138.258778) (xy 128.489504 -138.268044)
			(xy 128.462024 -138.269218) (xy 128.437935 -138.270379) (xy 128.39082 -138.280646) (xy 128.346483 -138.299605)
			(xy 128.30651 -138.326576) (xy 128.272333 -138.360594) (xy 128.245176 -138.400441) (xy 128.226011 -138.444689)
			(xy 128.220216 -138.4681) (xy 128.213705 -138.495027) (xy 128.194027 -138.546808) (xy 128.167064 -138.595198)
			(xy 128.133385 -138.639179) (xy 128.093698 -138.677824) (xy 128.048838 -138.710323) (xy 127.999748 -138.735989)
			(xy 127.947462 -138.754285) (xy 127.893079 -138.764824) (xy 127.837744 -138.767385) (xy 127.78262 -138.761914)
			(xy 127.728867 -138.748527) (xy 127.677616 -138.727504) (xy 127.629946 -138.699289) (xy 127.586859 -138.664474)
			(xy 127.549261 -138.623792) (xy 127.517944 -138.5781) (xy 127.493567 -138.528357) (xy 127.484632 -138.502136)
			(xy 127.477284 -138.480872) (xy 127.456189 -138.44114) (xy 127.428429 -138.405741) (xy 127.394871 -138.375783)
			(xy 127.356563 -138.3522) (xy 127.314702 -138.335729) (xy 127.270595 -138.326884) (xy 127.225619 -138.325943)
			(xy 127.181181 -138.332934) (xy 127.159766 -138.33983) (xy 127.133751 -138.348396) (xy 127.079963 -138.358723)
			(xy 127.02525 -138.361254) (xy 126.970738 -138.355935) (xy 126.917546 -138.342877) (xy 126.866768 -138.322348)
			(xy 126.819447 -138.294769) (xy 126.776555 -138.260707) (xy 126.738975 -138.220863) (xy 126.707477 -138.176055)
			(xy 126.68271 -138.127203) (xy 126.665182 -138.075312) (xy 126.655254 -138.021449) (xy 126.653129 -137.966719)
			(xy 125.330712 -137.966719) (xy 125.330712 -139.1793) (xy 138.152884 -139.1793) (xy 138.156955 -139.123678)
			(xy 138.169081 -139.069241) (xy 138.189004 -139.01715) (xy 138.2163 -138.968515) (xy 138.250386 -138.924372)
			(xy 138.290535 -138.885663) (xy 138.335893 -138.853212) (xy 138.385493 -138.827711) (xy 138.438277 -138.809704)
			(xy 138.49312 -138.799574) (xy 138.548854 -138.797537) (xy 138.604291 -138.803637) (xy 138.658248 -138.817743)
			(xy 138.709577 -138.839555) (xy 138.757183 -138.868609) (xy 138.800051 -138.904284) (xy 138.837268 -138.945821)
			(xy 138.858749 -138.978289) (xy 139.612918 -138.978289) (xy 139.616592 -138.922681) (xy 139.628318 -138.868199)
			(xy 139.647846 -138.816004) (xy 139.674761 -138.767205) (xy 139.70849 -138.722842) (xy 139.748315 -138.683858)
			(xy 139.793388 -138.651084) (xy 139.84275 -138.625217) (xy 139.895351 -138.606808) (xy 139.95007 -138.596248)
			(xy 140.005744 -138.593762) (xy 140.061187 -138.599404) (xy 140.115219 -138.613052) (xy 140.16669 -138.634417)
			(xy 140.214504 -138.663044) (xy 140.257645 -138.698323) (xy 140.295193 -138.739504) (xy 140.32635 -138.78571)
			(xy 140.350452 -138.835957) (xy 140.366987 -138.889177) (xy 140.375602 -138.944236) (xy 140.376114 -138.999963)
			(xy 140.368512 -139.055171) (xy 140.352958 -139.108686) (xy 140.329784 -139.159368) (xy 140.299481 -139.206138)
			(xy 140.262696 -139.248002) (xy 140.241782 -139.266422) (xy 140.224464 -139.281835) (xy 140.195169 -139.31776)
			(xy 140.17287 -139.3584) (xy 140.158306 -139.402408) (xy 140.151958 -139.448326) (xy 140.154038 -139.494635)
			(xy 140.164476 -139.5398) (xy 140.182927 -139.582325) (xy 140.208779 -139.620802) (xy 140.241177 -139.653957)
			(xy 140.259816 -139.667742) (xy 140.282265 -139.684255) (xy 140.322629 -139.722676) (xy 140.356973 -139.76656)
			(xy 140.384566 -139.814975) (xy 140.404822 -139.866889) (xy 140.417308 -139.921198) (xy 140.421759 -139.976746)
			(xy 140.41808 -140.03235) (xy 140.40635 -140.086827) (xy 140.386818 -140.139018) (xy 140.3599 -140.187812)
			(xy 140.326169 -140.232169) (xy 140.286343 -140.271147) (xy 140.241269 -140.303914) (xy 140.191907 -140.329775)
			(xy 140.139308 -140.348179) (xy 140.084591 -140.358733) (xy 140.02892 -140.361213) (xy 139.973481 -140.355567)
			(xy 139.919454 -140.341914) (xy 139.867988 -140.320545) (xy 139.820178 -140.291915) (xy 139.777044 -140.256634)
			(xy 139.739502 -140.215452) (xy 139.708351 -140.169245) (xy 139.684256 -140.118998) (xy 139.667728 -140.06578)
			(xy 139.659119 -140.010723) (xy 139.658612 -139.955) (xy 139.666219 -139.899796) (xy 139.681778 -139.846286)
			(xy 139.704956 -139.795609) (xy 139.735262 -139.748844) (xy 139.772049 -139.706987) (xy 139.792964 -139.68857)
			(xy 139.810296 -139.67317) (xy 139.839598 -139.637245) (xy 139.861901 -139.596604) (xy 139.876469 -139.552593)
			(xy 139.882817 -139.50667) (xy 139.880736 -139.460358) (xy 139.870294 -139.41519) (xy 139.851838 -139.372663)
			(xy 139.825979 -139.334185) (xy 139.793574 -139.301033) (xy 139.77493 -139.28725) (xy 139.752446 -139.270784)
			(xy 139.712076 -139.232365) (xy 139.677726 -139.188481) (xy 139.650127 -139.140066) (xy 139.629866 -139.08815)
			(xy 139.617374 -139.033839) (xy 139.612918 -138.978289) (xy 138.858749 -138.978289) (xy 138.868041 -138.992334)
			(xy 138.891713 -139.042831) (xy 138.907781 -139.096238) (xy 138.915901 -139.151414) (xy 138.91641 -139.1793)
			(xy 138.915901 -139.207186) (xy 138.907781 -139.262362) (xy 138.891713 -139.315769) (xy 138.868041 -139.366266)
			(xy 138.837268 -139.412779) (xy 138.800051 -139.454316) (xy 138.757183 -139.489991) (xy 138.709577 -139.519045)
			(xy 138.658248 -139.540857) (xy 138.604291 -139.554963) (xy 138.548854 -139.561063) (xy 138.49312 -139.559026)
			(xy 138.438277 -139.548896) (xy 138.385493 -139.530889) (xy 138.335893 -139.505388) (xy 138.290535 -139.472937)
			(xy 138.250386 -139.434228) (xy 138.2163 -139.390085) (xy 138.189004 -139.34145) (xy 138.169081 -139.289359)
			(xy 138.156955 -139.234922) (xy 138.152884 -139.1793) (xy 125.330712 -139.1793) (xy 125.330712 -139.902716)
			(xy 126.628076 -139.902716) (xy 126.629413 -139.847305) (xy 126.638753 -139.79267) (xy 126.6559 -139.739961)
			(xy 126.680493 -139.690287) (xy 126.712014 -139.644695) (xy 126.7498 -139.604144) (xy 126.793056 -139.569486)
			(xy 126.840871 -139.541452) (xy 126.89224 -139.520631) (xy 126.946081 -139.507461) (xy 127.00126 -139.50222)
			(xy 127.056617 -139.505019) (xy 127.110987 -139.515797) (xy 127.163225 -139.534329) (xy 127.18796 -139.546838)
			(xy 127.209347 -139.557569) (xy 127.255077 -139.571639) (xy 127.302633 -139.576898) (xy 127.350332 -139.573162)
			(xy 127.396489 -139.560561) (xy 127.43947 -139.539542) (xy 127.477756 -139.510847) (xy 127.509994 -139.475493)
			(xy 127.522986 -139.455398) (xy 127.537896 -139.432033) (xy 127.57349 -139.389545) (xy 127.614857 -139.352654)
			(xy 127.661127 -139.322136) (xy 127.711325 -139.298635) (xy 127.764396 -139.282644) (xy 127.819221 -139.274499)
			(xy 127.874649 -139.274374) (xy 127.929511 -139.282269) (xy 127.982653 -139.298019) (xy 128.032958 -139.321292)
			(xy 128.079365 -139.351599) (xy 128.1209 -139.388302) (xy 128.156686 -139.430628) (xy 128.185972 -139.477687)
			(xy 128.208141 -139.528487) (xy 128.222727 -139.581961) (xy 128.229422 -139.636983) (xy 128.228085 -139.692394)
			(xy 128.218746 -139.747029) (xy 128.201599 -139.799737) (xy 128.177007 -139.84941) (xy 128.145486 -139.895002)
			(xy 128.1077 -139.935554) (xy 128.064445 -139.970211) (xy 128.01663 -139.998246) (xy 127.965262 -140.019067)
			(xy 127.911422 -140.032237) (xy 127.856243 -140.037478) (xy 127.800886 -140.03468) (xy 127.746517 -140.023902)
			(xy 127.694279 -140.005371) (xy 127.669544 -139.992862) (xy 127.648155 -139.982135) (xy 127.602425 -139.968065)
			(xy 127.55487 -139.962805) (xy 127.507171 -139.966541) (xy 127.461015 -139.979141) (xy 127.418034 -140.00016)
			(xy 127.379748 -140.028853) (xy 127.34751 -140.064208) (xy 127.334518 -140.084302) (xy 127.319607 -140.107667)
			(xy 127.284012 -140.150155) (xy 127.242645 -140.187047) (xy 127.196375 -140.217565) (xy 127.146177 -140.241066)
			(xy 127.093106 -140.257058) (xy 127.03828 -140.265202) (xy 126.982852 -140.265328) (xy 126.92799 -140.257433)
			(xy 126.874847 -140.241683) (xy 126.824542 -140.21841) (xy 126.778134 -140.188102) (xy 126.736599 -140.151399)
			(xy 126.700812 -140.109073) (xy 126.671526 -140.062014) (xy 126.649357 -140.011213) (xy 126.634771 -139.957738)
			(xy 126.628076 -139.902716) (xy 125.330712 -139.902716) (xy 125.330712 -141.20495) (xy 126.627634 -141.20495)
			(xy 126.631705 -141.149328) (xy 126.643831 -141.094891) (xy 126.663754 -141.0428) (xy 126.69105 -140.994165)
			(xy 126.725136 -140.950022) (xy 126.765285 -140.911313) (xy 126.810643 -140.878862) (xy 126.860243 -140.853361)
			(xy 126.913027 -140.835354) (xy 126.96787 -140.825224) (xy 127.023604 -140.823187) (xy 127.079041 -140.829287)
			(xy 127.132998 -140.843393) (xy 127.184327 -140.865205) (xy 127.231933 -140.894259) (xy 127.274801 -140.929934)
			(xy 127.312018 -140.971471) (xy 127.342791 -141.017984) (xy 127.366463 -141.068481) (xy 127.382531 -141.121888)
			(xy 127.390651 -141.177064) (xy 127.39116 -141.20495) (xy 127.390651 -141.232836) (xy 127.382531 -141.288012)
			(xy 127.366463 -141.341419) (xy 127.342791 -141.391916) (xy 127.312018 -141.438429) (xy 127.293631 -141.45895)
			(xy 130.132834 -141.45895) (xy 130.136905 -141.403328) (xy 130.149031 -141.348891) (xy 130.168954 -141.2968)
			(xy 130.19625 -141.248165) (xy 130.230336 -141.204022) (xy 130.270485 -141.165313) (xy 130.315843 -141.132862)
			(xy 130.365443 -141.107361) (xy 130.418227 -141.089354) (xy 130.47307 -141.079224) (xy 130.528804 -141.077187)
			(xy 130.584241 -141.083287) (xy 130.638198 -141.097393) (xy 130.689527 -141.119205) (xy 130.737133 -141.148259)
			(xy 130.780001 -141.183934) (xy 130.817218 -141.225471) (xy 130.847991 -141.271984) (xy 130.871663 -141.322481)
			(xy 130.887731 -141.375888) (xy 130.895851 -141.431064) (xy 130.89636 -141.45895) (xy 130.895851 -141.486836)
			(xy 130.887731 -141.542012) (xy 130.871663 -141.595419) (xy 130.847991 -141.645916) (xy 130.817218 -141.692429)
			(xy 130.780001 -141.733966) (xy 130.737133 -141.769641) (xy 130.689527 -141.798695) (xy 130.638198 -141.820507)
			(xy 130.584241 -141.834613) (xy 130.528804 -141.840713) (xy 130.47307 -141.838676) (xy 130.418227 -141.828546)
			(xy 130.365443 -141.810539) (xy 130.315843 -141.785038) (xy 130.270485 -141.752587) (xy 130.230336 -141.713878)
			(xy 130.19625 -141.669735) (xy 130.168954 -141.6211) (xy 130.149031 -141.569009) (xy 130.136905 -141.514572)
			(xy 130.132834 -141.45895) (xy 127.293631 -141.45895) (xy 127.274801 -141.479966) (xy 127.231933 -141.515641)
			(xy 127.184327 -141.544695) (xy 127.132998 -141.566507) (xy 127.079041 -141.580613) (xy 127.023604 -141.586713)
			(xy 126.96787 -141.584676) (xy 126.913027 -141.574546) (xy 126.860243 -141.556539) (xy 126.810643 -141.531038)
			(xy 126.765285 -141.498587) (xy 126.725136 -141.459878) (xy 126.69105 -141.415735) (xy 126.663754 -141.3671)
			(xy 126.643831 -141.315009) (xy 126.631705 -141.260572) (xy 126.627634 -141.20495) (xy 125.330712 -141.20495)
			(xy 125.330712 -142.55115) (xy 139.683234 -142.55115) (xy 139.687305 -142.495528) (xy 139.699431 -142.441091)
			(xy 139.719354 -142.389) (xy 139.74665 -142.340365) (xy 139.780736 -142.296222) (xy 139.820885 -142.257513)
			(xy 139.866243 -142.225062) (xy 139.915843 -142.199561) (xy 139.968627 -142.181554) (xy 140.02347 -142.171424)
			(xy 140.079204 -142.169387) (xy 140.134641 -142.175487) (xy 140.188598 -142.189593) (xy 140.239927 -142.211405)
			(xy 140.287533 -142.240459) (xy 140.330401 -142.276134) (xy 140.367618 -142.317671) (xy 140.398391 -142.364184)
			(xy 140.422063 -142.414681) (xy 140.438131 -142.468088) (xy 140.446251 -142.523264) (xy 140.44676 -142.55115)
			(xy 140.446251 -142.579036) (xy 140.438131 -142.634212) (xy 140.422063 -142.687619) (xy 140.398391 -142.738116)
			(xy 140.367618 -142.784629) (xy 140.330401 -142.826166) (xy 140.287533 -142.861841) (xy 140.239927 -142.890895)
			(xy 140.188598 -142.912707) (xy 140.134641 -142.926813) (xy 140.079204 -142.932913) (xy 140.02347 -142.930876)
			(xy 139.968627 -142.920746) (xy 139.915843 -142.902739) (xy 139.866243 -142.877238) (xy 139.820885 -142.844787)
			(xy 139.780736 -142.806078) (xy 139.74665 -142.761935) (xy 139.719354 -142.7133) (xy 139.699431 -142.661209)
			(xy 139.687305 -142.606772) (xy 139.683234 -142.55115) (xy 125.330712 -142.55115) (xy 125.330712 -143.012182)
			(xy 126.653244 -143.012182) (xy 126.656704 -142.956969) (xy 126.668103 -142.902835) (xy 126.687201 -142.850915)
			(xy 126.7136 -142.802298) (xy 126.746744 -142.758005) (xy 126.785939 -142.718964) (xy 126.830362 -142.685994)
			(xy 126.879082 -142.659786) (xy 126.931076 -142.640891) (xy 126.985255 -142.629705) (xy 127.040481 -142.626462)
			(xy 127.095596 -142.63123) (xy 127.149445 -142.64391) (xy 127.200897 -142.664236) (xy 127.248873 -142.69178)
			(xy 127.292368 -142.725966) (xy 127.330468 -142.766075) (xy 127.362375 -142.811268) (xy 127.387419 -142.860596)
			(xy 127.405076 -142.913024) (xy 127.414973 -142.967453) (xy 127.416905 -143.02274) (xy 127.410831 -143.077727)
			(xy 127.396877 -143.13126) (xy 127.375337 -143.182215) (xy 127.346662 -143.229525) (xy 127.329438 -143.251174)
			(xy 127.314738 -143.269883) (xy 127.291789 -143.311552) (xy 127.276993 -143.356764) (xy 127.270866 -143.403939)
			(xy 127.273622 -143.45143) (xy 127.285164 -143.49758) (xy 127.305091 -143.540776) (xy 127.332706 -143.579512)
			(xy 127.349504 -143.59636) (xy 127.369117 -143.615882) (xy 127.40316 -143.659505) (xy 127.430541 -143.70759)
			(xy 127.450685 -143.759127) (xy 127.463168 -143.813035) (xy 127.467729 -143.868181) (xy 127.464272 -143.923407)
			(xy 127.452869 -143.977554) (xy 127.43376 -144.029484) (xy 127.407347 -144.078107) (xy 127.39116 -144.10055)
			(xy 127.37752 -144.119531) (xy 127.356795 -144.161423) (xy 127.344077 -144.206398) (xy 127.339794 -144.25294)
			(xy 127.344091 -144.299481) (xy 127.356824 -144.344451) (xy 127.377562 -144.386337) (xy 127.39116 -144.40535)
			(xy 127.40712 -144.427438) (xy 127.433241 -144.475264) (xy 127.452289 -144.52632) (xy 127.463877 -144.579567)
			(xy 127.467769 -144.633922) (xy 127.463885 -144.688277) (xy 127.452305 -144.741526) (xy 127.433264 -144.792585)
			(xy 127.40715 -144.840415) (xy 127.374495 -144.884041) (xy 127.335964 -144.922575) (xy 127.29234 -144.955233)
			(xy 127.244513 -144.98135) (xy 127.193455 -145.000395) (xy 127.140207 -145.011979) (xy 127.085852 -145.015867)
			(xy 127.031497 -145.011979) (xy 126.978249 -145.000395) (xy 126.927191 -144.98135) (xy 126.879364 -144.955233)
			(xy 126.83574 -144.922575) (xy 126.797209 -144.884041) (xy 126.764554 -144.840415) (xy 126.73844 -144.792585)
			(xy 126.719399 -144.741526) (xy 126.707819 -144.688277) (xy 126.703935 -144.633922) (xy 126.707827 -144.579567)
			(xy 126.719415 -144.52632) (xy 126.738463 -144.475264) (xy 126.764584 -144.427438) (xy 126.780544 -144.40535)
			(xy 126.794091 -144.386306) (xy 126.814824 -144.34443) (xy 126.827553 -144.29947) (xy 126.831849 -144.25294)
			(xy 126.827568 -144.206409) (xy 126.814853 -144.161445) (xy 126.794133 -144.119563) (xy 126.780544 -144.10055)
			(xy 126.764012 -144.077635) (xy 126.737187 -144.027904) (xy 126.717987 -143.974762) (xy 126.70683 -143.91937)
			(xy 126.703961 -143.862939) (xy 126.709443 -143.806702) (xy 126.723155 -143.751887) (xy 126.744798 -143.699692)
			(xy 126.773899 -143.651258) (xy 126.791466 -143.629126) (xy 126.806165 -143.610417) (xy 126.829114 -143.568747)
			(xy 126.84391 -143.523536) (xy 126.850037 -143.476361) (xy 126.847281 -143.42887) (xy 126.835739 -143.38272)
			(xy 126.815812 -143.339524) (xy 126.788198 -143.300788) (xy 126.7714 -143.28394) (xy 126.751759 -143.264458)
			(xy 126.717744 -143.220829) (xy 126.690388 -143.172745) (xy 126.670265 -143.121213) (xy 126.657796 -143.067315)
			(xy 126.653244 -143.012182) (xy 125.330712 -143.012182) (xy 125.330712 -145.11655) (xy 129.243834 -145.11655)
			(xy 129.247905 -145.060928) (xy 129.260031 -145.006491) (xy 129.279954 -144.9544) (xy 129.30725 -144.905765)
			(xy 129.341336 -144.861622) (xy 129.381485 -144.822913) (xy 129.426843 -144.790462) (xy 129.476443 -144.764961)
			(xy 129.529227 -144.746954) (xy 129.58407 -144.736824) (xy 129.639804 -144.734787) (xy 129.695241 -144.740887)
			(xy 129.749198 -144.754993) (xy 129.800527 -144.776805) (xy 129.848133 -144.805859) (xy 129.891001 -144.841534)
			(xy 129.928218 -144.883071) (xy 129.958991 -144.929584) (xy 129.982663 -144.980081) (xy 129.998731 -145.033488)
			(xy 130.006851 -145.088664) (xy 130.00736 -145.11655) (xy 130.006851 -145.144436) (xy 129.998731 -145.199612)
			(xy 129.991564 -145.223434) (xy 139.632414 -145.223434) (xy 139.635735 -145.167673) (xy 139.647151 -145.112992)
			(xy 139.66642 -145.060561) (xy 139.693128 -145.0115) (xy 139.726706 -144.966858) (xy 139.746228 -144.946878)
			(xy 139.761681 -144.930985) (xy 139.787316 -144.894825) (xy 139.806288 -144.854764) (xy 139.818019 -144.812019)
			(xy 139.822155 -144.767887) (xy 139.81857 -144.723707) (xy 139.807373 -144.680819) (xy 139.788902 -144.640525)
			(xy 139.776708 -144.622012) (xy 139.761267 -144.598733) (xy 139.73658 -144.548623) (xy 139.719465 -144.49545)
			(xy 139.710287 -144.440348) (xy 139.709243 -144.384498) (xy 139.716354 -144.329092) (xy 139.73147 -144.275316)
			(xy 139.754266 -144.224318) (xy 139.784255 -144.177191) (xy 139.820796 -144.13494) (xy 139.863108 -144.09847)
			(xy 139.910287 -144.068561) (xy 139.961322 -144.045851) (xy 140.015124 -144.030826) (xy 140.070542 -144.023808)
			(xy 140.126391 -144.024947) (xy 140.181476 -144.034218) (xy 140.234621 -144.051423) (xy 140.284689 -144.076194)
			(xy 140.330608 -144.108001) (xy 140.371399 -144.146166) (xy 140.406188 -144.189871) (xy 140.434231 -144.238181)
			(xy 140.45493 -144.290065) (xy 140.467841 -144.344413) (xy 140.472688 -144.400063) (xy 140.469368 -144.455824)
			(xy 140.457952 -144.510506) (xy 140.438684 -144.562938) (xy 140.411975 -144.611999) (xy 140.378398 -144.656641)
			(xy 140.358876 -144.676622) (xy 140.343423 -144.692515) (xy 140.317787 -144.728675) (xy 140.298816 -144.768736)
			(xy 140.287084 -144.811481) (xy 140.282948 -144.855613) (xy 140.286533 -144.899793) (xy 140.297731 -144.942681)
			(xy 140.316201 -144.982975) (xy 140.328396 -145.001488) (xy 140.343832 -145.024771) (xy 140.368518 -145.07488)
			(xy 140.385633 -145.128053) (xy 140.39481 -145.183154) (xy 140.395854 -145.239004) (xy 140.388743 -145.29441)
			(xy 140.373627 -145.348186) (xy 140.350831 -145.399182) (xy 140.320841 -145.44631) (xy 140.2843 -145.48856)
			(xy 140.241988 -145.525029) (xy 140.19481 -145.554938) (xy 140.143774 -145.577648) (xy 140.089973 -145.592672)
			(xy 140.034556 -145.599689) (xy 139.978707 -145.59855) (xy 139.923622 -145.589279) (xy 139.870478 -145.572074)
			(xy 139.820411 -145.547303) (xy 139.774491 -145.515495) (xy 139.733701 -145.47733) (xy 139.698913 -145.433626)
			(xy 139.67087 -145.385315) (xy 139.650172 -145.333431) (xy 139.637261 -145.279084) (xy 139.632414 -145.223434)
			(xy 129.991564 -145.223434) (xy 129.982663 -145.253019) (xy 129.958991 -145.303516) (xy 129.928218 -145.350029)
			(xy 129.891001 -145.391566) (xy 129.848133 -145.427241) (xy 129.800527 -145.456295) (xy 129.749198 -145.478107)
			(xy 129.695241 -145.492213) (xy 129.639804 -145.498313) (xy 129.58407 -145.496276) (xy 129.529227 -145.486146)
			(xy 129.476443 -145.468139) (xy 129.426843 -145.442638) (xy 129.381485 -145.410187) (xy 129.341336 -145.371478)
			(xy 129.30725 -145.327335) (xy 129.279954 -145.2787) (xy 129.260031 -145.226609) (xy 129.247905 -145.172172)
			(xy 129.243834 -145.11655) (xy 125.330712 -145.11655) (xy 125.330712 -145.775934) (xy 125.585728 -146.03095)
			(xy 126.729234 -146.03095) (xy 126.733305 -145.975328) (xy 126.745431 -145.920891) (xy 126.765354 -145.8688)
			(xy 126.79265 -145.820165) (xy 126.826736 -145.776022) (xy 126.866885 -145.737313) (xy 126.912243 -145.704862)
			(xy 126.961843 -145.679361) (xy 127.014627 -145.661354) (xy 127.06947 -145.651224) (xy 127.125204 -145.649187)
			(xy 127.180641 -145.655287) (xy 127.234598 -145.669393) (xy 127.285927 -145.691205) (xy 127.333533 -145.720259)
			(xy 127.376401 -145.755934) (xy 127.413618 -145.797471) (xy 127.444391 -145.843984) (xy 127.468063 -145.894481)
			(xy 127.484131 -145.947888) (xy 127.492251 -146.003064) (xy 127.49276 -146.03095) (xy 127.492251 -146.058836)
			(xy 127.484131 -146.114012) (xy 127.468063 -146.167419) (xy 127.444391 -146.217916) (xy 127.413618 -146.264429)
			(xy 127.376401 -146.305966) (xy 127.333533 -146.341641) (xy 127.285927 -146.370695) (xy 127.234598 -146.392507)
			(xy 127.180641 -146.406613) (xy 127.125204 -146.412713) (xy 127.06947 -146.410676) (xy 127.014627 -146.400546)
			(xy 126.961843 -146.382539) (xy 126.912243 -146.357038) (xy 126.866885 -146.324587) (xy 126.826736 -146.285878)
			(xy 126.79265 -146.241735) (xy 126.765354 -146.1931) (xy 126.745431 -146.141009) (xy 126.733305 -146.086572)
			(xy 126.729234 -146.03095) (xy 125.585728 -146.03095) (xy 125.603 -146.048222) (xy 125.603 -148.791997)
			(xy 126.584838 -148.791997) (xy 126.586279 -148.736437) (xy 126.595766 -148.681673) (xy 126.613097 -148.628866)
			(xy 126.637907 -148.579131) (xy 126.669669 -148.533522) (xy 126.707712 -148.493004) (xy 126.751231 -148.458433)
			(xy 126.799304 -148.430542) (xy 126.850916 -148.40992) (xy 126.904973 -148.397005) (xy 126.960333 -148.392068)
			(xy 127.015822 -148.395215) (xy 127.070269 -148.406379) (xy 127.122519 -148.425324) (xy 127.171468 -148.451649)
			(xy 127.21608 -148.484797) (xy 127.255411 -148.524066) (xy 127.288629 -148.568627) (xy 127.315031 -148.617534)
			(xy 127.334058 -148.669755) (xy 127.345307 -148.724183) (xy 127.348541 -148.779668) (xy 127.343691 -148.835035)
			(xy 127.33086 -148.889113) (xy 127.321056 -148.91512) (xy 127.313289 -148.935987) (xy 127.30431 -148.979591)
			(xy 127.30307 -149.024094) (xy 127.309607 -149.068131) (xy 127.323722 -149.110354) (xy 127.344982 -149.149469)
			(xy 127.369761 -149.18055) (xy 139.556234 -149.18055) (xy 139.560305 -149.124928) (xy 139.572431 -149.070491)
			(xy 139.592354 -149.0184) (xy 139.61965 -148.969765) (xy 139.653736 -148.925622) (xy 139.693885 -148.886913)
			(xy 139.739243 -148.854462) (xy 139.788843 -148.828961) (xy 139.841627 -148.810954) (xy 139.89647 -148.800824)
			(xy 139.952204 -148.798787) (xy 140.007641 -148.804887) (xy 140.061598 -148.818993) (xy 140.112927 -148.840805)
			(xy 140.160533 -148.869859) (xy 140.203401 -148.905534) (xy 140.240618 -148.947071) (xy 140.271391 -148.993584)
			(xy 140.295063 -149.044081) (xy 140.311131 -149.097488) (xy 140.319251 -149.152664) (xy 140.31976 -149.18055)
			(xy 140.319251 -149.208436) (xy 140.311131 -149.263612) (xy 140.295063 -149.317019) (xy 140.271391 -149.367516)
			(xy 140.240618 -149.414029) (xy 140.203401 -149.455566) (xy 140.160533 -149.491241) (xy 140.112927 -149.520295)
			(xy 140.061598 -149.542107) (xy 140.007641 -149.556213) (xy 139.952204 -149.562313) (xy 139.89647 -149.560276)
			(xy 139.841627 -149.550146) (xy 139.788843 -149.532139) (xy 139.739243 -149.506638) (xy 139.693885 -149.474187)
			(xy 139.653736 -149.435478) (xy 139.61965 -149.391335) (xy 139.592354 -149.3427) (xy 139.572431 -149.290609)
			(xy 139.560305 -149.236172) (xy 139.556234 -149.18055) (xy 127.369761 -149.18055) (xy 127.372735 -149.18428)
			(xy 127.389128 -149.199346) (xy 127.409613 -149.218129) (xy 127.445499 -149.260565) (xy 127.474849 -149.307758)
			(xy 127.497043 -149.35871) (xy 127.511609 -149.412342) (xy 127.518241 -149.46752) (xy 127.516797 -149.523077)
			(xy 127.507309 -149.577836) (xy 127.489976 -149.63064) (xy 127.465167 -149.68037) (xy 127.433405 -149.725975)
			(xy 127.395363 -149.76649) (xy 127.351845 -149.801056) (xy 127.303773 -149.828944) (xy 127.252164 -149.849562)
			(xy 127.19811 -149.862476) (xy 127.142754 -149.86741) (xy 127.087268 -149.864261) (xy 127.032826 -149.853096)
			(xy 126.980579 -149.83415) (xy 126.931634 -149.807826) (xy 126.887026 -149.774679) (xy 126.847698 -149.73541)
			(xy 126.814484 -149.690852) (xy 126.788085 -149.641947) (xy 126.769061 -149.589729) (xy 126.757814 -149.535304)
			(xy 126.754581 -149.479822) (xy 126.759432 -149.424459) (xy 126.772264 -149.370385) (xy 126.782068 -149.34438)
			(xy 126.789857 -149.32352) (xy 126.798839 -149.279913) (xy 126.80008 -149.235407) (xy 126.79354 -149.191367)
			(xy 126.779421 -149.149142) (xy 126.758155 -149.110026) (xy 126.730393 -149.075218) (xy 126.713996 -149.060154)
			(xy 126.693484 -149.041399) (xy 126.657593 -148.998962) (xy 126.628239 -148.951768) (xy 126.606042 -148.900814)
			(xy 126.591472 -148.847178) (xy 126.584838 -148.791997) (xy 125.603 -148.791997) (xy 125.603 -150.053878)
			(xy 129.756095 -150.053878) (xy 129.762276 -149.999318) (xy 129.776212 -149.946207) (xy 129.797617 -149.895641)
			(xy 129.826048 -149.848666) (xy 129.860919 -149.80625) (xy 129.901508 -149.76927) (xy 129.946979 -149.738489)
			(xy 129.996391 -149.714543) (xy 130.048726 -149.697926) (xy 130.102902 -149.688982) (xy 130.1578 -149.687894)
			(xy 130.212288 -149.694686) (xy 130.26524 -149.709217) (xy 130.315562 -149.731187) (xy 130.362216 -149.760143)
			(xy 130.383534 -149.77745) (xy 130.40215 -149.792449) (xy 130.443833 -149.815847) (xy 130.48916 -149.831029)
			(xy 130.536527 -149.83746) (xy 130.58426 -149.834912) (xy 130.630673 -149.823475) (xy 130.674126 -149.803554)
			(xy 130.693922 -149.79015) (xy 130.71658 -149.774637) (xy 130.765445 -149.749586) (xy 130.817396 -149.731797)
			(xy 130.87136 -149.721637) (xy 130.926223 -149.719317) (xy 130.980852 -149.724883) (xy 131.03412 -149.738221)
			(xy 131.084926 -149.759056) (xy 131.132221 -149.786958) (xy 131.175029 -149.82135) (xy 131.212467 -149.861522)
			(xy 131.24376 -149.906645) (xy 131.261663 -149.94255) (xy 133.638034 -149.94255) (xy 133.642105 -149.886928)
			(xy 133.654231 -149.832491) (xy 133.674154 -149.7804) (xy 133.70145 -149.731765) (xy 133.735536 -149.687622)
			(xy 133.775685 -149.648913) (xy 133.821043 -149.616462) (xy 133.870643 -149.590961) (xy 133.923427 -149.572954)
			(xy 133.97827 -149.562824) (xy 134.034004 -149.560787) (xy 134.089441 -149.566887) (xy 134.143398 -149.580993)
			(xy 134.194727 -149.602805) (xy 134.242333 -149.631859) (xy 134.285201 -149.667534) (xy 134.322418 -149.709071)
			(xy 134.353191 -149.755584) (xy 134.376863 -149.806081) (xy 134.392931 -149.859488) (xy 134.401051 -149.914664)
			(xy 134.40156 -149.94255) (xy 135.009634 -149.94255) (xy 135.013705 -149.886928) (xy 135.025831 -149.832491)
			(xy 135.045754 -149.7804) (xy 135.07305 -149.731765) (xy 135.107136 -149.687622) (xy 135.147285 -149.648913)
			(xy 135.192643 -149.616462) (xy 135.242243 -149.590961) (xy 135.295027 -149.572954) (xy 135.34987 -149.562824)
			(xy 135.405604 -149.560787) (xy 135.461041 -149.566887) (xy 135.514998 -149.580993) (xy 135.566327 -149.602805)
			(xy 135.613933 -149.631859) (xy 135.656801 -149.667534) (xy 135.694018 -149.709071) (xy 135.724791 -149.755584)
			(xy 135.748463 -149.806081) (xy 135.764531 -149.859488) (xy 135.770662 -149.901148) (xy 136.956036 -149.901148)
			(xy 136.960107 -149.845526) (xy 136.972233 -149.791089) (xy 136.992156 -149.738998) (xy 137.019452 -149.690363)
			(xy 137.053538 -149.64622) (xy 137.093687 -149.607511) (xy 137.139045 -149.57506) (xy 137.188645 -149.549559)
			(xy 137.241429 -149.531552) (xy 137.296272 -149.521422) (xy 137.352006 -149.519385) (xy 137.407443 -149.525485)
			(xy 137.4614 -149.539591) (xy 137.512729 -149.561403) (xy 137.560335 -149.590457) (xy 137.603203 -149.626132)
			(xy 137.64042 -149.667669) (xy 137.671193 -149.714182) (xy 137.694865 -149.764679) (xy 137.710933 -149.818086)
			(xy 137.719053 -149.873262) (xy 137.719562 -149.901148) (xy 137.719557 -149.901402) (xy 138.555982 -149.901402)
			(xy 138.560053 -149.84578) (xy 138.572179 -149.791343) (xy 138.592102 -149.739252) (xy 138.619398 -149.690617)
			(xy 138.653484 -149.646474) (xy 138.693633 -149.607765) (xy 138.738991 -149.575314) (xy 138.788591 -149.549813)
			(xy 138.841375 -149.531806) (xy 138.896218 -149.521676) (xy 138.951952 -149.519639) (xy 139.007389 -149.525739)
			(xy 139.061346 -149.539845) (xy 139.112675 -149.561657) (xy 139.160281 -149.590711) (xy 139.203149 -149.626386)
			(xy 139.240366 -149.667923) (xy 139.271139 -149.714436) (xy 139.294811 -149.764933) (xy 139.310879 -149.81834)
			(xy 139.318999 -149.873516) (xy 139.319508 -149.901402) (xy 139.318999 -149.929288) (xy 139.310879 -149.984464)
			(xy 139.294811 -150.037871) (xy 139.271139 -150.088368) (xy 139.240366 -150.134881) (xy 139.203149 -150.176418)
			(xy 139.160281 -150.212093) (xy 139.112675 -150.241147) (xy 139.061346 -150.262959) (xy 139.007389 -150.277065)
			(xy 138.951952 -150.283165) (xy 138.896218 -150.281128) (xy 138.841375 -150.270998) (xy 138.788591 -150.252991)
			(xy 138.738991 -150.22749) (xy 138.693633 -150.195039) (xy 138.653484 -150.15633) (xy 138.619398 -150.112187)
			(xy 138.592102 -150.063552) (xy 138.572179 -150.011461) (xy 138.560053 -149.957024) (xy 138.555982 -149.901402)
			(xy 137.719557 -149.901402) (xy 137.719053 -149.929034) (xy 137.710933 -149.98421) (xy 137.694865 -150.037617)
			(xy 137.671193 -150.088114) (xy 137.64042 -150.134627) (xy 137.603203 -150.176164) (xy 137.560335 -150.211839)
			(xy 137.512729 -150.240893) (xy 137.4614 -150.262705) (xy 137.407443 -150.276811) (xy 137.352006 -150.282911)
			(xy 137.296272 -150.280874) (xy 137.241429 -150.270744) (xy 137.188645 -150.252737) (xy 137.139045 -150.227236)
			(xy 137.093687 -150.194785) (xy 137.053538 -150.156076) (xy 137.019452 -150.111933) (xy 136.992156 -150.063298)
			(xy 136.972233 -150.011207) (xy 136.960107 -149.95677) (xy 136.956036 -149.901148) (xy 135.770662 -149.901148)
			(xy 135.772651 -149.914664) (xy 135.77316 -149.94255) (xy 135.772651 -149.970436) (xy 135.764531 -150.025612)
			(xy 135.748463 -150.079019) (xy 135.724791 -150.129516) (xy 135.694018 -150.176029) (xy 135.656801 -150.217566)
			(xy 135.613933 -150.253241) (xy 135.566327 -150.282295) (xy 135.514998 -150.304107) (xy 135.461041 -150.318213)
			(xy 135.405604 -150.324313) (xy 135.34987 -150.322276) (xy 135.295027 -150.312146) (xy 135.242243 -150.294139)
			(xy 135.192643 -150.268638) (xy 135.147285 -150.236187) (xy 135.107136 -150.197478) (xy 135.07305 -150.153335)
			(xy 135.045754 -150.1047) (xy 135.025831 -150.052609) (xy 135.013705 -149.998172) (xy 135.009634 -149.94255)
			(xy 134.40156 -149.94255) (xy 134.401051 -149.970436) (xy 134.392931 -150.025612) (xy 134.376863 -150.079019)
			(xy 134.353191 -150.129516) (xy 134.322418 -150.176029) (xy 134.285201 -150.217566) (xy 134.242333 -150.253241)
			(xy 134.194727 -150.282295) (xy 134.143398 -150.304107) (xy 134.089441 -150.318213) (xy 134.034004 -150.324313)
			(xy 133.97827 -150.322276) (xy 133.923427 -150.312146) (xy 133.870643 -150.294139) (xy 133.821043 -150.268638)
			(xy 133.775685 -150.236187) (xy 133.735536 -150.197478) (xy 133.70145 -150.153335) (xy 133.674154 -150.1047)
			(xy 133.654231 -150.052609) (xy 133.642105 -149.998172) (xy 133.638034 -149.94255) (xy 131.261663 -149.94255)
			(xy 131.268263 -149.955787) (xy 131.28547 -150.007933) (xy 131.295026 -150.062007) (xy 131.296733 -150.116893)
			(xy 131.290556 -150.171456) (xy 131.276623 -150.224571) (xy 131.255222 -150.275141) (xy 131.226793 -150.322122)
			(xy 131.191925 -150.364543) (xy 131.151337 -150.401529) (xy 131.105867 -150.432315) (xy 131.056454 -150.456268)
			(xy 131.004118 -150.472891) (xy 130.949941 -150.481841) (xy 130.89504 -150.482935) (xy 130.840548 -150.476148)
			(xy 130.787592 -150.461623) (xy 130.737265 -150.439657) (xy 130.690605 -150.410705) (xy 130.669284 -150.3934)
			(xy 130.650656 -150.378418) (xy 130.608974 -150.355024) (xy 130.563651 -150.339842) (xy 130.516287 -150.33341)
			(xy 130.468557 -150.335955) (xy 130.422145 -150.347386) (xy 130.378693 -150.3673) (xy 130.358896 -150.3807)
			(xy 130.336193 -150.396148) (xy 130.28733 -150.421196) (xy 130.235381 -150.438982) (xy 130.181419 -150.449138)
			(xy 130.126559 -150.451456) (xy 130.071932 -150.445887) (xy 130.018668 -150.432547) (xy 129.967866 -150.41171)
			(xy 129.920575 -150.383807) (xy 129.877771 -150.349415) (xy 129.840338 -150.309242) (xy 129.80905 -150.264119)
			(xy 129.784551 -150.214978) (xy 129.767349 -150.162833) (xy 129.757798 -150.108761) (xy 129.756095 -150.053878)
			(xy 125.603 -150.053878) (xy 125.603 -152.02535) (xy 126.2126 -152.63495) (xy 126.754634 -152.63495)
			(xy 126.758705 -152.579328) (xy 126.770831 -152.524891) (xy 126.790754 -152.4728) (xy 126.81805 -152.424165)
			(xy 126.852136 -152.380022) (xy 126.892285 -152.341313) (xy 126.937643 -152.308862) (xy 126.987243 -152.283361)
			(xy 127.040027 -152.265354) (xy 127.09487 -152.255224) (xy 127.150604 -152.253187) (xy 127.206041 -152.259287)
			(xy 127.259998 -152.273393) (xy 127.311327 -152.295205) (xy 127.358933 -152.324259) (xy 127.401801 -152.359934)
			(xy 127.439018 -152.401471) (xy 127.469791 -152.447984) (xy 127.493463 -152.498481) (xy 127.496312 -152.50795)
			(xy 128.075434 -152.50795) (xy 128.079505 -152.452328) (xy 128.091631 -152.397891) (xy 128.111554 -152.3458)
			(xy 128.13885 -152.297165) (xy 128.172936 -152.253022) (xy 128.213085 -152.214313) (xy 128.258443 -152.181862)
			(xy 128.308043 -152.156361) (xy 128.360827 -152.138354) (xy 128.41567 -152.128224) (xy 128.471404 -152.126187)
			(xy 128.526841 -152.132287) (xy 128.580798 -152.146393) (xy 128.632127 -152.168205) (xy 128.679733 -152.197259)
			(xy 128.722601 -152.232934) (xy 128.759818 -152.274471) (xy 128.790591 -152.320984) (xy 128.814263 -152.371481)
			(xy 128.830331 -152.424888) (xy 128.838451 -152.480064) (xy 128.83896 -152.50795) (xy 128.838451 -152.535836)
			(xy 128.830331 -152.591012) (xy 128.814263 -152.644419) (xy 128.790591 -152.694916) (xy 128.759818 -152.741429)
			(xy 128.722601 -152.782966) (xy 128.679733 -152.818641) (xy 128.632127 -152.847695) (xy 128.580798 -152.869507)
			(xy 128.526841 -152.883613) (xy 128.471404 -152.889713) (xy 128.41567 -152.887676) (xy 128.360827 -152.877546)
			(xy 128.308043 -152.859539) (xy 128.258443 -152.834038) (xy 128.213085 -152.801587) (xy 128.172936 -152.762878)
			(xy 128.13885 -152.718735) (xy 128.111554 -152.6701) (xy 128.091631 -152.618009) (xy 128.079505 -152.563572)
			(xy 128.075434 -152.50795) (xy 127.496312 -152.50795) (xy 127.509531 -152.551888) (xy 127.517651 -152.607064)
			(xy 127.51816 -152.63495) (xy 127.517651 -152.662836) (xy 127.509531 -152.718012) (xy 127.493463 -152.771419)
			(xy 127.469791 -152.821916) (xy 127.439018 -152.868429) (xy 127.401801 -152.909966) (xy 127.358933 -152.945641)
			(xy 127.311327 -152.974695) (xy 127.259998 -152.996507) (xy 127.206041 -153.010613) (xy 127.150604 -153.016713)
			(xy 127.09487 -153.014676) (xy 127.040027 -153.004546) (xy 126.987243 -152.986539) (xy 126.937643 -152.961038)
			(xy 126.892285 -152.928587) (xy 126.852136 -152.889878) (xy 126.81805 -152.845735) (xy 126.790754 -152.7971)
			(xy 126.770831 -152.745009) (xy 126.758705 -152.690572) (xy 126.754634 -152.63495) (xy 126.2126 -152.63495)
			(xy 127.02032 -153.44267) (xy 129.060194 -153.44267)
		)
		(stroke
			(width 0)
			(type solid)
		)
		(fill yes)
		(layer "In2.Cu")
		(net "P1V0_NODE1")
	)
	(gr_poly
		(pts
			(xy 141.363446 -55.984648) (xy 145.790666 -55.984648) (xy 145.821908 -56.015636) (xy 146.803872 -56.015636)
			(xy 146.87042 -55.96763) (xy 146.883374 -55.928514) (xy 146.892662 -55.901987) (xy 146.91793 -55.851783)
			(xy 146.95029 -55.805831) (xy 146.989043 -55.765124) (xy 147.03335 -55.730545) (xy 147.082252 -55.702841)
			(xy 147.134689 -55.682613) (xy 147.189527 -55.670298) (xy 147.245578 -55.666163) (xy 147.301629 -55.670298)
			(xy 147.356467 -55.682613) (xy 147.408904 -55.702841) (xy 147.457806 -55.730545) (xy 147.502113 -55.765124)
			(xy 147.540866 -55.805831) (xy 147.573226 -55.851783) (xy 147.598494 -55.901987) (xy 147.607782 -55.928514)
			(xy 147.620736 -55.96763) (xy 147.687284 -56.015636) (xy 147.787868 -56.015636) (xy 147.80311 -56.015183)
			(xy 147.832721 -56.007942) (xy 147.859773 -55.99389) (xy 147.882723 -55.973827) (xy 147.900265 -55.948896)
			(xy 147.906232 -55.934864) (xy 147.916446 -55.909965) (xy 147.942865 -55.863078) (xy 147.975611 -55.82037)
			(xy 148.014036 -55.782689) (xy 148.057375 -55.750783) (xy 148.104769 -55.725285) (xy 148.155277 -55.706702)
			(xy 148.207894 -55.695403) (xy 148.261578 -55.691611) (xy 148.315262 -55.695403) (xy 148.367879 -55.706702)
			(xy 148.418387 -55.725285) (xy 148.465781 -55.750783) (xy 148.50912 -55.782689) (xy 148.547545 -55.82037)
			(xy 148.580291 -55.863078) (xy 148.60671 -55.909965) (xy 148.616924 -55.934864) (xy 148.631148 -55.97144)
			(xy 148.695918 -56.015636) (xy 148.800566 -56.015636) (xy 148.917406 -55.934102) (xy 148.931884 -55.903114)
			(xy 148.943773 -55.878822) (xy 148.973383 -55.833567) (xy 149.009085 -55.792944) (xy 149.050164 -55.757767)
			(xy 149.095797 -55.728742) (xy 149.14507 -55.706448) (xy 149.196997 -55.691333) (xy 149.250537 -55.683699)
			(xy 149.304619 -55.683699) (xy 149.358159 -55.691333) (xy 149.410086 -55.706448) (xy 149.459359 -55.728742)
			(xy 149.504992 -55.757767) (xy 149.546071 -55.792944) (xy 149.581773 -55.833567) (xy 149.611383 -55.878822)
			(xy 149.623272 -55.903114) (xy 149.63775 -55.934102) (xy 149.75459 -56.015636) (xy 149.862286 -56.015636)
			(xy 149.968204 -55.956962) (xy 149.984714 -55.934102) (xy 150.000727 -55.912778) (xy 150.037739 -55.874387)
			(xy 150.079736 -55.841524) (xy 150.1259 -55.814829) (xy 150.175332 -55.794823) (xy 150.227067 -55.781894)
			(xy 150.280099 -55.776294) (xy 150.333394 -55.778134) (xy 150.385914 -55.787376) (xy 150.436635 -55.803842)
			(xy 150.484569 -55.827209) (xy 150.528783 -55.857024) (xy 150.568414 -55.892704) (xy 150.602691 -55.933555)
			(xy 150.617174 -55.955946) (xy 150.6347 -55.983886) (xy 150.69185 -56.015636) (xy 150.864062 -56.015636)
			(xy 150.972774 -55.950866) (xy 150.98903 -55.92572) (xy 151.004748 -55.90231) (xy 151.041971 -55.859956)
			(xy 151.085022 -55.823541) (xy 151.132963 -55.793858) (xy 151.18475 -55.771553) (xy 151.239255 -55.757112)
			(xy 151.295292 -55.75085) (xy 151.351641 -55.752901) (xy 151.407074 -55.763223) (xy 151.460385 -55.78159)
			(xy 151.510413 -55.807602) (xy 151.556068 -55.840693) (xy 151.596356 -55.880142) (xy 151.630401 -55.925091)
			(xy 151.64435 -55.949596) (xy 151.661114 -55.98033) (xy 151.720804 -56.015636) (xy 153.05151 -56.015636)
			(xy 153.068159 -56.015092) (xy 153.100323 -56.006473) (xy 153.129161 -55.989825) (xy 153.152709 -55.966282)
			(xy 153.169363 -55.937447) (xy 153.177988 -55.905285) (xy 153.17851 -55.888636) (xy 153.17851 -42.852848)
			(xy 153.137108 -42.760138) (xy 153.119074 -42.742612) (xy 153.085618 -42.710125) (xy 153.023756 -42.640333)
			(xy 152.968066 -42.565523) (xy 152.918953 -42.48624) (xy 152.876776 -42.403059) (xy 152.84184 -42.316587)
			(xy 152.8144 -42.227453) (xy 152.794655 -42.136305) (xy 152.78275 -42.043805) (xy 152.77877 -41.950628)
			(xy 152.782745 -41.85745) (xy 152.794646 -41.76495) (xy 152.814386 -41.6738) (xy 152.841821 -41.584664)
			(xy 152.876753 -41.498191) (xy 152.918926 -41.415009) (xy 152.968035 -41.335723) (xy 153.023721 -41.26091)
			(xy 153.08558 -41.191115) (xy 153.119074 -41.158668) (xy 153.137108 -41.141142) (xy 153.17851 -41.048432)
			(xy 153.17851 -24.499062) (xy 153.178004 -24.475541) (xy 153.169357 -24.429301) (xy 153.152347 -24.385443)
			(xy 153.127555 -24.345464) (xy 153.095828 -24.310732) (xy 153.058251 -24.282433) (xy 153.016107 -24.261533)
			(xy 152.970836 -24.248748) (xy 152.923986 -24.244513) (xy 152.877156 -24.248974) (xy 152.854406 -24.254968)
			(xy 152.827418 -24.262218) (xy 152.772033 -24.269658) (xy 152.716156 -24.268938) (xy 152.660982 -24.260076)
			(xy 152.60769 -24.243259) (xy 152.557422 -24.218848) (xy 152.511253 -24.187366) (xy 152.470169 -24.149485)
			(xy 152.435052 -24.106017) (xy 152.40665 -24.057891) (xy 152.385573 -24.006136) (xy 152.37841 -23.979124)
			(xy 152.37249 -23.953124) (xy 152.367119 -23.900072) (xy 152.369185 -23.846789) (xy 152.378647 -23.794312)
			(xy 152.395321 -23.743663) (xy 152.418882 -23.695828) (xy 152.448873 -23.651738) (xy 152.484708 -23.612251)
			(xy 152.525691 -23.578137) (xy 152.571023 -23.550059) (xy 152.619822 -23.528564) (xy 152.645364 -23.520908)
			(xy 152.66729 -23.513294) (xy 152.708136 -23.491264) (xy 152.744304 -23.462183) (xy 152.774589 -23.427018)
			(xy 152.797986 -23.386939) (xy 152.813717 -23.343277) (xy 152.821257 -23.297485) (xy 152.821386 -23.274274)
			(xy 152.820149 -23.247459) (xy 152.824301 -23.193939) (xy 152.835907 -23.141529) (xy 152.854738 -23.091261)
			(xy 152.880424 -23.044125) (xy 152.896062 -23.022306) (xy 152.914451 -22.998472) (xy 152.957467 -22.956364)
			(xy 153.006564 -22.921537) (xy 153.060524 -22.894857) (xy 153.089102 -22.8854) (xy 153.12898 -22.872954)
			(xy 153.17851 -22.805898) (xy 153.17851 -3.21945) (xy 153.177976 -3.20283) (xy 153.169394 -3.170718)
			(xy 153.152801 -3.141916) (xy 153.141426 -3.129788) (xy 151.649684 -1.6383) (xy 93.872304 -1.6383)
			(xy 93.59646 -1.914144) (xy 93.59646 -4.497134) (xy 96.123297 -4.497134) (xy 96.130284 -4.442681)
			(xy 96.145005 -4.389792) (xy 96.167155 -4.339559) (xy 96.196277 -4.293021) (xy 96.231769 -4.251137)
			(xy 96.272898 -4.214774) (xy 96.318816 -4.184682) (xy 96.368572 -4.161483) (xy 96.421141 -4.145655)
			(xy 96.475435 -4.137527) (xy 96.530334 -4.137265) (xy 96.584703 -4.144876) (xy 96.63742 -4.160201)
			(xy 96.687395 -4.182925) (xy 96.710754 -4.19735) (xy 96.731173 -4.2098) (xy 96.775553 -4.227605)
			(xy 96.822479 -4.236802) (xy 96.870297 -4.237068) (xy 96.917323 -4.228394) (xy 96.961899 -4.211084)
			(xy 97.002455 -4.18575) (xy 97.02038 -4.169918) (xy 97.040894 -4.151679) (xy 97.086105 -4.120556)
			(xy 97.135311 -4.096236) (xy 97.187495 -4.07922) (xy 97.241579 -4.069859) (xy 97.296447 -4.068348)
			(xy 97.350964 -4.074718) (xy 97.404006 -4.088836) (xy 97.454476 -4.110412) (xy 97.501332 -4.138999)
			(xy 97.543606 -4.174007) (xy 97.580426 -4.214714) (xy 97.61103 -4.260278) (xy 97.634787 -4.309758)
			(xy 97.651206 -4.362133) (xy 97.659949 -4.416321) (xy 97.660489 -4.449826) (xy 100.96449 -4.449826)
			(xy 100.968561 -4.394204) (xy 100.980687 -4.339767) (xy 101.00061 -4.287676) (xy 101.027906 -4.239041)
			(xy 101.061992 -4.194898) (xy 101.102141 -4.156189) (xy 101.147499 -4.123738) (xy 101.197099 -4.098237)
			(xy 101.249883 -4.08023) (xy 101.304726 -4.0701) (xy 101.36046 -4.068063) (xy 101.415897 -4.074163)
			(xy 101.469854 -4.088269) (xy 101.521183 -4.110081) (xy 101.568789 -4.139135) (xy 101.611657 -4.17481)
			(xy 101.648874 -4.216347) (xy 101.679647 -4.26286) (xy 101.703319 -4.313357) (xy 101.719387 -4.366764)
			(xy 101.727507 -4.42194) (xy 101.728016 -4.449826) (xy 101.727507 -4.477712) (xy 101.719387 -4.532888)
			(xy 101.703319 -4.586295) (xy 101.679647 -4.636792) (xy 101.648874 -4.683305) (xy 101.611657 -4.724842)
			(xy 101.568789 -4.760517) (xy 101.521183 -4.789571) (xy 101.469854 -4.811383) (xy 101.415897 -4.825489)
			(xy 101.36046 -4.831589) (xy 101.304726 -4.829552) (xy 101.249883 -4.819422) (xy 101.197099 -4.801415)
			(xy 101.147499 -4.775914) (xy 101.102141 -4.743463) (xy 101.061992 -4.704754) (xy 101.027906 -4.660611)
			(xy 101.00061 -4.611976) (xy 100.980687 -4.559885) (xy 100.968561 -4.505448) (xy 100.96449 -4.449826)
			(xy 97.660489 -4.449826) (xy 97.660833 -4.471202) (xy 97.653842 -4.525643) (xy 97.639119 -4.578519)
			(xy 97.616969 -4.62874) (xy 97.587848 -4.675266) (xy 97.55236 -4.717138) (xy 97.511236 -4.753491)
			(xy 97.465325 -4.783573) (xy 97.415577 -4.806764) (xy 97.363018 -4.822584) (xy 97.308734 -4.830707)
			(xy 97.253847 -4.830965) (xy 97.199489 -4.823353) (xy 97.146784 -4.808027) (xy 97.096819 -4.785305)
			(xy 97.073466 -4.770882) (xy 97.053031 -4.758461) (xy 97.008654 -4.74066) (xy 96.961733 -4.731463)
			(xy 96.91392 -4.731194) (xy 96.866898 -4.739863) (xy 96.822324 -4.757164) (xy 96.781767 -4.782487)
			(xy 96.76384 -4.798314) (xy 96.743396 -4.816637) (xy 96.69818 -4.847773) (xy 96.648968 -4.872105)
			(xy 96.596776 -4.889133) (xy 96.542682 -4.898503) (xy 96.487804 -4.900022) (xy 96.433274 -4.893659)
			(xy 96.38022 -4.879545) (xy 96.329738 -4.857972) (xy 96.282868 -4.829385) (xy 96.240581 -4.794374)
			(xy 96.203749 -4.753664) (xy 96.173133 -4.708095) (xy 96.149365 -4.658607) (xy 96.132937 -4.606223)
			(xy 96.124187 -4.552026) (xy 96.123297 -4.497134) (xy 93.59646 -4.497134) (xy 93.59646 -5.462778)
			(xy 96.62236 -5.462778) (xy 96.626431 -5.407156) (xy 96.638557 -5.352719) (xy 96.65848 -5.300628)
			(xy 96.685776 -5.251993) (xy 96.719862 -5.20785) (xy 96.760011 -5.169141) (xy 96.805369 -5.13669)
			(xy 96.854969 -5.111189) (xy 96.907753 -5.093182) (xy 96.962596 -5.083052) (xy 97.01833 -5.081015)
			(xy 97.073767 -5.087115) (xy 97.127724 -5.101221) (xy 97.179053 -5.123033) (xy 97.226659 -5.152087)
			(xy 97.269527 -5.187762) (xy 97.27304 -5.191683) (xy 98.485923 -5.191683) (xy 98.493832 -5.137209)
			(xy 98.509487 -5.084436) (xy 98.532563 -5.034461) (xy 98.56258 -4.988321) (xy 98.598916 -4.946972)
			(xy 98.640817 -4.911275) (xy 98.687412 -4.881969) (xy 98.737735 -4.859662) (xy 98.790742 -4.844819)
			(xy 98.845331 -4.837746) (xy 98.90037 -4.838591) (xy 98.954716 -4.847336) (xy 99.007241 -4.8638)
			(xy 99.056856 -4.887641) (xy 99.10253 -4.918364) (xy 99.123246 -4.93649) (xy 99.140928 -4.951784)
			(xy 99.180733 -4.976293) (xy 99.22435 -4.993107) (xy 99.270307 -5.001658) (xy 99.317053 -5.001658)
			(xy 99.36301 -4.993107) (xy 99.406627 -4.976293) (xy 99.446432 -4.951784) (xy 99.464114 -4.93649)
			(xy 99.484838 -4.91837) (xy 99.530513 -4.887641) (xy 99.58013 -4.863795) (xy 99.632658 -4.847327)
			(xy 99.687008 -4.838578) (xy 99.742051 -4.83773) (xy 99.796644 -4.8448) (xy 99.849655 -4.859643)
			(xy 99.899982 -4.881949) (xy 99.946582 -4.911255) (xy 99.988487 -4.946955) (xy 100.024827 -4.988305)
			(xy 100.054847 -5.034448) (xy 100.077925 -5.084427) (xy 100.093582 -5.137203) (xy 100.101492 -5.191681)
			(xy 100.101491 -5.24673) (xy 100.09358 -5.301208) (xy 100.077922 -5.353983) (xy 100.054842 -5.403961)
			(xy 100.044833 -5.419344) (xy 100.622352 -5.419344) (xy 100.626423 -5.363722) (xy 100.638549 -5.309285)
			(xy 100.658472 -5.257194) (xy 100.685768 -5.208559) (xy 100.719854 -5.164416) (xy 100.760003 -5.125707)
			(xy 100.805361 -5.093256) (xy 100.854961 -5.067755) (xy 100.907745 -5.049748) (xy 100.962588 -5.039618)
			(xy 101.018322 -5.037581) (xy 101.073759 -5.043681) (xy 101.127716 -5.057787) (xy 101.179045 -5.079599)
			(xy 101.226651 -5.108653) (xy 101.269519 -5.144328) (xy 101.306736 -5.185865) (xy 101.337509 -5.232378)
			(xy 101.361181 -5.282875) (xy 101.377249 -5.336282) (xy 101.385369 -5.391458) (xy 101.385878 -5.419344)
			(xy 101.385369 -5.44723) (xy 101.377249 -5.502406) (xy 101.361181 -5.555813) (xy 101.337509 -5.60631)
			(xy 101.306736 -5.652823) (xy 101.269519 -5.69436) (xy 101.226651 -5.730035) (xy 101.179045 -5.759089)
			(xy 101.127716 -5.780901) (xy 101.073759 -5.795007) (xy 101.018322 -5.801107) (xy 100.962588 -5.79907)
			(xy 100.907745 -5.78894) (xy 100.854961 -5.770933) (xy 100.805361 -5.745432) (xy 100.760003 -5.712981)
			(xy 100.719854 -5.674272) (xy 100.685768 -5.630129) (xy 100.658472 -5.581494) (xy 100.638549 -5.529403)
			(xy 100.626423 -5.474966) (xy 100.622352 -5.419344) (xy 100.044833 -5.419344) (xy 100.02482 -5.450104)
			(xy 99.988479 -5.491453) (xy 99.946574 -5.527151) (xy 99.899973 -5.556456) (xy 99.849645 -5.578761)
			(xy 99.796634 -5.593602) (xy 99.74204 -5.600671) (xy 99.686997 -5.599821) (xy 99.632648 -5.591071)
			(xy 99.58012 -5.574601) (xy 99.530504 -5.550754) (xy 99.48483 -5.520024) (xy 99.464114 -5.501894)
			(xy 99.446432 -5.4866) (xy 99.406627 -5.462091) (xy 99.36301 -5.445277) (xy 99.317053 -5.436726)
			(xy 99.270307 -5.436726) (xy 99.22435 -5.445277) (xy 99.180733 -5.462091) (xy 99.140928 -5.4866)
			(xy 99.123246 -5.501894) (xy 99.102538 -5.52003) (xy 99.056865 -5.550754) (xy 99.007251 -5.574596)
			(xy 98.954726 -5.591061) (xy 98.90038 -5.599808) (xy 98.845341 -5.600655) (xy 98.790752 -5.593584)
			(xy 98.737746 -5.578741) (xy 98.687422 -5.556437) (xy 98.640826 -5.527132) (xy 98.598924 -5.491435)
			(xy 98.562587 -5.450088) (xy 98.532568 -5.403948) (xy 98.509491 -5.353974) (xy 98.493835 -5.301202)
			(xy 98.485924 -5.246728) (xy 98.485923 -5.191683) (xy 97.27304 -5.191683) (xy 97.306744 -5.229299)
			(xy 97.337517 -5.275812) (xy 97.361189 -5.326309) (xy 97.377257 -5.379716) (xy 97.385377 -5.434892)
			(xy 97.385886 -5.462778) (xy 97.385377 -5.490664) (xy 97.377257 -5.54584) (xy 97.361189 -5.599247)
			(xy 97.337517 -5.649744) (xy 97.306744 -5.696257) (xy 97.269527 -5.737794) (xy 97.226659 -5.773469)
			(xy 97.179053 -5.802523) (xy 97.127724 -5.824335) (xy 97.073767 -5.838441) (xy 97.01833 -5.844541)
			(xy 96.962596 -5.842504) (xy 96.907753 -5.832374) (xy 96.854969 -5.814367) (xy 96.805369 -5.788866)
			(xy 96.760011 -5.756415) (xy 96.719862 -5.717706) (xy 96.685776 -5.673563) (xy 96.65848 -5.624928)
			(xy 96.638557 -5.572837) (xy 96.626431 -5.5184) (xy 96.62236 -5.462778) (xy 93.59646 -5.462778) (xy 93.59646 -7.33552)
			(xy 94.3737 -8.11276) (xy 118.13413 -8.11276) (xy 118.25859 -8.010144) (xy 118.26748 -7.966202) (xy 118.286013 -7.878035)
			(xy 118.329988 -7.703298) (xy 118.381759 -7.53071) (xy 118.441224 -7.36062) (xy 118.508261 -7.193369)
			(xy 118.582736 -7.029295) (xy 118.664499 -6.868729) (xy 118.753385 -6.711993) (xy 118.849215 -6.559404)
			(xy 118.951795 -6.411269) (xy 119.06092 -6.267887) (xy 119.176369 -6.129546) (xy 119.29791 -5.996525)
			(xy 119.425298 -5.869092) (xy 119.558276 -5.747504) (xy 119.696577 -5.632006) (xy 119.839921 -5.522831)
			(xy 119.988019 -5.420198) (xy 120.140575 -5.324314) (xy 120.297279 -5.235373) (xy 120.457817 -5.153554)
			(xy 120.621864 -5.079021) (xy 120.789091 -5.011925) (xy 120.959161 -4.9524) (xy 121.13173 -4.900568)
			(xy 121.306452 -4.856532) (xy 121.482973 -4.82038) (xy 121.660939 -4.792187) (xy 121.839991 -4.772008)
			(xy 122.019768 -4.759884) (xy 122.199908 -4.755841) (xy 122.380048 -4.759884) (xy 122.559825 -4.772008)
			(xy 122.738877 -4.792187) (xy 122.916843 -4.82038) (xy 123.093364 -4.856532) (xy 123.268086 -4.900568)
			(xy 123.440655 -4.9524) (xy 123.610725 -5.011925) (xy 123.777952 -5.079021) (xy 123.941999 -5.153554)
			(xy 124.102537 -5.235373) (xy 124.259241 -5.324314) (xy 124.411797 -5.420198) (xy 124.559895 -5.522831)
			(xy 124.703239 -5.632006) (xy 124.84154 -5.747504) (xy 124.974518 -5.869092) (xy 125.101906 -5.996525)
			(xy 125.223447 -6.129546) (xy 125.338896 -6.267887) (xy 125.448021 -6.411269) (xy 125.550601 -6.559404)
			(xy 125.646431 -6.711993) (xy 125.735317 -6.868729) (xy 125.81708 -7.029295) (xy 125.891555 -7.193369)
			(xy 125.940692 -7.315962) (xy 129.787911 -7.315962) (xy 129.791914 -7.2281) (xy 129.80389 -7.140966)
			(xy 129.823741 -7.055282) (xy 129.8513 -6.971758) (xy 129.886341 -6.891086) (xy 129.928572 -6.813935)
			(xy 129.977644 -6.740944) (xy 130.033151 -6.672718) (xy 130.094631 -6.609822) (xy 130.161576 -6.552777)
			(xy 130.233431 -6.502056) (xy 130.309601 -6.458079) (xy 130.389454 -6.421211) (xy 130.472329 -6.391758)
			(xy 130.557539 -6.369962) (xy 130.644378 -6.356006) (xy 130.732126 -6.350003) (xy 130.820056 -6.352005)
			(xy 130.907441 -6.361995) (xy 130.993554 -6.37989) (xy 131.077684 -6.405541) (xy 131.159132 -6.438736)
			(xy 131.237225 -6.4792) (xy 131.311314 -6.526598) (xy 131.380786 -6.580537) (xy 131.445065 -6.64057)
			(xy 131.503619 -6.706199) (xy 131.555963 -6.776881) (xy 131.601662 -6.85203) (xy 131.640338 -6.931023)
			(xy 131.67167 -7.013206) (xy 131.6954 -7.097898) (xy 131.71133 -7.184397) (xy 131.719328 -7.271985)
			(xy 131.719828 -7.315962) (xy 132.327911 -7.315962) (xy 132.331914 -7.2281) (xy 132.34389 -7.140966)
			(xy 132.363741 -7.055282) (xy 132.3913 -6.971758) (xy 132.426341 -6.891086) (xy 132.468572 -6.813935)
			(xy 132.517644 -6.740944) (xy 132.573151 -6.672718) (xy 132.634631 -6.609822) (xy 132.701576 -6.552777)
			(xy 132.773431 -6.502056) (xy 132.849601 -6.458079) (xy 132.929454 -6.421211) (xy 133.012329 -6.391758)
			(xy 133.097539 -6.369962) (xy 133.184378 -6.356006) (xy 133.272126 -6.350003) (xy 133.360056 -6.352005)
			(xy 133.447441 -6.361995) (xy 133.533554 -6.37989) (xy 133.617684 -6.405541) (xy 133.699132 -6.438736)
			(xy 133.777225 -6.4792) (xy 133.851314 -6.526598) (xy 133.920786 -6.580537) (xy 133.985065 -6.64057)
			(xy 134.043619 -6.706199) (xy 134.095963 -6.776881) (xy 134.141662 -6.85203) (xy 134.180338 -6.931023)
			(xy 134.21167 -7.013206) (xy 134.2354 -7.097898) (xy 134.25133 -7.184397) (xy 134.259328 -7.271985)
			(xy 134.259828 -7.315962) (xy 134.867911 -7.315962) (xy 134.871914 -7.2281) (xy 134.88389 -7.140966)
			(xy 134.903741 -7.055282) (xy 134.9313 -6.971758) (xy 134.966341 -6.891086) (xy 135.008572 -6.813935)
			(xy 135.057644 -6.740944) (xy 135.113151 -6.672718) (xy 135.174631 -6.609822) (xy 135.241576 -6.552777)
			(xy 135.313431 -6.502056) (xy 135.389601 -6.458079) (xy 135.469454 -6.421211) (xy 135.552329 -6.391758)
			(xy 135.637539 -6.369962) (xy 135.724378 -6.356006) (xy 135.812126 -6.350003) (xy 135.900056 -6.352005)
			(xy 135.987441 -6.361995) (xy 136.073554 -6.37989) (xy 136.157684 -6.405541) (xy 136.239132 -6.438736)
			(xy 136.317225 -6.4792) (xy 136.391314 -6.526598) (xy 136.460786 -6.580537) (xy 136.525065 -6.64057)
			(xy 136.583619 -6.706199) (xy 136.635963 -6.776881) (xy 136.681662 -6.85203) (xy 136.720338 -6.931023)
			(xy 136.75167 -7.013206) (xy 136.7754 -7.097898) (xy 136.79133 -7.184397) (xy 136.799328 -7.271985)
			(xy 136.799828 -7.315962) (xy 137.407911 -7.315962) (xy 137.411914 -7.2281) (xy 137.42389 -7.140966)
			(xy 137.443741 -7.055282) (xy 137.4713 -6.971758) (xy 137.506341 -6.891086) (xy 137.548572 -6.813935)
			(xy 137.597644 -6.740944) (xy 137.653151 -6.672718) (xy 137.714631 -6.609822) (xy 137.781576 -6.552777)
			(xy 137.853431 -6.502056) (xy 137.929601 -6.458079) (xy 138.009454 -6.421211) (xy 138.092329 -6.391758)
			(xy 138.177539 -6.369962) (xy 138.264378 -6.356006) (xy 138.352126 -6.350003) (xy 138.440056 -6.352005)
			(xy 138.527441 -6.361995) (xy 138.613554 -6.37989) (xy 138.697684 -6.405541) (xy 138.779132 -6.438736)
			(xy 138.857225 -6.4792) (xy 138.931314 -6.526598) (xy 139.000786 -6.580537) (xy 139.065065 -6.64057)
			(xy 139.123619 -6.706199) (xy 139.175963 -6.776881) (xy 139.221662 -6.85203) (xy 139.260338 -6.931023)
			(xy 139.29167 -7.013206) (xy 139.3154 -7.097898) (xy 139.33133 -7.184397) (xy 139.339328 -7.271985)
			(xy 139.339828 -7.315962) (xy 139.947911 -7.315962) (xy 139.951914 -7.2281) (xy 139.96389 -7.140966)
			(xy 139.983741 -7.055282) (xy 140.0113 -6.971758) (xy 140.046341 -6.891086) (xy 140.088572 -6.813935)
			(xy 140.137644 -6.740944) (xy 140.193151 -6.672718) (xy 140.254631 -6.609822) (xy 140.321576 -6.552777)
			(xy 140.393431 -6.502056) (xy 140.469601 -6.458079) (xy 140.549454 -6.421211) (xy 140.632329 -6.391758)
			(xy 140.717539 -6.369962) (xy 140.804378 -6.356006) (xy 140.892126 -6.350003) (xy 140.980056 -6.352005)
			(xy 141.067441 -6.361995) (xy 141.153554 -6.37989) (xy 141.237684 -6.405541) (xy 141.319132 -6.438736)
			(xy 141.397225 -6.4792) (xy 141.471314 -6.526598) (xy 141.540786 -6.580537) (xy 141.605065 -6.64057)
			(xy 141.663619 -6.706199) (xy 141.715963 -6.776881) (xy 141.761662 -6.85203) (xy 141.800338 -6.931023)
			(xy 141.83167 -7.013206) (xy 141.8554 -7.097898) (xy 141.87133 -7.184397) (xy 141.879328 -7.271985)
			(xy 141.879828 -7.315962) (xy 145.686025 -7.315962) (xy 145.690028 -7.2281) (xy 145.702004 -7.140966)
			(xy 145.721855 -7.055282) (xy 145.749414 -6.971758) (xy 145.784455 -6.891086) (xy 145.826686 -6.813935)
			(xy 145.875758 -6.740944) (xy 145.931265 -6.672718) (xy 145.992745 -6.609822) (xy 146.05969 -6.552777)
			(xy 146.131545 -6.502056) (xy 146.207715 -6.458079) (xy 146.287568 -6.421211) (xy 146.370443 -6.391758)
			(xy 146.455653 -6.369962) (xy 146.542492 -6.356006) (xy 146.63024 -6.350003) (xy 146.71817 -6.352005)
			(xy 146.805555 -6.361995) (xy 146.891668 -6.37989) (xy 146.975798 -6.405541) (xy 147.057246 -6.438736)
			(xy 147.135339 -6.4792) (xy 147.209428 -6.526598) (xy 147.2789 -6.580537) (xy 147.343179 -6.64057)
			(xy 147.401733 -6.706199) (xy 147.454077 -6.776881) (xy 147.499776 -6.85203) (xy 147.538452 -6.931023)
			(xy 147.569784 -7.013206) (xy 147.593514 -7.097898) (xy 147.609444 -7.184397) (xy 147.617442 -7.271985)
			(xy 147.617942 -7.315962) (xy 148.226025 -7.315962) (xy 148.230028 -7.2281) (xy 148.242004 -7.140966)
			(xy 148.261855 -7.055282) (xy 148.289414 -6.971758) (xy 148.324455 -6.891086) (xy 148.366686 -6.813935)
			(xy 148.415758 -6.740944) (xy 148.471265 -6.672718) (xy 148.532745 -6.609822) (xy 148.59969 -6.552777)
			(xy 148.671545 -6.502056) (xy 148.747715 -6.458079) (xy 148.827568 -6.421211) (xy 148.910443 -6.391758)
			(xy 148.995653 -6.369962) (xy 149.082492 -6.356006) (xy 149.17024 -6.350003) (xy 149.25817 -6.352005)
			(xy 149.345555 -6.361995) (xy 149.431668 -6.37989) (xy 149.515798 -6.405541) (xy 149.597246 -6.438736)
			(xy 149.675339 -6.4792) (xy 149.749428 -6.526598) (xy 149.8189 -6.580537) (xy 149.883179 -6.64057)
			(xy 149.941733 -6.706199) (xy 149.994077 -6.776881) (xy 150.039776 -6.85203) (xy 150.078452 -6.931023)
			(xy 150.109784 -7.013206) (xy 150.133514 -7.097898) (xy 150.149444 -7.184397) (xy 150.157442 -7.271985)
			(xy 150.157942 -7.315962) (xy 150.766025 -7.315962) (xy 150.770028 -7.2281) (xy 150.782004 -7.140966)
			(xy 150.801855 -7.055282) (xy 150.829414 -6.971758) (xy 150.864455 -6.891086) (xy 150.906686 -6.813935)
			(xy 150.955758 -6.740944) (xy 151.011265 -6.672718) (xy 151.072745 -6.609822) (xy 151.13969 -6.552777)
			(xy 151.211545 -6.502056) (xy 151.287715 -6.458079) (xy 151.367568 -6.421211) (xy 151.450443 -6.391758)
			(xy 151.535653 -6.369962) (xy 151.622492 -6.356006) (xy 151.71024 -6.350003) (xy 151.79817 -6.352005)
			(xy 151.885555 -6.361995) (xy 151.971668 -6.37989) (xy 152.055798 -6.405541) (xy 152.137246 -6.438736)
			(xy 152.215339 -6.4792) (xy 152.289428 -6.526598) (xy 152.3589 -6.580537) (xy 152.423179 -6.64057)
			(xy 152.481733 -6.706199) (xy 152.534077 -6.776881) (xy 152.579776 -6.85203) (xy 152.618452 -6.931023)
			(xy 152.649784 -7.013206) (xy 152.673514 -7.097898) (xy 152.689444 -7.184397) (xy 152.697442 -7.271985)
			(xy 152.697942 -7.315962) (xy 152.697442 -7.359939) (xy 152.689444 -7.447527) (xy 152.673514 -7.534026)
			(xy 152.649784 -7.618718) (xy 152.618452 -7.700901) (xy 152.579776 -7.779894) (xy 152.534077 -7.855043)
			(xy 152.481733 -7.925725) (xy 152.423179 -7.991354) (xy 152.3589 -8.051387) (xy 152.289428 -8.105326)
			(xy 152.215339 -8.152724) (xy 152.137246 -8.193188) (xy 152.055798 -8.226383) (xy 151.971668 -8.252034)
			(xy 151.885555 -8.269929) (xy 151.79817 -8.279919) (xy 151.71024 -8.281921) (xy 151.622492 -8.275918)
			(xy 151.535653 -8.261962) (xy 151.450443 -8.240166) (xy 151.367568 -8.210713) (xy 151.287715 -8.173845)
			(xy 151.211545 -8.129868) (xy 151.13969 -8.079147) (xy 151.072745 -8.022102) (xy 151.011265 -7.959206)
			(xy 150.955758 -7.89098) (xy 150.906686 -7.817989) (xy 150.864455 -7.740838) (xy 150.829414 -7.660166)
			(xy 150.801855 -7.576642) (xy 150.782004 -7.490958) (xy 150.770028 -7.403824) (xy 150.766025 -7.315962)
			(xy 150.157942 -7.315962) (xy 150.157442 -7.359939) (xy 150.149444 -7.447527) (xy 150.133514 -7.534026)
			(xy 150.109784 -7.618718) (xy 150.078452 -7.700901) (xy 150.039776 -7.779894) (xy 149.994077 -7.855043)
			(xy 149.941733 -7.925725) (xy 149.883179 -7.991354) (xy 149.8189 -8.051387) (xy 149.749428 -8.105326)
			(xy 149.675339 -8.152724) (xy 149.597246 -8.193188) (xy 149.515798 -8.226383) (xy 149.431668 -8.252034)
			(xy 149.345555 -8.269929) (xy 149.25817 -8.279919) (xy 149.17024 -8.281921) (xy 149.082492 -8.275918)
			(xy 148.995653 -8.261962) (xy 148.910443 -8.240166) (xy 148.827568 -8.210713) (xy 148.747715 -8.173845)
			(xy 148.671545 -8.129868) (xy 148.59969 -8.079147) (xy 148.532745 -8.022102) (xy 148.471265 -7.959206)
			(xy 148.415758 -7.89098) (xy 148.366686 -7.817989) (xy 148.324455 -7.740838) (xy 148.289414 -7.660166)
			(xy 148.261855 -7.576642) (xy 148.242004 -7.490958) (xy 148.230028 -7.403824) (xy 148.226025 -7.315962)
			(xy 147.617942 -7.315962) (xy 147.617442 -7.359939) (xy 147.609444 -7.447527) (xy 147.593514 -7.534026)
			(xy 147.569784 -7.618718) (xy 147.538452 -7.700901) (xy 147.499776 -7.779894) (xy 147.454077 -7.855043)
			(xy 147.401733 -7.925725) (xy 147.343179 -7.991354) (xy 147.2789 -8.051387) (xy 147.209428 -8.105326)
			(xy 147.135339 -8.152724) (xy 147.057246 -8.193188) (xy 146.975798 -8.226383) (xy 146.891668 -8.252034)
			(xy 146.805555 -8.269929) (xy 146.71817 -8.279919) (xy 146.63024 -8.281921) (xy 146.542492 -8.275918)
			(xy 146.455653 -8.261962) (xy 146.370443 -8.240166) (xy 146.287568 -8.210713) (xy 146.207715 -8.173845)
			(xy 146.131545 -8.129868) (xy 146.05969 -8.079147) (xy 145.992745 -8.022102) (xy 145.931265 -7.959206)
			(xy 145.875758 -7.89098) (xy 145.826686 -7.817989) (xy 145.784455 -7.740838) (xy 145.749414 -7.660166)
			(xy 145.721855 -7.576642) (xy 145.702004 -7.490958) (xy 145.690028 -7.403824) (xy 145.686025 -7.315962)
			(xy 141.879828 -7.315962) (xy 141.879328 -7.359939) (xy 141.87133 -7.447527) (xy 141.8554 -7.534026)
			(xy 141.83167 -7.618718) (xy 141.800338 -7.700901) (xy 141.761662 -7.779894) (xy 141.715963 -7.855043)
			(xy 141.663619 -7.925725) (xy 141.605065 -7.991354) (xy 141.540786 -8.051387) (xy 141.471314 -8.105326)
			(xy 141.397225 -8.152724) (xy 141.319132 -8.193188) (xy 141.237684 -8.226383) (xy 141.153554 -8.252034)
			(xy 141.067441 -8.269929) (xy 140.980056 -8.279919) (xy 140.892126 -8.281921) (xy 140.804378 -8.275918)
			(xy 140.717539 -8.261962) (xy 140.632329 -8.240166) (xy 140.549454 -8.210713) (xy 140.469601 -8.173845)
			(xy 140.393431 -8.129868) (xy 140.321576 -8.079147) (xy 140.254631 -8.022102) (xy 140.193151 -7.959206)
			(xy 140.137644 -7.89098) (xy 140.088572 -7.817989) (xy 140.046341 -7.740838) (xy 140.0113 -7.660166)
			(xy 139.983741 -7.576642) (xy 139.96389 -7.490958) (xy 139.951914 -7.403824) (xy 139.947911 -7.315962)
			(xy 139.339828 -7.315962) (xy 139.339328 -7.359939) (xy 139.33133 -7.447527) (xy 139.3154 -7.534026)
			(xy 139.29167 -7.618718) (xy 139.260338 -7.700901) (xy 139.221662 -7.779894) (xy 139.175963 -7.855043)
			(xy 139.123619 -7.925725) (xy 139.065065 -7.991354) (xy 139.000786 -8.051387) (xy 138.931314 -8.105326)
			(xy 138.857225 -8.152724) (xy 138.779132 -8.193188) (xy 138.697684 -8.226383) (xy 138.613554 -8.252034)
			(xy 138.527441 -8.269929) (xy 138.440056 -8.279919) (xy 138.352126 -8.281921) (xy 138.264378 -8.275918)
			(xy 138.177539 -8.261962) (xy 138.092329 -8.240166) (xy 138.009454 -8.210713) (xy 137.929601 -8.173845)
			(xy 137.853431 -8.129868) (xy 137.781576 -8.079147) (xy 137.714631 -8.022102) (xy 137.653151 -7.959206)
			(xy 137.597644 -7.89098) (xy 137.548572 -7.817989) (xy 137.506341 -7.740838) (xy 137.4713 -7.660166)
			(xy 137.443741 -7.576642) (xy 137.42389 -7.490958) (xy 137.411914 -7.403824) (xy 137.407911 -7.315962)
			(xy 136.799828 -7.315962) (xy 136.799328 -7.359939) (xy 136.79133 -7.447527) (xy 136.7754 -7.534026)
			(xy 136.75167 -7.618718) (xy 136.720338 -7.700901) (xy 136.681662 -7.779894) (xy 136.635963 -7.855043)
			(xy 136.583619 -7.925725) (xy 136.525065 -7.991354) (xy 136.460786 -8.051387) (xy 136.391314 -8.105326)
			(xy 136.317225 -8.152724) (xy 136.239132 -8.193188) (xy 136.157684 -8.226383) (xy 136.073554 -8.252034)
			(xy 135.987441 -8.269929) (xy 135.900056 -8.279919) (xy 135.812126 -8.281921) (xy 135.724378 -8.275918)
			(xy 135.637539 -8.261962) (xy 135.552329 -8.240166) (xy 135.469454 -8.210713) (xy 135.389601 -8.173845)
			(xy 135.313431 -8.129868) (xy 135.241576 -8.079147) (xy 135.174631 -8.022102) (xy 135.113151 -7.959206)
			(xy 135.057644 -7.89098) (xy 135.008572 -7.817989) (xy 134.966341 -7.740838) (xy 134.9313 -7.660166)
			(xy 134.903741 -7.576642) (xy 134.88389 -7.490958) (xy 134.871914 -7.403824) (xy 134.867911 -7.315962)
			(xy 134.259828 -7.315962) (xy 134.259328 -7.359939) (xy 134.25133 -7.447527) (xy 134.2354 -7.534026)
			(xy 134.21167 -7.618718) (xy 134.180338 -7.700901) (xy 134.141662 -7.779894) (xy 134.095963 -7.855043)
			(xy 134.043619 -7.925725) (xy 133.985065 -7.991354) (xy 133.920786 -8.051387) (xy 133.851314 -8.105326)
			(xy 133.777225 -8.152724) (xy 133.699132 -8.193188) (xy 133.617684 -8.226383) (xy 133.533554 -8.252034)
			(xy 133.447441 -8.269929) (xy 133.360056 -8.279919) (xy 133.272126 -8.281921) (xy 133.184378 -8.275918)
			(xy 133.097539 -8.261962) (xy 133.012329 -8.240166) (xy 132.929454 -8.210713) (xy 132.849601 -8.173845)
			(xy 132.773431 -8.129868) (xy 132.701576 -8.079147) (xy 132.634631 -8.022102) (xy 132.573151 -7.959206)
			(xy 132.517644 -7.89098) (xy 132.468572 -7.817989) (xy 132.426341 -7.740838) (xy 132.3913 -7.660166)
			(xy 132.363741 -7.576642) (xy 132.34389 -7.490958) (xy 132.331914 -7.403824) (xy 132.327911 -7.315962)
			(xy 131.719828 -7.315962) (xy 131.719328 -7.359939) (xy 131.71133 -7.447527) (xy 131.6954 -7.534026)
			(xy 131.67167 -7.618718) (xy 131.640338 -7.700901) (xy 131.601662 -7.779894) (xy 131.555963 -7.855043)
			(xy 131.503619 -7.925725) (xy 131.445065 -7.991354) (xy 131.380786 -8.051387) (xy 131.311314 -8.105326)
			(xy 131.237225 -8.152724) (xy 131.159132 -8.193188) (xy 131.077684 -8.226383) (xy 130.993554 -8.252034)
			(xy 130.907441 -8.269929) (xy 130.820056 -8.279919) (xy 130.732126 -8.281921) (xy 130.644378 -8.275918)
			(xy 130.557539 -8.261962) (xy 130.472329 -8.240166) (xy 130.389454 -8.210713) (xy 130.309601 -8.173845)
			(xy 130.233431 -8.129868) (xy 130.161576 -8.079147) (xy 130.094631 -8.022102) (xy 130.033151 -7.959206)
			(xy 129.977644 -7.89098) (xy 129.928572 -7.817989) (xy 129.886341 -7.740838) (xy 129.8513 -7.660166)
			(xy 129.823741 -7.576642) (xy 129.80389 -7.490958) (xy 129.791914 -7.403824) (xy 129.787911 -7.315962)
			(xy 125.940692 -7.315962) (xy 125.958592 -7.36062) (xy 126.018057 -7.53071) (xy 126.069828 -7.703298)
			(xy 126.113803 -7.878035) (xy 126.132336 -7.966202) (xy 126.141226 -8.010144) (xy 126.265686 -8.11276)
			(xy 127.25654 -8.11276) (xy 128.999742 -9.855962) (xy 129.787911 -9.855962) (xy 129.791914 -9.7681)
			(xy 129.80389 -9.680966) (xy 129.823741 -9.595282) (xy 129.8513 -9.511758) (xy 129.886341 -9.431086)
			(xy 129.928572 -9.353935) (xy 129.977644 -9.280944) (xy 130.033151 -9.212718) (xy 130.094631 -9.149822)
			(xy 130.161576 -9.092777) (xy 130.233431 -9.042056) (xy 130.309601 -8.998079) (xy 130.389454 -8.961211)
			(xy 130.472329 -8.931758) (xy 130.557539 -8.909962) (xy 130.644378 -8.896006) (xy 130.732126 -8.890003)
			(xy 130.820056 -8.892005) (xy 130.907441 -8.901995) (xy 130.993554 -8.91989) (xy 131.077684 -8.945541)
			(xy 131.159132 -8.978736) (xy 131.237225 -9.0192) (xy 131.311314 -9.066598) (xy 131.380786 -9.120537)
			(xy 131.445065 -9.18057) (xy 131.503619 -9.246199) (xy 131.555963 -9.316881) (xy 131.601662 -9.39203)
			(xy 131.640338 -9.471023) (xy 131.67167 -9.553206) (xy 131.6954 -9.637898) (xy 131.71133 -9.724397)
			(xy 131.719328 -9.811985) (xy 131.719828 -9.855962) (xy 132.327911 -9.855962) (xy 132.331914 -9.7681)
			(xy 132.34389 -9.680966) (xy 132.363741 -9.595282) (xy 132.3913 -9.511758) (xy 132.426341 -9.431086)
			(xy 132.468572 -9.353935) (xy 132.517644 -9.280944) (xy 132.573151 -9.212718) (xy 132.634631 -9.149822)
			(xy 132.701576 -9.092777) (xy 132.773431 -9.042056) (xy 132.849601 -8.998079) (xy 132.929454 -8.961211)
			(xy 133.012329 -8.931758) (xy 133.097539 -8.909962) (xy 133.184378 -8.896006) (xy 133.272126 -8.890003)
			(xy 133.360056 -8.892005) (xy 133.447441 -8.901995) (xy 133.533554 -8.91989) (xy 133.617684 -8.945541)
			(xy 133.699132 -8.978736) (xy 133.777225 -9.0192) (xy 133.851314 -9.066598) (xy 133.920786 -9.120537)
			(xy 133.985065 -9.18057) (xy 134.043619 -9.246199) (xy 134.095963 -9.316881) (xy 134.141662 -9.39203)
			(xy 134.180338 -9.471023) (xy 134.21167 -9.553206) (xy 134.2354 -9.637898) (xy 134.25133 -9.724397)
			(xy 134.259328 -9.811985) (xy 134.259828 -9.855962) (xy 134.867911 -9.855962) (xy 134.871914 -9.7681)
			(xy 134.88389 -9.680966) (xy 134.903741 -9.595282) (xy 134.9313 -9.511758) (xy 134.966341 -9.431086)
			(xy 135.008572 -9.353935) (xy 135.057644 -9.280944) (xy 135.113151 -9.212718) (xy 135.174631 -9.149822)
			(xy 135.241576 -9.092777) (xy 135.313431 -9.042056) (xy 135.389601 -8.998079) (xy 135.469454 -8.961211)
			(xy 135.552329 -8.931758) (xy 135.637539 -8.909962) (xy 135.724378 -8.896006) (xy 135.812126 -8.890003)
			(xy 135.900056 -8.892005) (xy 135.987441 -8.901995) (xy 136.073554 -8.91989) (xy 136.157684 -8.945541)
			(xy 136.239132 -8.978736) (xy 136.317225 -9.0192) (xy 136.391314 -9.066598) (xy 136.460786 -9.120537)
			(xy 136.525065 -9.18057) (xy 136.583619 -9.246199) (xy 136.635963 -9.316881) (xy 136.681662 -9.39203)
			(xy 136.720338 -9.471023) (xy 136.75167 -9.553206) (xy 136.7754 -9.637898) (xy 136.79133 -9.724397)
			(xy 136.799328 -9.811985) (xy 136.799828 -9.855962) (xy 137.407911 -9.855962) (xy 137.411914 -9.7681)
			(xy 137.42389 -9.680966) (xy 137.443741 -9.595282) (xy 137.4713 -9.511758) (xy 137.506341 -9.431086)
			(xy 137.548572 -9.353935) (xy 137.597644 -9.280944) (xy 137.653151 -9.212718) (xy 137.714631 -9.149822)
			(xy 137.781576 -9.092777) (xy 137.853431 -9.042056) (xy 137.929601 -8.998079) (xy 138.009454 -8.961211)
			(xy 138.092329 -8.931758) (xy 138.177539 -8.909962) (xy 138.264378 -8.896006) (xy 138.352126 -8.890003)
			(xy 138.440056 -8.892005) (xy 138.527441 -8.901995) (xy 138.613554 -8.91989) (xy 138.697684 -8.945541)
			(xy 138.779132 -8.978736) (xy 138.857225 -9.0192) (xy 138.931314 -9.066598) (xy 139.000786 -9.120537)
			(xy 139.065065 -9.18057) (xy 139.123619 -9.246199) (xy 139.175963 -9.316881) (xy 139.221662 -9.39203)
			(xy 139.260338 -9.471023) (xy 139.29167 -9.553206) (xy 139.3154 -9.637898) (xy 139.33133 -9.724397)
			(xy 139.339328 -9.811985) (xy 139.339828 -9.855962) (xy 139.947911 -9.855962) (xy 139.951914 -9.7681)
			(xy 139.96389 -9.680966) (xy 139.983741 -9.595282) (xy 140.0113 -9.511758) (xy 140.046341 -9.431086)
			(xy 140.088572 -9.353935) (xy 140.137644 -9.280944) (xy 140.193151 -9.212718) (xy 140.254631 -9.149822)
			(xy 140.321576 -9.092777) (xy 140.393431 -9.042056) (xy 140.469601 -8.998079) (xy 140.549454 -8.961211)
			(xy 140.632329 -8.931758) (xy 140.717539 -8.909962) (xy 140.804378 -8.896006) (xy 140.892126 -8.890003)
			(xy 140.980056 -8.892005) (xy 141.067441 -8.901995) (xy 141.153554 -8.91989) (xy 141.237684 -8.945541)
			(xy 141.319132 -8.978736) (xy 141.397225 -9.0192) (xy 141.471314 -9.066598) (xy 141.540786 -9.120537)
			(xy 141.605065 -9.18057) (xy 141.663619 -9.246199) (xy 141.715963 -9.316881) (xy 141.761662 -9.39203)
			(xy 141.800338 -9.471023) (xy 141.83167 -9.553206) (xy 141.8554 -9.637898) (xy 141.87133 -9.724397)
			(xy 141.879328 -9.811985) (xy 141.879828 -9.855962) (xy 145.686025 -9.855962) (xy 145.690028 -9.7681)
			(xy 145.702004 -9.680966) (xy 145.721855 -9.595282) (xy 145.749414 -9.511758) (xy 145.784455 -9.431086)
			(xy 145.826686 -9.353935) (xy 145.875758 -9.280944) (xy 145.931265 -9.212718) (xy 145.992745 -9.149822)
			(xy 146.05969 -9.092777) (xy 146.131545 -9.042056) (xy 146.207715 -8.998079) (xy 146.287568 -8.961211)
			(xy 146.370443 -8.931758) (xy 146.455653 -8.909962) (xy 146.542492 -8.896006) (xy 146.63024 -8.890003)
			(xy 146.71817 -8.892005) (xy 146.805555 -8.901995) (xy 146.891668 -8.91989) (xy 146.975798 -8.945541)
			(xy 147.057246 -8.978736) (xy 147.135339 -9.0192) (xy 147.209428 -9.066598) (xy 147.2789 -9.120537)
			(xy 147.343179 -9.18057) (xy 147.401733 -9.246199) (xy 147.454077 -9.316881) (xy 147.499776 -9.39203)
			(xy 147.538452 -9.471023) (xy 147.569784 -9.553206) (xy 147.593514 -9.637898) (xy 147.609444 -9.724397)
			(xy 147.617442 -9.811985) (xy 147.617942 -9.855962) (xy 148.226025 -9.855962) (xy 148.230028 -9.7681)
			(xy 148.242004 -9.680966) (xy 148.261855 -9.595282) (xy 148.289414 -9.511758) (xy 148.324455 -9.431086)
			(xy 148.366686 -9.353935) (xy 148.415758 -9.280944) (xy 148.471265 -9.212718) (xy 148.532745 -9.149822)
			(xy 148.59969 -9.092777) (xy 148.671545 -9.042056) (xy 148.747715 -8.998079) (xy 148.827568 -8.961211)
			(xy 148.910443 -8.931758) (xy 148.995653 -8.909962) (xy 149.082492 -8.896006) (xy 149.17024 -8.890003)
			(xy 149.25817 -8.892005) (xy 149.345555 -8.901995) (xy 149.431668 -8.91989) (xy 149.515798 -8.945541)
			(xy 149.597246 -8.978736) (xy 149.675339 -9.0192) (xy 149.749428 -9.066598) (xy 149.8189 -9.120537)
			(xy 149.883179 -9.18057) (xy 149.941733 -9.246199) (xy 149.994077 -9.316881) (xy 150.039776 -9.39203)
			(xy 150.078452 -9.471023) (xy 150.109784 -9.553206) (xy 150.133514 -9.637898) (xy 150.149444 -9.724397)
			(xy 150.157442 -9.811985) (xy 150.157942 -9.855962) (xy 150.766025 -9.855962) (xy 150.770028 -9.7681)
			(xy 150.782004 -9.680966) (xy 150.801855 -9.595282) (xy 150.829414 -9.511758) (xy 150.864455 -9.431086)
			(xy 150.906686 -9.353935) (xy 150.955758 -9.280944) (xy 151.011265 -9.212718) (xy 151.072745 -9.149822)
			(xy 151.13969 -9.092777) (xy 151.211545 -9.042056) (xy 151.287715 -8.998079) (xy 151.367568 -8.961211)
			(xy 151.450443 -8.931758) (xy 151.535653 -8.909962) (xy 151.622492 -8.896006) (xy 151.71024 -8.890003)
			(xy 151.79817 -8.892005) (xy 151.885555 -8.901995) (xy 151.971668 -8.91989) (xy 152.055798 -8.945541)
			(xy 152.137246 -8.978736) (xy 152.215339 -9.0192) (xy 152.289428 -9.066598) (xy 152.3589 -9.120537)
			(xy 152.423179 -9.18057) (xy 152.481733 -9.246199) (xy 152.534077 -9.316881) (xy 152.579776 -9.39203)
			(xy 152.618452 -9.471023) (xy 152.649784 -9.553206) (xy 152.673514 -9.637898) (xy 152.689444 -9.724397)
			(xy 152.697442 -9.811985) (xy 152.697942 -9.855962) (xy 152.697442 -9.899939) (xy 152.689444 -9.987527)
			(xy 152.673514 -10.074026) (xy 152.649784 -10.158718) (xy 152.618452 -10.240901) (xy 152.579776 -10.319894)
			(xy 152.534077 -10.395043) (xy 152.481733 -10.465725) (xy 152.423179 -10.531354) (xy 152.3589 -10.591387)
			(xy 152.289428 -10.645326) (xy 152.215339 -10.692724) (xy 152.137246 -10.733188) (xy 152.055798 -10.766383)
			(xy 151.971668 -10.792034) (xy 151.885555 -10.809929) (xy 151.79817 -10.819919) (xy 151.71024 -10.821921)
			(xy 151.622492 -10.815918) (xy 151.535653 -10.801962) (xy 151.450443 -10.780166) (xy 151.367568 -10.750713)
			(xy 151.287715 -10.713845) (xy 151.211545 -10.669868) (xy 151.13969 -10.619147) (xy 151.072745 -10.562102)
			(xy 151.011265 -10.499206) (xy 150.955758 -10.43098) (xy 150.906686 -10.357989) (xy 150.864455 -10.280838)
			(xy 150.829414 -10.200166) (xy 150.801855 -10.116642) (xy 150.782004 -10.030958) (xy 150.770028 -9.943824)
			(xy 150.766025 -9.855962) (xy 150.157942 -9.855962) (xy 150.157442 -9.899939) (xy 150.149444 -9.987527)
			(xy 150.133514 -10.074026) (xy 150.109784 -10.158718) (xy 150.078452 -10.240901) (xy 150.039776 -10.319894)
			(xy 149.994077 -10.395043) (xy 149.941733 -10.465725) (xy 149.883179 -10.531354) (xy 149.8189 -10.591387)
			(xy 149.749428 -10.645326) (xy 149.675339 -10.692724) (xy 149.597246 -10.733188) (xy 149.515798 -10.766383)
			(xy 149.431668 -10.792034) (xy 149.345555 -10.809929) (xy 149.25817 -10.819919) (xy 149.17024 -10.821921)
			(xy 149.082492 -10.815918) (xy 148.995653 -10.801962) (xy 148.910443 -10.780166) (xy 148.827568 -10.750713)
			(xy 148.747715 -10.713845) (xy 148.671545 -10.669868) (xy 148.59969 -10.619147) (xy 148.532745 -10.562102)
			(xy 148.471265 -10.499206) (xy 148.415758 -10.43098) (xy 148.366686 -10.357989) (xy 148.324455 -10.280838)
			(xy 148.289414 -10.200166) (xy 148.261855 -10.116642) (xy 148.242004 -10.030958) (xy 148.230028 -9.943824)
			(xy 148.226025 -9.855962) (xy 147.617942 -9.855962) (xy 147.617442 -9.899939) (xy 147.609444 -9.987527)
			(xy 147.593514 -10.074026) (xy 147.569784 -10.158718) (xy 147.538452 -10.240901) (xy 147.499776 -10.319894)
			(xy 147.454077 -10.395043) (xy 147.401733 -10.465725) (xy 147.343179 -10.531354) (xy 147.2789 -10.591387)
			(xy 147.209428 -10.645326) (xy 147.135339 -10.692724) (xy 147.057246 -10.733188) (xy 146.975798 -10.766383)
			(xy 146.891668 -10.792034) (xy 146.805555 -10.809929) (xy 146.71817 -10.819919) (xy 146.63024 -10.821921)
			(xy 146.542492 -10.815918) (xy 146.455653 -10.801962) (xy 146.370443 -10.780166) (xy 146.287568 -10.750713)
			(xy 146.207715 -10.713845) (xy 146.131545 -10.669868) (xy 146.05969 -10.619147) (xy 145.992745 -10.562102)
			(xy 145.931265 -10.499206) (xy 145.875758 -10.43098) (xy 145.826686 -10.357989) (xy 145.784455 -10.280838)
			(xy 145.749414 -10.200166) (xy 145.721855 -10.116642) (xy 145.702004 -10.030958) (xy 145.690028 -9.943824)
			(xy 145.686025 -9.855962) (xy 141.879828 -9.855962) (xy 141.879328 -9.899939) (xy 141.87133 -9.987527)
			(xy 141.8554 -10.074026) (xy 141.83167 -10.158718) (xy 141.800338 -10.240901) (xy 141.761662 -10.319894)
			(xy 141.715963 -10.395043) (xy 141.663619 -10.465725) (xy 141.605065 -10.531354) (xy 141.540786 -10.591387)
			(xy 141.471314 -10.645326) (xy 141.397225 -10.692724) (xy 141.319132 -10.733188) (xy 141.237684 -10.766383)
			(xy 141.153554 -10.792034) (xy 141.067441 -10.809929) (xy 140.980056 -10.819919) (xy 140.892126 -10.821921)
			(xy 140.804378 -10.815918) (xy 140.717539 -10.801962) (xy 140.632329 -10.780166) (xy 140.549454 -10.750713)
			(xy 140.469601 -10.713845) (xy 140.393431 -10.669868) (xy 140.321576 -10.619147) (xy 140.254631 -10.562102)
			(xy 140.193151 -10.499206) (xy 140.137644 -10.43098) (xy 140.088572 -10.357989) (xy 140.046341 -10.280838)
			(xy 140.0113 -10.200166) (xy 139.983741 -10.116642) (xy 139.96389 -10.030958) (xy 139.951914 -9.943824)
			(xy 139.947911 -9.855962) (xy 139.339828 -9.855962) (xy 139.339328 -9.899939) (xy 139.33133 -9.987527)
			(xy 139.3154 -10.074026) (xy 139.29167 -10.158718) (xy 139.260338 -10.240901) (xy 139.221662 -10.319894)
			(xy 139.175963 -10.395043) (xy 139.123619 -10.465725) (xy 139.065065 -10.531354) (xy 139.000786 -10.591387)
			(xy 138.931314 -10.645326) (xy 138.857225 -10.692724) (xy 138.779132 -10.733188) (xy 138.697684 -10.766383)
			(xy 138.613554 -10.792034) (xy 138.527441 -10.809929) (xy 138.440056 -10.819919) (xy 138.352126 -10.821921)
			(xy 138.264378 -10.815918) (xy 138.177539 -10.801962) (xy 138.092329 -10.780166) (xy 138.009454 -10.750713)
			(xy 137.929601 -10.713845) (xy 137.853431 -10.669868) (xy 137.781576 -10.619147) (xy 137.714631 -10.562102)
			(xy 137.653151 -10.499206) (xy 137.597644 -10.43098) (xy 137.548572 -10.357989) (xy 137.506341 -10.280838)
			(xy 137.4713 -10.200166) (xy 137.443741 -10.116642) (xy 137.42389 -10.030958) (xy 137.411914 -9.943824)
			(xy 137.407911 -9.855962) (xy 136.799828 -9.855962) (xy 136.799328 -9.899939) (xy 136.79133 -9.987527)
			(xy 136.7754 -10.074026) (xy 136.75167 -10.158718) (xy 136.720338 -10.240901) (xy 136.681662 -10.319894)
			(xy 136.635963 -10.395043) (xy 136.583619 -10.465725) (xy 136.525065 -10.531354) (xy 136.460786 -10.591387)
			(xy 136.391314 -10.645326) (xy 136.317225 -10.692724) (xy 136.239132 -10.733188) (xy 136.157684 -10.766383)
			(xy 136.073554 -10.792034) (xy 135.987441 -10.809929) (xy 135.900056 -10.819919) (xy 135.812126 -10.821921)
			(xy 135.724378 -10.815918) (xy 135.637539 -10.801962) (xy 135.552329 -10.780166) (xy 135.469454 -10.750713)
			(xy 135.389601 -10.713845) (xy 135.313431 -10.669868) (xy 135.241576 -10.619147) (xy 135.174631 -10.562102)
			(xy 135.113151 -10.499206) (xy 135.057644 -10.43098) (xy 135.008572 -10.357989) (xy 134.966341 -10.280838)
			(xy 134.9313 -10.200166) (xy 134.903741 -10.116642) (xy 134.88389 -10.030958) (xy 134.871914 -9.943824)
			(xy 134.867911 -9.855962) (xy 134.259828 -9.855962) (xy 134.259328 -9.899939) (xy 134.25133 -9.987527)
			(xy 134.2354 -10.074026) (xy 134.21167 -10.158718) (xy 134.180338 -10.240901) (xy 134.141662 -10.319894)
			(xy 134.095963 -10.395043) (xy 134.043619 -10.465725) (xy 133.985065 -10.531354) (xy 133.920786 -10.591387)
			(xy 133.851314 -10.645326) (xy 133.777225 -10.692724) (xy 133.699132 -10.733188) (xy 133.617684 -10.766383)
			(xy 133.533554 -10.792034) (xy 133.447441 -10.809929) (xy 133.360056 -10.819919) (xy 133.272126 -10.821921)
			(xy 133.184378 -10.815918) (xy 133.097539 -10.801962) (xy 133.012329 -10.780166) (xy 132.929454 -10.750713)
			(xy 132.849601 -10.713845) (xy 132.773431 -10.669868) (xy 132.701576 -10.619147) (xy 132.634631 -10.562102)
			(xy 132.573151 -10.499206) (xy 132.517644 -10.43098) (xy 132.468572 -10.357989) (xy 132.426341 -10.280838)
			(xy 132.3913 -10.200166) (xy 132.363741 -10.116642) (xy 132.34389 -10.030958) (xy 132.331914 -9.943824)
			(xy 132.327911 -9.855962) (xy 131.719828 -9.855962) (xy 131.719328 -9.899939) (xy 131.71133 -9.987527)
			(xy 131.6954 -10.074026) (xy 131.67167 -10.158718) (xy 131.640338 -10.240901) (xy 131.601662 -10.319894)
			(xy 131.555963 -10.395043) (xy 131.503619 -10.465725) (xy 131.445065 -10.531354) (xy 131.380786 -10.591387)
			(xy 131.311314 -10.645326) (xy 131.237225 -10.692724) (xy 131.159132 -10.733188) (xy 131.077684 -10.766383)
			(xy 130.993554 -10.792034) (xy 130.907441 -10.809929) (xy 130.820056 -10.819919) (xy 130.732126 -10.821921)
			(xy 130.644378 -10.815918) (xy 130.557539 -10.801962) (xy 130.472329 -10.780166) (xy 130.389454 -10.750713)
			(xy 130.309601 -10.713845) (xy 130.233431 -10.669868) (xy 130.161576 -10.619147) (xy 130.094631 -10.562102)
			(xy 130.033151 -10.499206) (xy 129.977644 -10.43098) (xy 129.928572 -10.357989) (xy 129.886341 -10.280838)
			(xy 129.8513 -10.200166) (xy 129.823741 -10.116642) (xy 129.80389 -10.030958) (xy 129.791914 -9.943824)
			(xy 129.787911 -9.855962) (xy 128.999742 -9.855962) (xy 136.714992 -17.571212) (xy 147.308316 -17.571212)
			(xy 147.308773 -17.52685) (xy 147.316505 -17.438465) (xy 147.331911 -17.351089) (xy 147.354874 -17.265389)
			(xy 147.385219 -17.182016) (xy 147.422715 -17.101605) (xy 147.467076 -17.024769) (xy 147.517966 -16.952091)
			(xy 147.574997 -16.884125) (xy 147.637734 -16.821389) (xy 147.7057 -16.764359) (xy 147.778379 -16.71347)
			(xy 147.855216 -16.669109) (xy 147.935627 -16.631614) (xy 148.019 -16.60127) (xy 148.104701 -16.578309)
			(xy 148.192076 -16.562904) (xy 148.280462 -16.555173) (xy 148.324824 -16.554704) (xy 148.368922 -16.555205)
			(xy 148.456769 -16.563042) (xy 148.543572 -16.578651) (xy 148.628646 -16.601909) (xy 148.711317 -16.632632)
			(xy 148.790932 -16.670577) (xy 148.866862 -16.715445) (xy 148.938507 -16.76688) (xy 149.005299 -16.824476)
			(xy 149.06671 -16.887777) (xy 149.122256 -16.956284) (xy 149.147276 -16.9926) (xy 149.160394 -17.011225)
			(xy 149.192087 -17.043939) (xy 149.229106 -17.070476) (xy 149.270264 -17.089985) (xy 149.314243 -17.101841)
			(xy 149.35963 -17.105664) (xy 149.404972 -17.101331) (xy 149.448814 -17.088981) (xy 149.489751 -17.06901)
			(xy 149.526469 -17.042058) (xy 149.5425 -17.025874) (xy 149.570372 -16.997157) (xy 149.631082 -16.945009)
			(xy 149.696766 -16.899285) (xy 149.766748 -16.860454) (xy 149.840305 -16.828919) (xy 149.91668 -16.805002)
			(xy 149.995086 -16.788952) (xy 150.074716 -16.780933) (xy 150.154748 -16.781027) (xy 150.234358 -16.789235)
			(xy 150.312726 -16.805471) (xy 150.389045 -16.829568) (xy 150.462527 -16.861278) (xy 150.532416 -16.900273)
			(xy 150.597992 -16.946154) (xy 150.658579 -16.998445) (xy 150.713552 -17.056609) (xy 150.762346 -17.120047)
			(xy 150.804457 -17.188104) (xy 150.839452 -17.26008) (xy 150.86697 -17.335233) (xy 150.886728 -17.412788)
			(xy 150.898521 -17.491946) (xy 150.902229 -17.571893) (xy 150.897813 -17.651803) (xy 150.885319 -17.730854)
			(xy 150.864875 -17.808231) (xy 150.836692 -17.883137) (xy 150.801061 -17.9548) (xy 150.758348 -18.022482)
			(xy 150.708994 -18.085484) (xy 150.653508 -18.143159) (xy 150.59246 -18.194912) (xy 150.52648 -18.240209)
			(xy 150.456248 -18.278584) (xy 150.382488 -18.309642) (xy 150.305959 -18.333062) (xy 150.22745 -18.348603)
			(xy 150.14777 -18.356105) (xy 150.06774 -18.35549) (xy 149.988185 -18.346766) (xy 149.909924 -18.330021)
			(xy 149.833764 -18.305429) (xy 149.760489 -18.273243) (xy 149.690854 -18.233794) (xy 149.625578 -18.187489)
			(xy 149.565332 -18.134806) (xy 149.537674 -18.105882) (xy 149.521799 -18.089514) (xy 149.485267 -18.06223)
			(xy 149.444453 -18.041905) (xy 149.400666 -18.029191) (xy 149.355313 -18.024497) (xy 149.309851 -18.027973)
			(xy 149.265739 -18.039507) (xy 149.224394 -18.05873) (xy 149.187143 -18.085024) (xy 149.155185 -18.117544)
			(xy 149.141942 -18.136108) (xy 149.115926 -18.173573) (xy 149.05796 -18.244008) (xy 148.993843 -18.308893)
			(xy 148.924103 -18.367694) (xy 148.849317 -18.419925) (xy 148.770099 -18.465156) (xy 148.687106 -18.503012)
			(xy 148.601019 -18.533183) (xy 148.512551 -18.555419) (xy 148.42243 -18.569538) (xy 148.331399 -18.575421)
			(xy 148.240211 -18.573021) (xy 148.149616 -18.562358) (xy 148.060362 -18.54352) (xy 147.973185 -18.516661)
			(xy 147.888805 -18.482005) (xy 147.807917 -18.439835) (xy 147.731188 -18.390501) (xy 147.659252 -18.334409)
			(xy 147.592702 -18.272022) (xy 147.532086 -18.203854) (xy 147.477905 -18.130468) (xy 147.430605 -18.052468)
			(xy 147.390577 -17.970499) (xy 147.358151 -17.885237) (xy 147.333594 -17.797384) (xy 147.317109 -17.707666)
			(xy 147.308832 -17.616822) (xy 147.308316 -17.571212) (xy 136.714992 -17.571212) (xy 137.43178 -18.288)
			(xy 137.43178 -19.608347) (xy 149.326343 -19.608347) (xy 149.326343 -19.528481) (xy 149.334423 -19.449026)
			(xy 149.3505 -19.370796) (xy 149.374409 -19.294594) (xy 149.405904 -19.221201) (xy 149.444663 -19.151371)
			(xy 149.490287 -19.085821) (xy 149.542309 -19.025222) (xy 149.600194 -18.970198) (xy 149.66335 -18.921312)
			(xy 149.731127 -18.879066) (xy 149.80283 -18.843894) (xy 149.877724 -18.816157) (xy 149.955039 -18.796138)
			(xy 150.033983 -18.784045) (xy 150.113746 -18.78) (xy 150.193509 -18.784045) (xy 150.272453 -18.796138)
			(xy 150.349768 -18.816157) (xy 150.424662 -18.843894) (xy 150.496365 -18.879066) (xy 150.564142 -18.921312)
			(xy 150.627298 -18.970198) (xy 150.685183 -19.025222) (xy 150.737205 -19.085821) (xy 150.782829 -19.151371)
			(xy 150.821588 -19.221201) (xy 150.853083 -19.294594) (xy 150.876992 -19.370796) (xy 150.893069 -19.449026)
			(xy 150.901149 -19.528481) (xy 150.901654 -19.568414) (xy 150.901149 -19.608347) (xy 150.893069 -19.687802)
			(xy 150.876992 -19.766032) (xy 150.853083 -19.842234) (xy 150.821588 -19.915627) (xy 150.782829 -19.985457)
			(xy 150.737205 -20.051007) (xy 150.685183 -20.111606) (xy 150.627298 -20.16663) (xy 150.564142 -20.215516)
			(xy 150.496365 -20.257762) (xy 150.424662 -20.292934) (xy 150.349768 -20.320671) (xy 150.272453 -20.34069)
			(xy 150.193509 -20.352783) (xy 150.113746 -20.356829) (xy 150.033983 -20.352783) (xy 149.955039 -20.34069)
			(xy 149.877724 -20.320671) (xy 149.80283 -20.292934) (xy 149.731127 -20.257762) (xy 149.66335 -20.215516)
			(xy 149.600194 -20.16663) (xy 149.542309 -20.111606) (xy 149.490287 -20.051007) (xy 149.444663 -19.985457)
			(xy 149.405904 -19.915627) (xy 149.374409 -19.842234) (xy 149.3505 -19.766032) (xy 149.334423 -19.687802)
			(xy 149.326343 -19.608347) (xy 137.43178 -19.608347) (xy 137.43178 -20.799806) (xy 137.82727 -20.799806)
			(xy 137.831236 -20.715275) (xy 137.843101 -20.631488) (xy 137.862759 -20.549179) (xy 137.890039 -20.469073)
			(xy 137.9247 -20.391874) (xy 137.966438 -20.318259) (xy 138.014885 -20.248876) (xy 138.069617 -20.184335)
			(xy 138.130153 -20.125203) (xy 138.195959 -20.071999) (xy 138.266459 -20.025191) (xy 138.341031 -19.98519)
			(xy 138.419022 -19.952348) (xy 138.499746 -19.926954) (xy 138.582493 -19.909231) (xy 138.666535 -19.899333)
			(xy 138.751136 -19.89735) (xy 138.83555 -19.903297) (xy 138.919037 -19.917122) (xy 139.000862 -19.938705)
			(xy 139.080306 -19.967855) (xy 139.156672 -20.004316) (xy 139.229288 -20.047768) (xy 139.297516 -20.097829)
			(xy 139.360756 -20.154059) (xy 139.418453 -20.215964) (xy 139.4701 -20.283) (xy 139.515242 -20.354577)
			(xy 139.553484 -20.430067) (xy 139.584488 -20.508806) (xy 139.607983 -20.590103) (xy 139.623762 -20.673242)
			(xy 139.631686 -20.757494) (xy 139.632182 -20.799806) (xy 139.631686 -20.842118) (xy 139.623762 -20.92637)
			(xy 139.607983 -21.009509) (xy 139.584488 -21.090806) (xy 139.553484 -21.169545) (xy 139.515242 -21.245035)
			(xy 139.4701 -21.316612) (xy 139.418453 -21.383648) (xy 139.360756 -21.445553) (xy 139.297516 -21.501783)
			(xy 139.229288 -21.551844) (xy 139.156672 -21.595296) (xy 139.129346 -21.608343) (xy 149.326343 -21.608343)
			(xy 149.326343 -21.528477) (xy 149.334423 -21.449022) (xy 149.3505 -21.370792) (xy 149.374409 -21.29459)
			(xy 149.405904 -21.221197) (xy 149.444663 -21.151367) (xy 149.490287 -21.085817) (xy 149.542309 -21.025218)
			(xy 149.600194 -20.970194) (xy 149.66335 -20.921308) (xy 149.731127 -20.879062) (xy 149.80283 -20.84389)
			(xy 149.877724 -20.816153) (xy 149.955039 -20.796134) (xy 150.033983 -20.784041) (xy 150.113746 -20.779996)
			(xy 150.193509 -20.784041) (xy 150.272453 -20.796134) (xy 150.349768 -20.816153) (xy 150.424662 -20.84389)
			(xy 150.496365 -20.879062) (xy 150.564142 -20.921308) (xy 150.627298 -20.970194) (xy 150.685183 -21.025218)
			(xy 150.737205 -21.085817) (xy 150.782829 -21.151367) (xy 150.821588 -21.221197) (xy 150.853083 -21.29459)
			(xy 150.876992 -21.370792) (xy 150.893069 -21.449022) (xy 150.901149 -21.528477) (xy 150.901654 -21.56841)
			(xy 150.901149 -21.608343) (xy 150.893069 -21.687798) (xy 150.876992 -21.766028) (xy 150.853083 -21.84223)
			(xy 150.821588 -21.915623) (xy 150.782829 -21.985453) (xy 150.737205 -22.051003) (xy 150.685183 -22.111602)
			(xy 150.627298 -22.166626) (xy 150.564142 -22.215512) (xy 150.496365 -22.257758) (xy 150.424662 -22.29293)
			(xy 150.349768 -22.320667) (xy 150.272453 -22.340686) (xy 150.193509 -22.352779) (xy 150.113746 -22.356825)
			(xy 150.033983 -22.352779) (xy 149.955039 -22.340686) (xy 149.877724 -22.320667) (xy 149.80283 -22.29293)
			(xy 149.731127 -22.257758) (xy 149.66335 -22.215512) (xy 149.600194 -22.166626) (xy 149.542309 -22.111602)
			(xy 149.490287 -22.051003) (xy 149.444663 -21.985453) (xy 149.405904 -21.915623) (xy 149.374409 -21.84223)
			(xy 149.3505 -21.766028) (xy 149.334423 -21.687798) (xy 149.326343 -21.608343) (xy 139.129346 -21.608343)
			(xy 139.080306 -21.631757) (xy 139.000862 -21.660907) (xy 138.919037 -21.68249) (xy 138.83555 -21.696315)
			(xy 138.751136 -21.702262) (xy 138.666535 -21.700279) (xy 138.582493 -21.690381) (xy 138.499746 -21.672658)
			(xy 138.419022 -21.647264) (xy 138.341031 -21.614422) (xy 138.266459 -21.574421) (xy 138.195959 -21.527613)
			(xy 138.130153 -21.474409) (xy 138.069617 -21.415277) (xy 138.014885 -21.350736) (xy 137.966438 -21.281353)
			(xy 137.9247 -21.207738) (xy 137.890039 -21.130539) (xy 137.862759 -21.050433) (xy 137.843101 -20.968124)
			(xy 137.831236 -20.884337) (xy 137.82727 -20.799806) (xy 137.43178 -20.799806) (xy 137.43178 -23.608339)
			(xy 149.326343 -23.608339) (xy 149.326343 -23.528473) (xy 149.334423 -23.449018) (xy 149.3505 -23.370788)
			(xy 149.374409 -23.294586) (xy 149.405904 -23.221193) (xy 149.444663 -23.151363) (xy 149.490287 -23.085813)
			(xy 149.542309 -23.025214) (xy 149.600194 -22.97019) (xy 149.66335 -22.921304) (xy 149.731127 -22.879058)
			(xy 149.80283 -22.843886) (xy 149.877724 -22.816149) (xy 149.955039 -22.79613) (xy 150.033983 -22.784037)
			(xy 150.113746 -22.779992) (xy 150.193509 -22.784037) (xy 150.272453 -22.79613) (xy 150.349768 -22.816149)
			(xy 150.424662 -22.843886) (xy 150.496365 -22.879058) (xy 150.564142 -22.921304) (xy 150.627298 -22.97019)
			(xy 150.685183 -23.025214) (xy 150.737205 -23.085813) (xy 150.782829 -23.151363) (xy 150.821588 -23.221193)
			(xy 150.853083 -23.294586) (xy 150.876992 -23.370788) (xy 150.893069 -23.449018) (xy 150.901149 -23.528473)
			(xy 150.901654 -23.568406) (xy 150.901149 -23.608339) (xy 150.893069 -23.687794) (xy 150.876992 -23.766024)
			(xy 150.853083 -23.842226) (xy 150.821588 -23.915619) (xy 150.782829 -23.985449) (xy 150.737205 -24.050999)
			(xy 150.685183 -24.111598) (xy 150.627298 -24.166622) (xy 150.564142 -24.215508) (xy 150.496365 -24.257754)
			(xy 150.424662 -24.292926) (xy 150.349768 -24.320663) (xy 150.272453 -24.340682) (xy 150.193509 -24.352775)
			(xy 150.113746 -24.356821) (xy 150.033983 -24.352775) (xy 149.955039 -24.340682) (xy 149.877724 -24.320663)
			(xy 149.80283 -24.292926) (xy 149.731127 -24.257754) (xy 149.66335 -24.215508) (xy 149.600194 -24.166622)
			(xy 149.542309 -24.111598) (xy 149.490287 -24.050999) (xy 149.444663 -23.985449) (xy 149.405904 -23.915619)
			(xy 149.374409 -23.842226) (xy 149.3505 -23.766024) (xy 149.334423 -23.687794) (xy 149.326343 -23.608339)
			(xy 137.43178 -23.608339) (xy 137.43178 -24.677116) (xy 139.687298 -24.677116) (xy 139.691369 -24.621494)
			(xy 139.703495 -24.567057) (xy 139.723418 -24.514966) (xy 139.750714 -24.466331) (xy 139.7848 -24.422188)
			(xy 139.824949 -24.383479) (xy 139.870307 -24.351028) (xy 139.919907 -24.325527) (xy 139.972691 -24.30752)
			(xy 140.027534 -24.29739) (xy 140.083268 -24.295353) (xy 140.138705 -24.301453) (xy 140.192662 -24.315559)
			(xy 140.243991 -24.337371) (xy 140.291597 -24.366425) (xy 140.334465 -24.4021) (xy 140.371682 -24.443637)
			(xy 140.402455 -24.49015) (xy 140.426127 -24.540647) (xy 140.442195 -24.594054) (xy 140.450315 -24.64923)
			(xy 140.450824 -24.677116) (xy 140.450315 -24.705002) (xy 140.44926 -24.712168) (xy 140.826234 -24.712168)
			(xy 140.830305 -24.656546) (xy 140.842431 -24.602109) (xy 140.862354 -24.550018) (xy 140.88965 -24.501383)
			(xy 140.923736 -24.45724) (xy 140.963885 -24.418531) (xy 141.009243 -24.38608) (xy 141.058843 -24.360579)
			(xy 141.111627 -24.342572) (xy 141.16647 -24.332442) (xy 141.222204 -24.330405) (xy 141.277641 -24.336505)
			(xy 141.331598 -24.350611) (xy 141.382927 -24.372423) (xy 141.430533 -24.401477) (xy 141.473401 -24.437152)
			(xy 141.510618 -24.478689) (xy 141.541391 -24.525202) (xy 141.565063 -24.575699) (xy 141.581131 -24.629106)
			(xy 141.589251 -24.684282) (xy 141.58931 -24.68753) (xy 142.096234 -24.68753) (xy 142.100305 -24.631908)
			(xy 142.112431 -24.577471) (xy 142.132354 -24.52538) (xy 142.15965 -24.476745) (xy 142.193736 -24.432602)
			(xy 142.233885 -24.393893) (xy 142.279243 -24.361442) (xy 142.328843 -24.335941) (xy 142.381627 -24.317934)
			(xy 142.43647 -24.307804) (xy 142.492204 -24.305767) (xy 142.547641 -24.311867) (xy 142.601598 -24.325973)
			(xy 142.652927 -24.347785) (xy 142.700533 -24.376839) (xy 142.743401 -24.412514) (xy 142.780618 -24.454051)
			(xy 142.811391 -24.500564) (xy 142.835063 -24.551061) (xy 142.851131 -24.604468) (xy 142.859251 -24.659644)
			(xy 142.85976 -24.68753) (xy 142.859251 -24.715416) (xy 142.851131 -24.770592) (xy 142.835063 -24.823999)
			(xy 142.811391 -24.874496) (xy 142.780618 -24.921009) (xy 142.743401 -24.962546) (xy 142.700533 -24.998221)
			(xy 142.652927 -25.027275) (xy 142.601598 -25.049087) (xy 142.547641 -25.063193) (xy 142.492204 -25.069293)
			(xy 142.43647 -25.067256) (xy 142.381627 -25.057126) (xy 142.328843 -25.039119) (xy 142.279243 -25.013618)
			(xy 142.233885 -24.981167) (xy 142.193736 -24.942458) (xy 142.15965 -24.898315) (xy 142.132354 -24.84968)
			(xy 142.112431 -24.797589) (xy 142.100305 -24.743152) (xy 142.096234 -24.68753) (xy 141.58931 -24.68753)
			(xy 141.58976 -24.712168) (xy 141.589251 -24.740054) (xy 141.581131 -24.79523) (xy 141.565063 -24.848637)
			(xy 141.541391 -24.899134) (xy 141.510618 -24.945647) (xy 141.473401 -24.987184) (xy 141.430533 -25.022859)
			(xy 141.382927 -25.051913) (xy 141.331598 -25.073725) (xy 141.277641 -25.087831) (xy 141.222204 -25.093931)
			(xy 141.16647 -25.091894) (xy 141.111627 -25.081764) (xy 141.058843 -25.063757) (xy 141.009243 -25.038256)
			(xy 140.963885 -25.005805) (xy 140.923736 -24.967096) (xy 140.88965 -24.922953) (xy 140.862354 -24.874318)
			(xy 140.842431 -24.822227) (xy 140.830305 -24.76779) (xy 140.826234 -24.712168) (xy 140.44926 -24.712168)
			(xy 140.442195 -24.760178) (xy 140.426127 -24.813585) (xy 140.402455 -24.864082) (xy 140.371682 -24.910595)
			(xy 140.334465 -24.952132) (xy 140.291597 -24.987807) (xy 140.243991 -25.016861) (xy 140.192662 -25.038673)
			(xy 140.138705 -25.052779) (xy 140.083268 -25.058879) (xy 140.027534 -25.056842) (xy 139.972691 -25.046712)
			(xy 139.919907 -25.028705) (xy 139.870307 -25.003204) (xy 139.824949 -24.970753) (xy 139.7848 -24.932044)
			(xy 139.750714 -24.887901) (xy 139.723418 -24.839266) (xy 139.703495 -24.787175) (xy 139.691369 -24.732738)
			(xy 139.687298 -24.677116) (xy 137.43178 -24.677116) (xy 137.43178 -25.157274) (xy 149.210008 -25.157274)
			(xy 149.210977 -25.102449) (xy 149.219786 -25.048326) (xy 149.236251 -24.996023) (xy 149.260034 -24.946615)
			(xy 149.290646 -24.901121) (xy 149.327455 -24.860477) (xy 149.369703 -24.825522) (xy 149.416519 -24.796974)
			(xy 149.466941 -24.775423) (xy 149.519928 -24.761312) (xy 149.57439 -24.754931) (xy 149.629204 -24.756413)
			(xy 149.683241 -24.765726) (xy 149.735389 -24.782679) (xy 149.784572 -24.806923) (xy 149.829779 -24.837958)
			(xy 149.870077 -24.875145) (xy 149.904636 -24.917717) (xy 149.932745 -24.964799) (xy 149.953824 -25.015419)
			(xy 149.961092 -25.04186) (xy 149.96712 -25.063155) (xy 149.985376 -25.103464) (xy 150.010344 -25.139998)
			(xy 150.041267 -25.17165) (xy 150.07721 -25.197462) (xy 150.117083 -25.216652) (xy 150.159679 -25.228638)
			(xy 150.203708 -25.233059) (xy 150.247837 -25.22978) (xy 150.290729 -25.2189) (xy 150.311104 -25.210262)
			(xy 150.338804 -25.198431) (xy 150.396945 -25.182703) (xy 150.456835 -25.17631) (xy 150.516986 -25.179413)
			(xy 150.546562 -25.185116) (xy 150.570077 -25.189483) (xy 150.617886 -25.190468) (xy 150.665034 -25.182485)
			(xy 150.709853 -25.165815) (xy 150.750758 -25.141047) (xy 150.786303 -25.109059) (xy 150.815229 -25.070981)
			(xy 150.836513 -25.02816) (xy 150.843488 -25.005284) (xy 150.851458 -24.978732) (xy 150.874045 -24.928105)
			(xy 150.90372 -24.881279) (xy 150.939858 -24.839239) (xy 150.981699 -24.802871) (xy 151.028362 -24.77294)
			(xy 151.078864 -24.750076) (xy 151.132143 -24.734759) (xy 151.187078 -24.727313) (xy 151.242512 -24.727894)
			(xy 151.297279 -24.73649) (xy 151.350226 -24.75292) (xy 151.400238 -24.776839) (xy 151.446262 -24.807741)
			(xy 151.487332 -24.844979) (xy 151.52258 -24.887767) (xy 151.551267 -24.935204) (xy 151.572788 -24.986294)
			(xy 151.58669 -25.03996) (xy 151.592681 -25.095072) (xy 151.590634 -25.150472) (xy 151.580593 -25.204992)
			(xy 151.562768 -25.257485) (xy 151.537536 -25.306847) (xy 151.505427 -25.352039) (xy 151.467116 -25.392109)
			(xy 151.423411 -25.426214) (xy 151.375231 -25.453636) (xy 151.323591 -25.473798) (xy 151.269576 -25.486276)
			(xy 151.214324 -25.490808) (xy 151.158999 -25.487296) (xy 151.131778 -25.482042) (xy 151.10828 -25.47757)
			(xy 151.060459 -25.476593) (xy 151.013302 -25.484588) (xy 150.968476 -25.501272) (xy 150.927568 -25.526055)
			(xy 150.892023 -25.55806) (xy 150.8631 -25.596154) (xy 150.841822 -25.638991) (xy 150.834852 -25.661874)
			(xy 150.82901 -25.68067) (xy 150.822542 -25.701182) (xy 150.815806 -25.743658) (xy 150.816326 -25.786662)
			(xy 150.824085 -25.828963) (xy 150.838863 -25.869351) (xy 150.860236 -25.90667) (xy 150.866149 -25.913842)
			(xy 151.541224 -25.913842) (xy 151.545295 -25.85822) (xy 151.557421 -25.803783) (xy 151.577344 -25.751692)
			(xy 151.60464 -25.703057) (xy 151.638726 -25.658914) (xy 151.678875 -25.620205) (xy 151.724233 -25.587754)
			(xy 151.773833 -25.562253) (xy 151.826617 -25.544246) (xy 151.88146 -25.534116) (xy 151.937194 -25.532079)
			(xy 151.992631 -25.538179) (xy 152.046588 -25.552285) (xy 152.097917 -25.574097) (xy 152.145523 -25.603151)
			(xy 152.188391 -25.638826) (xy 152.225608 -25.680363) (xy 152.256381 -25.726876) (xy 152.280053 -25.777373)
			(xy 152.296121 -25.83078) (xy 152.304241 -25.885956) (xy 152.30475 -25.913842) (xy 152.304241 -25.941728)
			(xy 152.296121 -25.996904) (xy 152.280053 -26.050311) (xy 152.256381 -26.100808) (xy 152.225608 -26.147321)
			(xy 152.188391 -26.188858) (xy 152.145523 -26.224533) (xy 152.097917 -26.253587) (xy 152.046588 -26.275399)
			(xy 151.992631 -26.289505) (xy 151.937194 -26.295605) (xy 151.88146 -26.293568) (xy 151.826617 -26.283438)
			(xy 151.773833 -26.265431) (xy 151.724233 -26.23993) (xy 151.678875 -26.207479) (xy 151.638726 -26.16877)
			(xy 151.60464 -26.124627) (xy 151.577344 -26.075992) (xy 151.557421 -26.023901) (xy 151.545295 -25.969464)
			(xy 151.541224 -25.913842) (xy 150.866149 -25.913842) (xy 150.887594 -25.939854) (xy 150.920152 -25.967952)
			(xy 150.956981 -25.990161) (xy 150.976838 -25.998424) (xy 151.0026 -26.008981) (xy 151.050957 -26.036573)
			(xy 151.094791 -26.070899) (xy 151.133172 -26.111229) (xy 151.165286 -26.156709) (xy 151.19045 -26.206373)
			(xy 151.20813 -26.259166) (xy 151.217952 -26.313967) (xy 151.219706 -26.369615) (xy 151.213356 -26.424926)
			(xy 151.199036 -26.478728) (xy 151.17705 -26.529878) (xy 151.147865 -26.57729) (xy 151.112101 -26.619958)
			(xy 151.070515 -26.656977) (xy 151.023993 -26.68756) (xy 150.97352 -26.711058) (xy 150.920168 -26.726973)
			(xy 150.86507 -26.734967) (xy 150.809395 -26.734869) (xy 150.754325 -26.726683) (xy 150.70103 -26.710581)
			(xy 150.650639 -26.686906) (xy 150.604224 -26.65616) (xy 150.562769 -26.618996) (xy 150.527154 -26.576203)
			(xy 150.498135 -26.528689) (xy 150.476329 -26.477462) (xy 150.462197 -26.42361) (xy 150.456041 -26.368277)
			(xy 150.45799 -26.312636) (xy 150.468003 -26.257869) (xy 150.476458 -26.231342) (xy 150.482932 -26.210831)
			(xy 150.48967 -26.168354) (xy 150.489153 -26.125349) (xy 150.481394 -26.083047) (xy 150.466615 -26.042657)
			(xy 150.445241 -26.005337) (xy 150.417881 -25.972153) (xy 150.38532 -25.944056) (xy 150.348489 -25.921849)
			(xy 150.32863 -25.913588) (xy 150.304729 -25.903807) (xy 150.259612 -25.878674) (xy 150.218298 -25.847687)
			(xy 150.181539 -25.811411) (xy 150.150007 -25.77051) (xy 150.12428 -25.725731) (xy 150.104825 -25.677891)
			(xy 150.097998 -25.652984) (xy 150.092015 -25.631676) (xy 150.07375 -25.591368) (xy 150.048774 -25.554836)
			(xy 150.017845 -25.523187) (xy 149.981897 -25.497378) (xy 149.94202 -25.47819) (xy 149.899421 -25.466205)
			(xy 149.855389 -25.461785) (xy 149.811258 -25.465065) (xy 149.768363 -25.475944) (xy 149.747986 -25.484582)
			(xy 149.722783 -25.495387) (xy 149.670069 -25.510486) (xy 149.615736 -25.517882) (xy 149.560904 -25.517425)
			(xy 149.506702 -25.509122) (xy 149.454247 -25.493146) (xy 149.404619 -25.469825) (xy 149.358841 -25.43964)
			(xy 149.317855 -25.403213) (xy 149.282507 -25.361293) (xy 149.253523 -25.314745) (xy 149.231502 -25.264527)
			(xy 149.216897 -25.211674) (xy 149.210008 -25.157274) (xy 137.43178 -25.157274) (xy 137.43178 -26.193242)
			(xy 144.285968 -26.193242) (xy 144.290039 -26.13762) (xy 144.302165 -26.083183) (xy 144.322088 -26.031092)
			(xy 144.349384 -25.982457) (xy 144.38347 -25.938314) (xy 144.423619 -25.899605) (xy 144.468977 -25.867154)
			(xy 144.518577 -25.841653) (xy 144.571361 -25.823646) (xy 144.626204 -25.813516) (xy 144.681938 -25.811479)
			(xy 144.737375 -25.817579) (xy 144.791332 -25.831685) (xy 144.842661 -25.853497) (xy 144.890267 -25.882551)
			(xy 144.933135 -25.918226) (xy 144.970352 -25.959763) (xy 145.001125 -26.006276) (xy 145.024797 -26.056773)
			(xy 145.040865 -26.11018) (xy 145.048985 -26.165356) (xy 145.049494 -26.193242) (xy 146.668234 -26.193242)
			(xy 146.672305 -26.13762) (xy 146.684431 -26.083183) (xy 146.704354 -26.031092) (xy 146.73165 -25.982457)
			(xy 146.765736 -25.938314) (xy 146.805885 -25.899605) (xy 146.851243 -25.867154) (xy 146.900843 -25.841653)
			(xy 146.953627 -25.823646) (xy 147.00847 -25.813516) (xy 147.064204 -25.811479) (xy 147.119641 -25.817579)
			(xy 147.173598 -25.831685) (xy 147.224927 -25.853497) (xy 147.272533 -25.882551) (xy 147.315401 -25.918226)
			(xy 147.352618 -25.959763) (xy 147.383391 -26.006276) (xy 147.407063 -26.056773) (xy 147.423131 -26.11018)
			(xy 147.431251 -26.165356) (xy 147.43176 -26.193242) (xy 147.431251 -26.221128) (xy 147.423131 -26.276304)
			(xy 147.407063 -26.329711) (xy 147.383391 -26.380208) (xy 147.361391 -26.41346) (xy 149.302214 -26.41346)
			(xy 149.306285 -26.357838) (xy 149.318411 -26.303401) (xy 149.338334 -26.25131) (xy 149.36563 -26.202675)
			(xy 149.399716 -26.158532) (xy 149.439865 -26.119823) (xy 149.485223 -26.087372) (xy 149.534823 -26.061871)
			(xy 149.587607 -26.043864) (xy 149.64245 -26.033734) (xy 149.698184 -26.031697) (xy 149.753621 -26.037797)
			(xy 149.807578 -26.051903) (xy 149.858907 -26.073715) (xy 149.906513 -26.102769) (xy 149.949381 -26.138444)
			(xy 149.986598 -26.179981) (xy 150.017371 -26.226494) (xy 150.041043 -26.276991) (xy 150.057111 -26.330398)
			(xy 150.065231 -26.385574) (xy 150.06574 -26.41346) (xy 150.065231 -26.441346) (xy 150.057111 -26.496522)
			(xy 150.041043 -26.549929) (xy 150.017371 -26.600426) (xy 149.986598 -26.646939) (xy 149.949381 -26.688476)
			(xy 149.906513 -26.724151) (xy 149.858907 -26.753205) (xy 149.807578 -26.775017) (xy 149.753621 -26.789123)
			(xy 149.698184 -26.795223) (xy 149.64245 -26.793186) (xy 149.587607 -26.783056) (xy 149.534823 -26.765049)
			(xy 149.485223 -26.739548) (xy 149.439865 -26.707097) (xy 149.399716 -26.668388) (xy 149.36563 -26.624245)
			(xy 149.338334 -26.57561) (xy 149.318411 -26.523519) (xy 149.306285 -26.469082) (xy 149.302214 -26.41346)
			(xy 147.361391 -26.41346) (xy 147.352618 -26.426721) (xy 147.315401 -26.468258) (xy 147.272533 -26.503933)
			(xy 147.224927 -26.532987) (xy 147.173598 -26.554799) (xy 147.119641 -26.568905) (xy 147.064204 -26.575005)
			(xy 147.00847 -26.572968) (xy 146.953627 -26.562838) (xy 146.900843 -26.544831) (xy 146.851243 -26.51933)
			(xy 146.805885 -26.486879) (xy 146.765736 -26.44817) (xy 146.73165 -26.404027) (xy 146.704354 -26.355392)
			(xy 146.684431 -26.303301) (xy 146.672305 -26.248864) (xy 146.668234 -26.193242) (xy 145.049494 -26.193242)
			(xy 145.048985 -26.221128) (xy 145.040865 -26.276304) (xy 145.024797 -26.329711) (xy 145.001125 -26.380208)
			(xy 144.970352 -26.426721) (xy 144.933135 -26.468258) (xy 144.890267 -26.503933) (xy 144.842661 -26.532987)
			(xy 144.791332 -26.554799) (xy 144.737375 -26.568905) (xy 144.681938 -26.575005) (xy 144.626204 -26.572968)
			(xy 144.571361 -26.562838) (xy 144.518577 -26.544831) (xy 144.468977 -26.51933) (xy 144.423619 -26.486879)
			(xy 144.38347 -26.44817) (xy 144.349384 -26.404027) (xy 144.322088 -26.355392) (xy 144.302165 -26.303301)
			(xy 144.290039 -26.248864) (xy 144.285968 -26.193242) (xy 137.43178 -26.193242) (xy 137.43178 -26.374598)
			(xy 137.432281 -26.397559) (xy 137.440543 -26.442733) (xy 137.45678 -26.48569) (xy 137.480466 -26.525034)
			(xy 137.51083 -26.559487) (xy 137.546885 -26.587929) (xy 137.587461 -26.609436) (xy 137.631239 -26.623309)
			(xy 137.676796 -26.629098) (xy 137.69975 -26.628344) (xy 137.728198 -26.627074) (xy 137.755438 -26.627364)
			(xy 137.809413 -26.634718) (xy 137.861796 -26.649663) (xy 137.911527 -26.671895) (xy 137.957596 -26.700964)
			(xy 137.978642 -26.71826) (xy 137.998459 -26.735753) (xy 138.033556 -26.775279) (xy 138.06286 -26.819272)
			(xy 138.085809 -26.86689) (xy 138.101963 -26.91722) (xy 138.111014 -26.969299) (xy 138.112788 -27.022129)
			(xy 138.110468 -27.04846) (xy 138.108536 -27.072033) (xy 138.112415 -27.119165) (xy 138.124941 -27.164768)
			(xy 138.145683 -27.207268) (xy 138.173925 -27.245201) (xy 138.208694 -27.277258) (xy 138.24879 -27.302334)
			(xy 138.292831 -27.319564) (xy 138.339299 -27.328355) (xy 138.362944 -27.328876) (xy 138.365484 -27.328876)
			(xy 138.387723 -27.328417) (xy 138.431522 -27.320676) (xy 138.473304 -27.305428) (xy 138.511793 -27.283139)
			(xy 138.545814 -27.254488) (xy 138.574327 -27.220352) (xy 138.596461 -27.181773) (xy 138.611541 -27.13993)
			(xy 138.619105 -27.096101) (xy 138.619484 -27.07386) (xy 138.61986 -27.045058) (xy 138.628219 -26.98807)
			(xy 138.645043 -26.932983) (xy 138.669951 -26.881048) (xy 138.702376 -26.833444) (xy 138.721592 -26.811986)
			(xy 138.740916 -26.791946) (xy 138.784347 -26.75712) (xy 138.832378 -26.728976) (xy 138.883989 -26.70811)
			(xy 138.938085 -26.694966) (xy 138.993517 -26.689824) (xy 139.049107 -26.692791) (xy 139.103676 -26.703806)
			(xy 139.156065 -26.722634) (xy 139.205161 -26.748876) (xy 139.249923 -26.781974) (xy 139.2894 -26.821225)
			(xy 139.322753 -26.865797) (xy 139.349274 -26.914743) (xy 139.368401 -26.967024) (xy 139.379728 -27.021529)
			(xy 139.383013 -27.077101) (xy 139.378187 -27.132561) (xy 139.365353 -27.186731) (xy 139.355576 -27.212798)
			(xy 139.34472 -27.238751) (xy 139.316488 -27.28741) (xy 139.281415 -27.331394) (xy 139.240263 -27.36975)
			(xy 139.193924 -27.401647) (xy 139.168886 -27.414474) (xy 139.148868 -27.42603) (xy 139.113029 -27.455213)
			(xy 139.083055 -27.490392) (xy 139.059931 -27.530409) (xy 139.04442 -27.573946) (xy 139.037032 -27.61957)
			(xy 139.038011 -27.665777) (xy 139.047325 -27.711046) (xy 139.064666 -27.753887) (xy 139.076684 -27.77363)
			(xy 139.093709 -27.799593) (xy 139.119995 -27.855836) (xy 139.13681 -27.915597) (xy 139.143709 -27.977295)
			(xy 139.142926 -28.001976) (xy 141.348712 -28.001976) (xy 141.352783 -27.946354) (xy 141.364909 -27.891917)
			(xy 141.384832 -27.839826) (xy 141.412128 -27.791191) (xy 141.446214 -27.747048) (xy 141.486363 -27.708339)
			(xy 141.531721 -27.675888) (xy 141.581321 -27.650387) (xy 141.634105 -27.63238) (xy 141.688948 -27.62225)
			(xy 141.744682 -27.620213) (xy 141.800119 -27.626313) (xy 141.854076 -27.640419) (xy 141.905405 -27.662231)
			(xy 141.953011 -27.691285) (xy 141.988169 -27.720544) (xy 143.404842 -27.720544) (xy 143.408913 -27.664922)
			(xy 143.421039 -27.610485) (xy 143.440962 -27.558394) (xy 143.468258 -27.509759) (xy 143.502344 -27.465616)
			(xy 143.542493 -27.426907) (xy 143.587851 -27.394456) (xy 143.637451 -27.368955) (xy 143.690235 -27.350948)
			(xy 143.745078 -27.340818) (xy 143.800812 -27.338781) (xy 143.856249 -27.344881) (xy 143.910206 -27.358987)
			(xy 143.961535 -27.380799) (xy 144.009141 -27.409853) (xy 144.052009 -27.445528) (xy 144.089226 -27.487065)
			(xy 144.119999 -27.533578) (xy 144.143671 -27.584075) (xy 144.159739 -27.637482) (xy 144.167859 -27.692658)
			(xy 144.168368 -27.720544) (xy 144.167859 -27.74843) (xy 144.159739 -27.803606) (xy 144.143671 -27.857013)
			(xy 144.119999 -27.90751) (xy 144.089226 -27.954023) (xy 144.052009 -27.99556) (xy 144.009141 -28.031235)
			(xy 143.961535 -28.060289) (xy 143.910206 -28.082101) (xy 143.856249 -28.096207) (xy 143.800812 -28.102307)
			(xy 143.745078 -28.10027) (xy 143.690235 -28.09014) (xy 143.637451 -28.072133) (xy 143.587851 -28.046632)
			(xy 143.542493 -28.014181) (xy 143.502344 -27.975472) (xy 143.468258 -27.931329) (xy 143.440962 -27.882694)
			(xy 143.421039 -27.830603) (xy 143.408913 -27.776166) (xy 143.404842 -27.720544) (xy 141.988169 -27.720544)
			(xy 141.995879 -27.72696) (xy 142.033096 -27.768497) (xy 142.063869 -27.81501) (xy 142.087541 -27.865507)
			(xy 142.103609 -27.918914) (xy 142.111729 -27.97409) (xy 142.112238 -28.001976) (xy 142.111729 -28.029862)
			(xy 142.103609 -28.085038) (xy 142.087541 -28.138445) (xy 142.063869 -28.188942) (xy 142.033096 -28.235455)
			(xy 141.995879 -28.276992) (xy 141.953011 -28.312667) (xy 141.905405 -28.341721) (xy 141.854076 -28.363533)
			(xy 141.800119 -28.377639) (xy 141.744682 -28.383739) (xy 141.688948 -28.381702) (xy 141.634105 -28.371572)
			(xy 141.581321 -28.353565) (xy 141.531721 -28.328064) (xy 141.486363 -28.295613) (xy 141.446214 -28.256904)
			(xy 141.412128 -28.212761) (xy 141.384832 -28.164126) (xy 141.364909 -28.112035) (xy 141.352783 -28.057598)
			(xy 141.348712 -28.001976) (xy 139.142926 -28.001976) (xy 139.142724 -28.008326) (xy 139.141703 -28.025376)
			(xy 139.136994 -28.059208) (xy 139.133326 -28.07589) (xy 139.128614 -28.098268) (xy 139.126379 -28.14394)
			(xy 139.132348 -28.189276) (xy 139.14633 -28.232813) (xy 139.167873 -28.273148) (xy 139.196283 -28.308979)
			(xy 139.230643 -28.339151) (xy 139.269845 -28.362691) (xy 139.312626 -28.37884) (xy 139.357605 -28.387077)
			(xy 139.380468 -28.387548) (xy 139.601448 -28.387548) (xy 139.63142 -28.370022) (xy 139.655531 -28.35645)
			(xy 139.706798 -28.335642) (xy 139.760533 -28.322456) (xy 139.815608 -28.317167) (xy 139.87087 -28.319888)
			(xy 139.925159 -28.33056) (xy 139.977339 -28.34896) (xy 140.026314 -28.374702) (xy 140.071059 -28.407247)
			(xy 140.110635 -28.445912) (xy 140.144212 -28.489887) (xy 140.171088 -28.53825) (xy 140.190697 -28.589987)
			(xy 140.191202 -28.592272) (xy 152.047954 -28.592272) (xy 152.052025 -28.53665) (xy 152.064151 -28.482213)
			(xy 152.084074 -28.430122) (xy 152.11137 -28.381487) (xy 152.145456 -28.337344) (xy 152.185605 -28.298635)
			(xy 152.230963 -28.266184) (xy 152.280563 -28.240683) (xy 152.333347 -28.222676) (xy 152.38819 -28.212546)
			(xy 152.443924 -28.210509) (xy 152.499361 -28.216609) (xy 152.553318 -28.230715) (xy 152.604647 -28.252527)
			(xy 152.652253 -28.281581) (xy 152.695121 -28.317256) (xy 152.732338 -28.358793) (xy 152.763111 -28.405306)
			(xy 152.786783 -28.455803) (xy 152.802851 -28.50921) (xy 152.810971 -28.564386) (xy 152.81148 -28.592272)
			(xy 152.810971 -28.620158) (xy 152.802851 -28.675334) (xy 152.786783 -28.728741) (xy 152.763111 -28.779238)
			(xy 152.732338 -28.825751) (xy 152.695121 -28.867288) (xy 152.652253 -28.902963) (xy 152.604647 -28.932017)
			(xy 152.553318 -28.953829) (xy 152.499361 -28.967935) (xy 152.443924 -28.974035) (xy 152.38819 -28.971998)
			(xy 152.333347 -28.961868) (xy 152.280563 -28.943861) (xy 152.230963 -28.91836) (xy 152.185605 -28.885909)
			(xy 152.145456 -28.8472) (xy 152.11137 -28.803057) (xy 152.084074 -28.754422) (xy 152.064151 -28.702331)
			(xy 152.052025 -28.647894) (xy 152.047954 -28.592272) (xy 140.191202 -28.592272) (xy 140.20263 -28.644014)
			(xy 140.206636 -28.699197) (xy 140.202631 -28.75438) (xy 140.190699 -28.808407) (xy 140.17109 -28.860144)
			(xy 140.144216 -28.908508) (xy 140.110639 -28.952483) (xy 140.071063 -28.991149) (xy 140.026319 -29.023695)
			(xy 139.977344 -29.049438) (xy 139.925165 -29.067839) (xy 139.870876 -29.078512) (xy 139.815614 -29.081233)
			(xy 139.760539 -29.075945) (xy 139.706804 -29.06276) (xy 139.655537 -29.041953) (xy 139.63142 -29.02839)
			(xy 139.601448 -29.010864) (xy 138.519154 -29.010864) (xy 138.424412 -28.916122) (xy 138.404346 -28.895802)
			(xy 138.384988 -28.879071) (xy 138.341013 -28.852928) (xy 138.292705 -28.836093) (xy 138.26744 -28.832048)
			(xy 138.161522 -28.887674) (xy 138.144758 -28.908756) (xy 138.120882 -28.935934) (xy 138.09599 -28.95981)
			(xy 138.075751 -28.976787) (xy 138.031468 -29.005587) (xy 137.983636 -29.028007) (xy 137.933171 -29.043619)
			(xy 137.881035 -29.052125) (xy 137.828225 -29.053362) (xy 137.775748 -29.047306) (xy 137.724607 -29.034074)
			(xy 137.675778 -29.013919) (xy 137.65276 -29.000958) (xy 137.622788 -28.983432) (xy 137.55878 -28.983432)
			(xy 137.542129 -28.983929) (xy 137.509962 -28.992554) (xy 137.481123 -29.009211) (xy 137.457579 -29.032765)
			(xy 137.440934 -29.06161) (xy 137.432322 -29.09378) (xy 137.43178 -29.110432) (xy 137.43178 -29.903928)
			(xy 147.910548 -29.903928) (xy 147.914619 -29.848306) (xy 147.926745 -29.793869) (xy 147.946668 -29.741778)
			(xy 147.973964 -29.693143) (xy 148.00805 -29.649) (xy 148.048199 -29.610291) (xy 148.093557 -29.57784)
			(xy 148.143157 -29.552339) (xy 148.195941 -29.534332) (xy 148.250784 -29.524202) (xy 148.306518 -29.522165)
			(xy 148.361955 -29.528265) (xy 148.415912 -29.542371) (xy 148.467241 -29.564183) (xy 148.514847 -29.593237)
			(xy 148.557715 -29.628912) (xy 148.594932 -29.670449) (xy 148.625705 -29.716962) (xy 148.649377 -29.767459)
			(xy 148.665445 -29.820866) (xy 148.673565 -29.876042) (xy 148.673664 -29.881457) (xy 150.224214 -29.881457)
			(xy 150.228813 -29.825601) (xy 150.241533 -29.771019) (xy 150.262101 -29.718885) (xy 150.290074 -29.67032)
			(xy 150.324849 -29.62637) (xy 150.36568 -29.587979) (xy 150.411687 -29.555974) (xy 150.461882 -29.531043)
			(xy 150.515183 -29.513723) (xy 150.570444 -29.504386) (xy 150.626477 -29.503233) (xy 150.682075 -29.510289)
			(xy 150.736044 -29.525402) (xy 150.787221 -29.548246) (xy 150.834506 -29.578332) (xy 150.876882 -29.615011)
			(xy 150.913436 -29.657493) (xy 150.943382 -29.704866) (xy 150.966077 -29.75611) (xy 150.981032 -29.810123)
			(xy 150.987925 -29.865742) (xy 150.98776 -29.893768) (xy 150.987728 -29.915751) (xy 150.994291 -29.959213)
			(xy 151.008228 -30.0009) (xy 151.029126 -30.039569) (xy 151.056362 -30.074069) (xy 151.089123 -30.103373)
			(xy 151.126436 -30.126607) (xy 151.167188 -30.143079) (xy 151.210165 -30.152299) (xy 151.232108 -30.15361)
			(xy 151.260168 -30.155127) (xy 151.315398 -30.165492) (xy 151.368511 -30.183847) (xy 151.418356 -30.209794)
			(xy 151.463857 -30.242772) (xy 151.504028 -30.282067) (xy 151.538 -30.32683) (xy 151.56504 -30.376091)
			(xy 151.58456 -30.428786) (xy 151.596141 -30.483775) (xy 151.59953 -30.539867) (xy 151.594654 -30.59585)
			(xy 151.581619 -30.650512) (xy 151.560708 -30.702671) (xy 151.532372 -30.751198) (xy 151.497224 -30.795044)
			(xy 151.476964 -30.814518) (xy 151.461221 -30.829753) (xy 151.434696 -30.864616) (xy 151.414535 -30.903508)
			(xy 151.401333 -30.945277) (xy 151.395481 -30.988691) (xy 151.397151 -31.032466) (xy 151.406294 -31.075307)
			(xy 151.42264 -31.11595) (xy 151.433784 -31.134812) (xy 151.448001 -31.158732) (xy 151.470167 -31.209768)
			(xy 151.484683 -31.263482) (xy 151.491241 -31.318736) (xy 151.4897 -31.374357) (xy 151.480094 -31.429163)
			(xy 151.462627 -31.481992) (xy 151.43767 -31.531722) (xy 151.405751 -31.577298) (xy 151.36755 -31.617753)
			(xy 151.323875 -31.652228) (xy 151.275655 -31.679992) (xy 151.223913 -31.700454) (xy 151.169746 -31.713181)
			(xy 151.114305 -31.717903) (xy 151.058767 -31.71452) (xy 151.004309 -31.703102) (xy 150.952088 -31.683893)
			(xy 150.903213 -31.657301) (xy 150.85872 -31.623889) (xy 150.819553 -31.584367) (xy 150.786545 -31.539574)
			(xy 150.760396 -31.49046) (xy 150.74166 -31.438067) (xy 150.730735 -31.383509) (xy 150.727854 -31.327942)
			(xy 150.733077 -31.272546) (xy 150.746293 -31.218497) (xy 150.767223 -31.166941) (xy 150.795421 -31.118974)
			(xy 150.83029 -31.075613) (xy 150.850346 -31.056326) (xy 150.866045 -31.041046) (xy 150.892579 -31.006195)
			(xy 150.912749 -30.967312) (xy 150.925959 -30.925549) (xy 150.931818 -30.88214) (xy 150.930153 -30.838369)
			(xy 150.921013 -30.795531) (xy 150.904669 -30.754892) (xy 150.893526 -30.736032) (xy 150.879372 -30.712314)
			(xy 150.857277 -30.661693) (xy 150.842714 -30.608415) (xy 150.835987 -30.553594) (xy 150.836122 -30.525974)
			(xy 150.836131 -30.503991) (xy 150.829575 -30.460529) (xy 150.815643 -30.418841) (xy 150.794749 -30.380171)
			(xy 150.767516 -30.345669) (xy 150.734756 -30.316365) (xy 150.697445 -30.293131) (xy 150.656694 -30.27666)
			(xy 150.613717 -30.267441) (xy 150.591774 -30.266132) (xy 150.563792 -30.264529) (xy 150.508703 -30.254226)
			(xy 150.455713 -30.235976) (xy 150.405963 -30.21017) (xy 150.360523 -30.177365) (xy 150.32037 -30.138266)
			(xy 150.286369 -30.093713) (xy 150.25925 -30.044666) (xy 150.239598 -29.99218) (xy 150.227835 -29.937384)
			(xy 150.224214 -29.881457) (xy 148.673664 -29.881457) (xy 148.674074 -29.903928) (xy 148.673565 -29.931814)
			(xy 148.665445 -29.98699) (xy 148.649377 -30.040397) (xy 148.625705 -30.090894) (xy 148.594932 -30.137407)
			(xy 148.557715 -30.178944) (xy 148.514847 -30.214619) (xy 148.467241 -30.243673) (xy 148.415912 -30.265485)
			(xy 148.361955 -30.279591) (xy 148.306518 -30.285691) (xy 148.250784 -30.283654) (xy 148.195941 -30.273524)
			(xy 148.143157 -30.255517) (xy 148.093557 -30.230016) (xy 148.048199 -30.197565) (xy 148.00805 -30.158856)
			(xy 147.973964 -30.114713) (xy 147.946668 -30.066078) (xy 147.926745 -30.013987) (xy 147.914619 -29.95955)
			(xy 147.910548 -29.903928) (xy 137.43178 -29.903928) (xy 137.43178 -30.946344) (xy 147.867876 -30.946344)
			(xy 147.871947 -30.890722) (xy 147.884073 -30.836285) (xy 147.903996 -30.784194) (xy 147.931292 -30.735559)
			(xy 147.965378 -30.691416) (xy 148.005527 -30.652707) (xy 148.050885 -30.620256) (xy 148.100485 -30.594755)
			(xy 148.153269 -30.576748) (xy 148.208112 -30.566618) (xy 148.263846 -30.564581) (xy 148.319283 -30.570681)
			(xy 148.37324 -30.584787) (xy 148.424569 -30.606599) (xy 148.472175 -30.635653) (xy 148.515043 -30.671328)
			(xy 148.55226 -30.712865) (xy 148.583033 -30.759378) (xy 148.606705 -30.809875) (xy 148.622773 -30.863282)
			(xy 148.630893 -30.918458) (xy 148.631402 -30.946344) (xy 148.630893 -30.97423) (xy 148.622773 -31.029406)
			(xy 148.606705 -31.082813) (xy 148.583033 -31.13331) (xy 148.55226 -31.179823) (xy 148.515043 -31.22136)
			(xy 148.472175 -31.257035) (xy 148.424569 -31.286089) (xy 148.37324 -31.307901) (xy 148.319283 -31.322007)
			(xy 148.263846 -31.328107) (xy 148.208112 -31.32607) (xy 148.153269 -31.31594) (xy 148.100485 -31.297933)
			(xy 148.050885 -31.272432) (xy 148.005527 -31.239981) (xy 147.965378 -31.201272) (xy 147.931292 -31.157129)
			(xy 147.903996 -31.108494) (xy 147.884073 -31.056403) (xy 147.871947 -31.001966) (xy 147.867876 -30.946344)
			(xy 137.43178 -30.946344) (xy 137.43178 -32.570928) (xy 147.83892 -32.570928) (xy 147.842991 -32.515306)
			(xy 147.855117 -32.460869) (xy 147.87504 -32.408778) (xy 147.902336 -32.360143) (xy 147.936422 -32.316)
			(xy 147.976571 -32.277291) (xy 148.021929 -32.24484) (xy 148.071529 -32.219339) (xy 148.124313 -32.201332)
			(xy 148.179156 -32.191202) (xy 148.23489 -32.189165) (xy 148.290327 -32.195265) (xy 148.344284 -32.209371)
			(xy 148.395613 -32.231183) (xy 148.443219 -32.260237) (xy 148.486087 -32.295912) (xy 148.523304 -32.337449)
			(xy 148.554077 -32.383962) (xy 148.577749 -32.434459) (xy 148.592901 -32.484822) (xy 150.732234 -32.484822)
			(xy 150.736305 -32.4292) (xy 150.748431 -32.374763) (xy 150.768354 -32.322672) (xy 150.79565 -32.274037)
			(xy 150.829736 -32.229894) (xy 150.869885 -32.191185) (xy 150.915243 -32.158734) (xy 150.964843 -32.133233)
			(xy 151.017627 -32.115226) (xy 151.07247 -32.105096) (xy 151.128204 -32.103059) (xy 151.183641 -32.109159)
			(xy 151.237598 -32.123265) (xy 151.288927 -32.145077) (xy 151.336533 -32.174131) (xy 151.379401 -32.209806)
			(xy 151.416618 -32.251343) (xy 151.447391 -32.297856) (xy 151.471063 -32.348353) (xy 151.487131 -32.40176)
			(xy 151.495251 -32.456936) (xy 151.49576 -32.484822) (xy 151.495251 -32.512708) (xy 151.487131 -32.567884)
			(xy 151.471063 -32.621291) (xy 151.447391 -32.671788) (xy 151.416618 -32.718301) (xy 151.379401 -32.759838)
			(xy 151.336533 -32.795513) (xy 151.288927 -32.824567) (xy 151.237598 -32.846379) (xy 151.183641 -32.860485)
			(xy 151.128204 -32.866585) (xy 151.07247 -32.864548) (xy 151.017627 -32.854418) (xy 150.964843 -32.836411)
			(xy 150.915243 -32.81091) (xy 150.869885 -32.778459) (xy 150.829736 -32.73975) (xy 150.79565 -32.695607)
			(xy 150.768354 -32.646972) (xy 150.748431 -32.594881) (xy 150.736305 -32.540444) (xy 150.732234 -32.484822)
			(xy 148.592901 -32.484822) (xy 148.593817 -32.487866) (xy 148.601937 -32.543042) (xy 148.602446 -32.570928)
			(xy 148.601937 -32.598814) (xy 148.593817 -32.65399) (xy 148.577749 -32.707397) (xy 148.554077 -32.757894)
			(xy 148.523304 -32.804407) (xy 148.486087 -32.845944) (xy 148.443219 -32.881619) (xy 148.395613 -32.910673)
			(xy 148.344284 -32.932485) (xy 148.290327 -32.946591) (xy 148.23489 -32.952691) (xy 148.179156 -32.950654)
			(xy 148.124313 -32.940524) (xy 148.071529 -32.922517) (xy 148.021929 -32.897016) (xy 147.976571 -32.864565)
			(xy 147.936422 -32.825856) (xy 147.902336 -32.781713) (xy 147.87504 -32.733078) (xy 147.855117 -32.680987)
			(xy 147.842991 -32.62655) (xy 147.83892 -32.570928) (xy 137.43178 -32.570928) (xy 137.43178 -34.410052)
			(xy 138.903371 -34.410052) (xy 138.905212 -34.355184) (xy 138.914897 -34.301146) (xy 138.932225 -34.249054)
			(xy 138.95684 -34.199983) (xy 138.988232 -34.154946) (xy 139.025754 -34.114872) (xy 139.068632 -34.080588)
			(xy 139.11598 -34.052803) (xy 139.166821 -34.03209) (xy 139.220105 -34.018875) (xy 139.247372 -34.01568)
			(xy 139.269837 -34.012919) (xy 139.31336 -34.000513) (xy 139.353998 -33.980595) (xy 139.390466 -33.953796)
			(xy 139.421612 -33.920961) (xy 139.44645 -33.88313) (xy 139.464196 -33.841498) (xy 139.474289 -33.797381)
			(xy 139.47641 -33.752175) (xy 139.47394 -33.729676) (xy 139.470793 -33.702404) (xy 139.471433 -33.64751)
			(xy 139.479932 -33.593274) (xy 139.496117 -33.540816) (xy 139.519651 -33.491219) (xy 139.550051 -33.445506)
			(xy 139.586687 -33.404621) (xy 139.628804 -33.369408) (xy 139.675532 -33.340594) (xy 139.725907 -33.318774)
			(xy 139.77889 -33.304398) (xy 139.833385 -33.297763) (xy 139.888269 -33.299006) (xy 139.942408 -33.3081)
			(xy 139.994685 -33.32486) (xy 140.044021 -33.348938) (xy 140.089398 -33.379837) (xy 140.129878 -33.41692)
			(xy 140.164626 -33.459421) (xy 140.192925 -33.506463) (xy 140.214191 -33.557074) (xy 140.22194 -33.586928)
			(xy 147.910548 -33.586928) (xy 147.914619 -33.531306) (xy 147.926745 -33.476869) (xy 147.946668 -33.424778)
			(xy 147.973964 -33.376143) (xy 148.00805 -33.332) (xy 148.048199 -33.293291) (xy 148.093557 -33.26084)
			(xy 148.143157 -33.235339) (xy 148.195941 -33.217332) (xy 148.250784 -33.207202) (xy 148.306518 -33.205165)
			(xy 148.361955 -33.211265) (xy 148.415912 -33.225371) (xy 148.467241 -33.247183) (xy 148.514847 -33.276237)
			(xy 148.557715 -33.311912) (xy 148.594932 -33.353449) (xy 148.625705 -33.399962) (xy 148.649377 -33.450459)
			(xy 148.665445 -33.503866) (xy 148.673565 -33.559042) (xy 148.674074 -33.586928) (xy 148.673565 -33.614814)
			(xy 148.665445 -33.66999) (xy 148.649377 -33.723397) (xy 148.625705 -33.773894) (xy 148.594932 -33.820407)
			(xy 148.576545 -33.840928) (xy 150.224234 -33.840928) (xy 150.228305 -33.785306) (xy 150.240431 -33.730869)
			(xy 150.260354 -33.678778) (xy 150.28765 -33.630143) (xy 150.321736 -33.586) (xy 150.361885 -33.547291)
			(xy 150.407243 -33.51484) (xy 150.456843 -33.489339) (xy 150.509627 -33.471332) (xy 150.56447 -33.461202)
			(xy 150.620204 -33.459165) (xy 150.675641 -33.465265) (xy 150.729598 -33.479371) (xy 150.780927 -33.501183)
			(xy 150.828533 -33.530237) (xy 150.871401 -33.565912) (xy 150.908618 -33.607449) (xy 150.939391 -33.653962)
			(xy 150.963063 -33.704459) (xy 150.979131 -33.757866) (xy 150.987251 -33.813042) (xy 150.98776 -33.840928)
			(xy 150.987251 -33.868814) (xy 150.979131 -33.92399) (xy 150.963063 -33.977397) (xy 150.939391 -34.027894)
			(xy 150.908618 -34.074407) (xy 150.871401 -34.115944) (xy 150.828533 -34.151619) (xy 150.780927 -34.180673)
			(xy 150.729598 -34.202485) (xy 150.675641 -34.216591) (xy 150.620204 -34.222691) (xy 150.56447 -34.220654)
			(xy 150.509627 -34.210524) (xy 150.456843 -34.192517) (xy 150.407243 -34.167016) (xy 150.361885 -34.134565)
			(xy 150.321736 -34.095856) (xy 150.28765 -34.051713) (xy 150.260354 -34.003078) (xy 150.240431 -33.950987)
			(xy 150.228305 -33.89655) (xy 150.224234 -33.840928) (xy 148.576545 -33.840928) (xy 148.557715 -33.861944)
			(xy 148.514847 -33.897619) (xy 148.467241 -33.926673) (xy 148.415912 -33.948485) (xy 148.361955 -33.962591)
			(xy 148.306518 -33.968691) (xy 148.250784 -33.966654) (xy 148.195941 -33.956524) (xy 148.143157 -33.938517)
			(xy 148.093557 -33.913016) (xy 148.048199 -33.880565) (xy 148.00805 -33.841856) (xy 147.973964 -33.797713)
			(xy 147.946668 -33.749078) (xy 147.926745 -33.696987) (xy 147.914619 -33.64255) (xy 147.910548 -33.586928)
			(xy 140.22194 -33.586928) (xy 140.227984 -33.610211) (xy 140.234021 -33.664776) (xy 140.232175 -33.719643)
			(xy 140.222487 -33.773679) (xy 140.205154 -33.825769) (xy 140.180536 -33.874838) (xy 140.149141 -33.919872)
			(xy 140.111616 -33.959943) (xy 140.068736 -33.994222) (xy 140.021386 -34.022003) (xy 139.970544 -34.042712)
			(xy 139.917259 -34.055921) (xy 139.889992 -34.059114) (xy 139.867524 -34.061853) (xy 139.824002 -34.074264)
			(xy 139.783365 -34.094186) (xy 139.746898 -34.12099) (xy 139.715753 -34.153827) (xy 139.690916 -34.19166)
			(xy 139.67317 -34.233293) (xy 139.663077 -34.277411) (xy 139.660955 -34.322619) (xy 139.663424 -34.345118)
			(xy 139.666616 -34.372384) (xy 139.665978 -34.427279) (xy 139.65748 -34.481516) (xy 139.641297 -34.533975)
			(xy 139.617764 -34.583574) (xy 139.587366 -34.629288) (xy 139.550731 -34.670175) (xy 139.508615 -34.70539)
			(xy 139.461887 -34.734206) (xy 139.411513 -34.756029) (xy 139.35853 -34.770408) (xy 139.304035 -34.777046)
			(xy 139.24915 -34.775806) (xy 139.19501 -34.766714) (xy 139.142731 -34.749957) (xy 139.093393 -34.725882)
			(xy 139.048014 -34.694985) (xy 139.007532 -34.657904) (xy 138.97278 -34.615405) (xy 138.944478 -34.568364)
			(xy 138.923209 -34.517753) (xy 138.909411 -34.464617) (xy 138.903371 -34.410052) (xy 137.43178 -34.410052)
			(xy 137.43178 -35.41141) (xy 138.81176 -35.41141) (xy 138.815831 -35.355788) (xy 138.827957 -35.301351)
			(xy 138.84788 -35.24926) (xy 138.875176 -35.200625) (xy 138.909262 -35.156482) (xy 138.949411 -35.117773)
			(xy 138.994769 -35.085322) (xy 139.044369 -35.059821) (xy 139.097153 -35.041814) (xy 139.151996 -35.031684)
			(xy 139.20773 -35.029647) (xy 139.263167 -35.035747) (xy 139.317124 -35.049853) (xy 139.368453 -35.071665)
			(xy 139.416059 -35.100719) (xy 139.458927 -35.136394) (xy 139.496144 -35.177931) (xy 139.501557 -35.186112)
			(xy 139.869924 -35.186112) (xy 139.873995 -35.13049) (xy 139.886121 -35.076053) (xy 139.906044 -35.023962)
			(xy 139.93334 -34.975327) (xy 139.967426 -34.931184) (xy 140.007575 -34.892475) (xy 140.052933 -34.860024)
			(xy 140.102533 -34.834523) (xy 140.155317 -34.816516) (xy 140.21016 -34.806386) (xy 140.265894 -34.804349)
			(xy 140.321331 -34.810449) (xy 140.375288 -34.824555) (xy 140.426617 -34.846367) (xy 140.474223 -34.875421)
			(xy 140.517091 -34.911096) (xy 140.554308 -34.952633) (xy 140.585081 -34.999146) (xy 140.608753 -35.049643)
			(xy 140.624821 -35.10305) (xy 140.629868 -35.137344) (xy 147.065236 -35.137344) (xy 147.069307 -35.081722)
			(xy 147.081433 -35.027285) (xy 147.101356 -34.975194) (xy 147.128652 -34.926559) (xy 147.162738 -34.882416)
			(xy 147.202887 -34.843707) (xy 147.248245 -34.811256) (xy 147.297845 -34.785755) (xy 147.350629 -34.767748)
			(xy 147.405472 -34.757618) (xy 147.461206 -34.755581) (xy 147.516643 -34.761681) (xy 147.5706 -34.775787)
			(xy 147.621929 -34.797599) (xy 147.669535 -34.826653) (xy 147.712403 -34.862328) (xy 147.74962 -34.903865)
			(xy 147.780393 -34.950378) (xy 147.804065 -35.000875) (xy 147.820133 -35.054282) (xy 147.828253 -35.109458)
			(xy 147.828762 -35.137344) (xy 147.828253 -35.16523) (xy 147.820133 -35.220406) (xy 147.804065 -35.273813)
			(xy 147.780393 -35.32431) (xy 147.74962 -35.370823) (xy 147.712403 -35.41236) (xy 147.669535 -35.448035)
			(xy 147.621929 -35.477089) (xy 147.5706 -35.498901) (xy 147.516643 -35.513007) (xy 147.461206 -35.519107)
			(xy 147.405472 -35.51707) (xy 147.350629 -35.50694) (xy 147.297845 -35.488933) (xy 147.248245 -35.463432)
			(xy 147.202887 -35.430981) (xy 147.162738 -35.392272) (xy 147.128652 -35.348129) (xy 147.101356 -35.299494)
			(xy 147.081433 -35.247403) (xy 147.069307 -35.192966) (xy 147.065236 -35.137344) (xy 140.629868 -35.137344)
			(xy 140.632941 -35.158226) (xy 140.63345 -35.186112) (xy 140.632941 -35.213998) (xy 140.624821 -35.269174)
			(xy 140.608753 -35.322581) (xy 140.585081 -35.373078) (xy 140.554308 -35.419591) (xy 140.517091 -35.461128)
			(xy 140.474223 -35.496803) (xy 140.426617 -35.525857) (xy 140.375288 -35.547669) (xy 140.321331 -35.561775)
			(xy 140.265894 -35.567875) (xy 140.21016 -35.565838) (xy 140.155317 -35.555708) (xy 140.102533 -35.537701)
			(xy 140.052933 -35.5122) (xy 140.007575 -35.479749) (xy 139.967426 -35.44104) (xy 139.93334 -35.396897)
			(xy 139.906044 -35.348262) (xy 139.886121 -35.296171) (xy 139.873995 -35.241734) (xy 139.869924 -35.186112)
			(xy 139.501557 -35.186112) (xy 139.526917 -35.224444) (xy 139.550589 -35.274941) (xy 139.566657 -35.328348)
			(xy 139.574777 -35.383524) (xy 139.575286 -35.41141) (xy 139.574777 -35.439296) (xy 139.566657 -35.494472)
			(xy 139.550589 -35.547879) (xy 139.526917 -35.598376) (xy 139.496144 -35.644889) (xy 139.458927 -35.686426)
			(xy 139.429764 -35.710696) (xy 150.225062 -35.710696) (xy 150.232453 -35.656441) (xy 150.247525 -35.603799)
			(xy 150.269968 -35.553853) (xy 150.299322 -35.507629) (xy 150.334983 -35.466076) (xy 150.376218 -35.430048)
			(xy 150.42218 -35.400286) (xy 150.471926 -35.377401) (xy 150.524432 -35.361863) (xy 150.57862 -35.353992)
			(xy 150.605998 -35.353498) (xy 150.628491 -35.352919) (xy 150.672771 -35.344979) (xy 150.714961 -35.329364)
			(xy 150.75374 -35.306563) (xy 150.787898 -35.277288) (xy 150.816366 -35.242454) (xy 150.838253 -35.203151)
			(xy 150.852877 -35.160608) (xy 150.859779 -35.116154) (xy 150.859744 -35.093656) (xy 150.859621 -35.066271)
			(xy 150.866218 -35.011909) (xy 150.880521 -34.959048) (xy 150.902234 -34.908775) (xy 150.930911 -34.862123)
			(xy 150.965964 -34.82005) (xy 151.006671 -34.783421) (xy 151.052198 -34.752988) (xy 151.101608 -34.729377)
			(xy 151.153885 -34.713073) (xy 151.207957 -34.70441) (xy 151.262712 -34.703568) (xy 151.317025 -34.710562)
			(xy 151.36978 -34.725249) (xy 151.419893 -34.747328) (xy 151.466335 -34.776345) (xy 151.508151 -34.811704)
			(xy 151.544482 -34.852678) (xy 151.574582 -34.898425) (xy 151.597832 -34.948006) (xy 151.613754 -35.000401)
			(xy 151.622022 -35.054535) (xy 151.622465 -35.109294) (xy 151.615075 -35.163555) (xy 151.600003 -35.216201)
			(xy 151.577559 -35.266152) (xy 151.548204 -35.312381) (xy 151.512541 -35.353937) (xy 151.471304 -35.389969)
			(xy 151.425338 -35.419734) (xy 151.375589 -35.442621) (xy 151.323079 -35.458161) (xy 151.268886 -35.466034)
			(xy 151.241506 -35.466528) (xy 151.219012 -35.467084) (xy 151.174729 -35.475025) (xy 151.132537 -35.490641)
			(xy 151.093755 -35.513445) (xy 151.059597 -35.542723) (xy 151.031129 -35.57756) (xy 151.009243 -35.616866)
			(xy 150.994622 -35.659413) (xy 150.987723 -35.70387) (xy 150.98776 -35.72637) (xy 150.987852 -35.753753)
			(xy 150.981251 -35.808111) (xy 150.966946 -35.860966) (xy 150.945232 -35.911234) (xy 150.916554 -35.95788)
			(xy 150.881502 -35.999948) (xy 150.840795 -36.036571) (xy 150.795271 -36.066999) (xy 150.745864 -36.090605)
			(xy 150.693589 -36.106906) (xy 150.639521 -36.115565) (xy 150.584771 -36.116405) (xy 150.530463 -36.109409)
			(xy 150.477713 -36.09472) (xy 150.427605 -36.072641) (xy 150.381168 -36.043624) (xy 150.339357 -36.008267)
			(xy 150.303031 -35.967295) (xy 150.272935 -35.92155) (xy 150.249689 -35.871973) (xy 150.233769 -35.819581)
			(xy 150.225504 -35.765452) (xy 150.225062 -35.710696) (xy 139.429764 -35.710696) (xy 139.416059 -35.722101)
			(xy 139.368453 -35.751155) (xy 139.317124 -35.772967) (xy 139.263167 -35.787073) (xy 139.20773 -35.793173)
			(xy 139.151996 -35.791136) (xy 139.097153 -35.781006) (xy 139.044369 -35.762999) (xy 138.994769 -35.737498)
			(xy 138.949411 -35.705047) (xy 138.909262 -35.666338) (xy 138.875176 -35.622195) (xy 138.84788 -35.57356)
			(xy 138.827957 -35.521469) (xy 138.815831 -35.467032) (xy 138.81176 -35.41141) (xy 137.43178 -35.41141)
			(xy 137.43178 -36.411765) (xy 138.694136 -36.411765) (xy 138.700462 -36.356447) (xy 138.71476 -36.302636)
			(xy 138.736728 -36.251474) (xy 138.765897 -36.204048) (xy 138.80165 -36.161365) (xy 138.843226 -36.124331)
			(xy 138.889743 -36.093733) (xy 138.940213 -36.070221) (xy 138.993565 -36.054293) (xy 139.048665 -36.046288)
			(xy 139.104343 -36.046377) (xy 139.159418 -36.054556) (xy 139.212718 -36.070653) (xy 139.263114 -36.094325)
			(xy 139.309534 -36.125071) (xy 139.350992 -36.162236) (xy 139.386609 -36.205032) (xy 139.40155 -36.228528)
			(xy 139.414047 -36.247951) (xy 139.444878 -36.282334) (xy 139.481414 -36.31058) (xy 139.522451 -36.331761)
			(xy 139.56664 -36.345178) (xy 139.612526 -36.350391) (xy 139.658599 -36.347229) (xy 139.703342 -36.335794)
			(xy 139.745283 -36.316463) (xy 139.783041 -36.289873) (xy 139.799568 -36.27374) (xy 139.819425 -36.254221)
			(xy 139.863786 -36.220572) (xy 139.912566 -36.193728) (xy 139.96473 -36.174258) (xy 140.01917 -36.162576)
			(xy 140.074729 -36.15893) (xy 140.130228 -36.163398) (xy 140.184489 -36.175885) (xy 140.236359 -36.196125)
			(xy 140.239288 -36.197794) (xy 141.438374 -36.197794) (xy 141.442445 -36.142172) (xy 141.454571 -36.087735)
			(xy 141.474494 -36.035644) (xy 141.50179 -35.987009) (xy 141.535876 -35.942866) (xy 141.576025 -35.904157)
			(xy 141.621383 -35.871706) (xy 141.670983 -35.846205) (xy 141.723767 -35.828198) (xy 141.77861 -35.818068)
			(xy 141.834344 -35.816031) (xy 141.889781 -35.822131) (xy 141.943738 -35.836237) (xy 141.995067 -35.858049)
			(xy 142.042673 -35.887103) (xy 142.085541 -35.922778) (xy 142.122758 -35.964315) (xy 142.153531 -36.010828)
			(xy 142.177203 -36.061325) (xy 142.193271 -36.114732) (xy 142.201391 -36.169908) (xy 142.2019 -36.197794)
			(xy 142.201391 -36.22568) (xy 142.193271 -36.280856) (xy 142.177203 -36.334263) (xy 142.153531 -36.38476)
			(xy 142.143967 -36.399216) (xy 146.821142 -36.399216) (xy 146.825213 -36.343594) (xy 146.837339 -36.289157)
			(xy 146.857262 -36.237066) (xy 146.884558 -36.188431) (xy 146.918644 -36.144288) (xy 146.958793 -36.105579)
			(xy 147.004151 -36.073128) (xy 147.053751 -36.047627) (xy 147.106535 -36.02962) (xy 147.161378 -36.01949)
			(xy 147.217112 -36.017453) (xy 147.272549 -36.023553) (xy 147.326506 -36.037659) (xy 147.377835 -36.059471)
			(xy 147.425441 -36.088525) (xy 147.468309 -36.1242) (xy 147.505526 -36.165737) (xy 147.536299 -36.21225)
			(xy 147.559971 -36.262747) (xy 147.576039 -36.316154) (xy 147.584159 -36.37133) (xy 147.584668 -36.399216)
			(xy 147.584159 -36.427102) (xy 147.576039 -36.482278) (xy 147.559971 -36.535685) (xy 147.536299 -36.586182)
			(xy 147.505526 -36.632695) (xy 147.468309 -36.674232) (xy 147.425441 -36.709907) (xy 147.399718 -36.725606)
			(xy 147.946362 -36.725606) (xy 147.950433 -36.669984) (xy 147.962559 -36.615547) (xy 147.982482 -36.563456)
			(xy 148.009778 -36.514821) (xy 148.043864 -36.470678) (xy 148.084013 -36.431969) (xy 148.129371 -36.399518)
			(xy 148.178971 -36.374017) (xy 148.231755 -36.35601) (xy 148.286598 -36.34588) (xy 148.342332 -36.343843)
			(xy 148.397769 -36.349943) (xy 148.451726 -36.364049) (xy 148.503055 -36.385861) (xy 148.550661 -36.414915)
			(xy 148.593529 -36.45059) (xy 148.630746 -36.492127) (xy 148.661519 -36.53864) (xy 148.685191 -36.589137)
			(xy 148.701259 -36.642544) (xy 148.709379 -36.69772) (xy 148.709888 -36.725606) (xy 148.709379 -36.753492)
			(xy 148.701259 -36.808668) (xy 148.685191 -36.862075) (xy 148.661519 -36.912572) (xy 148.630746 -36.959085)
			(xy 148.593529 -37.000622) (xy 148.550661 -37.036297) (xy 148.503055 -37.065351) (xy 148.451726 -37.087163)
			(xy 148.397769 -37.101269) (xy 148.342332 -37.107369) (xy 148.286598 -37.105332) (xy 148.231755 -37.095202)
			(xy 148.178971 -37.077195) (xy 148.129371 -37.051694) (xy 148.084013 -37.019243) (xy 148.043864 -36.980534)
			(xy 148.009778 -36.936391) (xy 147.982482 -36.887756) (xy 147.962559 -36.835665) (xy 147.950433 -36.781228)
			(xy 147.946362 -36.725606) (xy 147.399718 -36.725606) (xy 147.377835 -36.738961) (xy 147.326506 -36.760773)
			(xy 147.272549 -36.774879) (xy 147.217112 -36.780979) (xy 147.161378 -36.778942) (xy 147.106535 -36.768812)
			(xy 147.053751 -36.750805) (xy 147.004151 -36.725304) (xy 146.958793 -36.692853) (xy 146.918644 -36.654144)
			(xy 146.884558 -36.610001) (xy 146.857262 -36.561366) (xy 146.837339 -36.509275) (xy 146.825213 -36.454838)
			(xy 146.821142 -36.399216) (xy 142.143967 -36.399216) (xy 142.122758 -36.431273) (xy 142.085541 -36.47281)
			(xy 142.042673 -36.508485) (xy 141.995067 -36.537539) (xy 141.943738 -36.559351) (xy 141.889781 -36.573457)
			(xy 141.834344 -36.579557) (xy 141.77861 -36.57752) (xy 141.723767 -36.56739) (xy 141.670983 -36.549383)
			(xy 141.621383 -36.523882) (xy 141.576025 -36.491431) (xy 141.535876 -36.452722) (xy 141.50179 -36.408579)
			(xy 141.474494 -36.359944) (xy 141.454571 -36.307853) (xy 141.442445 -36.253416) (xy 141.438374 -36.197794)
			(xy 140.239288 -36.197794) (xy 140.284736 -36.223689) (xy 140.328594 -36.257991) (xy 140.367 -36.298304)
			(xy 140.39914 -36.34377) (xy 140.42433 -36.393425) (xy 140.442036 -36.446213) (xy 140.451882 -36.501015)
			(xy 140.453659 -36.556665) (xy 140.447329 -36.611983) (xy 140.433026 -36.665794) (xy 140.411054 -36.716954)
			(xy 140.38188 -36.764378) (xy 140.346124 -36.807058) (xy 140.304543 -36.844088) (xy 140.258023 -36.874682)
			(xy 140.20755 -36.89819) (xy 140.154196 -36.914112) (xy 140.099095 -36.922111) (xy 140.043416 -36.922017)
			(xy 139.988342 -36.913832) (xy 139.935043 -36.897729) (xy 139.884649 -36.874051) (xy 139.838233 -36.843299)
			(xy 139.796778 -36.806129) (xy 139.761166 -36.763328) (xy 139.746228 -36.73983) (xy 139.733763 -36.720386)
			(xy 139.702925 -36.686007) (xy 139.666384 -36.657765) (xy 139.625342 -36.636588) (xy 139.58115 -36.623174)
			(xy 139.535262 -36.617963) (xy 139.489187 -36.621128) (xy 139.444442 -36.632564) (xy 139.402499 -36.651895)
			(xy 139.364739 -36.678485) (xy 139.34821 -36.694618) (xy 139.328388 -36.714171) (xy 139.284029 -36.747822)
			(xy 139.235251 -36.774668) (xy 139.183088 -36.79414) (xy 139.12865 -36.805825) (xy 139.073091 -36.809473)
			(xy 139.017592 -36.805008) (xy 138.963331 -36.792525) (xy 138.91146 -36.772288) (xy 138.863082 -36.744727)
			(xy 138.819223 -36.710427) (xy 138.780814 -36.670118) (xy 138.748671 -36.624654) (xy 138.723478 -36.575002)
			(xy 138.705768 -36.522215) (xy 138.695918 -36.467415) (xy 138.694136 -36.411765) (xy 137.43178 -36.411765)
			(xy 137.43178 -36.924488) (xy 142.893286 -36.924488) (xy 142.897357 -36.868866) (xy 142.909483 -36.814429)
			(xy 142.929406 -36.762338) (xy 142.956702 -36.713703) (xy 142.990788 -36.66956) (xy 143.030937 -36.630851)
			(xy 143.076295 -36.5984) (xy 143.125895 -36.572899) (xy 143.178679 -36.554892) (xy 143.233522 -36.544762)
			(xy 143.289256 -36.542725) (xy 143.344693 -36.548825) (xy 143.39865 -36.562931) (xy 143.449979 -36.584743)
			(xy 143.497585 -36.613797) (xy 143.540453 -36.649472) (xy 143.57767 -36.691009) (xy 143.608443 -36.737522)
			(xy 143.632115 -36.788019) (xy 143.648183 -36.841426) (xy 143.656303 -36.896602) (xy 143.656812 -36.924488)
			(xy 143.656303 -36.952374) (xy 143.648183 -37.00755) (xy 143.632115 -37.060957) (xy 143.608443 -37.111454)
			(xy 143.57767 -37.157967) (xy 143.540453 -37.199504) (xy 143.497585 -37.235179) (xy 143.449979 -37.264233)
			(xy 143.39865 -37.286045) (xy 143.344693 -37.300151) (xy 143.289256 -37.306251) (xy 143.233522 -37.304214)
			(xy 143.178679 -37.294084) (xy 143.125895 -37.276077) (xy 143.076295 -37.250576) (xy 143.030937 -37.218125)
			(xy 142.990788 -37.179416) (xy 142.956702 -37.135273) (xy 142.929406 -37.086638) (xy 142.909483 -37.034547)
			(xy 142.897357 -36.98011) (xy 142.893286 -36.924488) (xy 137.43178 -36.924488) (xy 137.43178 -38.527228)
			(xy 139.457682 -38.527228) (xy 139.461753 -38.471606) (xy 139.473879 -38.417169) (xy 139.493802 -38.365078)
			(xy 139.521098 -38.316443) (xy 139.555184 -38.2723) (xy 139.595333 -38.233591) (xy 139.640691 -38.20114)
			(xy 139.690291 -38.175639) (xy 139.743075 -38.157632) (xy 139.797918 -38.147502) (xy 139.853652 -38.145465)
			(xy 139.909089 -38.151565) (xy 139.927538 -38.156388) (xy 142.678402 -38.156388) (xy 142.682473 -38.100766)
			(xy 142.694599 -38.046329) (xy 142.714522 -37.994238) (xy 142.741818 -37.945603) (xy 142.775904 -37.90146)
			(xy 142.816053 -37.862751) (xy 142.861411 -37.8303) (xy 142.911011 -37.804799) (xy 142.963795 -37.786792)
			(xy 143.018638 -37.776662) (xy 143.074372 -37.774625) (xy 143.129809 -37.780725) (xy 143.183766 -37.794831)
			(xy 143.235095 -37.816643) (xy 143.239082 -37.819076) (xy 146.983702 -37.819076) (xy 146.987773 -37.763454)
			(xy 146.999899 -37.709017) (xy 147.019822 -37.656926) (xy 147.047118 -37.608291) (xy 147.081204 -37.564148)
			(xy 147.121353 -37.525439) (xy 147.166711 -37.492988) (xy 147.216311 -37.467487) (xy 147.269095 -37.44948)
			(xy 147.323938 -37.43935) (xy 147.379672 -37.437313) (xy 147.435109 -37.443413) (xy 147.489066 -37.457519)
			(xy 147.540395 -37.479331) (xy 147.588001 -37.508385) (xy 147.630869 -37.54406) (xy 147.668086 -37.585597)
			(xy 147.698859 -37.63211) (xy 147.722531 -37.682607) (xy 147.738599 -37.736014) (xy 147.746719 -37.79119)
			(xy 147.747228 -37.819076) (xy 147.746719 -37.846962) (xy 147.738599 -37.902138) (xy 147.722531 -37.955545)
			(xy 147.698859 -38.006042) (xy 147.668086 -38.052555) (xy 147.630869 -38.094092) (xy 147.588001 -38.129767)
			(xy 147.540395 -38.158821) (xy 147.489066 -38.180633) (xy 147.435109 -38.194739) (xy 147.379672 -38.200839)
			(xy 147.323938 -38.198802) (xy 147.269095 -38.188672) (xy 147.216311 -38.170665) (xy 147.166711 -38.145164)
			(xy 147.121353 -38.112713) (xy 147.081204 -38.074004) (xy 147.047118 -38.029861) (xy 147.019822 -37.981226)
			(xy 146.999899 -37.929135) (xy 146.987773 -37.874698) (xy 146.983702 -37.819076) (xy 143.239082 -37.819076)
			(xy 143.282701 -37.845697) (xy 143.325569 -37.881372) (xy 143.362786 -37.922909) (xy 143.393559 -37.969422)
			(xy 143.417231 -38.019919) (xy 143.433299 -38.073326) (xy 143.441419 -38.128502) (xy 143.441928 -38.156388)
			(xy 143.441419 -38.184274) (xy 143.433299 -38.23945) (xy 143.417231 -38.292857) (xy 143.393559 -38.343354)
			(xy 143.362786 -38.389867) (xy 143.325569 -38.431404) (xy 143.282701 -38.467079) (xy 143.235095 -38.496133)
			(xy 143.183766 -38.517945) (xy 143.129809 -38.532051) (xy 143.074372 -38.538151) (xy 143.018638 -38.536114)
			(xy 142.963795 -38.525984) (xy 142.911011 -38.507977) (xy 142.861411 -38.482476) (xy 142.816053 -38.450025)
			(xy 142.775904 -38.411316) (xy 142.741818 -38.367173) (xy 142.714522 -38.318538) (xy 142.694599 -38.266447)
			(xy 142.682473 -38.21201) (xy 142.678402 -38.156388) (xy 139.927538 -38.156388) (xy 139.963046 -38.165671)
			(xy 140.014375 -38.187483) (xy 140.061981 -38.216537) (xy 140.104849 -38.252212) (xy 140.142066 -38.293749)
			(xy 140.172839 -38.340262) (xy 140.196511 -38.390759) (xy 140.212579 -38.444166) (xy 140.220699 -38.499342)
			(xy 140.221208 -38.527228) (xy 140.220699 -38.555114) (xy 140.212579 -38.61029) (xy 140.196511 -38.663697)
			(xy 140.172839 -38.714194) (xy 140.142066 -38.760707) (xy 140.104849 -38.802244) (xy 140.061981 -38.837919)
			(xy 140.014375 -38.866973) (xy 139.963046 -38.888785) (xy 139.909089 -38.902891) (xy 139.853652 -38.908991)
			(xy 139.797918 -38.906954) (xy 139.743075 -38.896824) (xy 139.690291 -38.878817) (xy 139.640691 -38.853316)
			(xy 139.595333 -38.820865) (xy 139.555184 -38.782156) (xy 139.521098 -38.738013) (xy 139.493802 -38.689378)
			(xy 139.473879 -38.637287) (xy 139.461753 -38.58285) (xy 139.457682 -38.527228) (xy 137.43178 -38.527228)
			(xy 137.43178 -39.180516) (xy 141.364968 -39.180516) (xy 141.369039 -39.124894) (xy 141.381165 -39.070457)
			(xy 141.401088 -39.018366) (xy 141.428384 -38.969731) (xy 141.46247 -38.925588) (xy 141.502619 -38.886879)
			(xy 141.547977 -38.854428) (xy 141.597577 -38.828927) (xy 141.650361 -38.81092) (xy 141.705204 -38.80079)
			(xy 141.760938 -38.798753) (xy 141.816375 -38.804853) (xy 141.870332 -38.818959) (xy 141.921661 -38.840771)
			(xy 141.969267 -38.869825) (xy 142.012135 -38.9055) (xy 142.049352 -38.947037) (xy 142.080125 -38.99355)
			(xy 142.103797 -39.044047) (xy 142.119865 -39.097454) (xy 142.127985 -39.15263) (xy 142.128494 -39.180516)
			(xy 142.127985 -39.208402) (xy 142.119865 -39.263578) (xy 142.103797 -39.316985) (xy 142.082636 -39.362126)
			(xy 147.335492 -39.362126) (xy 147.339563 -39.306504) (xy 147.351689 -39.252067) (xy 147.371612 -39.199976)
			(xy 147.398908 -39.151341) (xy 147.432994 -39.107198) (xy 147.473143 -39.068489) (xy 147.518501 -39.036038)
			(xy 147.568101 -39.010537) (xy 147.620885 -38.99253) (xy 147.675728 -38.9824) (xy 147.731462 -38.980363)
			(xy 147.786899 -38.986463) (xy 147.840856 -39.000569) (xy 147.892185 -39.022381) (xy 147.939791 -39.051435)
			(xy 147.982659 -39.08711) (xy 148.019876 -39.128647) (xy 148.050649 -39.17516) (xy 148.074321 -39.225657)
			(xy 148.090389 -39.279064) (xy 148.098509 -39.33424) (xy 148.099018 -39.362126) (xy 148.098509 -39.390012)
			(xy 148.090389 -39.445188) (xy 148.074321 -39.498595) (xy 148.050649 -39.549092) (xy 148.019876 -39.595605)
			(xy 147.982659 -39.637142) (xy 147.939791 -39.672817) (xy 147.892185 -39.701871) (xy 147.840856 -39.723683)
			(xy 147.786899 -39.737789) (xy 147.731462 -39.743889) (xy 147.675728 -39.741852) (xy 147.620885 -39.731722)
			(xy 147.568101 -39.713715) (xy 147.518501 -39.688214) (xy 147.473143 -39.655763) (xy 147.432994 -39.617054)
			(xy 147.398908 -39.572911) (xy 147.371612 -39.524276) (xy 147.351689 -39.472185) (xy 147.339563 -39.417748)
			(xy 147.335492 -39.362126) (xy 142.082636 -39.362126) (xy 142.080125 -39.367482) (xy 142.049352 -39.413995)
			(xy 142.012135 -39.455532) (xy 141.969267 -39.491207) (xy 141.921661 -39.520261) (xy 141.870332 -39.542073)
			(xy 141.816375 -39.556179) (xy 141.760938 -39.562279) (xy 141.705204 -39.560242) (xy 141.650361 -39.550112)
			(xy 141.597577 -39.532105) (xy 141.547977 -39.506604) (xy 141.502619 -39.474153) (xy 141.46247 -39.435444)
			(xy 141.428384 -39.391301) (xy 141.401088 -39.342666) (xy 141.381165 -39.290575) (xy 141.369039 -39.236138)
			(xy 141.364968 -39.180516) (xy 137.43178 -39.180516) (xy 137.43178 -39.995094) (xy 139.411962 -39.995094)
			(xy 139.416033 -39.939472) (xy 139.428159 -39.885035) (xy 139.448082 -39.832944) (xy 139.475378 -39.784309)
			(xy 139.509464 -39.740166) (xy 139.549613 -39.701457) (xy 139.594971 -39.669006) (xy 139.644571 -39.643505)
			(xy 139.697355 -39.625498) (xy 139.752198 -39.615368) (xy 139.807932 -39.613331) (xy 139.863369 -39.619431)
			(xy 139.917326 -39.633537) (xy 139.968655 -39.655349) (xy 140.016261 -39.684403) (xy 140.059129 -39.720078)
			(xy 140.096346 -39.761615) (xy 140.127119 -39.808128) (xy 140.150791 -39.858625) (xy 140.166859 -39.912032)
			(xy 140.174979 -39.967208) (xy 140.175488 -39.995094) (xy 140.174979 -40.02298) (xy 140.166859 -40.078156)
			(xy 140.150791 -40.131563) (xy 140.127119 -40.18206) (xy 140.096346 -40.228573) (xy 140.059129 -40.27011)
			(xy 140.023069 -40.300119) (xy 141.564717 -40.300119) (xy 141.569947 -40.245303) (xy 141.583005 -40.191809)
			(xy 141.603618 -40.140748) (xy 141.631358 -40.093181) (xy 141.66565 -40.050097) (xy 141.70578 -40.012391)
			(xy 141.750914 -39.980847) (xy 141.800114 -39.95612) (xy 141.852359 -39.938723) (xy 141.906562 -39.92902)
			(xy 141.961597 -39.92721) (xy 142.01632 -39.933332) (xy 142.069595 -39.947259) (xy 142.120314 -39.968701)
			(xy 142.167422 -39.997212) (xy 142.209942 -40.0322) (xy 142.228824 -40.052244) (xy 142.244991 -40.069225)
			(xy 142.282359 -40.097532) (xy 142.324288 -40.1185) (xy 142.369352 -40.131416) (xy 142.416022 -40.135842)
			(xy 142.462712 -40.131628) (xy 142.507835 -40.118917) (xy 142.549858 -40.098139) (xy 142.56893 -40.084502)
			(xy 142.59137 -40.068251) (xy 142.640055 -40.0418) (xy 142.692054 -40.02267) (xy 142.746273 -40.011264)
			(xy 142.801572 -40.00782) (xy 142.856788 -40.012413) (xy 142.910758 -40.024945) (xy 142.962348 -40.045152)
			(xy 143.010472 -40.07261) (xy 143.054118 -40.10674) (xy 143.092367 -40.146825) (xy 143.124415 -40.192022)
			(xy 143.149588 -40.24138) (xy 143.167356 -40.29386) (xy 143.177346 -40.348358) (xy 143.179346 -40.403728)
			(xy 143.173316 -40.458805) (xy 143.159382 -40.51243) (xy 143.149066 -40.538146) (xy 143.140489 -40.559682)
			(xy 143.130464 -40.604935) (xy 143.128816 -40.651257) (xy 143.135601 -40.697109) (xy 143.150594 -40.740968)
			(xy 143.173296 -40.781378) (xy 143.202954 -40.816999) (xy 143.238583 -40.846646) (xy 143.25854 -40.85844)
			(xy 143.281727 -40.871989) (xy 143.324377 -40.904625) (xy 143.362027 -40.94292) (xy 143.392496 -40.98417)
			(xy 146.91182 -40.98417) (xy 146.915891 -40.928548) (xy 146.928017 -40.874111) (xy 146.94794 -40.82202)
			(xy 146.975236 -40.773385) (xy 147.009322 -40.729242) (xy 147.049471 -40.690533) (xy 147.094829 -40.658082)
			(xy 147.144429 -40.632581) (xy 147.197213 -40.614574) (xy 147.252056 -40.604444) (xy 147.30779 -40.602407)
			(xy 147.363227 -40.608507) (xy 147.417184 -40.622613) (xy 147.468513 -40.644425) (xy 147.516119 -40.673479)
			(xy 147.558987 -40.709154) (xy 147.596204 -40.750691) (xy 147.626977 -40.797204) (xy 147.650649 -40.847701)
			(xy 147.659458 -40.876982) (xy 148.065234 -40.876982) (xy 148.069305 -40.82136) (xy 148.081431 -40.766923)
			(xy 148.101354 -40.714832) (xy 148.12865 -40.666197) (xy 148.162736 -40.622054) (xy 148.202885 -40.583345)
			(xy 148.248243 -40.550894) (xy 148.297843 -40.525393) (xy 148.350627 -40.507386) (xy 148.40547 -40.497256)
			(xy 148.461204 -40.495219) (xy 148.516641 -40.501319) (xy 148.570598 -40.515425) (xy 148.621927 -40.537237)
			(xy 148.669533 -40.566291) (xy 148.712401 -40.601966) (xy 148.749618 -40.643503) (xy 148.780391 -40.690016)
			(xy 148.804063 -40.740513) (xy 148.820131 -40.79392) (xy 148.828251 -40.849096) (xy 148.82876 -40.876982)
			(xy 148.828251 -40.904868) (xy 148.820131 -40.960044) (xy 148.804063 -41.013451) (xy 148.780391 -41.063948)
			(xy 148.749618 -41.110461) (xy 148.712401 -41.151998) (xy 148.669533 -41.187673) (xy 148.621927 -41.216727)
			(xy 148.570598 -41.238539) (xy 148.516641 -41.252645) (xy 148.461204 -41.258745) (xy 148.40547 -41.256708)
			(xy 148.350627 -41.246578) (xy 148.297843 -41.228571) (xy 148.248243 -41.20307) (xy 148.202885 -41.170619)
			(xy 148.162736 -41.13191) (xy 148.12865 -41.087767) (xy 148.101354 -41.039132) (xy 148.081431 -40.987041)
			(xy 148.069305 -40.932604) (xy 148.065234 -40.876982) (xy 147.659458 -40.876982) (xy 147.666717 -40.901108)
			(xy 147.674837 -40.956284) (xy 147.675346 -40.98417) (xy 147.674837 -41.012056) (xy 147.666717 -41.067232)
			(xy 147.650649 -41.120639) (xy 147.626977 -41.171136) (xy 147.596204 -41.217649) (xy 147.558987 -41.259186)
			(xy 147.516119 -41.294861) (xy 147.468513 -41.323915) (xy 147.417184 -41.345727) (xy 147.363227 -41.359833)
			(xy 147.30779 -41.365933) (xy 147.252056 -41.363896) (xy 147.197213 -41.353766) (xy 147.144429 -41.335759)
			(xy 147.094829 -41.310258) (xy 147.049471 -41.277807) (xy 147.009322 -41.239098) (xy 146.975236 -41.194955)
			(xy 146.94794 -41.14632) (xy 146.928017 -41.094229) (xy 146.915891 -41.039792) (xy 146.91182 -40.98417)
			(xy 143.392496 -40.98417) (xy 143.393934 -40.986117) (xy 143.419468 -41.033362) (xy 143.438124 -41.083722)
			(xy 143.449532 -41.1362) (xy 143.453467 -41.189759) (xy 143.449852 -41.243341) (xy 143.438757 -41.295886)
			(xy 143.420403 -41.346356) (xy 143.395152 -41.393753) (xy 143.379698 -41.415716) (xy 143.367399 -41.433252)
			(xy 143.348332 -41.471604) (xy 143.335968 -41.512611) (xy 143.330657 -41.555111) (xy 143.332549 -41.597899)
			(xy 143.341592 -41.639764) (xy 143.357529 -41.679519) (xy 143.379908 -41.716038) (xy 143.393668 -41.732454)
			(xy 143.41148 -41.753602) (xy 143.441466 -41.800056) (xy 143.464433 -41.850351) (xy 143.479901 -41.903434)
			(xy 143.487545 -41.958194) (xy 143.487206 -42.013484) (xy 143.47889 -42.068146) (xy 143.462772 -42.121035)
			(xy 143.439189 -42.171045) (xy 143.408635 -42.217127) (xy 143.37175 -42.258317) (xy 143.329307 -42.293752)
			(xy 143.282193 -42.32269) (xy 143.231397 -42.344525) (xy 143.17798 -42.3588) (xy 143.123063 -42.365216)
			(xy 143.067795 -42.363639) (xy 143.013332 -42.354101) (xy 142.960817 -42.336803) (xy 142.911348 -42.312106)
			(xy 142.865962 -42.280528) (xy 142.825608 -42.24273) (xy 142.791133 -42.199504) (xy 142.763257 -42.151754)
			(xy 142.742565 -42.100482) (xy 142.729489 -42.046759) (xy 142.724304 -41.991712) (xy 142.727119 -41.936492)
			(xy 142.737874 -41.882257) (xy 142.756343 -41.830143) (xy 142.782142 -41.781239) (xy 142.798038 -41.758616)
			(xy 142.810312 -41.741063) (xy 142.829386 -41.702716) (xy 142.841757 -41.661712) (xy 142.847073 -41.619214)
			(xy 142.845184 -41.576427) (xy 142.836144 -41.534563) (xy 142.820208 -41.494809) (xy 142.797828 -41.458293)
			(xy 142.784068 -41.441878) (xy 142.766879 -41.421511) (xy 142.737788 -41.376856) (xy 142.71519 -41.32859)
			(xy 142.699523 -41.27765) (xy 142.691091 -41.225026) (xy 142.69006 -41.171742) (xy 142.696447 -41.118831)
			(xy 142.710131 -41.067323) (xy 142.72006 -41.04259) (xy 142.728586 -41.021036) (xy 142.738614 -40.975788)
			(xy 142.740267 -40.929472) (xy 142.733488 -40.883626) (xy 142.718502 -40.83977) (xy 142.695808 -40.799361)
			(xy 142.666159 -40.763741) (xy 142.630539 -40.734091) (xy 142.610586 -40.722296) (xy 142.584222 -40.706823)
			(xy 142.536371 -40.668786) (xy 142.515336 -40.646604) (xy 142.499203 -40.629589) (xy 142.46183 -40.601278)
			(xy 142.419895 -40.580309) (xy 142.374824 -40.567394) (xy 142.328147 -40.562972) (xy 142.281452 -40.567193)
			(xy 142.236326 -40.579914) (xy 142.194301 -40.600702) (xy 142.17523 -40.614346) (xy 142.152862 -40.630409)
			(xy 142.104493 -40.656725) (xy 142.052842 -40.675812) (xy 141.998984 -40.687275) (xy 141.944037 -40.690876)
			(xy 141.889143 -40.686538) (xy 141.835443 -40.674353) (xy 141.784053 -40.654574) (xy 141.736041 -40.627612)
			(xy 141.692405 -40.594026) (xy 141.654051 -40.554516) (xy 141.621776 -40.509901) (xy 141.596251 -40.461109)
			(xy 141.578007 -40.409155) (xy 141.567422 -40.355117) (xy 141.564717 -40.300119) (xy 140.023069 -40.300119)
			(xy 140.016261 -40.305785) (xy 139.968655 -40.334839) (xy 139.917326 -40.356651) (xy 139.863369 -40.370757)
			(xy 139.807932 -40.376857) (xy 139.752198 -40.37482) (xy 139.697355 -40.36469) (xy 139.644571 -40.346683)
			(xy 139.594971 -40.321182) (xy 139.549613 -40.288731) (xy 139.509464 -40.250022) (xy 139.475378 -40.205879)
			(xy 139.448082 -40.157244) (xy 139.428159 -40.105153) (xy 139.416033 -40.050716) (xy 139.411962 -39.995094)
			(xy 137.43178 -39.995094) (xy 137.43178 -42.690288) (xy 139.471398 -42.690288) (xy 139.475469 -42.634666)
			(xy 139.487595 -42.580229) (xy 139.507518 -42.528138) (xy 139.534814 -42.479503) (xy 139.5689 -42.43536)
			(xy 139.609049 -42.396651) (xy 139.654407 -42.3642) (xy 139.704007 -42.338699) (xy 139.756791 -42.320692)
			(xy 139.811634 -42.310562) (xy 139.867368 -42.308525) (xy 139.922805 -42.314625) (xy 139.976762 -42.328731)
			(xy 140.028091 -42.350543) (xy 140.075697 -42.379597) (xy 140.118565 -42.415272) (xy 140.155782 -42.456809)
			(xy 140.186555 -42.503322) (xy 140.210227 -42.553819) (xy 140.217661 -42.578528) (xy 147.64715 -42.578528)
			(xy 147.651221 -42.522906) (xy 147.663347 -42.468469) (xy 147.68327 -42.416378) (xy 147.710566 -42.367743)
			(xy 147.744652 -42.3236) (xy 147.784801 -42.284891) (xy 147.830159 -42.25244) (xy 147.879759 -42.226939)
			(xy 147.932543 -42.208932) (xy 147.987386 -42.198802) (xy 148.04312 -42.196765) (xy 148.098557 -42.202865)
			(xy 148.152514 -42.216971) (xy 148.203843 -42.238783) (xy 148.251449 -42.267837) (xy 148.294317 -42.303512)
			(xy 148.331534 -42.345049) (xy 148.362307 -42.391562) (xy 148.385979 -42.442059) (xy 148.402047 -42.495466)
			(xy 148.410167 -42.550642) (xy 148.410676 -42.578528) (xy 148.410167 -42.606414) (xy 148.402047 -42.66159)
			(xy 148.385979 -42.714997) (xy 148.362307 -42.765494) (xy 148.331534 -42.812007) (xy 148.294317 -42.853544)
			(xy 148.251449 -42.889219) (xy 148.203843 -42.918273) (xy 148.152514 -42.940085) (xy 148.098557 -42.954191)
			(xy 148.04312 -42.960291) (xy 147.987386 -42.958254) (xy 147.932543 -42.948124) (xy 147.879759 -42.930117)
			(xy 147.830159 -42.904616) (xy 147.784801 -42.872165) (xy 147.744652 -42.833456) (xy 147.710566 -42.789313)
			(xy 147.68327 -42.740678) (xy 147.663347 -42.688587) (xy 147.651221 -42.63415) (xy 147.64715 -42.578528)
			(xy 140.217661 -42.578528) (xy 140.226295 -42.607226) (xy 140.234415 -42.662402) (xy 140.234924 -42.690288)
			(xy 140.234415 -42.718174) (xy 140.226295 -42.77335) (xy 140.210227 -42.826757) (xy 140.186555 -42.877254)
			(xy 140.155782 -42.923767) (xy 140.118565 -42.965304) (xy 140.075697 -43.000979) (xy 140.028091 -43.030033)
			(xy 139.976762 -43.051845) (xy 139.922805 -43.065951) (xy 139.867368 -43.072051) (xy 139.811634 -43.070014)
			(xy 139.756791 -43.059884) (xy 139.704007 -43.041877) (xy 139.654407 -43.016376) (xy 139.609049 -42.983925)
			(xy 139.5689 -42.945216) (xy 139.534814 -42.901073) (xy 139.507518 -42.852438) (xy 139.487595 -42.800347)
			(xy 139.475469 -42.74591) (xy 139.471398 -42.690288) (xy 137.43178 -42.690288) (xy 137.43178 -44.239688)
			(xy 139.672312 -44.239688) (xy 139.676383 -44.184066) (xy 139.688509 -44.129629) (xy 139.708432 -44.077538)
			(xy 139.735728 -44.028903) (xy 139.769814 -43.98476) (xy 139.809963 -43.946051) (xy 139.855321 -43.9136)
			(xy 139.904921 -43.888099) (xy 139.957705 -43.870092) (xy 140.012548 -43.859962) (xy 140.068282 -43.857925)
			(xy 140.123719 -43.864025) (xy 140.177676 -43.878131) (xy 140.229005 -43.899943) (xy 140.276611 -43.928997)
			(xy 140.319479 -43.964672) (xy 140.356696 -44.006209) (xy 140.387469 -44.052722) (xy 140.411141 -44.103219)
			(xy 140.427209 -44.156626) (xy 140.431582 -44.186341) (xy 140.718328 -44.186341) (xy 140.719008 -44.131084)
			(xy 140.727654 -44.076503) (xy 140.744086 -44.023741) (xy 140.76796 -43.973902) (xy 140.798775 -43.92803)
			(xy 140.835887 -43.887085) (xy 140.878519 -43.851923) (xy 140.925779 -43.823281) (xy 140.976677 -43.801759)
			(xy 141.030148 -43.787806) (xy 141.085073 -43.781715) (xy 141.140302 -43.783613) (xy 141.194679 -43.793461)
			(xy 141.247066 -43.811053) (xy 141.296366 -43.83602) (xy 141.341547 -43.867839) (xy 141.381664 -43.905845)
			(xy 141.415877 -43.949243) (xy 141.44347 -43.997122) (xy 141.463864 -44.048483) (xy 141.476635 -44.102249)
			(xy 141.481513 -44.157294) (xy 141.478397 -44.212468) (xy 141.467352 -44.266615) (xy 141.458442 -44.292774)
			(xy 141.453391 -44.308323) (xy 141.450442 -44.34087) (xy 141.455868 -44.373097) (xy 141.46931 -44.402885)
			(xy 141.489885 -44.428275) (xy 141.516241 -44.447598) (xy 141.546644 -44.459584) (xy 141.579095 -44.463444)
			(xy 141.595348 -44.461684) (xy 141.607291 -44.460126) (xy 141.631312 -44.458349) (xy 141.643354 -44.458128)
			(xy 141.66018 -44.457462) (xy 141.692571 -44.448285) (xy 141.721433 -44.430954) (xy 141.744757 -44.406677)
			(xy 141.760919 -44.377145) (xy 141.768793 -44.344413) (xy 141.76883 -44.327572) (xy 141.768519 -44.300217)
			(xy 141.774814 -44.245875) (xy 141.788807 -44.192989) (xy 141.810209 -44.142644) (xy 141.838582 -44.095872)
			(xy 141.873345 -44.053632) (xy 141.913784 -44.016789) (xy 141.959071 -43.9861) (xy 142.008276 -43.962194)
			(xy 142.060392 -43.94556) (xy 142.114349 -43.93654) (xy 142.169041 -43.935319) (xy 142.223346 -43.941922)
			(xy 142.276152 -43.956213) (xy 142.326375 -43.9779) (xy 142.372986 -44.006537) (xy 142.41503 -44.041538)
			(xy 142.451643 -44.082185) (xy 142.482075 -44.127644) (xy 142.505703 -44.176984) (xy 142.522042 -44.229193)
			(xy 142.530756 -44.2832) (xy 142.531668 -44.337898) (xy 142.524758 -44.392165) (xy 142.510169 -44.444889)
			(xy 142.488199 -44.494989) (xy 142.459298 -44.541438) (xy 142.42406 -44.583282) (xy 142.383207 -44.619665)
			(xy 142.337576 -44.64984) (xy 142.288103 -44.673189) (xy 142.265495 -44.680124) (xy 150.110696 -44.680124)
			(xy 150.114767 -44.624502) (xy 150.126893 -44.570065) (xy 150.146816 -44.517974) (xy 150.174112 -44.469339)
			(xy 150.208198 -44.425196) (xy 150.248347 -44.386487) (xy 150.293705 -44.354036) (xy 150.343305 -44.328535)
			(xy 150.396089 -44.310528) (xy 150.450932 -44.300398) (xy 150.506666 -44.298361) (xy 150.562103 -44.304461)
			(xy 150.61606 -44.318567) (xy 150.667389 -44.340379) (xy 150.714995 -44.369433) (xy 150.757863 -44.405108)
			(xy 150.79508 -44.446645) (xy 150.825853 -44.493158) (xy 150.849525 -44.543655) (xy 150.865593 -44.597062)
			(xy 150.873713 -44.652238) (xy 150.874222 -44.680124) (xy 150.873713 -44.70801) (xy 150.865593 -44.763186)
			(xy 150.849525 -44.816593) (xy 150.825853 -44.86709) (xy 150.79508 -44.913603) (xy 150.757863 -44.95514)
			(xy 150.714995 -44.990815) (xy 150.667389 -45.019869) (xy 150.61606 -45.041681) (xy 150.562103 -45.055787)
			(xy 150.506666 -45.061887) (xy 150.450932 -45.05985) (xy 150.396089 -45.04972) (xy 150.343305 -45.031713)
			(xy 150.293705 -45.006212) (xy 150.248347 -44.973761) (xy 150.208198 -44.935052) (xy 150.174112 -44.890909)
			(xy 150.146816 -44.842274) (xy 150.126893 -44.790183) (xy 150.114767 -44.735746) (xy 150.110696 -44.680124)
			(xy 142.265495 -44.680124) (xy 142.235803 -44.689232) (xy 142.181748 -44.697641) (xy 142.154402 -44.698412)
			(xy 142.137579 -44.699101) (xy 142.105197 -44.708283) (xy 142.076341 -44.725613) (xy 142.053019 -44.749883)
			(xy 142.036855 -44.779407) (xy 142.028971 -44.81213) (xy 142.028926 -44.828968) (xy 142.029211 -44.857112)
			(xy 142.02254 -44.912996) (xy 142.007731 -44.967294) (xy 141.985104 -45.018826) (xy 141.955151 -45.066474)
			(xy 141.918522 -45.109204) (xy 141.876012 -45.146088) (xy 141.828544 -45.176326) (xy 141.777148 -45.199261)
			(xy 141.72294 -45.214396) (xy 141.667097 -45.221401) (xy 141.610831 -45.220125) (xy 141.555362 -45.210596)
			(xy 141.501896 -45.19302) (xy 141.451593 -45.167779) (xy 141.405544 -45.13542) (xy 141.36475 -45.096647)
			(xy 141.330095 -45.052301) (xy 141.302333 -45.003344) (xy 141.282065 -44.950839) (xy 141.269732 -44.895926)
			(xy 141.265601 -44.839797) (xy 141.26718 -44.811696) (xy 141.268312 -44.79042) (xy 141.264328 -44.748003)
			(xy 141.253317 -44.706846) (xy 141.235588 -44.668107) (xy 141.211638 -44.632872) (xy 141.18214 -44.602132)
			(xy 141.147924 -44.576749) (xy 141.109949 -44.557436) (xy 141.069282 -44.544737) (xy 141.048232 -44.54144)
			(xy 141.020927 -44.537172) (xy 140.967816 -44.521907) (xy 140.917463 -44.499139) (xy 140.870922 -44.469343)
			(xy 140.829168 -44.433143) (xy 140.793075 -44.391296) (xy 140.763397 -44.34468) (xy 140.740758 -44.294269)
			(xy 140.725629 -44.241119) (xy 140.718328 -44.186341) (xy 140.431582 -44.186341) (xy 140.435329 -44.211802)
			(xy 140.435838 -44.239688) (xy 140.435329 -44.267574) (xy 140.427209 -44.32275) (xy 140.411141 -44.376157)
			(xy 140.387469 -44.426654) (xy 140.356696 -44.473167) (xy 140.319479 -44.514704) (xy 140.276611 -44.550379)
			(xy 140.229005 -44.579433) (xy 140.177676 -44.601245) (xy 140.123719 -44.615351) (xy 140.068282 -44.621451)
			(xy 140.012548 -44.619414) (xy 139.957705 -44.609284) (xy 139.904921 -44.591277) (xy 139.855321 -44.565776)
			(xy 139.809963 -44.533325) (xy 139.769814 -44.494616) (xy 139.735728 -44.450473) (xy 139.708432 -44.401838)
			(xy 139.688509 -44.349747) (xy 139.676383 -44.29531) (xy 139.672312 -44.239688) (xy 137.43178 -44.239688)
			(xy 137.43178 -45.305726) (xy 142.652748 -45.305726) (xy 142.656819 -45.250104) (xy 142.668945 -45.195667)
			(xy 142.688868 -45.143576) (xy 142.716164 -45.094941) (xy 142.75025 -45.050798) (xy 142.790399 -45.012089)
			(xy 142.835757 -44.979638) (xy 142.885357 -44.954137) (xy 142.938141 -44.93613) (xy 142.992984 -44.926)
			(xy 143.048718 -44.923963) (xy 143.104155 -44.930063) (xy 143.158112 -44.944169) (xy 143.209441 -44.965981)
			(xy 143.257047 -44.995035) (xy 143.299915 -45.03071) (xy 143.337132 -45.072247) (xy 143.367905 -45.11876)
			(xy 143.391577 -45.169257) (xy 143.407645 -45.222664) (xy 143.415765 -45.27784) (xy 143.416274 -45.305726)
			(xy 143.415765 -45.333612) (xy 143.407645 -45.388788) (xy 143.391577 -45.442195) (xy 143.367905 -45.492692)
			(xy 143.337132 -45.539205) (xy 143.299915 -45.580742) (xy 143.257047 -45.616417) (xy 143.209441 -45.645471)
			(xy 143.158112 -45.667283) (xy 143.104155 -45.681389) (xy 143.048718 -45.687489) (xy 142.992984 -45.685452)
			(xy 142.938141 -45.675322) (xy 142.885357 -45.657315) (xy 142.835757 -45.631814) (xy 142.790399 -45.599363)
			(xy 142.75025 -45.560654) (xy 142.716164 -45.516511) (xy 142.688868 -45.467876) (xy 142.668945 -45.415785)
			(xy 142.656819 -45.361348) (xy 142.652748 -45.305726) (xy 137.43178 -45.305726) (xy 137.43178 -45.70857)
			(xy 147.424392 -45.70857) (xy 147.428463 -45.652948) (xy 147.440589 -45.598511) (xy 147.460512 -45.54642)
			(xy 147.487808 -45.497785) (xy 147.521894 -45.453642) (xy 147.562043 -45.414933) (xy 147.607401 -45.382482)
			(xy 147.657001 -45.356981) (xy 147.709785 -45.338974) (xy 147.764628 -45.328844) (xy 147.820362 -45.326807)
			(xy 147.875799 -45.332907) (xy 147.929756 -45.347013) (xy 147.981085 -45.368825) (xy 148.028691 -45.397879)
			(xy 148.071559 -45.433554) (xy 148.108776 -45.475091) (xy 148.139549 -45.521604) (xy 148.163221 -45.572101)
			(xy 148.179289 -45.625508) (xy 148.187409 -45.680684) (xy 148.187918 -45.70857) (xy 150.31034 -45.70857)
			(xy 150.314411 -45.652948) (xy 150.326537 -45.598511) (xy 150.34646 -45.54642) (xy 150.373756 -45.497785)
			(xy 150.407842 -45.453642) (xy 150.447991 -45.414933) (xy 150.493349 -45.382482) (xy 150.542949 -45.356981)
			(xy 150.595733 -45.338974) (xy 150.650576 -45.328844) (xy 150.70631 -45.326807) (xy 150.761747 -45.332907)
			(xy 150.815704 -45.347013) (xy 150.867033 -45.368825) (xy 150.914639 -45.397879) (xy 150.957507 -45.433554)
			(xy 150.994724 -45.475091) (xy 151.025497 -45.521604) (xy 151.049169 -45.572101) (xy 151.065237 -45.625508)
			(xy 151.073357 -45.680684) (xy 151.073866 -45.70857) (xy 151.073357 -45.736456) (xy 151.065237 -45.791632)
			(xy 151.049169 -45.845039) (xy 151.025497 -45.895536) (xy 150.994724 -45.942049) (xy 150.957507 -45.983586)
			(xy 150.914639 -46.019261) (xy 150.867033 -46.048315) (xy 150.815704 -46.070127) (xy 150.761747 -46.084233)
			(xy 150.70631 -46.090333) (xy 150.650576 -46.088296) (xy 150.595733 -46.078166) (xy 150.542949 -46.060159)
			(xy 150.493349 -46.034658) (xy 150.447991 -46.002207) (xy 150.407842 -45.963498) (xy 150.373756 -45.919355)
			(xy 150.34646 -45.87072) (xy 150.326537 -45.818629) (xy 150.314411 -45.764192) (xy 150.31034 -45.70857)
			(xy 148.187918 -45.70857) (xy 148.187409 -45.736456) (xy 148.179289 -45.791632) (xy 148.163221 -45.845039)
			(xy 148.139549 -45.895536) (xy 148.108776 -45.942049) (xy 148.071559 -45.983586) (xy 148.028691 -46.019261)
			(xy 147.981085 -46.048315) (xy 147.929756 -46.070127) (xy 147.875799 -46.084233) (xy 147.820362 -46.090333)
			(xy 147.764628 -46.088296) (xy 147.709785 -46.078166) (xy 147.657001 -46.060159) (xy 147.607401 -46.034658)
			(xy 147.562043 -46.002207) (xy 147.521894 -45.963498) (xy 147.487808 -45.919355) (xy 147.460512 -45.87072)
			(xy 147.440589 -45.818629) (xy 147.428463 -45.764192) (xy 147.424392 -45.70857) (xy 137.43178 -45.70857)
			(xy 137.43178 -48.754039) (xy 138.301983 -48.754039) (xy 138.308086 -48.698565) (xy 138.322202 -48.644572)
			(xy 138.344029 -48.593209) (xy 138.373102 -48.545571) (xy 138.408801 -48.502675) (xy 138.450365 -48.465433)
			(xy 138.496909 -48.434639) (xy 138.54744 -48.410951) (xy 138.600882 -48.394873) (xy 138.656096 -48.386747)
			(xy 138.684 -48.386238) (xy 138.711904 -48.386747) (xy 138.767118 -48.394873) (xy 138.82056 -48.410951)
			(xy 138.871091 -48.434639) (xy 138.917635 -48.465433) (xy 138.959199 -48.502675) (xy 138.994898 -48.545571)
			(xy 139.010199 -48.570642) (xy 141.545054 -48.570642) (xy 141.549125 -48.51502) (xy 141.561251 -48.460583)
			(xy 141.581174 -48.408492) (xy 141.60847 -48.359857) (xy 141.642556 -48.315714) (xy 141.682705 -48.277005)
			(xy 141.728063 -48.244554) (xy 141.777663 -48.219053) (xy 141.830447 -48.201046) (xy 141.88529 -48.190916)
			(xy 141.941024 -48.188879) (xy 141.996461 -48.194979) (xy 142.050418 -48.209085) (xy 142.101747 -48.230897)
			(xy 142.149353 -48.259951) (xy 142.192221 -48.295626) (xy 142.229438 -48.337163) (xy 142.260211 -48.383676)
			(xy 142.283883 -48.434173) (xy 142.299951 -48.48758) (xy 142.308071 -48.542756) (xy 142.30858 -48.570642)
			(xy 142.308071 -48.598528) (xy 142.299951 -48.653704) (xy 142.283883 -48.707111) (xy 142.260211 -48.757608)
			(xy 142.229438 -48.804121) (xy 142.192221 -48.845658) (xy 142.149353 -48.881333) (xy 142.101747 -48.910387)
			(xy 142.050418 -48.932199) (xy 141.996461 -48.946305) (xy 141.941024 -48.952405) (xy 141.88529 -48.950368)
			(xy 141.830447 -48.940238) (xy 141.777663 -48.922231) (xy 141.728063 -48.89673) (xy 141.682705 -48.864279)
			(xy 141.642556 -48.82557) (xy 141.60847 -48.781427) (xy 141.581174 -48.732792) (xy 141.561251 -48.680701)
			(xy 141.549125 -48.626264) (xy 141.545054 -48.570642) (xy 139.010199 -48.570642) (xy 139.023971 -48.593209)
			(xy 139.045798 -48.644572) (xy 139.059914 -48.698565) (xy 139.066017 -48.754039) (xy 139.063979 -48.80981)
			(xy 139.053842 -48.864689) (xy 139.035823 -48.917509) (xy 139.010305 -48.967141) (xy 138.977833 -49.012529)
			(xy 138.939098 -49.052706) (xy 138.894926 -49.086814) (xy 138.846258 -49.114128) (xy 138.794132 -49.134064)
			(xy 138.739659 -49.146199) (xy 138.684 -49.150273) (xy 138.628341 -49.146199) (xy 138.573868 -49.134064)
			(xy 138.521742 -49.114128) (xy 138.473074 -49.086814) (xy 138.428902 -49.052706) (xy 138.390167 -49.012529)
			(xy 138.357695 -48.967141) (xy 138.332177 -48.917509) (xy 138.314158 -48.864689) (xy 138.304021 -48.80981)
			(xy 138.301983 -48.754039) (xy 137.43178 -48.754039) (xy 137.43178 -49.33188) (xy 147.679662 -49.33188)
			(xy 147.683733 -49.276258) (xy 147.695859 -49.221821) (xy 147.715782 -49.16973) (xy 147.743078 -49.121095)
			(xy 147.777164 -49.076952) (xy 147.817313 -49.038243) (xy 147.862671 -49.005792) (xy 147.912271 -48.980291)
			(xy 147.965055 -48.962284) (xy 148.019898 -48.952154) (xy 148.075632 -48.950117) (xy 148.131069 -48.956217)
			(xy 148.185026 -48.970323) (xy 148.192469 -48.973486) (xy 149.14575 -48.973486) (xy 149.149821 -48.917864)
			(xy 149.161947 -48.863427) (xy 149.18187 -48.811336) (xy 149.209166 -48.762701) (xy 149.243252 -48.718558)
			(xy 149.283401 -48.679849) (xy 149.328759 -48.647398) (xy 149.378359 -48.621897) (xy 149.431143 -48.60389)
			(xy 149.485986 -48.59376) (xy 149.54172 -48.591723) (xy 149.597157 -48.597823) (xy 149.651114 -48.611929)
			(xy 149.702443 -48.633741) (xy 149.750049 -48.662795) (xy 149.792917 -48.69847) (xy 149.830134 -48.740007)
			(xy 149.860907 -48.78652) (xy 149.884579 -48.837017) (xy 149.900647 -48.890424) (xy 149.908767 -48.9456)
			(xy 149.909276 -48.973486) (xy 149.908767 -49.001372) (xy 149.900647 -49.056548) (xy 149.884579 -49.109955)
			(xy 149.860907 -49.160452) (xy 149.830134 -49.206965) (xy 149.792917 -49.248502) (xy 149.750049 -49.284177)
			(xy 149.702443 -49.313231) (xy 149.651114 -49.335043) (xy 149.597157 -49.349149) (xy 149.54172 -49.355249)
			(xy 149.485986 -49.353212) (xy 149.431143 -49.343082) (xy 149.378359 -49.325075) (xy 149.328759 -49.299574)
			(xy 149.283401 -49.267123) (xy 149.243252 -49.228414) (xy 149.209166 -49.184271) (xy 149.18187 -49.135636)
			(xy 149.161947 -49.083545) (xy 149.149821 -49.029108) (xy 149.14575 -48.973486) (xy 148.192469 -48.973486)
			(xy 148.236355 -48.992135) (xy 148.283961 -49.021189) (xy 148.326829 -49.056864) (xy 148.364046 -49.098401)
			(xy 148.394819 -49.144914) (xy 148.418491 -49.195411) (xy 148.434559 -49.248818) (xy 148.442679 -49.303994)
			(xy 148.443188 -49.33188) (xy 148.442679 -49.359766) (xy 148.434559 -49.414942) (xy 148.418491 -49.468349)
			(xy 148.394819 -49.518846) (xy 148.364046 -49.565359) (xy 148.326829 -49.606896) (xy 148.283961 -49.642571)
			(xy 148.236355 -49.671625) (xy 148.185026 -49.693437) (xy 148.131069 -49.707543) (xy 148.075632 -49.713643)
			(xy 148.019898 -49.711606) (xy 147.965055 -49.701476) (xy 147.912271 -49.683469) (xy 147.862671 -49.657968)
			(xy 147.817313 -49.625517) (xy 147.777164 -49.586808) (xy 147.743078 -49.542665) (xy 147.715782 -49.49403)
			(xy 147.695859 -49.441939) (xy 147.683733 -49.387502) (xy 147.679662 -49.33188) (xy 137.43178 -49.33188)
			(xy 137.43178 -50.165) (xy 137.920728 -50.165) (xy 137.924801 -50.109341) (xy 137.936936 -50.054868)
			(xy 137.956872 -50.002742) (xy 137.984186 -49.954074) (xy 138.018294 -49.909902) (xy 138.058471 -49.871167)
			(xy 138.103859 -49.838695) (xy 138.153491 -49.813177) (xy 138.206311 -49.795158) (xy 138.26119 -49.785021)
			(xy 138.316961 -49.782983) (xy 138.372435 -49.789086) (xy 138.426428 -49.803202) (xy 138.477791 -49.825029)
			(xy 138.525429 -49.854102) (xy 138.568325 -49.889801) (xy 138.605567 -49.931365) (xy 138.636361 -49.977909)
			(xy 138.660049 -50.02844) (xy 138.676127 -50.081882) (xy 138.684253 -50.137096) (xy 138.684762 -50.165)
			(xy 138.684253 -50.192904) (xy 138.676127 -50.248118) (xy 138.660049 -50.30156) (xy 138.636361 -50.352091)
			(xy 138.605567 -50.398635) (xy 138.568325 -50.440199) (xy 138.525429 -50.475898) (xy 138.477791 -50.504971)
			(xy 138.426428 -50.526798) (xy 138.372435 -50.540914) (xy 138.316961 -50.547017) (xy 138.26119 -50.544979)
			(xy 138.206311 -50.534842) (xy 138.153491 -50.516823) (xy 138.103859 -50.491305) (xy 138.058471 -50.458833)
			(xy 138.018294 -50.420098) (xy 137.984186 -50.375926) (xy 137.956872 -50.327258) (xy 137.936936 -50.275132)
			(xy 137.924801 -50.220659) (xy 137.920728 -50.165) (xy 137.43178 -50.165) (xy 137.43178 -51.151028)
			(xy 138.163046 -51.882294) (xy 138.163046 -52.679854) (xy 140.310868 -52.679854) (xy 140.314939 -52.624232)
			(xy 140.327065 -52.569795) (xy 140.346988 -52.517704) (xy 140.374284 -52.469069) (xy 140.40837 -52.424926)
			(xy 140.448519 -52.386217) (xy 140.493877 -52.353766) (xy 140.543477 -52.328265) (xy 140.596261 -52.310258)
			(xy 140.651104 -52.300128) (xy 140.706838 -52.298091) (xy 140.762275 -52.304191) (xy 140.816232 -52.318297)
			(xy 140.867561 -52.340109) (xy 140.915167 -52.369163) (xy 140.958035 -52.404838) (xy 140.995252 -52.446375)
			(xy 141.026025 -52.492888) (xy 141.049697 -52.543385) (xy 141.065765 -52.596792) (xy 141.073885 -52.651968)
			(xy 141.074357 -52.677822) (xy 142.342868 -52.677822) (xy 142.346939 -52.6222) (xy 142.359065 -52.567763)
			(xy 142.378988 -52.515672) (xy 142.406284 -52.467037) (xy 142.44037 -52.422894) (xy 142.480519 -52.384185)
			(xy 142.525877 -52.351734) (xy 142.575477 -52.326233) (xy 142.628261 -52.308226) (xy 142.683104 -52.298096)
			(xy 142.738838 -52.296059) (xy 142.794275 -52.302159) (xy 142.848232 -52.316265) (xy 142.899561 -52.338077)
			(xy 142.947167 -52.367131) (xy 142.990035 -52.402806) (xy 143.027252 -52.444343) (xy 143.058025 -52.490856)
			(xy 143.081697 -52.541353) (xy 143.097765 -52.59476) (xy 143.105885 -52.649936) (xy 143.106394 -52.677822)
			(xy 143.105885 -52.705708) (xy 143.097765 -52.760884) (xy 143.081697 -52.814291) (xy 143.058025 -52.864788)
			(xy 143.027252 -52.911301) (xy 142.990035 -52.952838) (xy 142.947167 -52.988513) (xy 142.899561 -53.017567)
			(xy 142.848232 -53.039379) (xy 142.794275 -53.053485) (xy 142.738838 -53.059585) (xy 142.683104 -53.057548)
			(xy 142.628261 -53.047418) (xy 142.575477 -53.029411) (xy 142.525877 -53.00391) (xy 142.480519 -52.971459)
			(xy 142.44037 -52.93275) (xy 142.406284 -52.888607) (xy 142.378988 -52.839972) (xy 142.359065 -52.787881)
			(xy 142.346939 -52.733444) (xy 142.342868 -52.677822) (xy 141.074357 -52.677822) (xy 141.074394 -52.679854)
			(xy 141.073885 -52.70774) (xy 141.065765 -52.762916) (xy 141.049697 -52.816323) (xy 141.026025 -52.86682)
			(xy 140.995252 -52.913333) (xy 140.958035 -52.95487) (xy 140.915167 -52.990545) (xy 140.867561 -53.019599)
			(xy 140.816232 -53.041411) (xy 140.762275 -53.055517) (xy 140.706838 -53.061617) (xy 140.651104 -53.05958)
			(xy 140.596261 -53.04945) (xy 140.543477 -53.031443) (xy 140.493877 -53.005942) (xy 140.448519 -52.973491)
			(xy 140.40837 -52.934782) (xy 140.374284 -52.890639) (xy 140.346988 -52.842004) (xy 140.327065 -52.789913)
			(xy 140.314939 -52.735476) (xy 140.310868 -52.679854) (xy 138.163046 -52.679854) (xy 138.163046 -53.513228)
			(xy 141.455646 -53.513228) (xy 141.459717 -53.457606) (xy 141.471843 -53.403169) (xy 141.491766 -53.351078)
			(xy 141.519062 -53.302443) (xy 141.553148 -53.2583) (xy 141.593297 -53.219591) (xy 141.638655 -53.18714)
			(xy 141.688255 -53.161639) (xy 141.741039 -53.143632) (xy 141.795882 -53.133502) (xy 141.851616 -53.131465)
			(xy 141.907053 -53.137565) (xy 141.96101 -53.151671) (xy 142.012339 -53.173483) (xy 142.059945 -53.202537)
			(xy 142.102813 -53.238212) (xy 142.14003 -53.279749) (xy 142.170803 -53.326262) (xy 142.194475 -53.376759)
			(xy 142.210543 -53.430166) (xy 142.216562 -53.471064) (xy 148.355302 -53.471064) (xy 148.359373 -53.415442)
			(xy 148.371499 -53.361005) (xy 148.391422 -53.308914) (xy 148.418718 -53.260279) (xy 148.452804 -53.216136)
			(xy 148.492953 -53.177427) (xy 148.538311 -53.144976) (xy 148.587911 -53.119475) (xy 148.640695 -53.101468)
			(xy 148.695538 -53.091338) (xy 148.751272 -53.089301) (xy 148.806709 -53.095401) (xy 148.860666 -53.109507)
			(xy 148.911995 -53.131319) (xy 148.959601 -53.160373) (xy 149.002469 -53.196048) (xy 149.039686 -53.237585)
			(xy 149.070459 -53.284098) (xy 149.094131 -53.334595) (xy 149.110199 -53.388002) (xy 149.118319 -53.443178)
			(xy 149.118828 -53.471064) (xy 149.118319 -53.49895) (xy 149.110199 -53.554126) (xy 149.094131 -53.607533)
			(xy 149.070459 -53.65803) (xy 149.039686 -53.704543) (xy 149.002469 -53.74608) (xy 148.959601 -53.781755)
			(xy 148.911995 -53.810809) (xy 148.860666 -53.832621) (xy 148.806709 -53.846727) (xy 148.751272 -53.852827)
			(xy 148.695538 -53.85079) (xy 148.640695 -53.84066) (xy 148.587911 -53.822653) (xy 148.538311 -53.797152)
			(xy 148.492953 -53.764701) (xy 148.452804 -53.725992) (xy 148.418718 -53.681849) (xy 148.391422 -53.633214)
			(xy 148.371499 -53.581123) (xy 148.359373 -53.526686) (xy 148.355302 -53.471064) (xy 142.216562 -53.471064)
			(xy 142.218663 -53.485342) (xy 142.219172 -53.513228) (xy 142.218663 -53.541114) (xy 142.210543 -53.59629)
			(xy 142.194475 -53.649697) (xy 142.170803 -53.700194) (xy 142.14003 -53.746707) (xy 142.102813 -53.788244)
			(xy 142.059945 -53.823919) (xy 142.012339 -53.852973) (xy 141.96101 -53.874785) (xy 141.907053 -53.888891)
			(xy 141.851616 -53.894991) (xy 141.795882 -53.892954) (xy 141.741039 -53.882824) (xy 141.688255 -53.864817)
			(xy 141.638655 -53.839316) (xy 141.593297 -53.806865) (xy 141.553148 -53.768156) (xy 141.519062 -53.724013)
			(xy 141.491766 -53.675378) (xy 141.471843 -53.623287) (xy 141.459717 -53.56885) (xy 141.455646 -53.513228)
			(xy 138.163046 -53.513228) (xy 138.163046 -53.89626) (xy 138.79144 -53.89626) (xy 138.795511 -53.840638)
			(xy 138.807637 -53.786201) (xy 138.82756 -53.73411) (xy 138.854856 -53.685475) (xy 138.888942 -53.641332)
			(xy 138.929091 -53.602623) (xy 138.974449 -53.570172) (xy 139.024049 -53.544671) (xy 139.076833 -53.526664)
			(xy 139.131676 -53.516534) (xy 139.18741 -53.514497) (xy 139.242847 -53.520597) (xy 139.296804 -53.534703)
			(xy 139.348133 -53.556515) (xy 139.395739 -53.585569) (xy 139.438607 -53.621244) (xy 139.475824 -53.662781)
			(xy 139.506597 -53.709294) (xy 139.530269 -53.759791) (xy 139.546337 -53.813198) (xy 139.554457 -53.868374)
			(xy 139.554966 -53.89626) (xy 139.554457 -53.924146) (xy 139.546337 -53.979322) (xy 139.530269 -54.032729)
			(xy 139.506597 -54.083226) (xy 139.475824 -54.129739) (xy 139.438607 -54.171276) (xy 139.395739 -54.206951)
			(xy 139.348133 -54.236005) (xy 139.296804 -54.257817) (xy 139.242847 -54.271923) (xy 139.18741 -54.278023)
			(xy 139.131676 -54.275986) (xy 139.076833 -54.265856) (xy 139.024049 -54.247849) (xy 138.974449 -54.222348)
			(xy 138.929091 -54.189897) (xy 138.888942 -54.151188) (xy 138.854856 -54.107045) (xy 138.82756 -54.05841)
			(xy 138.807637 -54.006319) (xy 138.795511 -53.951882) (xy 138.79144 -53.89626) (xy 138.163046 -53.89626)
			(xy 138.163046 -54.256686) (xy 138.163577 -54.280065) (xy 138.172128 -54.326033) (xy 138.188945 -54.369661)
			(xy 138.21346 -54.409476) (xy 138.244845 -54.444135) (xy 138.28204 -54.472466) (xy 138.323792 -54.493515)
			(xy 138.368689 -54.506571) (xy 138.3919 -54.509416) (xy 138.419809 -54.512715) (xy 138.474302 -54.526457)
			(xy 138.526193 -54.548036) (xy 138.574361 -54.576987) (xy 138.617765 -54.612685) (xy 138.655469 -54.654359)
			(xy 138.686659 -54.701108) (xy 138.71066 -54.751924) (xy 138.726955 -54.805709) (xy 138.735191 -54.861301)
			(xy 138.735191 -54.917499) (xy 138.726955 -54.973091) (xy 138.71066 -55.026876) (xy 138.686659 -55.077692)
			(xy 138.655469 -55.124441) (xy 138.617765 -55.166115) (xy 138.574361 -55.201813) (xy 138.526193 -55.230764)
			(xy 138.474302 -55.252343) (xy 138.419809 -55.266085) (xy 138.3919 -55.269384) (xy 138.368691 -55.272232)
			(xy 138.323799 -55.285298) (xy 138.282054 -55.306352) (xy 138.244862 -55.334685) (xy 138.213478 -55.369341)
			(xy 138.18896 -55.409151) (xy 138.172135 -55.452774) (xy 138.163571 -55.498737) (xy 138.163046 -55.522114)
			(xy 138.163046 -55.93588) (xy 138.593574 -55.93588) (xy 138.597645 -55.880258) (xy 138.609771 -55.825821)
			(xy 138.629694 -55.77373) (xy 138.65699 -55.725095) (xy 138.691076 -55.680952) (xy 138.731225 -55.642243)
			(xy 138.776583 -55.609792) (xy 138.826183 -55.584291) (xy 138.878967 -55.566284) (xy 138.93381 -55.556154)
			(xy 138.989544 -55.554117) (xy 139.044981 -55.560217) (xy 139.098938 -55.574323) (xy 139.150267 -55.596135)
			(xy 139.197873 -55.625189) (xy 139.240741 -55.660864) (xy 139.277958 -55.702401) (xy 139.308731 -55.748914)
			(xy 139.332403 -55.799411) (xy 139.348471 -55.852818) (xy 139.356591 -55.907994) (xy 139.3571 -55.93588)
			(xy 139.356591 -55.963766) (xy 139.348471 -56.018942) (xy 139.332403 -56.072349) (xy 139.308731 -56.122846)
			(xy 139.277958 -56.169359) (xy 139.240741 -56.210896) (xy 139.197873 -56.246571) (xy 139.150267 -56.275625)
			(xy 139.098938 -56.297437) (xy 139.044981 -56.311543) (xy 138.989544 -56.317643) (xy 138.93381 -56.315606)
			(xy 138.878967 -56.305476) (xy 138.826183 -56.287469) (xy 138.776583 -56.261968) (xy 138.731225 -56.229517)
			(xy 138.691076 -56.190808) (xy 138.65699 -56.146665) (xy 138.629694 -56.09803) (xy 138.609771 -56.045939)
			(xy 138.597645 -55.991502) (xy 138.593574 -55.93588) (xy 138.163046 -55.93588) (xy 138.163046 -57.671462)
			(xy 138.439906 -57.948322) (xy 139.399772 -57.948322)
		)
		(stroke
			(width 0)
			(type solid)
		)
		(fill yes)
		(layer "In2.Cu")
		(net "P5V_NODE1")
	)
	(gr_poly
		(pts
			(xy 62.748414 -148.349716) (xy 62.770013 -148.349281) (xy 62.812587 -148.34197) (xy 62.853311 -148.327562)
			(xy 62.89101 -148.306471) (xy 62.924597 -148.279306) (xy 62.953104 -148.24685) (xy 62.975709 -148.210039)
			(xy 62.99176 -148.169934) (xy 63.000794 -148.127691) (xy 63.00216 -148.10613) (xy 63.003793 -148.078125)
			(xy 63.014249 -148.023012) (xy 63.032663 -147.970024) (xy 63.058636 -147.920303) (xy 63.09161 -147.874921)
			(xy 63.130873 -147.834856) (xy 63.175579 -147.800972) (xy 63.224765 -147.773999) (xy 63.27737 -147.754518)
			(xy 63.33226 -147.742949) (xy 63.388253 -147.739542) (xy 63.444141 -147.74437) (xy 63.498719 -147.757329)
			(xy 63.550813 -147.77814) (xy 63.599297 -147.806354) (xy 63.643128 -147.841363) (xy 63.681361 -147.882412)
			(xy 63.713171 -147.928617) (xy 63.737874 -147.978981) (xy 63.746888 -148.005546) (xy 63.759588 -148.04517)
			(xy 63.82639 -148.094192) (xy 65.351152 -148.094192) (xy 65.372547 -148.092391) (xy 65.414329 -148.082525)
			(xy 65.453862 -148.065783) (xy 65.490021 -148.042641) (xy 65.521782 -148.013755) (xy 65.548241 -147.979946)
			(xy 65.568647 -147.942174) (xy 65.58242 -147.901512) (xy 65.58917 -147.859115) (xy 65.588705 -147.816186)
			(xy 65.58534 -147.79498) (xy 65.580067 -147.768266) (xy 65.576259 -147.713949) (xy 65.580213 -147.659643)
			(xy 65.591849 -147.606451) (xy 65.61093 -147.555454) (xy 65.637069 -147.507688) (xy 65.669734 -147.464124)
			(xy 65.708262 -147.425648) (xy 65.751869 -147.393042) (xy 65.79967 -147.366967) (xy 65.850693 -147.347954)
			(xy 65.9039 -147.33639) (xy 65.958212 -147.332509) (xy 66.012524 -147.33639) (xy 66.065731 -147.347954)
			(xy 66.116754 -147.366967) (xy 66.164555 -147.393042) (xy 66.208162 -147.425648) (xy 66.24669 -147.464124)
			(xy 66.279355 -147.507688) (xy 66.305494 -147.555454) (xy 66.324575 -147.606451) (xy 66.336211 -147.659643)
			(xy 66.340165 -147.713949) (xy 66.336357 -147.768266) (xy 66.331084 -147.79498) (xy 66.327679 -147.816184)
			(xy 66.327198 -147.859124) (xy 66.333938 -147.901535) (xy 66.347707 -147.94221) (xy 66.368115 -147.979994)
			(xy 66.39458 -148.013812) (xy 66.426351 -148.042702) (xy 66.462525 -148.065844) (xy 66.502072 -148.08258)
			(xy 66.543869 -148.092433) (xy 66.565272 -148.094192) (xy 66.736468 -148.094192) (xy 67.263264 -147.567396)
			(xy 67.344036 -147.486624) (xy 71.551546 -147.486624) (xy 71.567669 -147.486108) (xy 71.598869 -147.477949)
			(xy 71.627032 -147.462238) (xy 71.650364 -147.439976) (xy 71.66738 -147.412582) (xy 71.676995 -147.3818)
			(xy 71.678292 -147.36572) (xy 71.680135 -147.338089) (xy 71.690801 -147.28375) (xy 71.709212 -147.231525)
			(xy 71.734981 -147.18251) (xy 71.767567 -147.137737) (xy 71.806284 -147.098145) (xy 71.850318 -147.064568)
			(xy 71.898745 -147.037711) (xy 71.950547 -147.018138) (xy 72.004634 -147.006261) (xy 72.05987 -147.00233)
			(xy 72.115094 -147.006426) (xy 72.169145 -147.018464) (xy 72.220888 -147.038192) (xy 72.269234 -147.065193)
			(xy 72.313169 -147.098901) (xy 72.351767 -147.138608) (xy 72.36841 -147.160742) (xy 72.381426 -147.178046)
			(xy 72.412339 -147.208363) (xy 72.447946 -147.232996) (xy 72.487216 -147.251232) (xy 72.52901 -147.262542)
			(xy 72.572118 -147.266598) (xy 72.615288 -147.263282) (xy 72.65727 -147.252692) (xy 72.696848 -147.235132)
			(xy 72.732872 -147.211114) (xy 72.748902 -147.196556) (xy 73.13041 -146.815048) (xy 76.327 -146.815048)
			(xy 77.027024 -146.115024) (xy 77.027024 -145.734024) (xy 77.004926 -145.701512) (xy 76.989261 -145.677639)
			(xy 76.964483 -145.626195) (xy 76.947649 -145.571634) (xy 76.939135 -145.515173) (xy 76.939132 -145.458073)
			(xy 76.947639 -145.401611) (xy 76.964466 -145.347048) (xy 76.989237 -145.295601) (xy 77.004926 -145.271744)
			(xy 77.027024 -145.239232) (xy 77.027024 -131.116832) (xy 77.026587 -131.095161) (xy 77.019239 -131.052446)
			(xy 77.004748 -131.011598) (xy 76.983537 -130.9738) (xy 76.95622 -130.94015) (xy 76.92359 -130.911623)
			(xy 76.886592 -130.889046) (xy 76.8463 -130.873075) (xy 76.803882 -130.864172) (xy 76.760568 -130.862595)
			(xy 76.717615 -130.86839) (xy 76.696824 -130.874516) (xy 76.670216 -130.88336) (xy 76.615172 -130.894041)
			(xy 76.559158 -130.896552) (xy 76.503379 -130.890838) (xy 76.449037 -130.877023) (xy 76.397302 -130.855405)
			(xy 76.349287 -130.826447) (xy 76.306027 -130.790775) (xy 76.268454 -130.749156) (xy 76.237375 -130.702487)
			(xy 76.213462 -130.651772) (xy 76.197227 -130.598103) (xy 76.189021 -130.542636) (xy 76.189021 -130.486565)
			(xy 76.197227 -130.431098) (xy 76.213461 -130.37743) (xy 76.237375 -130.326714) (xy 76.268453 -130.280045)
			(xy 76.306026 -130.238426) (xy 76.349286 -130.202753) (xy 76.3973 -130.173796) (xy 76.449036 -130.152177)
			(xy 76.503378 -130.138362) (xy 76.559156 -130.132648) (xy 76.615171 -130.135159) (xy 76.670214 -130.14584)
			(xy 76.696824 -130.15468) (xy 76.717625 -130.16076) (xy 76.76057 -130.166554) (xy 76.803876 -130.164978)
			(xy 76.846285 -130.156076) (xy 76.88657 -130.140108) (xy 76.923561 -130.117535) (xy 76.956185 -130.089013)
			(xy 76.983497 -130.055369) (xy 77.004703 -130.017579) (xy 77.01919 -129.976738) (xy 77.026537 -129.934031)
			(xy 77.027024 -129.912364) (xy 77.027024 -124.742956) (xy 76.961746 -124.633228) (xy 76.936346 -124.616972)
			(xy 76.911091 -124.6001) (xy 76.865796 -124.55964) (xy 76.846176 -124.536454) (xy 76.83466 -124.523191)
			(xy 76.805914 -124.503029) (xy 76.772762 -124.491464) (xy 76.737713 -124.48937) (xy 76.70342 -124.496907)
			(xy 76.68768 -124.504704) (xy 76.663026 -124.517386) (xy 76.610904 -124.536281) (xy 76.556597 -124.547434)
			(xy 76.501247 -124.550609) (xy 76.44602 -124.545739) (xy 76.39208 -124.532928) (xy 76.340562 -124.512446)
			(xy 76.29255 -124.484722) (xy 76.249057 -124.450342) (xy 76.210997 -124.410029) (xy 76.179173 -124.364632)
			(xy 76.154254 -124.315107) (xy 76.136765 -124.262497) (xy 76.127074 -124.207909) (xy 76.125386 -124.152494)
			(xy 76.131736 -124.097418) (xy 76.14599 -124.043841) (xy 76.167849 -123.992891) (xy 76.196851 -123.945641)
			(xy 76.232387 -123.903086) (xy 76.273707 -123.866123) (xy 76.319942 -123.835528) (xy 76.370118 -123.811948)
			(xy 76.423179 -123.795878) (xy 76.478006 -123.787656) (xy 76.533447 -123.787456) (xy 76.588333 -123.795282)
			(xy 76.641508 -123.81097) (xy 76.666852 -123.822206) (xy 76.688075 -123.831407) (xy 76.732899 -123.842811)
			(xy 76.779047 -123.845917) (xy 76.824995 -123.840623) (xy 76.869227 -123.827103) (xy 76.910283 -123.805804)
			(xy 76.946808 -123.777428) (xy 76.977596 -123.742912) (xy 77.001632 -123.703396) (xy 77.018121 -123.660183)
			(xy 77.02652 -123.6147) (xy 77.027024 -123.591574) (xy 77.027024 -121.497852) (xy 74.3712 -118.842028)
			(xy 74.274172 -118.836694) (xy 74.236072 -118.867174) (xy 74.213665 -118.884525) (xy 74.164732 -118.913109)
			(xy 74.112109 -118.934142) (xy 74.056955 -118.94716) (xy 74.000481 -118.951877) (xy 73.943931 -118.94819)
			(xy 73.888549 -118.936179) (xy 73.835552 -118.916109) (xy 73.786106 -118.888421) (xy 73.763378 -118.871492)
			(xy 73.74544 -118.858166) (xy 73.705892 -118.83737) (xy 73.663316 -118.823812) (xy 73.619024 -118.817912)
			(xy 73.574384 -118.81985) (xy 73.53077 -118.829568) (xy 73.48953 -118.846765) (xy 73.451933 -118.870912)
			(xy 73.419141 -118.901263) (xy 73.392163 -118.936882) (xy 73.381616 -118.956582) (xy 73.374075 -118.970917)
			(xy 73.356909 -118.998388) (xy 73.347326 -119.011446) (xy 73.333733 -119.030457) (xy 73.313007 -119.072339)
			(xy 73.300288 -119.117304) (xy 73.296004 -119.163837) (xy 73.300301 -119.210368) (xy 73.313034 -119.25533)
			(xy 73.333772 -119.297205) (xy 73.347326 -119.316246) (xy 73.363821 -119.339145) (xy 73.390601 -119.388821)
			(xy 73.409772 -119.441899) (xy 73.420915 -119.497222) (xy 73.423788 -119.553584) (xy 73.418327 -119.609753)
			(xy 73.404653 -119.664506) (xy 73.383063 -119.716647) (xy 73.354028 -119.765039) (xy 73.318182 -119.808627)
			(xy 73.276307 -119.846459) (xy 73.229316 -119.877711) (xy 73.178234 -119.9017) (xy 73.124176 -119.917903)
			(xy 73.068321 -119.925967) (xy 73.011887 -119.925716) (xy 72.956106 -119.917155) (xy 72.928988 -119.909336)
			(xy 72.907117 -119.903052) (xy 72.861959 -119.897475) (xy 72.81653 -119.900037) (xy 72.772286 -119.910654)
			(xy 72.730642 -119.928987) (xy 72.692932 -119.954448) (xy 72.660364 -119.986224) (xy 72.633981 -120.023295)
			(xy 72.614628 -120.064474) (xy 72.602924 -120.108444) (xy 72.600566 -120.131078) (xy 72.597805 -120.158626)
			(xy 72.58534 -120.212567) (xy 72.56521 -120.264141) (xy 72.537837 -120.312263) (xy 72.503797 -120.355925)
			(xy 72.463804 -120.394208) (xy 72.418698 -120.42631) (xy 72.369427 -120.451555) (xy 72.317024 -120.469415)
			(xy 72.26259 -120.479513) (xy 72.207267 -120.481638) (xy 72.152219 -120.475746) (xy 72.0986 -120.46196)
			(xy 72.047537 -120.440569) (xy 72.000101 -120.412022) (xy 71.957289 -120.37692) (xy 71.92 -120.335999)
			(xy 71.889016 -120.290118) (xy 71.864988 -120.240241) (xy 71.848421 -120.187415) (xy 71.839663 -120.13275)
			(xy 71.838897 -120.077392) (xy 71.84614 -120.022505) (xy 71.861239 -119.969241) (xy 71.883878 -119.918719)
			(xy 71.913581 -119.871998) (xy 71.949724 -119.830061) (xy 71.991549 -119.793788) (xy 72.038177 -119.763941)
			(xy 72.088629 -119.741145) (xy 72.141846 -119.725881) (xy 72.19671 -119.718468) (xy 72.25207 -119.719062)
			(xy 72.306762 -119.727651) (xy 72.333358 -119.735346) (xy 72.355227 -119.741626) (xy 72.400378 -119.747195)
			(xy 72.445799 -119.744628) (xy 72.490036 -119.734007) (xy 72.531671 -119.715671) (xy 72.569371 -119.690209)
			(xy 72.601931 -119.658435) (xy 72.628305 -119.621367) (xy 72.647652 -119.580192) (xy 72.65935 -119.536228)
			(xy 72.66178 -119.513604) (xy 72.664435 -119.486983) (xy 72.676251 -119.434806) (xy 72.695236 -119.384789)
			(xy 72.721018 -119.337914) (xy 72.73671 -119.316246) (xy 72.750309 -119.297234) (xy 72.771049 -119.255349)
			(xy 72.783782 -119.210378) (xy 72.78808 -119.163837) (xy 72.783796 -119.117295) (xy 72.771076 -119.07232)
			(xy 72.750348 -119.030429) (xy 72.73671 -119.011446) (xy 72.720659 -118.989223) (xy 72.694418 -118.941093)
			(xy 72.675337 -118.889703) (xy 72.663809 -118.83611) (xy 72.660073 -118.781419) (xy 72.664205 -118.726756)
			(xy 72.676119 -118.673248) (xy 72.695572 -118.621996) (xy 72.722161 -118.574058) (xy 72.755339 -118.53042)
			(xy 72.794423 -118.491981) (xy 72.838607 -118.459533) (xy 72.886981 -118.433745) (xy 72.938549 -118.415148)
			(xy 72.992248 -118.404125) (xy 73.046971 -118.400903) (xy 73.101593 -118.405548) (xy 73.154987 -118.417965)
			(xy 73.206053 -118.437899) (xy 73.253739 -118.464937) (xy 73.275698 -118.481348) (xy 73.293636 -118.494665)
			(xy 73.33318 -118.515444) (xy 73.375749 -118.528987) (xy 73.420031 -118.534876) (xy 73.46466 -118.532929)
			(xy 73.508261 -118.523207) (xy 73.549489 -118.506008) (xy 73.587074 -118.481864) (xy 73.619856 -118.451518)
			(xy 73.646826 -118.415907) (xy 73.65746 -118.396258) (xy 73.666593 -118.379087) (xy 73.687847 -118.346515)
			(xy 73.699878 -118.331234) (xy 73.699878 -118.33098) (xy 73.730358 -118.29288) (xy 73.725024 -118.195852)
			(xy 73.015856 -117.486684) (xy 71.414386 -117.486684) (xy 71.392235 -117.487166) (xy 71.348605 -117.494855)
			(xy 71.30697 -117.509995) (xy 71.268593 -117.532129) (xy 71.234637 -117.560585) (xy 71.206134 -117.594501)
			(xy 71.183946 -117.632847) (xy 71.168747 -117.67446) (xy 71.160998 -117.71808) (xy 71.160933 -117.762382)
			(xy 71.168555 -117.806024) (xy 71.183633 -117.847682) (xy 71.194168 -117.867176) (xy 71.20783 -117.891941)
			(xy 71.228493 -117.94459) (xy 71.241147 -117.999714) (xy 71.245515 -118.056103) (xy 71.241501 -118.112518)
			(xy 71.235824 -118.140226) (xy 71.229728 -118.167912) (xy 71.241666 -118.222268) (xy 71.316088 -118.320058)
			(xy 71.350378 -118.333012) (xy 71.375739 -118.343016) (xy 71.423542 -118.369229) (xy 71.467125 -118.401983)
			(xy 71.505599 -118.440609) (xy 71.538181 -118.48432) (xy 71.564207 -118.532225) (xy 71.583145 -118.583348)
			(xy 71.59461 -118.636647) (xy 71.598368 -118.691036) (xy 71.594344 -118.745405) (xy 71.582617 -118.798648)
			(xy 71.563429 -118.849677) (xy 71.537169 -118.897455) (xy 71.504373 -118.941006) (xy 71.46571 -118.979442)
			(xy 71.421967 -119.011982) (xy 71.374036 -119.03796) (xy 71.322894 -119.056849) (xy 71.269584 -119.068262)
			(xy 71.215192 -119.071967) (xy 71.160826 -119.067889) (xy 71.107596 -119.056111) (xy 71.056584 -119.036873)
			(xy 71.008833 -119.010566) (xy 70.965314 -118.977728) (xy 70.926915 -118.939027) (xy 70.894418 -118.895253)
			(xy 70.868486 -118.847297) (xy 70.849648 -118.796137) (xy 70.838286 -118.742815) (xy 70.834634 -118.68842)
			(xy 70.838765 -118.634058) (xy 70.844156 -118.607332) (xy 70.850252 -118.579646) (xy 70.838314 -118.52529)
			(xy 70.763892 -118.4275) (xy 70.729602 -118.414546) (xy 70.703957 -118.404408) (xy 70.65565 -118.37781)
			(xy 70.611676 -118.344536) (xy 70.57295 -118.305277) (xy 70.540279 -118.260853) (xy 70.514344 -118.212188)
			(xy 70.495684 -118.160296) (xy 70.48469 -118.106258) (xy 70.481588 -118.051201) (xy 70.486446 -117.996271)
			(xy 70.49916 -117.942612) (xy 70.519466 -117.891342) (xy 70.532752 -117.867176) (xy 70.543366 -117.847726)
			(xy 70.55843 -117.806062) (xy 70.566039 -117.762416) (xy 70.565963 -117.718111) (xy 70.558203 -117.674492)
			(xy 70.542996 -117.632879) (xy 70.520801 -117.594535) (xy 70.492293 -117.560621) (xy 70.458334 -117.532167)
			(xy 70.419955 -117.510033) (xy 70.378318 -117.494892) (xy 70.334686 -117.487201) (xy 70.312534 -117.486684)
			(xy 67.194684 -117.486684) (xy 67.16903 -117.498622) (xy 67.143559 -117.510042) (xy 67.090112 -117.526143)
			(xy 67.034888 -117.534281) (xy 66.979068 -117.534281) (xy 66.923844 -117.526143) (xy 66.870397 -117.510042)
			(xy 66.844926 -117.498622) (xy 66.819272 -117.486684) (xy 66.068448 -117.486684) (xy 66.063368 -117.481604)
			(xy 66.047069 -117.465984) (xy 66.010023 -117.440192) (xy 65.969001 -117.421356) (xy 65.925295 -117.410069)
			(xy 65.880282 -117.406685) (xy 65.83538 -117.411313) (xy 65.792003 -117.423805) (xy 65.751518 -117.443768)
			(xy 65.715199 -117.470574) (xy 65.699386 -117.486684) (xy 65.68024 -117.506227) (xy 65.637341 -117.54018)
			(xy 65.590032 -117.567657) (xy 65.539284 -117.588095) (xy 65.486136 -117.601075) (xy 65.43168 -117.606331)
			(xy 65.377031 -117.603755) (xy 65.323311 -117.593399) (xy 65.27162 -117.575477) (xy 65.22302 -117.550355)
			(xy 65.178506 -117.518549) (xy 65.138991 -117.480711) (xy 65.105286 -117.437617) (xy 65.078082 -117.390151)
			(xy 65.057937 -117.339286) (xy 65.045263 -117.286064) (xy 65.040321 -117.231579) (xy 65.041272 -117.204236)
			(xy 65.042003 -117.181303) (xy 65.036183 -117.135794) (xy 65.022286 -117.09207) (xy 65.000764 -117.051551)
			(xy 64.972316 -117.015556) (xy 64.937868 -116.985254) (xy 64.898538 -116.961629) (xy 64.855606 -116.94545)
			(xy 64.810466 -116.937243) (xy 64.787526 -116.936774) (xy 64.460628 -116.936774) (xy 64.336168 -117.061234)
			(xy 64.331342 -117.105684) (xy 64.327831 -117.133368) (xy 64.313758 -117.187366) (xy 64.291969 -117.238738)
			(xy 64.262927 -117.286387) (xy 64.227254 -117.329298) (xy 64.18571 -117.366553) (xy 64.139181 -117.397359)
			(xy 64.088661 -117.421057) (xy 64.035228 -117.437143) (xy 63.980021 -117.445272) (xy 63.924219 -117.445272)
			(xy 63.869012 -117.437143) (xy 63.815579 -117.421057) (xy 63.765059 -117.397359) (xy 63.71853 -117.366553)
			(xy 63.676986 -117.329298) (xy 63.641313 -117.286387) (xy 63.612271 -117.238738) (xy 63.590482 -117.187366)
			(xy 63.576409 -117.133368) (xy 63.572898 -117.105684) (xy 63.568072 -117.061234) (xy 63.443612 -116.936774)
			(xy 62.327536 -116.936774) (xy 62.208664 -117.024658) (xy 62.195202 -117.057932) (xy 62.184078 -117.083929)
			(xy 62.155285 -117.132594) (xy 62.119627 -117.176478) (xy 62.077885 -117.214621) (xy 62.030972 -117.246189)
			(xy 61.979916 -117.270489) (xy 61.925832 -117.286991) (xy 61.869906 -117.295334) (xy 61.813362 -117.295334)
			(xy 61.757436 -117.286991) (xy 61.703352 -117.270489) (xy 61.652296 -117.246189) (xy 61.605383 -117.214621)
			(xy 61.563641 -117.176478) (xy 61.527983 -117.132594) (xy 61.49919 -117.083929) (xy 61.488066 -117.057932)
			(xy 61.474604 -117.024658) (xy 61.355478 -116.936774) (xy 61.050678 -116.936774) (xy 60.93079 -117.027452)
			(xy 60.917836 -117.061488) (xy 60.907754 -117.086657) (xy 60.8815 -117.134094) (xy 60.848795 -117.177337)
			(xy 60.810298 -117.215515) (xy 60.766783 -117.247858) (xy 60.719129 -117.273716) (xy 60.668293 -117.292567)
			(xy 60.615301 -117.304031) (xy 60.56122 -117.307879) (xy 60.507139 -117.304031) (xy 60.454147 -117.292567)
			(xy 60.403311 -117.273716) (xy 60.355657 -117.247858) (xy 60.312142 -117.215515) (xy 60.273645 -117.177337)
			(xy 60.24094 -117.134094) (xy 60.214686 -117.086657) (xy 60.204604 -117.061488) (xy 60.19165 -117.027452)
			(xy 60.071762 -116.936774) (xy 59.406282 -116.936774) (xy 59.383917 -116.937247) (xy 59.339878 -116.94508)
			(xy 59.297889 -116.960501) (xy 59.259249 -116.983035) (xy 59.22515 -117.011984) (xy 59.196645 -117.046456)
			(xy 59.174615 -117.085385) (xy 59.159739 -117.127569) (xy 59.152478 -117.171706) (xy 59.152282 -117.194076)
			(xy 59.152228 -117.217397) (xy 59.147137 -117.263756) (xy 59.142122 -117.286532) (xy 59.138356 -117.305212)
			(xy 59.140935 -117.343213) (xy 59.147202 -117.361208) (xy 59.156606 -117.387001) (xy 59.168756 -117.440539)
			(xy 59.173107 -117.495265) (xy 59.169569 -117.55005) (xy 59.158214 -117.603763) (xy 59.139278 -117.655293)
			(xy 59.113151 -117.703576) (xy 59.080373 -117.747616) (xy 59.041621 -117.786503) (xy 58.997696 -117.819434)
			(xy 58.949503 -117.845729) (xy 58.898039 -117.864844) (xy 58.844367 -117.876386) (xy 58.789594 -117.880115)
			(xy 58.734853 -117.875954) (xy 58.681273 -117.86399) (xy 58.629962 -117.84447) (xy 58.581978 -117.817796)
			(xy 58.538313 -117.78452) (xy 58.499869 -117.745329) (xy 58.467439 -117.701031) (xy 58.441694 -117.652543)
			(xy 58.423164 -117.600866) (xy 58.412234 -117.547066) (xy 58.409127 -117.492254) (xy 58.413909 -117.437564)
			(xy 58.419746 -117.410738) (xy 58.423508 -117.392059) (xy 58.420921 -117.354061) (xy 58.414666 -117.336062)
			(xy 58.406336 -117.313344) (xy 58.394823 -117.266347) (xy 58.389334 -117.218272) (xy 58.389266 -117.194076)
			(xy 58.389083 -117.171707) (xy 58.381821 -117.127571) (xy 58.366944 -117.085388) (xy 58.344911 -117.046461)
			(xy 58.316404 -117.011993) (xy 58.282302 -116.983048) (xy 58.24366 -116.96052) (xy 58.201671 -116.945106)
			(xy 58.157631 -116.937281) (xy 58.135266 -116.936774) (xy 57.98058 -116.936774) (xy 57.964871 -116.937244)
			(xy 57.934408 -116.944936) (xy 57.906754 -116.959848) (xy 57.883588 -116.981073) (xy 57.86632 -117.007321)
			(xy 57.855999 -117.036996) (xy 57.854088 -117.052598) (xy 57.851072 -117.080725) (xy 57.837797 -117.135714)
			(xy 57.816547 -117.188139) (xy 57.787789 -117.236851) (xy 57.752152 -117.280783) (xy 57.710419 -117.31897)
			(xy 57.663504 -117.350576) (xy 57.612437 -117.374908) (xy 57.558336 -117.391432) (xy 57.502388 -117.399785)
			(xy 57.44582 -117.399785) (xy 57.389872 -117.391432) (xy 57.335771 -117.374908) (xy 57.284704 -117.350576)
			(xy 57.237789 -117.31897) (xy 57.196056 -117.280783) (xy 57.160419 -117.236851) (xy 57.131661 -117.188139)
			(xy 57.110411 -117.135714) (xy 57.097136 -117.080725) (xy 57.09412 -117.052598) (xy 57.09227 -117.036989)
			(xy 57.081928 -117.007316) (xy 57.064645 -116.981073) (xy 57.041468 -116.959854) (xy 57.013807 -116.944946)
			(xy 56.983339 -116.937255) (xy 56.967628 -116.936774) (xy 56.837326 -116.936774) (xy 55.691278 -118.082822)
			(xy 62.220092 -118.082822) (xy 62.224163 -118.0272) (xy 62.236289 -117.972763) (xy 62.256212 -117.920672)
			(xy 62.283508 -117.872037) (xy 62.317594 -117.827894) (xy 62.357743 -117.789185) (xy 62.403101 -117.756734)
			(xy 62.452701 -117.731233) (xy 62.505485 -117.713226) (xy 62.560328 -117.703096) (xy 62.616062 -117.701059)
			(xy 62.671499 -117.707159) (xy 62.725456 -117.721265) (xy 62.776785 -117.743077) (xy 62.824391 -117.772131)
			(xy 62.867259 -117.807806) (xy 62.904476 -117.849343) (xy 62.935249 -117.895856) (xy 62.958921 -117.946353)
			(xy 62.974989 -117.99976) (xy 62.983109 -118.054936) (xy 62.983618 -118.082822) (xy 62.983109 -118.110708)
			(xy 62.974989 -118.165884) (xy 62.958921 -118.219291) (xy 62.935249 -118.269788) (xy 62.904476 -118.316301)
			(xy 62.867259 -118.357838) (xy 62.824391 -118.393513) (xy 62.776785 -118.422567) (xy 62.725456 -118.444379)
			(xy 62.671499 -118.458485) (xy 62.616062 -118.464585) (xy 62.560328 -118.462548) (xy 62.505485 -118.452418)
			(xy 62.452701 -118.434411) (xy 62.403101 -118.40891) (xy 62.357743 -118.376459) (xy 62.317594 -118.33775)
			(xy 62.283508 -118.293607) (xy 62.256212 -118.244972) (xy 62.236289 -118.192881) (xy 62.224163 -118.138444)
			(xy 62.220092 -118.082822) (xy 55.691278 -118.082822) (xy 53.850794 -119.923306) (xy 53.850794 -120.358662)
			(xy 55.000142 -120.358662) (xy 55.004213 -120.30304) (xy 55.016339 -120.248603) (xy 55.036262 -120.196512)
			(xy 55.063558 -120.147877) (xy 55.097644 -120.103734) (xy 55.137793 -120.065025) (xy 55.183151 -120.032574)
			(xy 55.232751 -120.007073) (xy 55.285535 -119.989066) (xy 55.340378 -119.978936) (xy 55.396112 -119.976899)
			(xy 55.451549 -119.982999) (xy 55.505506 -119.997105) (xy 55.556835 -120.018917) (xy 55.583296 -120.035066)
			(xy 57.086752 -120.035066) (xy 57.090823 -119.979444) (xy 57.102949 -119.925007) (xy 57.122872 -119.872916)
			(xy 57.150168 -119.824281) (xy 57.184254 -119.780138) (xy 57.224403 -119.741429) (xy 57.269761 -119.708978)
			(xy 57.319361 -119.683477) (xy 57.372145 -119.66547) (xy 57.426988 -119.65534) (xy 57.482722 -119.653303)
			(xy 57.538159 -119.659403) (xy 57.592116 -119.673509) (xy 57.643445 -119.695321) (xy 57.691051 -119.724375)
			(xy 57.733919 -119.76005) (xy 57.771136 -119.801587) (xy 57.801909 -119.8481) (xy 57.80311 -119.850662)
			(xy 69.927468 -119.850662) (xy 69.931539 -119.79504) (xy 69.943665 -119.740603) (xy 69.963588 -119.688512)
			(xy 69.990884 -119.639877) (xy 70.02497 -119.595734) (xy 70.065119 -119.557025) (xy 70.110477 -119.524574)
			(xy 70.160077 -119.499073) (xy 70.212861 -119.481066) (xy 70.267704 -119.470936) (xy 70.323438 -119.468899)
			(xy 70.378875 -119.474999) (xy 70.432832 -119.489105) (xy 70.484161 -119.510917) (xy 70.531767 -119.539971)
			(xy 70.574635 -119.575646) (xy 70.611852 -119.617183) (xy 70.642625 -119.663696) (xy 70.666297 -119.714193)
			(xy 70.682365 -119.7676) (xy 70.690485 -119.822776) (xy 70.690994 -119.850662) (xy 70.690485 -119.878548)
			(xy 70.682365 -119.933724) (xy 70.666297 -119.987131) (xy 70.642625 -120.037628) (xy 70.611852 -120.084141)
			(xy 70.574635 -120.125678) (xy 70.531767 -120.161353) (xy 70.484161 -120.190407) (xy 70.432832 -120.212219)
			(xy 70.378875 -120.226325) (xy 70.323438 -120.232425) (xy 70.267704 -120.230388) (xy 70.212861 -120.220258)
			(xy 70.160077 -120.202251) (xy 70.110477 -120.17675) (xy 70.065119 -120.144299) (xy 70.02497 -120.10559)
			(xy 69.990884 -120.061447) (xy 69.963588 -120.012812) (xy 69.943665 -119.960721) (xy 69.931539 -119.906284)
			(xy 69.927468 -119.850662) (xy 57.80311 -119.850662) (xy 57.825581 -119.898597) (xy 57.841649 -119.952004)
			(xy 57.849769 -120.00718) (xy 57.850278 -120.035066) (xy 57.849769 -120.062952) (xy 57.841649 -120.118128)
			(xy 57.825581 -120.171535) (xy 57.801909 -120.222032) (xy 57.771136 -120.268545) (xy 57.733919 -120.310082)
			(xy 57.691051 -120.345757) (xy 57.643445 -120.374811) (xy 57.592116 -120.396623) (xy 57.538159 -120.410729)
			(xy 57.482722 -120.416829) (xy 57.426988 -120.414792) (xy 57.372145 -120.404662) (xy 57.319361 -120.386655)
			(xy 57.269761 -120.361154) (xy 57.224403 -120.328703) (xy 57.184254 -120.289994) (xy 57.150168 -120.245851)
			(xy 57.122872 -120.197216) (xy 57.102949 -120.145125) (xy 57.090823 -120.090688) (xy 57.086752 -120.035066)
			(xy 55.583296 -120.035066) (xy 55.604441 -120.047971) (xy 55.647309 -120.083646) (xy 55.684526 -120.125183)
			(xy 55.715299 -120.171696) (xy 55.738971 -120.222193) (xy 55.755039 -120.2756) (xy 55.763159 -120.330776)
			(xy 55.763668 -120.358662) (xy 55.763159 -120.386548) (xy 55.755039 -120.441724) (xy 55.738971 -120.495131)
			(xy 55.715299 -120.545628) (xy 55.684526 -120.592141) (xy 55.647309 -120.633678) (xy 55.604441 -120.669353)
			(xy 55.556835 -120.698407) (xy 55.505506 -120.720219) (xy 55.451549 -120.734325) (xy 55.396112 -120.740425)
			(xy 55.340378 -120.738388) (xy 55.285535 -120.728258) (xy 55.232751 -120.710251) (xy 55.183151 -120.68475)
			(xy 55.137793 -120.652299) (xy 55.097644 -120.61359) (xy 55.063558 -120.569447) (xy 55.036262 -120.520812)
			(xy 55.016339 -120.468721) (xy 55.004213 -120.414284) (xy 55.000142 -120.358662) (xy 53.850794 -120.358662)
			(xy 53.850794 -121.914832) (xy 56.112376 -121.914832) (xy 56.1146 -121.860171) (xy 56.124608 -121.806387)
			(xy 56.142194 -121.754583) (xy 56.166997 -121.705822) (xy 56.19851 -121.661103) (xy 56.236085 -121.621342)
			(xy 56.278953 -121.587355) (xy 56.326236 -121.559837) (xy 56.351424 -121.54916) (xy 56.372047 -121.540341)
			(xy 56.410068 -121.516553) (xy 56.443318 -121.486457) (xy 56.470764 -121.450987) (xy 56.491552 -121.411247)
			(xy 56.505036 -121.368473) (xy 56.510797 -121.323996) (xy 56.508654 -121.279199) (xy 56.498675 -121.235474)
			(xy 56.490362 -121.214642) (xy 56.480163 -121.189263) (xy 56.466281 -121.13636) (xy 56.460097 -121.082016)
			(xy 56.461736 -121.027346) (xy 56.471165 -120.97347) (xy 56.48819 -120.921493) (xy 56.512464 -120.87248)
			(xy 56.543488 -120.827436) (xy 56.580626 -120.787283) (xy 56.623117 -120.752845) (xy 56.670091 -120.724828)
			(xy 56.720584 -120.703805) (xy 56.773561 -120.690209) (xy 56.827937 -120.684316) (xy 56.882598 -120.68625)
			(xy 56.936422 -120.695968) (xy 56.988306 -120.713273) (xy 57.037188 -120.73781) (xy 57.082065 -120.769076)
			(xy 57.122018 -120.806429) (xy 57.156227 -120.849105) (xy 57.183991 -120.896229) (xy 57.204741 -120.946834)
			(xy 57.218053 -120.999884) (xy 57.223653 -121.054291) (xy 57.221426 -121.10894) (xy 57.211418 -121.162711)
			(xy 57.193834 -121.214502) (xy 57.169034 -121.263251) (xy 57.137528 -121.307959) (xy 57.09996 -121.34771)
			(xy 57.057101 -121.381689) (xy 57.009828 -121.4092) (xy 56.984646 -121.419874) (xy 56.963999 -121.42864)
			(xy 56.925978 -121.452436) (xy 56.892728 -121.482541) (xy 56.865284 -121.518019) (xy 56.844498 -121.557765)
			(xy 56.831018 -121.600545) (xy 56.825262 -121.645028) (xy 56.827409 -121.68983) (xy 56.837393 -121.733558)
			(xy 56.845708 -121.754392) (xy 56.855983 -121.779746) (xy 56.869877 -121.832659) (xy 56.870626 -121.839228)
			(xy 57.683398 -121.839228) (xy 57.687469 -121.783606) (xy 57.699595 -121.729169) (xy 57.719518 -121.677078)
			(xy 57.746814 -121.628443) (xy 57.7809 -121.5843) (xy 57.821049 -121.545591) (xy 57.866407 -121.51314)
			(xy 57.916007 -121.487639) (xy 57.968791 -121.469632) (xy 58.023634 -121.459502) (xy 58.079368 -121.457465)
			(xy 58.134805 -121.463565) (xy 58.188762 -121.477671) (xy 58.240091 -121.499483) (xy 58.287697 -121.528537)
			(xy 58.330565 -121.564212) (xy 58.367782 -121.605749) (xy 58.398555 -121.652262) (xy 58.422227 -121.702759)
			(xy 58.438295 -121.756166) (xy 58.446415 -121.811342) (xy 58.446924 -121.839228) (xy 58.446415 -121.867114)
			(xy 58.438295 -121.92229) (xy 58.422227 -121.975697) (xy 58.398555 -122.026194) (xy 58.367782 -122.072707)
			(xy 58.330565 -122.114244) (xy 58.287697 -122.149919) (xy 58.2678 -122.162062) (xy 59.107068 -122.162062)
			(xy 59.111139 -122.10644) (xy 59.123265 -122.052003) (xy 59.143188 -121.999912) (xy 59.170484 -121.951277)
			(xy 59.20457 -121.907134) (xy 59.244719 -121.868425) (xy 59.290077 -121.835974) (xy 59.339677 -121.810473)
			(xy 59.392461 -121.792466) (xy 59.447304 -121.782336) (xy 59.503038 -121.780299) (xy 59.558475 -121.786399)
			(xy 59.612432 -121.800505) (xy 59.663761 -121.822317) (xy 59.711367 -121.851371) (xy 59.754235 -121.887046)
			(xy 59.791452 -121.928583) (xy 59.822225 -121.975096) (xy 59.845897 -122.025593) (xy 59.861965 -122.079)
			(xy 59.870085 -122.134176) (xy 59.870594 -122.162062) (xy 59.870085 -122.189948) (xy 59.861965 -122.245124)
			(xy 59.859911 -122.251951) (xy 70.096428 -122.251951) (xy 70.096432 -122.195996) (xy 70.104611 -122.140642)
			(xy 70.120788 -122.087076) (xy 70.144616 -122.036448) (xy 70.175586 -121.989845) (xy 70.213031 -121.948265)
			(xy 70.256149 -121.912602) (xy 70.304014 -121.883621) (xy 70.355599 -121.861943) (xy 70.409798 -121.848034)
			(xy 70.465447 -121.842191) (xy 70.521353 -121.844541) (xy 70.576316 -121.855033) (xy 70.629156 -121.873442)
			(xy 70.67874 -121.899373) (xy 70.724004 -121.932269) (xy 70.744334 -121.951496) (xy 70.760283 -121.966451)
			(xy 70.796314 -121.991211) (xy 70.836052 -122.009438) (xy 70.878323 -122.020593) (xy 70.92188 -122.024349)
			(xy 70.965437 -122.020593) (xy 71.007708 -122.009438) (xy 71.047446 -121.991211) (xy 71.083477 -121.966451)
			(xy 71.099426 -121.951496) (xy 71.11983 -121.932247) (xy 71.165227 -121.8993) (xy 71.214958 -121.873356)
			(xy 71.267953 -121.854975) (xy 71.323069 -121.844552) (xy 71.379116 -121.842313) (xy 71.434887 -121.848306)
			(xy 71.48918 -121.862401) (xy 71.540823 -121.884295) (xy 71.588703 -121.913516) (xy 71.631787 -121.949433)
			(xy 71.669148 -121.991272) (xy 71.699979 -122.038132) (xy 71.723615 -122.089001) (xy 71.739547 -122.142783)
			(xy 71.747431 -122.198318) (xy 71.747098 -122.25441) (xy 71.743316 -122.282204) (xy 71.740378 -122.304678)
			(xy 71.741546 -122.349981) (xy 71.750732 -122.394358) (xy 71.767646 -122.436402) (xy 71.791749 -122.474778)
			(xy 71.822279 -122.50827) (xy 71.858266 -122.535814) (xy 71.87819 -122.546618) (xy 71.902817 -122.559803)
			(xy 71.948243 -122.592311) (xy 71.988444 -122.631097) (xy 72.022558 -122.67533) (xy 72.049858 -122.724065)
			(xy 72.069759 -122.77626) (xy 72.081835 -122.830799) (xy 72.085829 -122.886516) (xy 72.081655 -122.94222)
			(xy 72.069403 -122.99672) (xy 72.049334 -123.048851) (xy 72.021877 -123.097498) (xy 71.98762 -123.14162)
			(xy 71.947295 -123.180276) (xy 71.901763 -123.212637) (xy 71.852 -123.238013) (xy 71.799067 -123.255861)
			(xy 71.744098 -123.265798) (xy 71.688267 -123.267614) (xy 71.632769 -123.261268) (xy 71.578789 -123.246897)
			(xy 71.527481 -123.224808) (xy 71.479944 -123.195473) (xy 71.437192 -123.159519) (xy 71.400141 -123.117715)
			(xy 71.369582 -123.070954) (xy 71.346169 -123.020238) (xy 71.330402 -122.966649) (xy 71.322618 -122.911334)
			(xy 71.322984 -122.855475) (xy 71.326756 -122.827796) (xy 71.329709 -122.805324) (xy 71.328541 -122.760019)
			(xy 71.319354 -122.715639) (xy 71.302438 -122.673594) (xy 71.278332 -122.635218) (xy 71.247798 -122.601727)
			(xy 71.211807 -122.574185) (xy 71.191882 -122.563382) (xy 71.166659 -122.549809) (xy 71.120228 -122.516271)
			(xy 71.099426 -122.49658) (xy 71.083477 -122.481625) (xy 71.047446 -122.456865) (xy 71.007708 -122.438638)
			(xy 70.965437 -122.427483) (xy 70.92188 -122.423727) (xy 70.878323 -122.427483) (xy 70.836052 -122.438638)
			(xy 70.796314 -122.456865) (xy 70.760283 -122.481625) (xy 70.744334 -122.49658) (xy 70.723963 -122.515765)
			(xy 70.678695 -122.548655) (xy 70.629107 -122.574579) (xy 70.576264 -122.59298) (xy 70.5213 -122.603465)
			(xy 70.465394 -122.605807) (xy 70.409745 -122.599957) (xy 70.355549 -122.58604) (xy 70.303966 -122.564355)
			(xy 70.256105 -122.535367) (xy 70.212992 -122.499698) (xy 70.175553 -122.458113) (xy 70.14459 -122.411505)
			(xy 70.120768 -122.360874) (xy 70.104599 -122.307306) (xy 70.096428 -122.251951) (xy 59.859911 -122.251951)
			(xy 59.845897 -122.298531) (xy 59.822225 -122.349028) (xy 59.791452 -122.395541) (xy 59.754235 -122.437078)
			(xy 59.711367 -122.472753) (xy 59.663761 -122.501807) (xy 59.612432 -122.523619) (xy 59.558475 -122.537725)
			(xy 59.503038 -122.543825) (xy 59.447304 -122.541788) (xy 59.392461 -122.531658) (xy 59.339677 -122.513651)
			(xy 59.290077 -122.48815) (xy 59.244719 -122.455699) (xy 59.20457 -122.41699) (xy 59.170484 -122.372847)
			(xy 59.143188 -122.324212) (xy 59.123265 -122.272121) (xy 59.111139 -122.217684) (xy 59.107068 -122.162062)
			(xy 58.2678 -122.162062) (xy 58.240091 -122.178973) (xy 58.188762 -122.200785) (xy 58.134805 -122.214891)
			(xy 58.079368 -122.220991) (xy 58.023634 -122.218954) (xy 57.968791 -122.208824) (xy 57.916007 -122.190817)
			(xy 57.866407 -122.165316) (xy 57.821049 -122.132865) (xy 57.7809 -122.094156) (xy 57.746814 -122.050013)
			(xy 57.719518 -122.001378) (xy 57.699595 -121.949287) (xy 57.687469 -121.89485) (xy 57.683398 -121.839228)
			(xy 56.870626 -121.839228) (xy 56.876073 -121.887014) (xy 56.874443 -121.941696) (xy 56.865021 -121.995586)
			(xy 56.848 -122.047577) (xy 56.823728 -122.096606) (xy 56.792704 -122.141665) (xy 56.755564 -122.181832)
			(xy 56.713067 -122.216284) (xy 56.666087 -122.244314) (xy 56.615585 -122.265348) (xy 56.562597 -122.278954)
			(xy 56.508209 -122.284854) (xy 56.453536 -122.282927) (xy 56.399699 -122.273212) (xy 56.347801 -122.255908)
			(xy 56.298906 -122.23137) (xy 56.254015 -122.200102) (xy 56.214051 -122.162743) (xy 56.179831 -122.12006)
			(xy 56.152056 -122.072928) (xy 56.131298 -122.022313) (xy 56.11798 -121.969251) (xy 56.112376 -121.914832)
			(xy 53.850794 -121.914832) (xy 53.850794 -123.535186) (xy 53.851294 -123.558228) (xy 53.859604 -123.603558)
			(xy 53.875954 -123.646645) (xy 53.899807 -123.686076) (xy 53.930381 -123.720558) (xy 53.966673 -123.74896)
			(xy 54.007493 -123.77035) (xy 54.051502 -123.784027) (xy 54.097255 -123.789541) (xy 54.120288 -123.788678)
			(xy 54.151757 -123.78641) (xy 54.214673 -123.791072) (xy 54.275963 -123.806031) (xy 54.3052 -123.817888)
			(xy 54.327259 -123.82773) (xy 54.368917 -123.852185) (xy 54.388258 -123.866656) (xy 54.406884 -123.879389)
			(xy 54.447627 -123.898759) (xy 54.49115 -123.91063) (xy 54.536086 -123.914629) (xy 54.581022 -123.91063)
			(xy 54.624545 -123.898759) (xy 54.665288 -123.879389) (xy 54.683914 -123.866656) (xy 54.706542 -123.849827)
			(xy 54.755764 -123.822311) (xy 54.8085 -123.802338) (xy 54.863601 -123.790345) (xy 54.919867 -123.786591)
			(xy 54.976073 -123.791159) (xy 55.030994 -123.80395) (xy 55.083436 -123.824684) (xy 55.132254 -123.85291)
			(xy 55.176387 -123.888013) (xy 55.214873 -123.92923) (xy 55.246874 -123.975661) (xy 55.271693 -124.026297)
			(xy 55.28879 -124.080034) (xy 55.297791 -124.135702) (xy 55.298502 -124.192089) (xy 55.290907 -124.247966)
			(xy 55.275171 -124.302117) (xy 55.263796 -124.32792) (xy 55.255499 -124.348357) (xy 55.245292 -124.391263)
			(xy 55.242644 -124.435287) (xy 55.247635 -124.479107) (xy 55.260115 -124.521408) (xy 55.279709 -124.56092)
			(xy 55.305829 -124.596456) (xy 55.337692 -124.626951) (xy 55.374339 -124.651488) (xy 55.414672 -124.669331)
			(xy 55.45748 -124.679944) (xy 55.479442 -124.681996) (xy 55.61711 -124.681996) (xy 55.925212 -124.990098)
			(xy 56.44515 -124.990098) (xy 56.56834 -124.881894) (xy 56.577738 -124.842524) (xy 56.584798 -124.815032)
			(xy 56.605938 -124.762358) (xy 56.634647 -124.713396) (xy 56.67029 -124.669226) (xy 56.712081 -124.630821)
			(xy 56.759099 -124.599028) (xy 56.810307 -124.574549) (xy 56.864575 -124.557923) (xy 56.920707 -124.549518)
			(xy 56.977465 -124.549518) (xy 57.033597 -124.557923) (xy 57.087865 -124.574549) (xy 57.139073 -124.599028)
			(xy 57.186091 -124.630821) (xy 57.227882 -124.669226) (xy 57.263525 -124.713396) (xy 57.292234 -124.762358)
			(xy 57.313374 -124.815032) (xy 57.320434 -124.842524) (xy 57.329832 -124.881894) (xy 57.342228 -124.892782)
			(xy 66.654839 -124.892782) (xy 66.660597 -124.838306) (xy 66.674085 -124.785214) (xy 66.695028 -124.734596)
			(xy 66.722994 -124.687493) (xy 66.757408 -124.644874) (xy 66.797564 -124.607613) (xy 66.842635 -124.576479)
			(xy 66.891695 -124.552109) (xy 66.943736 -124.535006) (xy 66.997688 -124.525521) (xy 67.052441 -124.523848)
			(xy 67.106872 -124.530023) (xy 67.159859 -124.543918) (xy 67.210315 -124.565247) (xy 67.257203 -124.593573)
			(xy 67.299557 -124.628313) (xy 67.318382 -124.648214) (xy 67.333632 -124.66416) (xy 67.368612 -124.691047)
			(xy 67.407708 -124.711492) (xy 67.449747 -124.72488) (xy 67.493465 -124.73081) (xy 67.537551 -124.729104)
			(xy 67.580681 -124.719813) (xy 67.621559 -124.703216) (xy 67.658958 -124.679811) (xy 67.691755 -124.650301)
			(xy 67.705732 -124.633228) (xy 67.723011 -124.611975) (xy 67.762591 -124.574114) (xy 67.807179 -124.542301)
			(xy 67.855857 -124.517192) (xy 67.907626 -124.499303) (xy 67.961421 -124.489) (xy 68.016136 -124.486496)
			(xy 68.070648 -124.491842) (xy 68.123834 -124.504928) (xy 68.174603 -124.525486) (xy 68.22191 -124.553092)
			(xy 68.264782 -124.58718) (xy 68.30234 -124.627048) (xy 68.33381 -124.671877) (xy 68.358547 -124.720746)
			(xy 68.37604 -124.77265) (xy 68.385931 -124.826523) (xy 68.388017 -124.881256) (xy 68.382255 -124.935724)
			(xy 68.368762 -124.988809) (xy 68.347817 -125.039419) (xy 68.31985 -125.086513) (xy 68.285435 -125.129125)
			(xy 68.245281 -125.166376) (xy 68.200213 -125.197503) (xy 68.151156 -125.221865) (xy 68.09912 -125.238961)
			(xy 68.045174 -125.24844) (xy 67.990426 -125.250108) (xy 67.936003 -125.243929) (xy 67.883023 -125.230031)
			(xy 67.832575 -125.2087) (xy 67.785695 -125.180373) (xy 67.743349 -125.145634) (xy 67.724528 -125.125734)
			(xy 67.709271 -125.109794) (xy 67.674294 -125.082902) (xy 67.635199 -125.062452) (xy 67.593161 -125.04906)
			(xy 67.549442 -125.043127) (xy 67.505355 -125.044833) (xy 67.462225 -125.054124) (xy 67.421346 -125.070723)
			(xy 67.383948 -125.094131) (xy 67.351153 -125.123645) (xy 67.337178 -125.14072) (xy 67.319952 -125.162019)
			(xy 67.280372 -125.199889) (xy 67.235783 -125.231711) (xy 67.187101 -125.256829) (xy 67.135329 -125.274727)
			(xy 67.081528 -125.285037) (xy 67.026807 -125.287548) (xy 66.972288 -125.282208) (xy 66.919094 -125.269126)
			(xy 66.868317 -125.248571) (xy 66.821002 -125.220967) (xy 66.77812 -125.18688) (xy 66.740553 -125.147011)
			(xy 66.709074 -125.10218) (xy 66.68433 -125.053308) (xy 66.666829 -125.001399) (xy 66.656931 -124.947522)
			(xy 66.654839 -124.892782) (xy 57.342228 -124.892782) (xy 57.453022 -124.990098) (xy 57.938924 -124.990098)
			(xy 59.790874 -126.842048) (xy 68.588716 -126.842048) (xy 68.595217 -126.789231) (xy 68.609701 -126.738024)
			(xy 68.631829 -126.689627) (xy 68.661082 -126.645172) (xy 68.678552 -126.625096) (xy 68.69369 -126.607642)
			(xy 68.718018 -126.568369) (xy 68.734842 -126.525344) (xy 68.743607 -126.479986) (xy 68.744025 -126.43379)
			(xy 68.73608 -126.388281) (xy 68.720036 -126.34496) (xy 68.696421 -126.305254) (xy 68.6816 -126.28753)
			(xy 68.664485 -126.267147) (xy 68.635971 -126.222211) (xy 68.614647 -126.17345) (xy 68.601013 -126.122006)
			(xy 68.595388 -126.069085) (xy 68.597905 -126.015925) (xy 68.608503 -125.963771) (xy 68.626936 -125.913845)
			(xy 68.65277 -125.867317) (xy 68.685402 -125.825275) (xy 68.724067 -125.788704) (xy 68.767858 -125.758462)
			(xy 68.815752 -125.735256) (xy 68.866626 -125.719629) (xy 68.919289 -125.711949) (xy 68.972506 -125.712393)
			(xy 69.025033 -125.720953) (xy 69.075639 -125.737428) (xy 69.123138 -125.761431) (xy 69.166418 -125.792401)
			(xy 69.204466 -125.829612) (xy 69.236391 -125.872194) (xy 69.261444 -125.919148) (xy 69.262622 -125.922511)
			(xy 72.798676 -125.922511) (xy 72.798676 -125.869213) (xy 72.806619 -125.816509) (xy 72.822329 -125.765579)
			(xy 72.845455 -125.717558) (xy 72.875479 -125.673521) (xy 72.911731 -125.63445) (xy 72.953402 -125.601219)
			(xy 72.99956 -125.57457) (xy 73.049174 -125.555098) (xy 73.101136 -125.543238) (xy 73.154286 -125.539255)
			(xy 73.207436 -125.543238) (xy 73.259398 -125.555098) (xy 73.309012 -125.57457) (xy 73.35517 -125.601219)
			(xy 73.396841 -125.63445) (xy 73.433093 -125.673521) (xy 73.463117 -125.717558) (xy 73.486243 -125.765579)
			(xy 73.501953 -125.816509) (xy 73.509896 -125.869213) (xy 73.510394 -125.895862) (xy 73.509896 -125.922511)
			(xy 73.501953 -125.975215) (xy 73.486243 -126.026145) (xy 73.463117 -126.074166) (xy 73.433093 -126.118203)
			(xy 73.396841 -126.157274) (xy 73.35517 -126.190505) (xy 73.309012 -126.217154) (xy 73.259398 -126.236626)
			(xy 73.207436 -126.248486) (xy 73.154286 -126.25247) (xy 73.101136 -126.248486) (xy 73.049174 -126.236626)
			(xy 72.99956 -126.217154) (xy 72.953402 -126.190505) (xy 72.911731 -126.157274) (xy 72.875479 -126.118203)
			(xy 72.845455 -126.074166) (xy 72.822329 -126.026145) (xy 72.806619 -125.975215) (xy 72.798676 -125.922511)
			(xy 69.262622 -125.922511) (xy 69.27904 -125.969374) (xy 69.288765 -126.021698) (xy 69.290393 -126.074893)
			(xy 69.283885 -126.127713) (xy 69.269393 -126.178922) (xy 69.247257 -126.227319) (xy 69.217996 -126.271773)
			(xy 69.200522 -126.291848) (xy 69.185342 -126.309267) (xy 69.161019 -126.348548) (xy 69.1442 -126.39158)
			(xy 69.13544 -126.436944) (xy 69.135029 -126.483144) (xy 69.142979 -126.528657) (xy 69.159029 -126.571982)
			(xy 69.18265 -126.61169) (xy 69.197474 -126.629414) (xy 69.214616 -126.649771) (xy 69.243126 -126.694705)
			(xy 69.264447 -126.743463) (xy 69.278078 -126.794904) (xy 69.282425 -126.835818) (xy 71.7697 -126.835818)
			(xy 71.776931 -126.782382) (xy 71.791788 -126.730546) (xy 71.813962 -126.681393) (xy 71.842989 -126.63595)
			(xy 71.878263 -126.595165) (xy 71.919048 -126.55989) (xy 71.964491 -126.530863) (xy 72.013644 -126.508689)
			(xy 72.065479 -126.493831) (xy 72.118915 -126.4866) (xy 72.172835 -126.487147) (xy 72.226113 -126.495461)
			(xy 72.277637 -126.511367) (xy 72.32633 -126.534534) (xy 72.371174 -126.564477) (xy 72.391524 -126.58217)
			(xy 72.40862 -126.596854) (xy 72.446895 -126.620636) (xy 72.488765 -126.637292) (xy 72.532917 -126.6463)
			(xy 72.577965 -126.647378) (xy 72.622497 -126.640491) (xy 72.665115 -126.625855) (xy 72.704483 -126.60393)
			(xy 72.722232 -126.590044) (xy 72.743251 -126.573503) (xy 72.789361 -126.546403) (xy 72.839082 -126.526694)
			(xy 72.891236 -126.514842) (xy 72.944592 -126.511127) (xy 72.997886 -126.515637) (xy 73.049858 -126.528265)
			(xy 73.099279 -126.548713) (xy 73.144981 -126.576497) (xy 73.185882 -126.610959) (xy 73.194389 -126.620724)
			(xy 75.15037 -126.620724) (xy 75.156483 -126.565556) (xy 75.170526 -126.511856) (xy 75.192203 -126.460759)
			(xy 75.221056 -126.413342) (xy 75.256476 -126.370608) (xy 75.297716 -126.333457) (xy 75.343903 -126.302675)
			(xy 75.394064 -126.278911) (xy 75.44714 -126.262667) (xy 75.502008 -126.254286) (xy 75.557513 -126.253945)
			(xy 75.585066 -126.257304) (xy 75.607833 -126.260075) (xy 75.653656 -126.258202) (xy 75.698399 -126.248133)
			(xy 75.740607 -126.230193) (xy 75.778907 -126.204966) (xy 75.812056 -126.173273) (xy 75.838975 -126.136142)
			(xy 75.85879 -126.094782) (xy 75.870857 -126.050536) (xy 75.874783 -126.004843) (xy 75.873102 -125.981968)
			(xy 75.871022 -125.954294) (xy 75.873937 -125.898874) (xy 75.884854 -125.844462) (xy 75.903539 -125.792206)
			(xy 75.9296 -125.74321) (xy 75.962486 -125.698507) (xy 76.001503 -125.659042) (xy 76.045827 -125.625647)
			(xy 76.094522 -125.599027) (xy 76.146561 -125.579745) (xy 76.200844 -125.568208) (xy 76.256227 -125.564659)
			(xy 76.311539 -125.569172) (xy 76.365614 -125.581653) (xy 76.417309 -125.601839) (xy 76.465533 -125.629303)
			(xy 76.509268 -125.663465) (xy 76.547592 -125.703604) (xy 76.579694 -125.748873) (xy 76.604897 -125.798316)
			(xy 76.62267 -125.850889) (xy 76.632636 -125.905483) (xy 76.634587 -125.960945) (xy 76.628479 -126.016104)
			(xy 76.614443 -126.069796) (xy 76.592774 -126.120887) (xy 76.563931 -126.168299) (xy 76.528521 -126.21103)
			(xy 76.487293 -126.24818) (xy 76.441117 -126.278962) (xy 76.390967 -126.302729) (xy 76.337903 -126.318977)
			(xy 76.283044 -126.327365) (xy 76.227549 -126.327714) (xy 76.2 -126.32436) (xy 76.177234 -126.321592)
			(xy 76.131413 -126.32347) (xy 76.086673 -126.333544) (xy 76.044469 -126.351485) (xy 76.006171 -126.376712)
			(xy 75.973024 -126.408404) (xy 75.946104 -126.445532) (xy 75.926288 -126.486889) (xy 75.914218 -126.531132)
			(xy 75.910286 -126.576822) (xy 75.911964 -126.599696) (xy 75.914023 -126.627377) (xy 75.91111 -126.682806)
			(xy 75.900196 -126.737228) (xy 75.88151 -126.789493) (xy 75.855447 -126.838499) (xy 75.822558 -126.883211)
			(xy 75.783536 -126.922684) (xy 75.739206 -126.956086) (xy 75.690503 -126.982711) (xy 75.638456 -127.001996)
			(xy 75.584164 -127.013536) (xy 75.528772 -127.017086) (xy 75.47345 -127.012572) (xy 75.419367 -127.000088)
			(xy 75.367664 -126.979898) (xy 75.319433 -126.952428) (xy 75.275691 -126.918259) (xy 75.237363 -126.878112)
			(xy 75.205258 -126.832834) (xy 75.180053 -126.783381) (xy 75.162281 -126.730798) (xy 75.152316 -126.676195)
			(xy 75.15037 -126.620724) (xy 73.194389 -126.620724) (xy 73.221015 -126.651286) (xy 73.249549 -126.696523)
			(xy 73.27081 -126.7456) (xy 73.284294 -126.797357) (xy 73.289683 -126.850569) (xy 73.286849 -126.903978)
			(xy 73.275859 -126.956322) (xy 73.256973 -127.006361) (xy 73.230638 -127.052912) (xy 73.197477 -127.094876)
			(xy 73.158273 -127.131258) (xy 73.113955 -127.161199) (xy 73.06557 -127.18399) (xy 73.014262 -127.199093)
			(xy 72.961245 -127.20615) (xy 72.907773 -127.204995) (xy 72.855111 -127.195654) (xy 72.804503 -127.178349)
			(xy 72.757148 -127.153489) (xy 72.714164 -127.121661) (xy 72.676568 -127.08362) (xy 72.66051 -127.06223)
			(xy 72.65122 -127.050042) (xy 72.627877 -127.030194) (xy 72.600471 -127.016492) (xy 72.570587 -127.009728)
			(xy 72.539952 -127.010293) (xy 72.510337 -127.018153) (xy 72.483455 -127.032856) (xy 72.460859 -127.053549)
			(xy 72.451976 -127.06604) (xy 72.444397 -127.077154) (xy 72.42787 -127.098383) (xy 72.418956 -127.108458)
			(xy 72.40423 -127.125548) (xy 72.38037 -127.163828) (xy 72.363647 -127.205719) (xy 72.354587 -127.249907)
			(xy 72.353475 -127.294999) (xy 72.360345 -127.33958) (xy 72.374983 -127.382245) (xy 72.396926 -127.421654)
			(xy 72.410828 -127.43942) (xy 72.426995 -127.459939) (xy 72.453626 -127.504879) (xy 72.473222 -127.553301)
			(xy 72.485342 -127.604114) (xy 72.48971 -127.656168) (xy 72.489512 -127.65913) (xy 73.394313 -127.65913)
			(xy 73.398388 -127.606049) (xy 73.410518 -127.554213) (xy 73.430419 -127.504836) (xy 73.457624 -127.459075)
			(xy 73.491496 -127.418003) (xy 73.53124 -127.382584) (xy 73.575925 -127.353646) (xy 73.624504 -127.331868)
			(xy 73.675837 -127.317762) (xy 73.728723 -127.311656) (xy 73.781921 -127.313695) (xy 73.834184 -127.323831)
			(xy 73.884287 -127.341826) (xy 73.931056 -127.367258) (xy 73.973395 -127.399532) (xy 74.010311 -127.43789)
			(xy 74.040939 -127.481434) (xy 74.064561 -127.529143) (xy 74.080624 -127.579899) (xy 74.088751 -127.632512)
			(xy 74.08926 -127.65913) (xy 74.088751 -127.685748) (xy 74.080624 -127.738361) (xy 74.064561 -127.789117)
			(xy 74.040939 -127.836826) (xy 74.010311 -127.88037) (xy 73.973395 -127.918728) (xy 73.931056 -127.951002)
			(xy 73.884287 -127.976434) (xy 73.834184 -127.994429) (xy 73.781921 -128.004565) (xy 73.728723 -128.006604)
			(xy 73.675837 -128.000498) (xy 73.624504 -127.986392) (xy 73.575925 -127.964614) (xy 73.53124 -127.935676)
			(xy 73.491496 -127.900257) (xy 73.457624 -127.859185) (xy 73.430419 -127.813424) (xy 73.410518 -127.764047)
			(xy 73.398388 -127.712211) (xy 73.394313 -127.65913) (xy 72.489512 -127.65913) (xy 72.486229 -127.70829)
			(xy 72.474977 -127.759301) (xy 72.456209 -127.808051) (xy 72.430348 -127.853438) (xy 72.397977 -127.894437)
			(xy 72.359829 -127.930122) (xy 72.316764 -127.959689) (xy 72.269754 -127.982468) (xy 72.219863 -127.997947)
			(xy 72.168215 -128.005774) (xy 72.115977 -128.005774) (xy 72.064329 -127.997947) (xy 72.014438 -127.982468)
			(xy 71.967428 -127.959689) (xy 71.924363 -127.930122) (xy 71.886215 -127.894437) (xy 71.853844 -127.853438)
			(xy 71.827983 -127.808051) (xy 71.809215 -127.759301) (xy 71.797963 -127.70829) (xy 71.794482 -127.656168)
			(xy 71.79885 -127.604114) (xy 71.81097 -127.553301) (xy 71.830566 -127.504879) (xy 71.857197 -127.459939)
			(xy 71.873364 -127.43942) (xy 71.88729 -127.421673) (xy 71.909221 -127.382254) (xy 71.923849 -127.339583)
			(xy 71.930715 -127.294999) (xy 71.929603 -127.249904) (xy 71.920549 -127.205714) (xy 71.903836 -127.163815)
			(xy 71.87999 -127.125525) (xy 71.865236 -127.108458) (xy 71.847579 -127.088076) (xy 71.817635 -127.043232)
			(xy 71.794468 -126.994539) (xy 71.778561 -126.943016) (xy 71.770248 -126.889738) (xy 71.7697 -126.835818)
			(xy 69.282425 -126.835818) (xy 69.283701 -126.847822) (xy 69.281184 -126.900978) (xy 69.270586 -126.953128)
			(xy 69.252155 -127.00305) (xy 69.226323 -127.049576) (xy 69.193694 -127.091615) (xy 69.155033 -127.128183)
			(xy 69.111244 -127.158424) (xy 69.063355 -127.18163) (xy 69.012485 -127.197258) (xy 68.959827 -127.20494)
			(xy 68.906613 -127.204498) (xy 68.854089 -127.195942) (xy 68.803486 -127.179471) (xy 68.755988 -127.155473)
			(xy 68.712709 -127.124508) (xy 68.67466 -127.087303) (xy 68.642735 -127.044727) (xy 68.617679 -126.997779)
			(xy 68.600079 -126.947558) (xy 68.590349 -126.895239) (xy 68.588716 -126.842048) (xy 59.790874 -126.842048)
			(xy 59.925204 -126.976378) (xy 59.925204 -127.684699) (xy 61.394431 -127.684699) (xy 61.394432 -127.631482)
			(xy 61.402555 -127.578889) (xy 61.418609 -127.528152) (xy 61.442217 -127.480459) (xy 61.472828 -127.436927)
			(xy 61.509723 -127.398577) (xy 61.552039 -127.366307) (xy 61.598784 -127.340872) (xy 61.648863 -127.322869)
			(xy 61.701103 -127.31272) (xy 61.754279 -127.310662) (xy 61.807147 -127.316743) (xy 61.858468 -127.33082)
			(xy 61.907039 -127.352565) (xy 61.951723 -127.381468) (xy 61.971936 -127.39878) (xy 61.98955 -127.413785)
			(xy 62.029098 -127.437797) (xy 62.072336 -127.454259) (xy 62.11784 -127.462628) (xy 62.164106 -127.462628)
			(xy 62.20961 -127.454259) (xy 62.252848 -127.437797) (xy 62.292396 -127.413785) (xy 62.31001 -127.39878)
			(xy 62.329218 -127.38233) (xy 62.371469 -127.354544) (xy 62.417304 -127.33318) (xy 62.465753 -127.318691)
			(xy 62.515791 -127.311381) (xy 62.566361 -127.311407) (xy 62.616391 -127.318767) (xy 62.664826 -127.333306)
			(xy 62.710639 -127.354716) (xy 62.752862 -127.382545) (xy 62.772036 -127.399034) (xy 62.789638 -127.414025)
			(xy 62.829158 -127.438012) (xy 62.872364 -127.454458) (xy 62.917831 -127.462818) (xy 62.964061 -127.462818)
			(xy 63.009528 -127.454458) (xy 63.052734 -127.438012) (xy 63.092254 -127.414025) (xy 63.109856 -127.399034)
			(xy 63.129042 -127.38253) (xy 63.171297 -127.354679) (xy 63.217147 -127.333257) (xy 63.265621 -127.318719)
			(xy 63.315692 -127.311372) (xy 63.3663 -127.311372) (xy 63.416371 -127.318719) (xy 63.464845 -127.333257)
			(xy 63.510695 -127.354679) (xy 63.55295 -127.38253) (xy 63.572136 -127.399034) (xy 63.589738 -127.414025)
			(xy 63.629258 -127.438012) (xy 63.672464 -127.454458) (xy 63.717931 -127.462818) (xy 63.764161 -127.462818)
			(xy 63.809628 -127.454458) (xy 63.852834 -127.438012) (xy 63.892354 -127.414025) (xy 63.909956 -127.399034)
			(xy 63.929118 -127.382528) (xy 63.971342 -127.354689) (xy 64.017157 -127.33327) (xy 64.065595 -127.318725)
			(xy 64.115631 -127.311362) (xy 64.166205 -127.311335) (xy 64.216249 -127.318646) (xy 64.264702 -127.33314)
			(xy 64.31054 -127.354511) (xy 64.352792 -127.382306) (xy 64.371982 -127.39878) (xy 64.389596 -127.413785)
			(xy 64.429144 -127.437797) (xy 64.472382 -127.454259) (xy 64.517886 -127.462628) (xy 64.564152 -127.462628)
			(xy 64.609656 -127.454259) (xy 64.652894 -127.437797) (xy 64.692442 -127.413785) (xy 64.710056 -127.39878)
			(xy 64.729974 -127.381619) (xy 64.774064 -127.352981) (xy 64.821968 -127.331318) (xy 64.872591 -127.317123)
			(xy 64.924774 -127.310722) (xy 64.977326 -127.312261) (xy 65.029046 -127.321705) (xy 65.078751 -127.338837)
			(xy 65.125305 -127.363267) (xy 65.167644 -127.394436) (xy 65.204801 -127.431632) (xy 65.235925 -127.474003)
			(xy 65.260307 -127.520583) (xy 65.277387 -127.570306) (xy 65.286777 -127.622035) (xy 65.288261 -127.674589)
			(xy 65.281805 -127.726766) (xy 65.267558 -127.777374) (xy 65.245844 -127.825255) (xy 65.21716 -127.869315)
			(xy 65.200022 -127.889254) (xy 65.185069 -127.906886) (xy 65.161083 -127.9464) (xy 65.144637 -127.9896)
			(xy 65.136274 -128.035061) (xy 65.136269 -128.081285) (xy 65.144623 -128.126748) (xy 65.161059 -128.169952)
			(xy 65.185037 -128.209471) (xy 65.200022 -128.227074) (xy 65.216538 -128.24625) (xy 65.244385 -128.288507)
			(xy 65.265804 -128.334359) (xy 65.28034 -128.382834) (xy 65.287684 -128.432906) (xy 65.287683 -128.483514)
			(xy 65.280335 -128.533586) (xy 65.265796 -128.582061) (xy 65.244375 -128.627911) (xy 65.216525 -128.670167)
			(xy 65.200022 -128.689354) (xy 65.185069 -128.706986) (xy 65.161083 -128.7465) (xy 65.144637 -128.7897)
			(xy 65.136274 -128.835161) (xy 65.136269 -128.881385) (xy 65.144623 -128.926848) (xy 65.161059 -128.970052)
			(xy 65.185037 -129.009571) (xy 65.200022 -129.027174) (xy 65.217142 -129.047123) (xy 65.24582 -129.091179)
			(xy 65.267528 -129.139054) (xy 65.281771 -129.189655) (xy 65.288224 -129.241825) (xy 65.286739 -129.294371)
			(xy 65.277349 -129.346093) (xy 65.26027 -129.395808) (xy 65.235891 -129.44238) (xy 65.204771 -129.484746)
			(xy 65.16762 -129.521935) (xy 65.125287 -129.5531) (xy 65.07874 -129.577527) (xy 65.029042 -129.594658)
			(xy 64.97733 -129.604101) (xy 64.924786 -129.605641) (xy 64.872609 -129.599243) (xy 64.821994 -129.585052)
			(xy 64.774096 -129.563393) (xy 64.73001 -129.534762) (xy 64.710056 -129.517648) (xy 64.692458 -129.502608)
			(xy 64.652925 -129.478535) (xy 64.609682 -129.462028) (xy 64.564162 -129.453635) (xy 64.517876 -129.453635)
			(xy 64.472356 -129.462028) (xy 64.429113 -129.478535) (xy 64.38958 -129.502608) (xy 64.371982 -129.517648)
			(xy 64.351176 -129.535386) (xy 64.305146 -129.564881) (xy 64.255063 -129.586798) (xy 64.202163 -129.600596)
			(xy 64.147755 -129.605935) (xy 64.093183 -129.602682) (xy 64.039795 -129.590918) (xy 63.988909 -129.570933)
			(xy 63.941784 -129.543222) (xy 63.899584 -129.508468) (xy 63.86335 -129.46753) (xy 63.848234 -129.44475)
			(xy 63.839234 -129.431557) (xy 63.815928 -129.409737) (xy 63.787936 -129.394384) (xy 63.757009 -129.38646)
			(xy 63.725083 -129.38646) (xy 63.694156 -129.394384) (xy 63.666164 -129.409737) (xy 63.642858 -129.431557)
			(xy 63.633858 -129.44475) (xy 63.628321 -129.45337) (xy 63.616375 -129.470018) (xy 63.609982 -129.478024)
			(xy 63.596105 -129.495782) (xy 63.57418 -129.535151) (xy 63.559542 -129.577769) (xy 63.552651 -129.622302)
			(xy 63.553722 -129.667351) (xy 63.562723 -129.711506) (xy 63.57937 -129.75338) (xy 63.603141 -129.791662)
			(xy 63.617856 -129.808732) (xy 63.636159 -129.829842) (xy 63.666943 -129.876466) (xy 63.690421 -129.927163)
			(xy 63.706068 -129.980796) (xy 63.713532 -130.036165) (xy 63.713532 -130.036168) (xy 66.16832 -130.036168)
			(xy 66.175784 -129.980793) (xy 66.191431 -129.927153) (xy 66.214911 -129.87645) (xy 66.245697 -129.829821)
			(xy 66.264028 -129.808732) (xy 66.278753 -129.79167) (xy 66.302527 -129.753386) (xy 66.319176 -129.71151)
			(xy 66.328178 -129.667353) (xy 66.329249 -129.622301) (xy 66.322357 -129.577766) (xy 66.307718 -129.535145)
			(xy 66.28579 -129.495774) (xy 66.271902 -129.478024) (xy 66.255077 -129.456546) (xy 66.227621 -129.409403)
			(xy 66.207871 -129.358547) (xy 66.196313 -129.305229) (xy 66.193231 -129.25076) (xy 66.198701 -129.196479)
			(xy 66.212588 -129.14372) (xy 66.234552 -129.093781) (xy 66.264051 -129.047888) (xy 66.281808 -129.027174)
			(xy 66.296835 -129.009601) (xy 66.320824 -128.970076) (xy 66.337268 -128.926864) (xy 66.345626 -128.881391)
			(xy 66.345621 -128.835156) (xy 66.337254 -128.789684) (xy 66.3208 -128.746476) (xy 66.296803 -128.706956)
			(xy 66.281808 -128.689354) (xy 66.265318 -128.670156) (xy 66.237467 -128.627904) (xy 66.216045 -128.582055)
			(xy 66.201506 -128.533583) (xy 66.194158 -128.483513) (xy 66.194157 -128.432907) (xy 66.201502 -128.382837)
			(xy 66.216038 -128.334364) (xy 66.237457 -128.288515) (xy 66.265306 -128.24626) (xy 66.281808 -128.227074)
			(xy 66.296835 -128.209501) (xy 66.320824 -128.169976) (xy 66.337268 -128.126764) (xy 66.345626 -128.081291)
			(xy 66.345621 -128.035056) (xy 66.337254 -127.989584) (xy 66.3208 -127.946376) (xy 66.296803 -127.906856)
			(xy 66.281808 -127.889254) (xy 66.264916 -127.869613) (xy 66.2366 -127.826234) (xy 66.215043 -127.779129)
			(xy 66.200725 -127.729344) (xy 66.193962 -127.677984) (xy 66.194905 -127.626189) (xy 66.203533 -127.57511)
			(xy 66.219655 -127.525879) (xy 66.242913 -127.47959) (xy 66.27279 -127.43727) (xy 66.308623 -127.39986)
			(xy 66.349617 -127.368188) (xy 66.394862 -127.342959) (xy 66.443353 -127.324733) (xy 66.494013 -127.313913)
			(xy 66.545719 -127.31074) (xy 66.597323 -127.315286) (xy 66.647678 -127.327448) (xy 66.695668 -127.346956)
			(xy 66.740226 -127.373379) (xy 66.760598 -127.389382) (xy 66.778333 -127.403324) (xy 66.817755 -127.425253)
			(xy 66.860429 -127.439878) (xy 66.905014 -127.446741) (xy 66.95011 -127.445627) (xy 66.994302 -127.436571)
			(xy 67.036202 -127.419856) (xy 67.074493 -127.396008) (xy 67.09156 -127.381254) (xy 67.112577 -127.362981)
			(xy 67.159037 -127.332275) (xy 67.20955 -127.308825) (xy 67.26299 -127.293153) (xy 67.318167 -127.285607)
			(xy 67.373852 -127.286357) (xy 67.428806 -127.295385) (xy 67.481805 -127.31249) (xy 67.531668 -127.337292)
			(xy 67.577285 -127.369237) (xy 67.61764 -127.407616) (xy 67.651835 -127.451572) (xy 67.679108 -127.500128)
			(xy 67.698851 -127.552201) (xy 67.710626 -127.606632) (xy 67.714169 -127.66221) (xy 67.712251 -127.684542)
			(xy 69.397006 -127.684542) (xy 69.397054 -127.63142) (xy 69.405193 -127.578926) (xy 69.421231 -127.528283)
			(xy 69.444795 -127.480674) (xy 69.475335 -127.437208) (xy 69.512138 -127.398901) (xy 69.554346 -127.366646)
			(xy 69.600974 -127.341195) (xy 69.650934 -127.323142) (xy 69.70306 -127.312909) (xy 69.756137 -127.310733)
			(xy 69.808927 -127.316666) (xy 69.860196 -127.33057) (xy 69.908751 -127.35212) (xy 69.953457 -127.380813)
			(xy 69.973698 -127.398018) (xy 69.99121 -127.412847) (xy 70.03053 -127.436501) (xy 70.073455 -127.452721)
			(xy 70.118592 -127.460979) (xy 70.164479 -127.461009) (xy 70.209627 -127.452809) (xy 70.252572 -127.436646)
			(xy 70.291923 -127.413042) (xy 70.309486 -127.398272) (xy 70.329786 -127.381137) (xy 70.374544 -127.35253)
			(xy 70.423136 -127.331074) (xy 70.47443 -127.317268) (xy 70.527227 -127.311436) (xy 70.580298 -127.313713)
			(xy 70.632402 -127.324046) (xy 70.682324 -127.342194) (xy 70.728901 -127.367733) (xy 70.771044 -127.400068)
			(xy 70.807771 -127.438444) (xy 70.838225 -127.481966) (xy 70.861696 -127.529618) (xy 70.877635 -127.580289)
			(xy 70.885671 -127.632797) (xy 70.885617 -127.685915) (xy 70.877473 -127.738406) (xy 70.86143 -127.789044)
			(xy 70.837861 -127.836649) (xy 70.807318 -127.880108) (xy 70.770512 -127.918408) (xy 70.728302 -127.950657)
			(xy 70.681674 -127.9761) (xy 70.631714 -127.994145) (xy 70.579588 -128.004371) (xy 70.526514 -128.006539)
			(xy 70.473728 -128.000598) (xy 70.422463 -127.986688) (xy 70.373915 -127.965132) (xy 70.329216 -127.936433)
			(xy 70.308978 -127.919226) (xy 70.291407 -127.904469) (xy 70.252101 -127.880806) (xy 70.209189 -127.864578)
			(xy 70.164061 -127.856309) (xy 70.118182 -127.856269) (xy 70.07304 -127.864459) (xy 70.030099 -127.880612)
			(xy 69.990752 -127.904206) (xy 69.97319 -127.918972) (xy 69.952946 -127.936172) (xy 69.908187 -127.964783)
			(xy 69.859593 -127.986243) (xy 69.808298 -128.000053) (xy 69.755498 -128.005889) (xy 69.702425 -128.003616)
			(xy 69.650317 -127.993286) (xy 69.60039 -127.975142) (xy 69.55381 -127.949605) (xy 69.511661 -127.917272)
			(xy 69.474929 -127.878897) (xy 69.444469 -127.835376) (xy 69.420993 -127.787723) (xy 69.405048 -127.737051)
			(xy 69.397006 -127.684542) (xy 67.712251 -127.684542) (xy 67.709403 -127.717696) (xy 67.696432 -127.771855)
			(xy 67.675546 -127.823481) (xy 67.647211 -127.871424) (xy 67.612056 -127.914617) (xy 67.570865 -127.952097)
			(xy 67.547998 -127.967994) (xy 67.535531 -127.976899) (xy 67.514852 -127.999492) (xy 67.500162 -128.026366)
			(xy 67.492309 -128.055969) (xy 67.491747 -128.086591) (xy 67.498509 -128.116463) (xy 67.512204 -128.143857)
			(xy 67.53204 -128.167193) (xy 67.544188 -128.176528) (xy 67.560698 -128.189482) (xy 67.578433 -128.203424)
			(xy 67.617855 -128.225353) (xy 67.660529 -128.239978) (xy 67.705114 -128.246841) (xy 67.75021 -128.245727)
			(xy 67.794402 -128.236671) (xy 67.836302 -128.219956) (xy 67.874593 -128.196108) (xy 67.89166 -128.181354)
			(xy 67.912736 -128.163011) (xy 67.959363 -128.132227) (xy 68.010063 -128.108749) (xy 68.0637 -128.093103)
			(xy 68.119072 -128.085639) (xy 68.174937 -128.086526) (xy 68.230044 -128.095742) (xy 68.283158 -128.113082)
			(xy 68.333088 -128.138157) (xy 68.378714 -128.170405) (xy 68.419016 -128.209103) (xy 68.453089 -128.253383)
			(xy 68.480169 -128.302255) (xy 68.49965 -128.354621) (xy 68.511095 -128.409308) (xy 68.514248 -128.465092)
			(xy 68.509037 -128.520721) (xy 68.495581 -128.574949) (xy 68.474179 -128.62656) (xy 68.445313 -128.674397)
			(xy 68.427854 -128.696212) (xy 68.414221 -128.713462) (xy 68.392411 -128.751632) (xy 68.377497 -128.792987)
			(xy 68.369925 -128.836291) (xy 68.36992 -128.880253) (xy 68.377483 -128.92356) (xy 68.392388 -128.964918)
			(xy 68.414189 -129.003092) (xy 68.427854 -129.020316) (xy 68.445044 -129.041804) (xy 68.473612 -129.088833)
			(xy 68.494952 -129.139553) (xy 68.5086 -129.19286) (xy 68.51426 -129.247594) (xy 68.511808 -129.302566)
			(xy 68.501298 -129.356579) (xy 68.482958 -129.408459) (xy 68.457188 -129.457077) (xy 68.424547 -129.501377)
			(xy 68.385746 -129.540394) (xy 68.341628 -129.57328) (xy 68.293153 -129.59932) (xy 68.241376 -129.617948)
			(xy 68.187422 -129.628757) (xy 68.132465 -129.631514) (xy 68.0777 -129.626159) (xy 68.024318 -129.612807)
			(xy 67.973481 -129.591749) (xy 67.926294 -129.563443) (xy 67.883782 -129.528505) (xy 67.846872 -129.487694)
			(xy 67.831208 -129.46507) (xy 67.822334 -129.452541) (xy 67.799728 -129.431781) (xy 67.772812 -129.417031)
			(xy 67.743149 -129.409148) (xy 67.712462 -129.408588) (xy 67.682532 -129.415385) (xy 67.655096 -129.429144)
			(xy 67.631748 -129.449065) (xy 67.62242 -129.46126) (xy 67.60972 -129.478024) (xy 67.595877 -129.495814)
			(xy 67.573947 -129.535187) (xy 67.559315 -129.577815) (xy 67.552441 -129.622356) (xy 67.553542 -129.667412)
			(xy 67.562583 -129.711564) (xy 67.579279 -129.753426) (xy 67.603106 -129.791682) (xy 67.617848 -129.808732)
			(xy 67.63616 -129.829835) (xy 67.666945 -129.876459) (xy 67.690424 -129.927157) (xy 67.706072 -129.980792)
			(xy 67.713537 -130.036162) (xy 67.712652 -130.092026) (xy 67.703437 -130.147131) (xy 67.686099 -130.200244)
			(xy 67.661025 -130.250172) (xy 67.628779 -130.295798) (xy 67.590083 -130.336098) (xy 67.545803 -130.37017)
			(xy 67.496933 -130.397249) (xy 67.444568 -130.416729) (xy 67.389882 -130.428173) (xy 67.3341 -130.431325)
			(xy 67.278473 -130.426113) (xy 67.224247 -130.412655) (xy 67.172638 -130.391253) (xy 67.124803 -130.362385)
			(xy 67.10299 -130.344926) (xy 67.085766 -130.33126) (xy 67.047589 -130.309455) (xy 67.006229 -130.294547)
			(xy 66.96292 -130.286979) (xy 66.918956 -130.286979) (xy 66.875647 -130.294547) (xy 66.834287 -130.309455)
			(xy 66.79611 -130.33126) (xy 66.778886 -130.344926) (xy 66.757107 -130.36243) (xy 66.709267 -130.391298)
			(xy 66.657653 -130.4127) (xy 66.603422 -130.426157) (xy 66.54779 -130.431368) (xy 66.492003 -130.428214)
			(xy 66.437313 -130.416768) (xy 66.384944 -130.397286) (xy 66.33607 -130.370204) (xy 66.291787 -130.336129)
			(xy 66.253088 -130.295825) (xy 66.220839 -130.250195) (xy 66.195763 -130.200263) (xy 66.178422 -130.147146)
			(xy 66.169206 -130.092036) (xy 66.16832 -130.036168) (xy 63.713532 -130.036168) (xy 63.712647 -130.092027)
			(xy 63.703432 -130.147132) (xy 63.686094 -130.200243) (xy 63.661021 -130.25017) (xy 63.628775 -130.295795)
			(xy 63.59008 -130.336094) (xy 63.545801 -130.370165) (xy 63.496933 -130.397244) (xy 63.444569 -130.416724)
			(xy 63.389884 -130.428168) (xy 63.334104 -130.43132) (xy 63.278478 -130.426109) (xy 63.224253 -130.412652)
			(xy 63.172645 -130.39125) (xy 63.124811 -130.362384) (xy 63.102998 -130.344926) (xy 63.085774 -130.33126)
			(xy 63.047597 -130.309455) (xy 63.006237 -130.294547) (xy 62.962928 -130.286979) (xy 62.918964 -130.286979)
			(xy 62.875655 -130.294547) (xy 62.834295 -130.309455) (xy 62.796118 -130.33126) (xy 62.778894 -130.344926)
			(xy 62.757869 -130.361724) (xy 62.711943 -130.389773) (xy 62.662461 -130.410925) (xy 62.61045 -130.424741)
			(xy 62.556994 -130.430932) (xy 62.503203 -130.42937) (xy 62.450195 -130.420088) (xy 62.399074 -130.403278)
			(xy 62.350902 -130.379291) (xy 62.306681 -130.348624) (xy 62.267331 -130.311916) (xy 62.233669 -130.26993)
			(xy 62.206397 -130.223539) (xy 62.18608 -130.173708) (xy 62.173141 -130.121473) (xy 62.16785 -130.06792)
			(xy 62.170316 -130.014162) (xy 62.180489 -129.961319) (xy 62.198156 -129.910488) (xy 62.222951 -129.862726)
			(xy 62.254357 -129.819027) (xy 62.291721 -129.7803) (xy 62.334268 -129.747349) (xy 62.381111 -129.720861)
			(xy 62.431277 -129.701385) (xy 62.483723 -129.689327) (xy 62.537357 -129.684938) (xy 62.591065 -129.688308)
			(xy 62.64373 -129.699368) (xy 62.694257 -129.717888) (xy 62.741595 -129.743482) (xy 62.784759 -129.775619)
			(xy 62.822852 -129.81363) (xy 62.839346 -129.834894) (xy 62.849861 -129.848086) (xy 62.876431 -129.868857)
			(xy 62.907518 -129.881931) (xy 62.940946 -129.886393) (xy 62.974374 -129.881931) (xy 63.005461 -129.868857)
			(xy 63.032031 -129.848086) (xy 63.042546 -129.834894) (xy 63.064136 -129.808732) (xy 63.078863 -129.79167)
			(xy 63.102646 -129.753389) (xy 63.119301 -129.711512) (xy 63.128305 -129.667354) (xy 63.129377 -129.622299)
			(xy 63.122482 -129.577763) (xy 63.107838 -129.535141) (xy 63.085902 -129.495773) (xy 63.07201 -129.478024)
			(xy 63.055184 -129.456547) (xy 63.027727 -129.409403) (xy 63.007977 -129.358547) (xy 62.996419 -129.30523)
			(xy 62.993337 -129.25076) (xy 62.998807 -129.196479) (xy 63.012695 -129.14372) (xy 63.034659 -129.093781)
			(xy 63.064159 -129.047888) (xy 63.081916 -129.027174) (xy 63.096943 -129.009601) (xy 63.120931 -128.970076)
			(xy 63.137375 -128.926864) (xy 63.145732 -128.881391) (xy 63.145727 -128.835156) (xy 63.13736 -128.789684)
			(xy 63.120907 -128.746476) (xy 63.096911 -128.706956) (xy 63.081916 -128.689354) (xy 63.064129 -128.668567)
			(xy 63.034562 -128.62254) (xy 63.012579 -128.572446) (xy 62.998726 -128.519523) (xy 62.993344 -128.465083)
			(xy 62.996567 -128.410473) (xy 63.008315 -128.357044) (xy 63.028297 -128.306119) (xy 63.056019 -128.258957)
			(xy 63.090794 -128.216727) (xy 63.131762 -128.180474) (xy 63.15456 -128.165352) (xy 63.167785 -128.156397)
			(xy 63.189601 -128.133081) (xy 63.204948 -128.10508) (xy 63.212867 -128.074146) (xy 63.212862 -128.042215)
			(xy 63.204934 -128.011284) (xy 63.189578 -127.983288) (xy 63.167755 -127.959978) (xy 63.15456 -127.950976)
			(xy 63.142799 -127.943334) (xy 63.120419 -127.926421) (xy 63.109856 -127.917194) (xy 63.092254 -127.902203)
			(xy 63.052734 -127.878216) (xy 63.009528 -127.86177) (xy 62.964061 -127.85341) (xy 62.917831 -127.85341)
			(xy 62.872364 -127.86177) (xy 62.829158 -127.878216) (xy 62.789638 -127.902203) (xy 62.772036 -127.917194)
			(xy 62.752882 -127.933711) (xy 62.710659 -127.961555) (xy 62.664843 -127.982978) (xy 62.616403 -127.997525)
			(xy 62.566365 -128.00489) (xy 62.515787 -128.004916) (xy 62.465742 -127.997602) (xy 62.417287 -127.983104)
			(xy 62.371449 -127.961727) (xy 62.329198 -127.933926) (xy 62.31001 -127.917448) (xy 62.292412 -127.902408)
			(xy 62.252879 -127.878335) (xy 62.209636 -127.861828) (xy 62.164116 -127.853435) (xy 62.11783 -127.853435)
			(xy 62.07231 -127.861828) (xy 62.029067 -127.878335) (xy 61.989534 -127.902408) (xy 61.971936 -127.917448)
			(xy 61.951708 -127.934743) (xy 61.907023 -127.963643) (xy 61.858451 -127.985386) (xy 61.807129 -127.999461)
			(xy 61.754261 -128.005539) (xy 61.701084 -128.003478) (xy 61.648845 -127.993326) (xy 61.598767 -127.97532)
			(xy 61.552024 -127.949883) (xy 61.509709 -127.91761) (xy 61.472816 -127.879258) (xy 61.442208 -127.835725)
			(xy 61.418602 -127.788031) (xy 61.402551 -127.737292) (xy 61.394431 -127.684699) (xy 59.925204 -127.684699)
			(xy 59.925204 -127.72263) (xy 59.079892 -128.567942) (xy 59.079892 -129.492502) (xy 59.273186 -129.685796)
			(xy 59.340496 -129.685796) (xy 59.366639 -129.686163) (xy 59.418429 -129.693336) (xy 59.468702 -129.707695)
			(xy 59.516467 -129.728958) (xy 59.53887 -129.742438) (xy 59.569858 -129.761742) (xy 59.812174 -129.761742)
			(xy 59.828836 -129.761249) (xy 59.861024 -129.752623) (xy 59.889878 -129.735954) (xy 59.91343 -129.712379)
			(xy 59.930071 -129.683508) (xy 59.938665 -129.651312) (xy 59.938626 -129.617988) (xy 59.929955 -129.585812)
			(xy 59.913246 -129.556981) (xy 59.901836 -129.544826) (xy 59.89701 -129.54) (xy 59.893962 -129.53746)
			(xy 59.870993 -129.516209) (xy 59.831796 -129.467435) (xy 59.815984 -129.440432) (xy 59.802103 -129.414522)
			(xy 59.781782 -129.359369) (xy 59.770371 -129.30171) (xy 59.768153 -129.242975) (xy 59.775182 -129.184619)
			(xy 59.78271 -129.156206) (xy 59.789981 -129.132168) (xy 59.810113 -129.08616) (xy 59.822842 -129.064512)
			(xy 59.842908 -129.034794) (xy 59.860124 -129.012677) (xy 59.900082 -128.973378) (xy 59.945474 -128.940504)
			(xy 59.995276 -128.914797) (xy 60.048366 -128.896837) (xy 60.103546 -128.887028) (xy 60.159574 -128.885592)
			(xy 60.215184 -128.89256) (xy 60.269125 -128.907776) (xy 60.320179 -128.930897) (xy 60.367196 -128.961402)
			(xy 60.409115 -128.998602) (xy 60.444993 -129.041659) (xy 60.474019 -129.089603) (xy 60.495539 -129.141352)
			(xy 60.509069 -129.19574) (xy 60.514303 -129.25154) (xy 60.513918 -129.258314) (xy 61.393321 -129.258314)
			(xy 61.397396 -129.205233) (xy 61.409526 -129.153397) (xy 61.429427 -129.10402) (xy 61.456632 -129.058259)
			(xy 61.490504 -129.017187) (xy 61.530248 -128.981768) (xy 61.574933 -128.95283) (xy 61.623512 -128.931052)
			(xy 61.674845 -128.916946) (xy 61.727731 -128.91084) (xy 61.780929 -128.912879) (xy 61.833192 -128.923015)
			(xy 61.883295 -128.94101) (xy 61.930064 -128.966442) (xy 61.972403 -128.998716) (xy 62.009319 -129.037074)
			(xy 62.039947 -129.080618) (xy 62.063569 -129.128327) (xy 62.079632 -129.179083) (xy 62.087759 -129.231696)
			(xy 62.088268 -129.258314) (xy 62.087759 -129.284932) (xy 62.079632 -129.337545) (xy 62.063569 -129.388301)
			(xy 62.039947 -129.43601) (xy 62.009319 -129.479554) (xy 61.972403 -129.517912) (xy 61.930064 -129.550186)
			(xy 61.883295 -129.575618) (xy 61.833192 -129.593613) (xy 61.780929 -129.603749) (xy 61.727731 -129.605788)
			(xy 61.674845 -129.599682) (xy 61.623512 -129.585576) (xy 61.574933 -129.563798) (xy 61.530248 -129.53486)
			(xy 61.490504 -129.499441) (xy 61.456632 -129.458369) (xy 61.429427 -129.412608) (xy 61.409526 -129.363231)
			(xy 61.397396 -129.311395) (xy 61.393321 -129.258314) (xy 60.513918 -129.258314) (xy 60.511123 -129.307496)
			(xy 60.505848 -129.335022) (xy 60.498734 -129.365652) (xy 60.475651 -129.424138) (xy 60.443094 -129.47793)
			(xy 60.423044 -129.502154) (xy 60.409189 -129.520756) (xy 60.387782 -129.561898) (xy 60.374204 -129.606243)
			(xy 60.368907 -129.652318) (xy 60.372067 -129.698588) (xy 60.383579 -129.743514) (xy 60.392818 -129.76479)
			(xy 60.412794 -129.782549) (xy 60.448151 -129.822635) (xy 60.477647 -129.867209) (xy 60.500722 -129.915422)
			(xy 60.516933 -129.966355) (xy 60.525974 -130.019035) (xy 60.52767 -130.072458) (xy 60.52199 -130.125606)
			(xy 60.509042 -130.177464) (xy 60.499498 -130.202432) (xy 60.494672 -130.21437) (xy 60.478162 -130.249676)
			(xy 60.478162 -130.278124) (xy 60.478708 -130.294772) (xy 60.487329 -130.326933) (xy 60.503978 -130.355768)
			(xy 60.527521 -130.379313) (xy 60.556354 -130.395965) (xy 60.588514 -130.40459) (xy 60.605162 -130.405124)
			(xy 60.606178 -130.405124) (xy 60.873894 -130.67284) (xy 75.033884 -130.67284) (xy 75.037955 -130.617218)
			(xy 75.050081 -130.562781) (xy 75.070004 -130.51069) (xy 75.0973 -130.462055) (xy 75.131386 -130.417912)
			(xy 75.171535 -130.379203) (xy 75.216893 -130.346752) (xy 75.266493 -130.321251) (xy 75.319277 -130.303244)
			(xy 75.37412 -130.293114) (xy 75.429854 -130.291077) (xy 75.485291 -130.297177) (xy 75.539248 -130.311283)
			(xy 75.590577 -130.333095) (xy 75.638183 -130.362149) (xy 75.681051 -130.397824) (xy 75.718268 -130.439361)
			(xy 75.749041 -130.485874) (xy 75.772713 -130.536371) (xy 75.788781 -130.589778) (xy 75.796901 -130.644954)
			(xy 75.79741 -130.67284) (xy 75.796901 -130.700726) (xy 75.788781 -130.755902) (xy 75.772713 -130.809309)
			(xy 75.749041 -130.859806) (xy 75.718268 -130.906319) (xy 75.681051 -130.947856) (xy 75.638183 -130.983531)
			(xy 75.590577 -131.012585) (xy 75.539248 -131.034397) (xy 75.485291 -131.048503) (xy 75.429854 -131.054603)
			(xy 75.37412 -131.052566) (xy 75.319277 -131.042436) (xy 75.266493 -131.024429) (xy 75.216893 -130.998928)
			(xy 75.171535 -130.966477) (xy 75.131386 -130.927768) (xy 75.0973 -130.883625) (xy 75.070004 -130.83499)
			(xy 75.050081 -130.782899) (xy 75.037955 -130.728462) (xy 75.033884 -130.67284) (xy 60.873894 -130.67284)
			(xy 61.565282 -131.364228) (xy 62.002668 -131.364228) (xy 62.006739 -131.308606) (xy 62.018865 -131.254169)
			(xy 62.038788 -131.202078) (xy 62.066084 -131.153443) (xy 62.10017 -131.1093) (xy 62.140319 -131.070591)
			(xy 62.185677 -131.03814) (xy 62.235277 -131.012639) (xy 62.288061 -130.994632) (xy 62.342904 -130.984502)
			(xy 62.398638 -130.982465) (xy 62.454075 -130.988565) (xy 62.508032 -131.002671) (xy 62.559361 -131.024483)
			(xy 62.606967 -131.053537) (xy 62.649835 -131.089212) (xy 62.687052 -131.130749) (xy 62.717825 -131.177262)
			(xy 62.741497 -131.227759) (xy 62.757565 -131.281166) (xy 62.765685 -131.336342) (xy 62.766194 -131.364228)
			(xy 62.765685 -131.392114) (xy 62.757565 -131.44729) (xy 62.741497 -131.500697) (xy 62.717825 -131.551194)
			(xy 62.687052 -131.597707) (xy 62.649835 -131.639244) (xy 62.606967 -131.674919) (xy 62.559361 -131.703973)
			(xy 62.508032 -131.725785) (xy 62.454075 -131.739891) (xy 62.398638 -131.745991) (xy 62.342904 -131.743954)
			(xy 62.288061 -131.733824) (xy 62.235277 -131.715817) (xy 62.185677 -131.690316) (xy 62.140319 -131.657865)
			(xy 62.10017 -131.619156) (xy 62.066084 -131.575013) (xy 62.038788 -131.526378) (xy 62.018865 -131.474287)
			(xy 62.006739 -131.41985) (xy 62.002668 -131.364228) (xy 61.565282 -131.364228) (xy 61.676788 -131.475734)
			(xy 61.676788 -134.048116) (xy 62.967957 -134.048116) (xy 62.973539 -133.993288) (xy 62.987135 -133.939881)
			(xy 63.008449 -133.889059) (xy 63.037014 -133.841929) (xy 63.05423 -133.820408) (xy 63.067941 -133.803217)
			(xy 63.089747 -133.765034) (xy 63.104655 -133.723667) (xy 63.112219 -133.680352) (xy 63.112213 -133.636381)
			(xy 63.104638 -133.593067) (xy 63.089719 -133.551704) (xy 63.067902 -133.513527) (xy 63.05423 -133.496304)
			(xy 63.037025 -133.474774) (xy 63.008458 -133.427646) (xy 62.987144 -133.376824) (xy 62.973547 -133.323417)
			(xy 62.967963 -133.26859) (xy 62.970516 -133.213538) (xy 62.981148 -133.159463) (xy 62.999628 -133.107544)
			(xy 63.025554 -133.058912) (xy 63.058358 -133.014628) (xy 63.097327 -132.975659) (xy 63.141611 -132.942854)
			(xy 63.190242 -132.916929) (xy 63.242162 -132.898448) (xy 63.296237 -132.887816) (xy 63.351288 -132.885263)
			(xy 63.406115 -132.890846) (xy 63.459522 -132.904443) (xy 63.510344 -132.925757) (xy 63.557473 -132.954324)
			(xy 63.578994 -132.97154) (xy 63.596218 -132.985206) (xy 63.634395 -133.007011) (xy 63.675755 -133.021919)
			(xy 63.719064 -133.029487) (xy 63.763028 -133.029487) (xy 63.806337 -133.021919) (xy 63.847697 -133.007011)
			(xy 63.885874 -132.985206) (xy 63.903098 -132.97154) (xy 63.925518 -132.953649) (xy 63.97477 -132.924252)
			(xy 64.027942 -132.902744) (xy 64.083781 -132.889633) (xy 64.140969 -132.885229) (xy 64.198157 -132.889633)
			(xy 64.253996 -132.902744) (xy 64.307168 -132.924252) (xy 64.35642 -132.953649) (xy 64.37884 -132.97154)
			(xy 64.396082 -132.985208) (xy 64.434292 -133.007013) (xy 64.475683 -133.021921) (xy 64.519022 -133.029488)
			(xy 64.563016 -133.029488) (xy 64.606355 -133.021921) (xy 64.647746 -133.007013) (xy 64.685956 -132.985208)
			(xy 64.703198 -132.97154) (xy 64.724754 -132.954407) (xy 64.771874 -132.925925) (xy 64.822672 -132.904686)
			(xy 64.876043 -132.891155) (xy 64.930824 -132.885626) (xy 64.985823 -132.888219) (xy 65.039841 -132.898878)
			(xy 65.091702 -132.91737) (xy 65.140277 -132.943294) (xy 65.184508 -132.976083) (xy 65.223431 -133.015026)
			(xy 65.2562 -133.059272) (xy 65.282101 -133.107859) (xy 65.300569 -133.159729) (xy 65.311202 -133.213752)
			(xy 65.313281 -133.258305) (xy 66.167655 -133.258305) (xy 66.172068 -133.201076) (xy 66.185204 -133.1452)
			(xy 66.206751 -133.091999) (xy 66.236201 -133.042731) (xy 66.254122 -133.020308) (xy 66.267829 -133.003115)
			(xy 66.289627 -132.96493) (xy 66.304529 -132.923564) (xy 66.31209 -132.88025) (xy 66.312084 -132.836282)
			(xy 66.304512 -132.79297) (xy 66.289599 -132.751608) (xy 66.26779 -132.713429) (xy 66.254122 -132.696204)
			(xy 66.236926 -132.674667) (xy 66.208361 -132.627539) (xy 66.187047 -132.576718) (xy 66.173451 -132.523313)
			(xy 66.167868 -132.468487) (xy 66.170421 -132.413437) (xy 66.181053 -132.359363) (xy 66.199533 -132.307445)
			(xy 66.225458 -132.258814) (xy 66.258262 -132.214532) (xy 66.29723 -132.175564) (xy 66.341512 -132.142759)
			(xy 66.390143 -132.116834) (xy 66.442061 -132.098354) (xy 66.496135 -132.087721) (xy 66.551185 -132.085168)
			(xy 66.60601 -132.090751) (xy 66.659416 -132.104347) (xy 66.710237 -132.125659) (xy 66.757365 -132.154225)
			(xy 66.778886 -132.17144) (xy 66.79611 -132.185106) (xy 66.834287 -132.206911) (xy 66.875647 -132.221819)
			(xy 66.918956 -132.229387) (xy 66.96292 -132.229387) (xy 67.006229 -132.221819) (xy 67.047589 -132.206911)
			(xy 67.085766 -132.185106) (xy 67.10299 -132.17144) (xy 67.125413 -132.153518) (xy 67.174681 -132.124066)
			(xy 67.227882 -132.102517) (xy 67.283758 -132.089381) (xy 67.340988 -132.084967) (xy 67.398218 -132.089381)
			(xy 67.454094 -132.102517) (xy 67.507295 -132.124066) (xy 67.556563 -132.153518) (xy 67.578986 -132.17144)
			(xy 67.59621 -132.185106) (xy 67.634387 -132.206911) (xy 67.675747 -132.221819) (xy 67.719056 -132.229387)
			(xy 67.76302 -132.229387) (xy 67.806329 -132.221819) (xy 67.847689 -132.206911) (xy 67.885866 -132.185106)
			(xy 67.90309 -132.17144) (xy 67.924616 -132.154229) (xy 67.971745 -132.125661) (xy 68.022568 -132.104345)
			(xy 68.075976 -132.090746) (xy 68.130804 -132.085162) (xy 68.185857 -132.087713) (xy 68.239934 -132.098345)
			(xy 68.291855 -132.116826) (xy 68.340488 -132.142751) (xy 68.384773 -132.175557) (xy 68.423743 -132.214527)
			(xy 68.456548 -132.258811) (xy 68.482474 -132.307444) (xy 68.500954 -132.359365) (xy 68.511586 -132.413442)
			(xy 68.513708 -132.459222) (xy 70.169034 -132.459222) (xy 70.17301 -132.404896) (xy 70.184853 -132.351727)
			(xy 70.204312 -132.30085) (xy 70.230972 -132.253348) (xy 70.264263 -132.210234) (xy 70.303477 -132.172427)
			(xy 70.347779 -132.140732) (xy 70.396222 -132.115826) (xy 70.447776 -132.098238) (xy 70.501342 -132.088344)
			(xy 70.555777 -132.086354) (xy 70.609922 -132.092312) (xy 70.662622 -132.10609) (xy 70.712755 -132.127394)
			(xy 70.759251 -132.15577) (xy 70.801121 -132.190614) (xy 70.83747 -132.231183) (xy 70.867526 -132.276612)
			(xy 70.890647 -132.325933) (xy 70.90634 -132.378095) (xy 70.914271 -132.431986) (xy 70.914768 -132.459222)
			(xy 70.914271 -132.486458) (xy 70.90634 -132.540349) (xy 70.890647 -132.592511) (xy 70.867526 -132.641832)
			(xy 70.83747 -132.687261) (xy 70.801121 -132.72783) (xy 70.759251 -132.762674) (xy 70.712755 -132.79105)
			(xy 70.662622 -132.812354) (xy 70.609922 -132.826132) (xy 70.555777 -132.83209) (xy 70.501342 -132.8301)
			(xy 70.447776 -132.820206) (xy 70.396222 -132.802618) (xy 70.347779 -132.777712) (xy 70.303477 -132.746017)
			(xy 70.264263 -132.70821) (xy 70.230972 -132.665096) (xy 70.204312 -132.617594) (xy 70.184853 -132.566717)
			(xy 70.17301 -132.513548) (xy 70.169034 -132.459222) (xy 68.513708 -132.459222) (xy 68.514138 -132.468495)
			(xy 68.508554 -132.523323) (xy 68.494956 -132.576731) (xy 68.47364 -132.627554) (xy 68.445071 -132.674683)
			(xy 68.427854 -132.696204) (xy 68.414229 -132.71346) (xy 68.392418 -132.751629) (xy 68.377504 -132.792982)
			(xy 68.369931 -132.836286) (xy 68.369925 -132.880247) (xy 68.377486 -132.923552) (xy 68.39239 -132.96491)
			(xy 68.41419 -133.003084) (xy 68.427854 -133.020308) (xy 68.445782 -133.042726) (xy 68.475235 -133.091995)
			(xy 68.496784 -133.145197) (xy 68.509921 -133.201074) (xy 68.514334 -133.258305) (xy 68.509919 -133.315535)
			(xy 68.496781 -133.371412) (xy 68.47523 -133.424614) (xy 68.445777 -133.473882) (xy 68.427854 -133.496304)
			(xy 68.414229 -133.51356) (xy 68.392418 -133.551729) (xy 68.377504 -133.593082) (xy 68.369931 -133.636386)
			(xy 68.369925 -133.680347) (xy 68.377486 -133.723652) (xy 68.39239 -133.76501) (xy 68.41419 -133.803184)
			(xy 68.427854 -133.820408) (xy 68.445091 -133.841914) (xy 68.473659 -133.889045) (xy 68.494975 -133.93987)
			(xy 68.508572 -133.99328) (xy 68.514156 -134.04811) (xy 68.511603 -134.103165) (xy 68.50097 -134.157243)
			(xy 68.482489 -134.209165) (xy 68.456562 -134.2578) (xy 68.423755 -134.302086) (xy 68.384784 -134.341057)
			(xy 68.340498 -134.373863) (xy 68.291863 -134.39979) (xy 68.239941 -134.418271) (xy 68.185862 -134.428904)
			(xy 68.130808 -134.431456) (xy 68.075978 -134.425872) (xy 68.022568 -134.412274) (xy 67.971743 -134.390958)
			(xy 67.924612 -134.362389) (xy 67.90309 -134.345172) (xy 67.885866 -134.331506) (xy 67.847689 -134.309701)
			(xy 67.806329 -134.294793) (xy 67.76302 -134.287225) (xy 67.719056 -134.287225) (xy 67.675747 -134.294793)
			(xy 67.634387 -134.309701) (xy 67.59621 -134.331506) (xy 67.578986 -134.345172) (xy 67.556563 -134.363094)
			(xy 67.507295 -134.392546) (xy 67.454094 -134.414095) (xy 67.398218 -134.427231) (xy 67.340988 -134.431645)
			(xy 67.283758 -134.427231) (xy 67.227882 -134.414095) (xy 67.174681 -134.392546) (xy 67.125413 -134.363094)
			(xy 67.10299 -134.345172) (xy 67.085766 -134.331506) (xy 67.047589 -134.309701) (xy 67.006229 -134.294793)
			(xy 66.96292 -134.287225) (xy 66.918956 -134.287225) (xy 66.875647 -134.294793) (xy 66.834287 -134.309701)
			(xy 66.79611 -134.331506) (xy 66.778886 -134.345172) (xy 66.75737 -134.362394) (xy 66.71024 -134.390959)
			(xy 66.659417 -134.412272) (xy 66.606009 -134.425867) (xy 66.551181 -134.431449) (xy 66.49613 -134.428896)
			(xy 66.442054 -134.418262) (xy 66.390134 -134.399781) (xy 66.341502 -134.373855) (xy 66.297219 -134.34105)
			(xy 66.25825 -134.302081) (xy 66.225444 -134.257797) (xy 66.199518 -134.209165) (xy 66.181037 -134.157245)
			(xy 66.170404 -134.10317) (xy 66.167851 -134.048118) (xy 66.173433 -133.99329) (xy 66.187028 -133.939883)
			(xy 66.208341 -133.88906) (xy 66.236906 -133.84193) (xy 66.254122 -133.820408) (xy 66.267829 -133.803215)
			(xy 66.289627 -133.76503) (xy 66.304529 -133.723664) (xy 66.31209 -133.68035) (xy 66.312084 -133.636382)
			(xy 66.304512 -133.59307) (xy 66.289599 -133.551708) (xy 66.26779 -133.513529) (xy 66.254122 -133.496304)
			(xy 66.236206 -133.473877) (xy 66.206755 -133.424609) (xy 66.185207 -133.371409) (xy 66.17207 -133.315534)
			(xy 66.167655 -133.258305) (xy 65.313281 -133.258305) (xy 65.313769 -133.268751) (xy 65.308214 -133.32353)
			(xy 65.294658 -133.376894) (xy 65.273396 -133.427683) (xy 65.244891 -133.474789) (xy 65.227708 -133.496304)
			(xy 65.214085 -133.513561) (xy 65.192278 -133.55173) (xy 65.177367 -133.593084) (xy 65.169795 -133.636386)
			(xy 65.169789 -133.680346) (xy 65.177349 -133.723651) (xy 65.19225 -133.765008) (xy 65.214046 -133.803183)
			(xy 65.227708 -133.820408) (xy 65.244852 -133.841966) (xy 65.273389 -133.889071) (xy 65.29468 -133.939865)
			(xy 65.308262 -133.993239) (xy 65.313837 -134.048032) (xy 65.311285 -134.103048) (xy 65.300661 -134.157089)
			(xy 65.282197 -134.208977) (xy 65.256295 -134.257582) (xy 65.22352 -134.301843) (xy 65.184585 -134.340797)
			(xy 65.14034 -134.373595) (xy 65.091749 -134.399521) (xy 65.03987 -134.418011) (xy 64.985834 -134.428662)
			(xy 64.930819 -134.431242) (xy 64.876024 -134.425694) (xy 64.822642 -134.41214) (xy 64.771838 -134.390874)
			(xy 64.724718 -134.362361) (xy 64.703198 -134.345172) (xy 64.685971 -134.331471) (xy 64.647773 -134.309606)
			(xy 64.606378 -134.294656) (xy 64.563025 -134.287066) (xy 64.519013 -134.287066) (xy 64.47566 -134.294656)
			(xy 64.434265 -134.309606) (xy 64.396067 -134.331471) (xy 64.37884 -134.345172) (xy 64.356433 -134.363093)
			(xy 64.307195 -134.392544) (xy 64.254022 -134.414093) (xy 64.198173 -134.427231) (xy 64.140969 -134.431644)
			(xy 64.083765 -134.427231) (xy 64.027916 -134.414093) (xy 63.974743 -134.392544) (xy 63.925505 -134.363093)
			(xy 63.903098 -134.345172) (xy 63.885874 -134.331506) (xy 63.847697 -134.309701) (xy 63.806337 -134.294793)
			(xy 63.763028 -134.287225) (xy 63.719064 -134.287225) (xy 63.675755 -134.294793) (xy 63.634395 -134.309701)
			(xy 63.596218 -134.331506) (xy 63.578994 -134.345172) (xy 63.557471 -134.362386) (xy 63.510342 -134.390951)
			(xy 63.459519 -134.412265) (xy 63.406112 -134.425861) (xy 63.351285 -134.431443) (xy 63.296233 -134.42889)
			(xy 63.242158 -134.418257) (xy 63.190238 -134.399776) (xy 63.141607 -134.373851) (xy 63.097323 -134.341046)
			(xy 63.058354 -134.302077) (xy 63.025549 -134.257793) (xy 62.999624 -134.209162) (xy 62.981143 -134.157242)
			(xy 62.97051 -134.103167) (xy 62.967957 -134.048116) (xy 61.676788 -134.048116) (xy 61.676788 -136.458319)
			(xy 62.967763 -136.458319) (xy 62.972174 -136.401117) (xy 62.98531 -136.345268) (xy 63.006858 -136.292096)
			(xy 63.036309 -136.24286) (xy 63.05423 -136.220454) (xy 63.067955 -136.203245) (xy 63.089818 -136.165044)
			(xy 63.104767 -136.123645) (xy 63.112353 -136.080288) (xy 63.11235 -136.036273) (xy 63.104757 -135.992918)
			(xy 63.089802 -135.951521) (xy 63.067933 -135.913323) (xy 63.05423 -135.896096) (xy 63.037103 -135.874536)
			(xy 63.008622 -135.827417) (xy 62.987385 -135.776619) (xy 62.973856 -135.72325) (xy 62.968328 -135.66847)
			(xy 62.970921 -135.613473) (xy 62.981581 -135.559456) (xy 63.000073 -135.507597) (xy 63.025996 -135.459023)
			(xy 63.058785 -135.414793) (xy 63.097726 -135.375871) (xy 63.141971 -135.343102) (xy 63.190557 -135.317202)
			(xy 63.242425 -135.298734) (xy 63.296447 -135.2881) (xy 63.351445 -135.285532) (xy 63.406222 -135.291086)
			(xy 63.459586 -135.304641) (xy 63.510373 -135.325901) (xy 63.557479 -135.354404) (xy 63.578994 -135.371586)
			(xy 63.596218 -135.385252) (xy 63.634395 -135.407057) (xy 63.675755 -135.421965) (xy 63.719064 -135.429533)
			(xy 63.763028 -135.429533) (xy 63.806337 -135.421965) (xy 63.847697 -135.407057) (xy 63.885874 -135.385252)
			(xy 63.903098 -135.371586) (xy 63.925518 -135.353695) (xy 63.97477 -135.324298) (xy 64.027942 -135.30279)
			(xy 64.083781 -135.289679) (xy 64.140969 -135.285275) (xy 64.198157 -135.289679) (xy 64.253996 -135.30279)
			(xy 64.307168 -135.324298) (xy 64.35642 -135.353695) (xy 64.37884 -135.371586) (xy 64.396082 -135.385254)
			(xy 64.434292 -135.407059) (xy 64.475683 -135.421967) (xy 64.519022 -135.429534) (xy 64.563016 -135.429534)
			(xy 64.606355 -135.421967) (xy 64.647746 -135.407059) (xy 64.685956 -135.385254) (xy 64.703198 -135.371586)
			(xy 64.724717 -135.354406) (xy 64.771822 -135.325894) (xy 64.822611 -135.304627) (xy 64.875977 -135.291068)
			(xy 64.930758 -135.285513) (xy 64.98576 -135.288082) (xy 65.039784 -135.29872) (xy 65.091654 -135.317195)
			(xy 65.14024 -135.343104) (xy 65.184482 -135.375883) (xy 65.223416 -135.414818) (xy 65.256195 -135.45906)
			(xy 65.282105 -135.507645) (xy 65.30058 -135.559515) (xy 65.311218 -135.613539) (xy 65.313787 -135.668541)
			(xy 65.308232 -135.723322) (xy 65.294673 -135.776689) (xy 65.273406 -135.827478) (xy 65.244895 -135.874583)
			(xy 65.227708 -135.896096) (xy 65.214063 -135.913355) (xy 65.192253 -135.951561) (xy 65.17734 -135.992949)
			(xy 65.169769 -136.036285) (xy 65.169766 -136.080277) (xy 65.17733 -136.123614) (xy 65.192237 -136.165004)
			(xy 65.214041 -136.203213) (xy 65.227708 -136.220454) (xy 65.245624 -136.242855) (xy 65.27502 -136.29211)
			(xy 65.296526 -136.345286) (xy 65.309635 -136.401128) (xy 65.314038 -136.458319) (xy 66.167657 -136.458319)
			(xy 66.172068 -136.401117) (xy 66.185203 -136.345269) (xy 66.206751 -136.292097) (xy 66.236202 -136.24286)
			(xy 66.254122 -136.220454) (xy 66.267848 -136.203245) (xy 66.289711 -136.165044) (xy 66.30466 -136.123645)
			(xy 66.312247 -136.080288) (xy 66.312244 -136.036273) (xy 66.304651 -135.992918) (xy 66.289695 -135.951521)
			(xy 66.267826 -135.913323) (xy 66.254122 -135.896096) (xy 66.236887 -135.874616) (xy 66.208392 -135.827487)
			(xy 66.187143 -135.776678) (xy 66.173604 -135.723295) (xy 66.16807 -135.668501) (xy 66.17066 -135.613489)
			(xy 66.18132 -135.559457) (xy 66.199815 -135.507582) (xy 66.225744 -135.458995) (xy 66.258542 -135.414753)
			(xy 66.297495 -135.37582) (xy 66.341753 -135.343044) (xy 66.390354 -135.317139) (xy 66.442237 -135.29867)
			(xy 66.496275 -135.288038) (xy 66.551288 -135.285475) (xy 66.60608 -135.291037) (xy 66.659456 -135.304603)
			(xy 66.710255 -135.325877) (xy 66.757369 -135.354396) (xy 66.778886 -135.371586) (xy 66.79611 -135.385252)
			(xy 66.834287 -135.407057) (xy 66.875647 -135.421965) (xy 66.918956 -135.429533) (xy 66.96292 -135.429533)
			(xy 67.006229 -135.421965) (xy 67.047589 -135.407057) (xy 67.085766 -135.385252) (xy 67.10299 -135.371586)
			(xy 67.125413 -135.353664) (xy 67.174681 -135.324212) (xy 67.227882 -135.302663) (xy 67.283758 -135.289527)
			(xy 67.340988 -135.285113) (xy 67.398218 -135.289527) (xy 67.454094 -135.302663) (xy 67.507295 -135.324212)
			(xy 67.556563 -135.353664) (xy 67.578986 -135.371586) (xy 67.59621 -135.385252) (xy 67.634387 -135.407057)
			(xy 67.675747 -135.421965) (xy 67.719056 -135.429533) (xy 67.76302 -135.429533) (xy 67.806329 -135.421965)
			(xy 67.847689 -135.407057) (xy 67.885866 -135.385252) (xy 67.90309 -135.371586) (xy 67.924582 -135.354351)
			(xy 67.971695 -135.325798) (xy 68.022499 -135.304493) (xy 68.075886 -135.290901) (xy 68.130692 -135.285318)
			(xy 68.185723 -135.287866) (xy 68.23978 -135.298488) (xy 68.291683 -135.316955) (xy 68.340301 -135.342862)
			(xy 68.384574 -135.375646) (xy 68.423538 -135.414591) (xy 68.456343 -135.458849) (xy 68.482274 -135.507455)
			(xy 68.500765 -135.559349) (xy 68.511413 -135.6134) (xy 68.513987 -135.66843) (xy 68.50843 -135.72324)
			(xy 68.494863 -135.776633) (xy 68.473582 -135.827447) (xy 68.445052 -135.874574) (xy 68.427854 -135.896096)
			(xy 68.414211 -135.913356) (xy 68.392406 -135.951563) (xy 68.377496 -135.99295) (xy 68.369927 -136.036285)
			(xy 68.369924 -136.080276) (xy 68.377486 -136.123612) (xy 68.392389 -136.165002) (xy 68.414189 -136.203212)
			(xy 68.427854 -136.220454) (xy 68.445768 -136.242856) (xy 68.47516 -136.292112) (xy 68.496664 -136.345288)
			(xy 68.509771 -136.401129) (xy 68.513231 -136.446085) (xy 70.969228 -136.446085) (xy 70.975104 -136.391994)
			(xy 70.988787 -136.339333) (xy 71.009985 -136.289223) (xy 71.038248 -136.24273) (xy 71.05523 -136.22147)
			(xy 71.06894 -136.204249) (xy 71.090804 -136.166051) (xy 71.105754 -136.124654) (xy 71.113342 -136.0813)
			(xy 71.113341 -136.037286) (xy 71.10575 -135.993932) (xy 71.090798 -135.952537) (xy 71.068932 -135.914339)
			(xy 71.05523 -135.897112) (xy 71.03812 -135.875539) (xy 71.009638 -135.828421) (xy 70.9884 -135.777625)
			(xy 70.974869 -135.724256) (xy 70.96934 -135.669477) (xy 70.971933 -135.61448) (xy 70.982591 -135.560464)
			(xy 71.001083 -135.508605) (xy 71.027005 -135.460032) (xy 71.059793 -135.415803) (xy 71.098734 -135.37688)
			(xy 71.142978 -135.344112) (xy 71.191564 -135.318213) (xy 71.243431 -135.299745) (xy 71.297452 -135.289112)
			(xy 71.35245 -135.286545) (xy 71.407226 -135.2921) (xy 71.460589 -135.305655) (xy 71.511375 -135.326916)
			(xy 71.55848 -135.35542) (xy 71.579994 -135.372602) (xy 71.597218 -135.386268) (xy 71.635395 -135.408073)
			(xy 71.676755 -135.422981) (xy 71.720064 -135.430549) (xy 71.764028 -135.430549) (xy 71.807337 -135.422981)
			(xy 71.848697 -135.408073) (xy 71.886874 -135.386268) (xy 71.904098 -135.372602) (xy 71.926521 -135.35468)
			(xy 71.975789 -135.325228) (xy 72.02899 -135.303679) (xy 72.084866 -135.290543) (xy 72.142096 -135.286129)
			(xy 72.199326 -135.290543) (xy 72.255202 -135.303679) (xy 72.308403 -135.325228) (xy 72.357671 -135.35468)
			(xy 72.380094 -135.372602) (xy 72.397318 -135.386268) (xy 72.435495 -135.408073) (xy 72.476855 -135.422981)
			(xy 72.520164 -135.430549) (xy 72.564128 -135.430549) (xy 72.607437 -135.422981) (xy 72.648797 -135.408073)
			(xy 72.686974 -135.386268) (xy 72.704198 -135.372602) (xy 72.726618 -135.354711) (xy 72.77587 -135.325314)
			(xy 72.829042 -135.303806) (xy 72.884881 -135.290695) (xy 72.942069 -135.286291) (xy 72.999257 -135.290695)
			(xy 73.055096 -135.303806) (xy 73.108268 -135.325314) (xy 73.15752 -135.354711) (xy 73.17994 -135.372602)
			(xy 73.197182 -135.38627) (xy 73.235392 -135.408075) (xy 73.276783 -135.422983) (xy 73.320122 -135.43055)
			(xy 73.364116 -135.43055) (xy 73.407455 -135.422983) (xy 73.448846 -135.408075) (xy 73.487056 -135.38627)
			(xy 73.504298 -135.372602) (xy 73.526718 -135.354711) (xy 73.57597 -135.325314) (xy 73.629142 -135.303806)
			(xy 73.684981 -135.290695) (xy 73.742169 -135.286291) (xy 73.799357 -135.290695) (xy 73.855196 -135.303806)
			(xy 73.908368 -135.325314) (xy 73.95762 -135.354711) (xy 73.98004 -135.372602) (xy 73.997264 -135.386268)
			(xy 74.035441 -135.408073) (xy 74.076801 -135.422981) (xy 74.12011 -135.430549) (xy 74.164074 -135.430549)
			(xy 74.207383 -135.422981) (xy 74.248743 -135.408073) (xy 74.28692 -135.386268) (xy 74.304144 -135.372602)
			(xy 74.325439 -135.355642) (xy 74.371945 -135.327348) (xy 74.422073 -135.306123) (xy 74.474755 -135.292418)
			(xy 74.528872 -135.286524) (xy 74.58327 -135.288568) (xy 74.636791 -135.298506) (xy 74.688297 -135.316125)
			(xy 74.736691 -135.341052) (xy 74.780943 -135.372755) (xy 74.82011 -135.41056) (xy 74.85336 -135.453662)
			(xy 74.879984 -135.501143) (xy 74.899416 -135.551993) (xy 74.911242 -135.605129) (xy 74.91521 -135.65942)
			(xy 74.911236 -135.713711) (xy 74.899404 -135.766846) (xy 74.879967 -135.817694) (xy 74.853338 -135.865172)
			(xy 74.820083 -135.908271) (xy 74.780911 -135.946071) (xy 74.736656 -135.977769) (xy 74.688259 -136.002691)
			(xy 74.636752 -136.020305) (xy 74.583229 -136.030236) (xy 74.528831 -136.032274) (xy 74.474715 -136.026375)
			(xy 74.422034 -136.012664) (xy 74.371908 -135.991433) (xy 74.325406 -135.963135) (xy 74.304144 -135.946134)
			(xy 74.28692 -135.932468) (xy 74.248743 -135.910663) (xy 74.207383 -135.895755) (xy 74.164074 -135.888187)
			(xy 74.12011 -135.888187) (xy 74.076801 -135.895755) (xy 74.035441 -135.910663) (xy 73.997264 -135.932468)
			(xy 73.98004 -135.946134) (xy 73.957633 -135.964055) (xy 73.908395 -135.993506) (xy 73.855222 -136.015055)
			(xy 73.799373 -136.028193) (xy 73.742169 -136.032606) (xy 73.684965 -136.028193) (xy 73.629116 -136.015055)
			(xy 73.575943 -135.993506) (xy 73.526705 -135.964055) (xy 73.504298 -135.946134) (xy 73.487071 -135.932433)
			(xy 73.448873 -135.910568) (xy 73.407478 -135.895618) (xy 73.364125 -135.888028) (xy 73.320113 -135.888028)
			(xy 73.27676 -135.895618) (xy 73.235365 -135.910568) (xy 73.197167 -135.932433) (xy 73.17994 -135.946134)
			(xy 73.157533 -135.964055) (xy 73.108295 -135.993506) (xy 73.055122 -136.015055) (xy 72.999273 -136.028193)
			(xy 72.942069 -136.032606) (xy 72.884865 -136.028193) (xy 72.829016 -136.015055) (xy 72.775843 -135.993506)
			(xy 72.726605 -135.964055) (xy 72.704198 -135.946134) (xy 72.686974 -135.932468) (xy 72.648797 -135.910663)
			(xy 72.607437 -135.895755) (xy 72.564128 -135.888187) (xy 72.520164 -135.888187) (xy 72.476855 -135.895755)
			(xy 72.435495 -135.910663) (xy 72.397318 -135.932468) (xy 72.380094 -135.946134) (xy 72.358605 -135.963269)
			(xy 72.311631 -135.991793) (xy 72.260975 -136.013108) (xy 72.207738 -136.026749) (xy 72.153075 -136.032422)
			(xy 72.098171 -136.030003) (xy 72.044219 -136.019545) (xy 71.992388 -136.001274) (xy 71.943803 -135.975588)
			(xy 71.899519 -135.943043) (xy 71.860496 -135.904345) (xy 71.843646 -135.882634) (xy 71.833131 -135.869442)
			(xy 71.806561 -135.848671) (xy 71.775474 -135.835597) (xy 71.742046 -135.831135) (xy 71.708618 -135.835597)
			(xy 71.677531 -135.848671) (xy 71.650961 -135.869442) (xy 71.640446 -135.882634) (xy 71.628762 -135.897112)
			(xy 71.615103 -135.914361) (xy 71.593298 -135.952569) (xy 71.57839 -135.993959) (xy 71.570822 -136.037297)
			(xy 71.570821 -136.08129) (xy 71.578386 -136.124627) (xy 71.593292 -136.166018) (xy 71.615095 -136.204228)
			(xy 71.628762 -136.22147) (xy 71.645744 -136.24273) (xy 71.674007 -136.289223) (xy 71.695205 -136.339333)
			(xy 71.708888 -136.391994) (xy 71.714764 -136.446085) (xy 71.712708 -136.500456) (xy 71.702764 -136.553949)
			(xy 71.685143 -136.605426) (xy 71.660221 -136.653792) (xy 71.628528 -136.698018) (xy 71.590738 -136.737163)
			(xy 71.547655 -136.770393) (xy 71.500196 -136.797002) (xy 71.449371 -136.816424) (xy 71.396261 -136.828245)
			(xy 71.341996 -136.832213) (xy 71.287731 -136.828245) (xy 71.234621 -136.816424) (xy 71.183796 -136.797002)
			(xy 71.136337 -136.770393) (xy 71.093254 -136.737163) (xy 71.055464 -136.698018) (xy 71.023771 -136.653792)
			(xy 70.998849 -136.605426) (xy 70.981228 -136.553949) (xy 70.971284 -136.500456) (xy 70.969228 -136.446085)
			(xy 68.513231 -136.446085) (xy 68.514173 -136.458319) (xy 68.509766 -136.515509) (xy 68.496652 -136.571349)
			(xy 68.475143 -136.624522) (xy 68.445745 -136.673775) (xy 68.427854 -136.696196) (xy 68.41414 -136.713385)
			(xy 68.392335 -136.751568) (xy 68.377429 -136.792936) (xy 68.369866 -136.836251) (xy 68.369872 -136.880222)
			(xy 68.377448 -136.923536) (xy 68.392366 -136.964899) (xy 68.414182 -137.003076) (xy 68.427854 -137.0203)
			(xy 68.445082 -137.041813) (xy 68.473651 -137.088943) (xy 68.494967 -137.139767) (xy 68.508566 -137.193177)
			(xy 68.51415 -137.248007) (xy 68.511598 -137.303061) (xy 68.500965 -137.357139) (xy 68.482484 -137.409061)
			(xy 68.456558 -137.457695) (xy 68.423751 -137.501981) (xy 68.38478 -137.540952) (xy 68.340494 -137.573758)
			(xy 68.29186 -137.599685) (xy 68.239938 -137.618166) (xy 68.185859 -137.628798) (xy 68.130805 -137.63135)
			(xy 68.075976 -137.625765) (xy 68.022566 -137.612167) (xy 67.971742 -137.590851) (xy 67.924611 -137.562282)
			(xy 67.90309 -137.545064) (xy 67.885866 -137.531398) (xy 67.847689 -137.509593) (xy 67.806329 -137.494685)
			(xy 67.76302 -137.487117) (xy 67.719056 -137.487117) (xy 67.675747 -137.494685) (xy 67.634387 -137.509593)
			(xy 67.59621 -137.531398) (xy 67.578986 -137.545064) (xy 67.556563 -137.562986) (xy 67.507295 -137.592438)
			(xy 67.454094 -137.613987) (xy 67.398218 -137.627123) (xy 67.340988 -137.631537) (xy 67.283758 -137.627123)
			(xy 67.227882 -137.613987) (xy 67.174681 -137.592438) (xy 67.125413 -137.562986) (xy 67.10299 -137.545064)
			(xy 67.085766 -137.531398) (xy 67.047589 -137.509593) (xy 67.006229 -137.494685) (xy 66.96292 -137.487117)
			(xy 66.918956 -137.487117) (xy 66.875647 -137.494685) (xy 66.834287 -137.509593) (xy 66.79611 -137.531398)
			(xy 66.778886 -137.545064) (xy 66.757377 -137.562295) (xy 66.710246 -137.590862) (xy 66.659422 -137.612176)
			(xy 66.606013 -137.625772) (xy 66.551184 -137.631354) (xy 66.496131 -137.628801) (xy 66.442054 -137.618168)
			(xy 66.390133 -137.599686) (xy 66.3415 -137.57376) (xy 66.297215 -137.540954) (xy 66.258245 -137.501983)
			(xy 66.225439 -137.457699) (xy 66.199513 -137.409065) (xy 66.181032 -137.357144) (xy 66.170399 -137.303067)
			(xy 66.167846 -137.248014) (xy 66.173428 -137.193185) (xy 66.187025 -137.139777) (xy 66.208339 -137.088953)
			(xy 66.236906 -137.041822) (xy 66.254122 -137.0203) (xy 66.26774 -137.00304) (xy 66.289544 -136.96487)
			(xy 66.304454 -136.923518) (xy 66.312025 -136.880216) (xy 66.312032 -136.836258) (xy 66.304473 -136.792954)
			(xy 66.289575 -136.751597) (xy 66.267782 -136.713421) (xy 66.254122 -136.696196) (xy 66.236224 -136.673771)
			(xy 66.206768 -136.624538) (xy 66.185215 -136.571368) (xy 66.172074 -136.515521) (xy 66.167657 -136.458319)
			(xy 65.314038 -136.458319) (xy 65.30963 -136.51551) (xy 65.296515 -136.571351) (xy 65.275003 -136.624524)
			(xy 65.245601 -136.673776) (xy 65.227708 -136.696196) (xy 65.213996 -136.713386) (xy 65.192195 -136.75157)
			(xy 65.177292 -136.792937) (xy 65.16973 -136.836252) (xy 65.169737 -136.880222) (xy 65.177311 -136.923534)
			(xy 65.192226 -136.964897) (xy 65.214038 -137.003075) (xy 65.227708 -137.0203) (xy 65.244844 -137.041864)
			(xy 65.273381 -137.088969) (xy 65.294673 -137.139762) (xy 65.308255 -137.193136) (xy 65.313831 -137.247929)
			(xy 65.311279 -137.302944) (xy 65.300656 -137.356985) (xy 65.282192 -137.408873) (xy 65.256291 -137.457478)
			(xy 65.223516 -137.501739) (xy 65.184582 -137.540693) (xy 65.140337 -137.57349) (xy 65.091746 -137.599416)
			(xy 65.039867 -137.617906) (xy 64.985832 -137.628557) (xy 64.930817 -137.631136) (xy 64.876022 -137.625588)
			(xy 64.822641 -137.612033) (xy 64.771837 -137.590767) (xy 64.724718 -137.562253) (xy 64.703198 -137.545064)
			(xy 64.685971 -137.531363) (xy 64.647773 -137.509498) (xy 64.606378 -137.494548) (xy 64.563025 -137.486958)
			(xy 64.519013 -137.486958) (xy 64.47566 -137.494548) (xy 64.434265 -137.509498) (xy 64.396067 -137.531363)
			(xy 64.37884 -137.545064) (xy 64.356433 -137.562985) (xy 64.307195 -137.592436) (xy 64.254022 -137.613985)
			(xy 64.198173 -137.627123) (xy 64.140969 -137.631536) (xy 64.083765 -137.627123) (xy 64.027916 -137.613985)
			(xy 63.974743 -137.592436) (xy 63.925505 -137.562985) (xy 63.903098 -137.545064) (xy 63.885874 -137.531398)
			(xy 63.847697 -137.509593) (xy 63.806337 -137.494685) (xy 63.763028 -137.487117) (xy 63.719064 -137.487117)
			(xy 63.675755 -137.494685) (xy 63.634395 -137.509593) (xy 63.596218 -137.531398) (xy 63.578994 -137.545064)
			(xy 63.557478 -137.562287) (xy 63.510348 -137.590854) (xy 63.459524 -137.612168) (xy 63.406116 -137.625765)
			(xy 63.351287 -137.631348) (xy 63.296235 -137.628795) (xy 63.242158 -137.618163) (xy 63.190237 -137.599682)
			(xy 63.141604 -137.573755) (xy 63.09732 -137.54095) (xy 63.05835 -137.501979) (xy 63.025544 -137.457695)
			(xy 62.999618 -137.409062) (xy 62.981137 -137.357141) (xy 62.970505 -137.303065) (xy 62.967952 -137.248012)
			(xy 62.973535 -137.193183) (xy 62.987132 -137.139775) (xy 63.008446 -137.088952) (xy 63.037014 -137.041821)
			(xy 63.05423 -137.0203) (xy 63.067852 -137.003042) (xy 63.089664 -136.964874) (xy 63.10458 -136.923521)
			(xy 63.112154 -136.880217) (xy 63.112161 -136.836256) (xy 63.104599 -136.792951) (xy 63.089695 -136.751593)
			(xy 63.067894 -136.713419) (xy 63.05423 -136.696196) (xy 63.036332 -136.673772) (xy 63.006875 -136.624538)
			(xy 62.985321 -136.571368) (xy 62.97218 -136.515521) (xy 62.967763 -136.458319) (xy 61.676788 -136.458319)
			(xy 61.676788 -136.673082) (xy 61.586364 -136.763506) (xy 61.15685 -136.763506) (xy 61.127386 -136.780524)
			(xy 61.100763 -136.795214) (xy 61.04388 -136.816686) (xy 60.984265 -136.828642) (xy 60.953904 -136.830308)
			(xy 60.903866 -136.832086) (xy 60.515246 -137.220706) (xy 60.513468 -137.270744) (xy 60.511182 -137.301224)
			(xy 60.505848 -137.33526) (xy 60.503054 -137.348214) (xy 60.503054 -137.967466) (xy 60.505848 -137.980674)
			(xy 60.510809 -138.006224) (xy 60.514431 -138.058143) (xy 60.514344 -138.059391) (xy 70.968852 -138.059391)
			(xy 70.972825 -138.005092) (xy 70.984657 -137.95195) (xy 71.004096 -137.901095) (xy 71.030728 -137.85361)
			(xy 71.063987 -137.810506) (xy 71.103164 -137.7727) (xy 71.147426 -137.740997) (xy 71.195829 -137.716073)
			(xy 71.247344 -137.698457) (xy 71.300874 -137.688525) (xy 71.35528 -137.686488) (xy 71.409403 -137.69239)
			(xy 71.462091 -137.706104) (xy 71.512222 -137.72734) (xy 71.55873 -137.755644) (xy 71.579994 -137.772648)
			(xy 71.597218 -137.786314) (xy 71.635395 -137.808119) (xy 71.676755 -137.823027) (xy 71.720064 -137.830595)
			(xy 71.764028 -137.830595) (xy 71.807337 -137.823027) (xy 71.848697 -137.808119) (xy 71.886874 -137.786314)
			(xy 71.904098 -137.772648) (xy 71.925511 -137.755416) (xy 71.972499 -137.726896) (xy 72.023167 -137.705589)
			(xy 72.076415 -137.691956) (xy 72.131088 -137.686292) (xy 72.186 -137.68872) (xy 72.239959 -137.699189)
			(xy 72.291796 -137.71747) (xy 72.340384 -137.743167) (xy 72.384671 -137.775723) (xy 72.423695 -137.814432)
			(xy 72.440546 -137.836148) (xy 72.451061 -137.84934) (xy 72.477631 -137.870111) (xy 72.508718 -137.883185)
			(xy 72.542146 -137.887647) (xy 72.575574 -137.883185) (xy 72.606661 -137.870111) (xy 72.633231 -137.84934)
			(xy 72.643746 -137.836148) (xy 72.65543 -137.821416) (xy 72.669133 -137.804219) (xy 72.69094 -137.766037)
			(xy 72.705849 -137.724672) (xy 72.713413 -137.681357) (xy 72.713408 -137.637387) (xy 72.705834 -137.594074)
			(xy 72.690917 -137.552712) (xy 72.669102 -137.514535) (xy 72.65543 -137.497312) (xy 72.638263 -137.47577)
			(xy 72.609718 -137.428663) (xy 72.588421 -137.377866) (xy 72.574834 -137.324487) (xy 72.569255 -137.26969)
			(xy 72.571804 -137.214668) (xy 72.582427 -137.160621) (xy 72.600891 -137.108727) (xy 72.626795 -137.060118)
			(xy 72.659573 -137.015851) (xy 72.698511 -136.976894) (xy 72.742761 -136.944094) (xy 72.791358 -136.918166)
			(xy 72.843243 -136.899676) (xy 72.897284 -136.889026) (xy 72.952305 -136.88645) (xy 73.007105 -136.892002)
			(xy 73.060491 -136.905562) (xy 73.111298 -136.926834) (xy 73.158419 -136.955355) (xy 73.17994 -136.972548)
			(xy 73.197182 -136.986216) (xy 73.235392 -137.008021) (xy 73.276783 -137.022929) (xy 73.320122 -137.030496)
			(xy 73.364116 -137.030496) (xy 73.407455 -137.022929) (xy 73.448846 -137.008021) (xy 73.487056 -136.986216)
			(xy 73.504298 -136.972548) (xy 73.526718 -136.954657) (xy 73.57597 -136.92526) (xy 73.629142 -136.903752)
			(xy 73.684981 -136.890641) (xy 73.742169 -136.886237) (xy 73.799357 -136.890641) (xy 73.855196 -136.903752)
			(xy 73.908368 -136.92526) (xy 73.95762 -136.954657) (xy 73.98004 -136.972548) (xy 73.997264 -136.986214)
			(xy 74.035441 -137.008019) (xy 74.076801 -137.022927) (xy 74.12011 -137.030495) (xy 74.164074 -137.030495)
			(xy 74.207383 -137.022927) (xy 74.248743 -137.008019) (xy 74.28692 -136.986214) (xy 74.304144 -136.972548)
			(xy 74.325187 -136.955766) (xy 74.371117 -136.927709) (xy 74.420605 -136.90655) (xy 74.472622 -136.89273)
			(xy 74.526086 -136.886535) (xy 74.579885 -136.888094) (xy 74.6329 -136.897376) (xy 74.684029 -136.914186)
			(xy 74.732208 -136.938176) (xy 74.776436 -136.968846) (xy 74.815792 -137.005558) (xy 74.849459 -137.04755)
			(xy 74.876735 -137.093948) (xy 74.897054 -137.143786) (xy 74.909994 -137.196029) (xy 74.915284 -137.24959)
			(xy 74.912816 -137.303355) (xy 74.90264 -137.356206) (xy 74.884968 -137.407043) (xy 74.860167 -137.45481)
			(xy 74.828754 -137.498513) (xy 74.791381 -137.537243) (xy 74.748826 -137.570195) (xy 74.701974 -137.596684)
			(xy 74.6518 -137.616158) (xy 74.599345 -137.628212) (xy 74.545703 -137.632597) (xy 74.491987 -137.62922)
			(xy 74.439316 -137.618152) (xy 74.388785 -137.599623) (xy 74.341444 -137.574019) (xy 74.298278 -137.541872)
			(xy 74.260185 -137.50385) (xy 74.243692 -137.48258) (xy 74.233177 -137.469388) (xy 74.206607 -137.448617)
			(xy 74.17552 -137.435543) (xy 74.142092 -137.431081) (xy 74.108664 -137.435543) (xy 74.077577 -137.448617)
			(xy 74.051007 -137.469388) (xy 74.040492 -137.48258) (xy 74.028808 -137.497312) (xy 74.015177 -137.514563)
			(xy 73.993371 -137.552734) (xy 73.97846 -137.594088) (xy 73.970889 -137.637392) (xy 73.970885 -137.681353)
			(xy 73.978446 -137.724658) (xy 73.993348 -137.766016) (xy 74.015145 -137.804191) (xy 74.028808 -137.821416)
			(xy 74.04596 -137.842967) (xy 74.074497 -137.890073) (xy 74.095788 -137.940867) (xy 74.109368 -137.994243)
			(xy 74.114943 -138.049035) (xy 74.112391 -138.104052) (xy 74.101766 -138.158093) (xy 74.083302 -138.209982)
			(xy 74.0574 -138.258586) (xy 74.024624 -138.302848) (xy 73.985689 -138.341802) (xy 73.941444 -138.3746)
			(xy 73.892852 -138.400527) (xy 73.840973 -138.419017) (xy 73.786937 -138.429668) (xy 73.731922 -138.432248)
			(xy 73.677126 -138.426701) (xy 73.623744 -138.413147) (xy 73.572939 -138.391881) (xy 73.525819 -138.363368)
			(xy 73.504298 -138.34618) (xy 73.487071 -138.332479) (xy 73.448873 -138.310614) (xy 73.407478 -138.295664)
			(xy 73.364125 -138.288074) (xy 73.320113 -138.288074) (xy 73.27676 -138.295664) (xy 73.235365 -138.310614)
			(xy 73.197167 -138.332479) (xy 73.17994 -138.34618) (xy 73.157533 -138.364101) (xy 73.108295 -138.393552)
			(xy 73.055122 -138.415101) (xy 72.999273 -138.428239) (xy 72.942069 -138.432652) (xy 72.884865 -138.428239)
			(xy 72.829016 -138.415101) (xy 72.775843 -138.393552) (xy 72.726605 -138.364101) (xy 72.704198 -138.34618)
			(xy 72.686974 -138.332514) (xy 72.648797 -138.310709) (xy 72.607437 -138.295801) (xy 72.564128 -138.288233)
			(xy 72.520164 -138.288233) (xy 72.476855 -138.295801) (xy 72.435495 -138.310709) (xy 72.397318 -138.332514)
			(xy 72.380094 -138.34618) (xy 72.357671 -138.364102) (xy 72.308403 -138.393554) (xy 72.255202 -138.415103)
			(xy 72.199326 -138.428239) (xy 72.142096 -138.432653) (xy 72.084866 -138.428239) (xy 72.02899 -138.415103)
			(xy 71.975789 -138.393554) (xy 71.926521 -138.364102) (xy 71.904098 -138.34618) (xy 71.886874 -138.332514)
			(xy 71.848697 -138.310709) (xy 71.807337 -138.295801) (xy 71.764028 -138.288233) (xy 71.720064 -138.288233)
			(xy 71.676755 -138.295801) (xy 71.635395 -138.310709) (xy 71.597218 -138.332514) (xy 71.579994 -138.34618)
			(xy 71.558716 -138.363166) (xy 71.512206 -138.391468) (xy 71.462074 -138.412701) (xy 71.409385 -138.426413)
			(xy 71.355262 -138.432313) (xy 71.300856 -138.430273) (xy 71.247327 -138.420339) (xy 71.195812 -138.40272)
			(xy 71.14741 -138.377794) (xy 71.10315 -138.346089) (xy 71.063975 -138.308281) (xy 71.030719 -138.265175)
			(xy 71.004088 -138.217689) (xy 70.984652 -138.166833) (xy 70.972822 -138.11369) (xy 70.968852 -138.059391)
			(xy 60.514344 -138.059391) (xy 60.510797 -138.110062) (xy 60.505848 -138.135614) (xy 60.503054 -138.148822)
			(xy 60.503054 -138.442954) (xy 58.488072 -140.457936) (xy 61.393321 -140.457936) (xy 61.397396 -140.404855)
			(xy 61.409526 -140.353019) (xy 61.429427 -140.303642) (xy 61.456632 -140.257881) (xy 61.490504 -140.216809)
			(xy 61.530248 -140.18139) (xy 61.574933 -140.152452) (xy 61.623512 -140.130674) (xy 61.674845 -140.116568)
			(xy 61.727731 -140.110462) (xy 61.780929 -140.112501) (xy 61.833192 -140.122637) (xy 61.883295 -140.140632)
			(xy 61.930064 -140.166064) (xy 61.972403 -140.198338) (xy 62.009319 -140.236696) (xy 62.039947 -140.28024)
			(xy 62.063569 -140.327949) (xy 62.079632 -140.378705) (xy 62.087759 -140.431318) (xy 62.088268 -140.457936)
			(xy 62.087759 -140.484554) (xy 62.079632 -140.537167) (xy 62.063569 -140.587923) (xy 62.039947 -140.635632)
			(xy 62.009319 -140.679176) (xy 61.972403 -140.717534) (xy 61.930064 -140.749808) (xy 61.883295 -140.77524)
			(xy 61.833192 -140.793235) (xy 61.780929 -140.803371) (xy 61.727731 -140.80541) (xy 61.674845 -140.799304)
			(xy 61.623512 -140.785198) (xy 61.574933 -140.76342) (xy 61.530248 -140.734482) (xy 61.490504 -140.699063)
			(xy 61.456632 -140.657991) (xy 61.429427 -140.61223) (xy 61.409526 -140.562853) (xy 61.397396 -140.511017)
			(xy 61.393321 -140.457936) (xy 58.488072 -140.457936) (xy 57.073292 -141.872716) (xy 57.073292 -142.036598)
			(xy 61.393826 -142.036598) (xy 61.401104 -141.984188) (xy 61.416247 -141.933488) (xy 61.438906 -141.885672)
			(xy 61.468554 -141.841846) (xy 61.504508 -141.803024) (xy 61.545933 -141.770105) (xy 61.591873 -141.743849)
			(xy 61.641263 -141.724866) (xy 61.692962 -141.713594) (xy 61.745772 -141.710293) (xy 61.798471 -141.715041)
			(xy 61.849841 -141.727727) (xy 61.898692 -141.748059) (xy 61.943894 -141.775564) (xy 61.984401 -141.809608)
			(xy 62.019276 -141.849401) (xy 62.033912 -141.871446) (xy 62.042905 -141.884619) (xy 62.066186 -141.906403)
			(xy 62.094144 -141.921729) (xy 62.125031 -141.92964) (xy 62.156915 -141.92964) (xy 62.187802 -141.921729)
			(xy 62.21576 -141.906403) (xy 62.239041 -141.884619) (xy 62.248034 -141.871446) (xy 62.255678 -141.859746)
			(xy 62.272591 -141.837495) (xy 62.281816 -141.826996) (xy 62.296821 -141.809405) (xy 62.32081 -141.769884)
			(xy 62.337256 -141.726676) (xy 62.345616 -141.681206) (xy 62.345614 -141.634973) (xy 62.33725 -141.589504)
			(xy 62.320801 -141.546297) (xy 62.296809 -141.506778) (xy 62.281816 -141.489176) (xy 62.264403 -141.468904)
			(xy 62.235364 -141.424044) (xy 62.213544 -141.375263) (xy 62.199456 -141.323715) (xy 62.193434 -141.270617)
			(xy 62.19562 -141.217223) (xy 62.205962 -141.164794) (xy 62.224216 -141.11457) (xy 62.249951 -141.067736)
			(xy 62.282559 -141.0254) (xy 62.32127 -140.98856) (xy 62.365169 -140.958087) (xy 62.413219 -140.934701)
			(xy 62.464285 -140.918955) (xy 62.517161 -140.91122) (xy 62.570597 -140.911679) (xy 62.623332 -140.920322)
			(xy 62.67412 -140.936943) (xy 62.721761 -140.961151) (xy 62.76513 -140.992374) (xy 62.803202 -141.029874)
			(xy 62.819534 -141.051026) (xy 62.828838 -141.062949) (xy 62.852085 -141.082288) (xy 62.879229 -141.095613)
			(xy 62.908747 -141.102179) (xy 62.93898 -141.101615) (xy 62.968233 -141.093953) (xy 62.994861 -141.079624)
			(xy 63.017371 -141.059432) (xy 63.02629 -141.047216) (xy 63.04661 -141.020038) (xy 63.060288 -141.002823)
			(xy 63.08209 -140.964644) (xy 63.096995 -140.923282) (xy 63.10456 -140.879972) (xy 63.104558 -140.836006)
			(xy 63.09699 -140.792697) (xy 63.082081 -140.751337) (xy 63.060276 -140.713159) (xy 63.04661 -140.695934)
			(xy 63.030401 -140.675613) (xy 63.003108 -140.631378) (xy 62.982225 -140.58378) (xy 62.968157 -140.533741)
			(xy 62.961178 -140.482234) (xy 62.961423 -140.430257) (xy 62.968887 -140.378818) (xy 62.983426 -140.328915)
			(xy 63.004756 -140.281515) (xy 63.032465 -140.237539) (xy 63.048896 -140.217398) (xy 63.062724 -140.2003)
			(xy 63.084902 -140.162332) (xy 63.10021 -140.121113) (xy 63.10819 -140.077873) (xy 63.108605 -140.033905)
			(xy 63.101441 -139.990523) (xy 63.086913 -139.949022) (xy 63.065455 -139.910643) (xy 63.051944 -139.893294)
			(xy 63.035121 -139.871895) (xy 63.007269 -139.82513) (xy 62.986517 -139.77481) (xy 62.973307 -139.722006)
			(xy 62.96792 -139.667843) (xy 62.970472 -139.613471) (xy 62.980907 -139.56005) (xy 62.999004 -139.508715)
			(xy 63.024377 -139.46056) (xy 63.056487 -139.416608) (xy 63.09465 -139.377797) (xy 63.138054 -139.344951)
			(xy 63.185775 -139.31877) (xy 63.236797 -139.29981) (xy 63.290035 -139.288476) (xy 63.344356 -139.285009)
			(xy 63.398603 -139.289482) (xy 63.451622 -139.3018) (xy 63.502284 -139.321701) (xy 63.549512 -139.348762)
			(xy 63.5923 -139.382406) (xy 63.629737 -139.421918) (xy 63.661028 -139.466457) (xy 63.685505 -139.515074)
			(xy 63.702648 -139.566735) (xy 63.712092 -139.62034) (xy 63.713461 -139.668603) (xy 66.167898 -139.668603)
			(xy 66.170448 -139.613555) (xy 66.181078 -139.559482) (xy 66.199556 -139.507565) (xy 66.225479 -139.458935)
			(xy 66.258282 -139.414654) (xy 66.297248 -139.375687) (xy 66.341529 -139.342883) (xy 66.390158 -139.316959)
			(xy 66.442075 -139.29848) (xy 66.496148 -139.287849) (xy 66.551196 -139.285298) (xy 66.60602 -139.290882)
			(xy 66.659424 -139.30448) (xy 66.710242 -139.325795) (xy 66.757367 -139.354362) (xy 66.778886 -139.371578)
			(xy 66.79611 -139.385244) (xy 66.834287 -139.407049) (xy 66.875647 -139.421957) (xy 66.918956 -139.429525)
			(xy 66.96292 -139.429525) (xy 67.006229 -139.421957) (xy 67.047589 -139.407049) (xy 67.085766 -139.385244)
			(xy 67.10299 -139.371578) (xy 67.124489 -139.354352) (xy 67.171601 -139.325801) (xy 67.222404 -139.304497)
			(xy 67.27579 -139.290906) (xy 67.330595 -139.285323) (xy 67.385625 -139.287871) (xy 67.43968 -139.298494)
			(xy 67.491581 -139.31696) (xy 67.540198 -139.342867) (xy 67.584471 -139.37565) (xy 67.623434 -139.414594)
			(xy 67.656238 -139.458851) (xy 67.682168 -139.507455) (xy 67.700659 -139.559348) (xy 67.711308 -139.613398)
			(xy 67.713882 -139.668427) (xy 67.708325 -139.723235) (xy 67.69476 -139.776627) (xy 67.67348 -139.82744)
			(xy 67.644951 -139.874566) (xy 67.627754 -139.896088) (xy 67.614119 -139.913354) (xy 67.592313 -139.951559)
			(xy 67.577403 -139.992946) (xy 67.569832 -140.03628) (xy 67.569828 -140.08027) (xy 67.57739 -140.123605)
			(xy 67.592291 -140.164994) (xy 67.61409 -140.203204) (xy 67.627754 -140.220446) (xy 67.644652 -140.241548)
			(xy 67.672779 -140.287715) (xy 67.693938 -140.337463) (xy 67.707683 -140.389747) (xy 67.713727 -140.443469)
			(xy 67.711942 -140.4975) (xy 67.702366 -140.550705) (xy 67.6852 -140.601968) (xy 67.660804 -140.650211)
			(xy 67.629691 -140.694421) (xy 67.592514 -140.733669) (xy 67.550054 -140.767132) (xy 67.503204 -140.794105)
			(xy 67.452947 -140.814024) (xy 67.400338 -140.826468) (xy 67.346483 -140.831178) (xy 67.292513 -140.828053)
			(xy 67.239561 -140.817161) (xy 67.18874 -140.798728) (xy 67.141117 -140.773143) (xy 67.097692 -140.740943)
			(xy 67.059378 -140.702805) (xy 67.042792 -140.681456) (xy 67.032268 -140.668239) (xy 67.005669 -140.647428)
			(xy 66.974541 -140.634327) (xy 66.941065 -140.629856) (xy 66.907589 -140.634327) (xy 66.876461 -140.647428)
			(xy 66.849862 -140.668239) (xy 66.839338 -140.681456) (xy 66.829432 -140.694156) (xy 66.815731 -140.711569)
			(xy 66.794058 -140.750211) (xy 66.779416 -140.792027) (xy 66.772248 -140.835748) (xy 66.772772 -140.880051)
			(xy 66.780973 -140.92359) (xy 66.7966 -140.965048) (xy 66.819182 -141.003167) (xy 66.833242 -141.020292)
			(xy 66.850651 -141.041291) (xy 66.879739 -141.087434) (xy 66.901788 -141.137326) (xy 66.916327 -141.189899)
			(xy 66.923046 -141.24403) (xy 66.9218 -141.298562) (xy 66.912617 -141.35233) (xy 66.895693 -141.404185)
			(xy 66.87139 -141.453018) (xy 66.840226 -141.497785) (xy 66.802868 -141.537531) (xy 66.760114 -141.571405)
			(xy 66.712879 -141.598684) (xy 66.662171 -141.618784) (xy 66.609074 -141.631276) (xy 66.554723 -141.635893)
			(xy 66.50028 -141.632537) (xy 66.446908 -141.621278) (xy 66.395748 -141.602358) (xy 66.347893 -141.576182)
			(xy 66.304366 -141.543307) (xy 66.266097 -141.504438) (xy 66.233904 -141.460405) (xy 66.208476 -141.412148)
			(xy 66.190354 -141.3607) (xy 66.179928 -141.307159) (xy 66.177419 -141.25267) (xy 66.182882 -141.198398)
			(xy 66.196199 -141.145502) (xy 66.217086 -141.095113) (xy 66.245096 -141.048308) (xy 66.261996 -141.026896)
			(xy 66.275644 -141.009445) (xy 66.297318 -140.97081) (xy 66.311964 -140.929003) (xy 66.319136 -140.885288)
			(xy 66.318619 -140.840993) (xy 66.310428 -140.797458) (xy 66.29481 -140.756004) (xy 66.27224 -140.717886)
			(xy 66.258186 -140.70076) (xy 66.241516 -140.680659) (xy 66.213394 -140.636657) (xy 66.191689 -140.58916)
			(xy 66.176829 -140.539099) (xy 66.169102 -140.487453) (xy 66.168661 -140.435234) (xy 66.175514 -140.383465)
			(xy 66.189528 -140.333159) (xy 66.210427 -140.285303) (xy 66.237802 -140.240832) (xy 66.254122 -140.220446)
			(xy 66.267792 -140.203225) (xy 66.289593 -140.165047) (xy 66.304498 -140.123686) (xy 66.312063 -140.080378)
			(xy 66.312063 -140.036413) (xy 66.304496 -139.993105) (xy 66.289589 -139.951745) (xy 66.267787 -139.913567)
			(xy 66.254122 -139.896342) (xy 66.236966 -139.874773) (xy 66.208398 -139.827649) (xy 66.187082 -139.776831)
			(xy 66.173483 -139.723427) (xy 66.167898 -139.668603) (xy 63.713461 -139.668603) (xy 63.713635 -139.67475)
			(xy 63.707247 -139.728804) (xy 63.693061 -139.781355) (xy 63.67138 -139.831281) (xy 63.642666 -139.877523)
			(xy 63.625476 -139.898628) (xy 63.611624 -139.915708) (xy 63.58945 -139.95368) (xy 63.574146 -139.994903)
			(xy 63.56617 -140.038145) (xy 63.565758 -140.082116) (xy 63.572925 -140.1255) (xy 63.587456 -140.167002)
			(xy 63.608916 -140.205382) (xy 63.622428 -140.222732) (xy 63.640037 -140.245146) (xy 63.668858 -140.294321)
			(xy 63.689856 -140.347312) (xy 63.702539 -140.402882) (xy 63.706612 -140.459736) (xy 63.70198 -140.516546)
			(xy 63.688751 -140.571989) (xy 63.667233 -140.62477) (xy 63.637929 -140.67366) (xy 63.620142 -140.695934)
			(xy 63.606488 -140.713168) (xy 63.584681 -140.751342) (xy 63.56977 -140.7927) (xy 63.5622 -140.836007)
			(xy 63.562198 -140.879971) (xy 63.569764 -140.923279) (xy 63.584672 -140.964638) (xy 63.606476 -141.002814)
			(xy 63.620142 -141.020038) (xy 63.63727 -141.04143) (xy 63.665747 -141.088248) (xy 63.687058 -141.138733)
			(xy 63.700745 -141.191795) (xy 63.706512 -141.24629) (xy 63.704234 -141.301041) (xy 63.693961 -141.354869)
			(xy 63.675915 -141.406611) (xy 63.650484 -141.455151) (xy 63.618217 -141.499443) (xy 63.579811 -141.538531)
			(xy 63.536093 -141.571571) (xy 63.488007 -141.597852) (xy 63.436591 -141.616806) (xy 63.382952 -141.628023)
			(xy 63.328249 -141.631264) (xy 63.273662 -141.626456) (xy 63.220367 -141.613704) (xy 63.169516 -141.593284)
			(xy 63.122203 -141.565635) (xy 63.079451 -141.531355) (xy 63.042182 -141.491181) (xy 63.02629 -141.468856)
			(xy 63.017441 -141.456581) (xy 62.994936 -141.436358) (xy 62.968299 -141.422009) (xy 62.939031 -141.414343)
			(xy 62.90878 -141.413792) (xy 62.879252 -141.420387) (xy 62.85211 -141.433756) (xy 62.828884 -141.453145)
			(xy 62.819534 -141.465046) (xy 62.799976 -141.489176) (xy 62.784998 -141.506789) (xy 62.761009 -141.546306)
			(xy 62.744561 -141.589509) (xy 62.736199 -141.634975) (xy 62.736197 -141.681204) (xy 62.744556 -141.72667)
			(xy 62.760999 -141.769875) (xy 62.784986 -141.809394) (xy 62.799976 -141.826996) (xy 62.816516 -141.846153)
			(xy 62.844366 -141.888412) (xy 62.865786 -141.934267) (xy 62.880322 -141.982746) (xy 62.887666 -142.032821)
			(xy 62.887662 -142.078438) (xy 63.801256 -142.078438) (xy 63.803397 -142.025266) (xy 63.813627 -141.973045)
			(xy 63.831708 -141.922996) (xy 63.857214 -141.876292) (xy 63.889549 -141.834029) (xy 63.927955 -141.797195)
			(xy 63.971533 -141.766653) (xy 64.019261 -141.74312) (xy 64.070021 -141.727146) (xy 64.122624 -141.719105)
			(xy 64.175839 -141.719187) (xy 64.228417 -141.727389) (xy 64.279128 -141.743518) (xy 64.326784 -141.767198)
			(xy 64.370268 -141.797873) (xy 64.40856 -141.834824) (xy 64.425068 -141.855698) (xy 64.434596 -141.867443)
			(xy 64.458014 -141.886562) (xy 64.485273 -141.899633) (xy 64.514843 -141.90592) (xy 64.545063 -141.905072)
			(xy 64.574233 -141.897136) (xy 64.600717 -141.882557) (xy 64.623025 -141.862154) (xy 64.631824 -141.849856)
			(xy 64.654176 -141.819884) (xy 64.66787 -141.802652) (xy 64.689731 -141.764455) (xy 64.704679 -141.723061)
			(xy 64.712268 -141.679709) (xy 64.712268 -141.635699) (xy 64.704681 -141.592347) (xy 64.689734 -141.550952)
			(xy 64.667874 -141.512754) (xy 64.654176 -141.495526) (xy 64.636267 -141.473136) (xy 64.606868 -141.423913)
			(xy 64.585359 -141.370766) (xy 64.572248 -141.314951) (xy 64.567844 -141.257786) (xy 64.572252 -141.200622)
			(xy 64.585367 -141.144808) (xy 64.60688 -141.091662) (xy 64.636283 -141.042442) (xy 64.654176 -141.020038)
			(xy 64.667914 -141.00284) (xy 64.689773 -140.964635) (xy 64.704717 -140.923234) (xy 64.7123 -140.879876)
			(xy 64.712295 -140.835861) (xy 64.704701 -140.792505) (xy 64.689746 -140.751108) (xy 64.667878 -140.712908)
			(xy 64.654176 -140.69568) (xy 64.637194 -140.67442) (xy 64.608931 -140.627927) (xy 64.587733 -140.577817)
			(xy 64.57405 -140.525156) (xy 64.568174 -140.471065) (xy 64.57023 -140.416694) (xy 64.580174 -140.363201)
			(xy 64.597795 -140.311724) (xy 64.622717 -140.263358) (xy 64.65441 -140.219132) (xy 64.6922 -140.179987)
			(xy 64.735283 -140.146757) (xy 64.782742 -140.120148) (xy 64.833567 -140.100726) (xy 64.886677 -140.088905)
			(xy 64.940942 -140.084937) (xy 64.995207 -140.088905) (xy 65.048317 -140.100726) (xy 65.099142 -140.120148)
			(xy 65.146601 -140.146757) (xy 65.189684 -140.179987) (xy 65.227474 -140.219132) (xy 65.259167 -140.263358)
			(xy 65.284089 -140.311724) (xy 65.30171 -140.363201) (xy 65.311654 -140.416694) (xy 65.31371 -140.471065)
			(xy 65.307834 -140.525156) (xy 65.294151 -140.577817) (xy 65.272953 -140.627927) (xy 65.24469 -140.67442)
			(xy 65.227708 -140.69568) (xy 65.214078 -140.712951) (xy 65.192267 -140.751154) (xy 65.177353 -140.792539)
			(xy 65.16978 -140.835873) (xy 65.169775 -140.879864) (xy 65.177337 -140.9232) (xy 65.192241 -140.964589)
			(xy 65.214042 -141.002797) (xy 65.227708 -141.020038) (xy 65.245579 -141.042456) (xy 65.274973 -141.091676)
			(xy 65.29648 -141.144818) (xy 65.309591 -141.200627) (xy 65.313998 -141.257786) (xy 65.309595 -141.314946)
			(xy 65.296488 -141.370756) (xy 65.274985 -141.423899) (xy 65.245595 -141.473121) (xy 65.227708 -141.495526)
			(xy 65.214034 -141.512764) (xy 65.192226 -141.550974) (xy 65.177316 -141.592366) (xy 65.169748 -141.635706)
			(xy 65.169749 -141.679702) (xy 65.177318 -141.723041) (xy 65.192229 -141.764433) (xy 65.214038 -141.802643)
			(xy 65.227708 -141.819884) (xy 65.245623 -141.842268) (xy 65.275015 -141.891495) (xy 65.296518 -141.944643)
			(xy 65.309626 -142.000458) (xy 65.314027 -142.057622) (xy 65.313092 -142.069752) (xy 67.76803 -142.069752)
			(xy 67.770492 -142.015992) (xy 67.78066 -141.963145) (xy 67.798323 -141.91231) (xy 67.823115 -141.864544)
			(xy 67.854518 -141.820841) (xy 67.891881 -141.782108) (xy 67.934426 -141.749152) (xy 67.981269 -141.722657)
			(xy 68.031435 -141.703176) (xy 68.083882 -141.691112) (xy 68.137519 -141.686717) (xy 68.19123 -141.690082)
			(xy 68.243898 -141.701137) (xy 68.294429 -141.719652) (xy 68.341772 -141.745243) (xy 68.384942 -141.777376)
			(xy 68.423041 -141.815385) (xy 68.439538 -141.836648) (xy 68.450053 -141.84984) (xy 68.476623 -141.870611)
			(xy 68.50771 -141.883685) (xy 68.541138 -141.888147) (xy 68.574566 -141.883685) (xy 68.605653 -141.870611)
			(xy 68.632223 -141.84984) (xy 68.642738 -141.836648) (xy 68.654676 -141.821662) (xy 68.668397 -141.804398)
			(xy 68.690345 -141.766156) (xy 68.705356 -141.724697) (xy 68.712978 -141.681269) (xy 68.712982 -141.637176)
			(xy 68.705368 -141.593746) (xy 68.690364 -141.552284) (xy 68.668422 -141.514039) (xy 68.654676 -141.496796)
			(xy 68.637928 -141.476099) (xy 68.610007 -141.430765) (xy 68.588824 -141.381917) (xy 68.574811 -141.330551)
			(xy 68.568253 -141.277713) (xy 68.569284 -141.22448) (xy 68.577882 -141.171935) (xy 68.593873 -141.12115)
			(xy 68.616931 -141.073159) (xy 68.646586 -141.028939) (xy 68.664074 -141.008862) (xy 68.678876 -140.991834)
			(xy 68.702729 -140.953541) (xy 68.719443 -140.911636) (xy 68.728493 -140.867438) (xy 68.729595 -140.822337)
			(xy 68.722713 -140.77775) (xy 68.708064 -140.735079) (xy 68.686109 -140.695667) (xy 68.672202 -140.6779)
			(xy 68.655525 -140.656804) (xy 68.628313 -140.610423) (xy 68.608578 -140.560399) (xy 68.596794 -140.507931)
			(xy 68.593241 -140.454274) (xy 68.598004 -140.40071) (xy 68.610971 -140.348521) (xy 68.631831 -140.298956)
			(xy 68.660083 -140.253201) (xy 68.695054 -140.21235) (xy 68.735906 -140.17738) (xy 68.781662 -140.149128)
			(xy 68.831227 -140.128269) (xy 68.883416 -140.115303) (xy 68.93698 -140.110541) (xy 68.990637 -140.114094)
			(xy 69.043105 -140.12588) (xy 69.093128 -140.145616) (xy 69.139509 -140.172829) (xy 69.160644 -140.189458)
			(xy 69.178418 -140.203349) (xy 69.21783 -140.225282) (xy 69.260496 -140.239914) (xy 69.305075 -140.246785)
			(xy 69.350166 -140.245678) (xy 69.394354 -140.236629) (xy 69.43625 -140.219922) (xy 69.474539 -140.196081)
			(xy 69.491606 -140.18133) (xy 69.511703 -140.163875) (xy 69.555925 -140.134247) (xy 69.603912 -140.111212)
			(xy 69.654688 -140.095239) (xy 69.707221 -140.086652) (xy 69.76044 -140.085627) (xy 69.813264 -140.092184)
			(xy 69.864618 -140.10619) (xy 69.913457 -140.12736) (xy 69.958787 -140.155262) (xy 69.97954 -140.171932)
			(xy 69.996789 -140.185658) (xy 70.03501 -140.207614) (xy 70.076443 -140.222652) (xy 70.119848 -140.230322)
			(xy 70.163926 -140.230393) (xy 70.207356 -140.222865) (xy 70.248838 -140.207962) (xy 70.287129 -140.186131)
			(xy 70.304406 -140.17244) (xy 70.325882 -140.155339) (xy 70.372823 -140.12688) (xy 70.423434 -140.105619)
			(xy 70.476616 -140.092016) (xy 70.531219 -140.086367) (xy 70.586061 -140.088793) (xy 70.639952 -140.099242)
			(xy 70.691725 -140.117488) (xy 70.740261 -140.143135) (xy 70.784506 -140.175628) (xy 70.823502 -140.214263)
			(xy 70.840346 -140.23594) (xy 70.850896 -140.249113) (xy 70.877515 -140.269842) (xy 70.90863 -140.282887)
			(xy 70.942073 -140.287338) (xy 70.975516 -140.282887) (xy 71.006631 -140.269842) (xy 71.03325 -140.249113)
			(xy 71.0438 -140.23594) (xy 71.064882 -140.210032) (xy 71.079608 -140.19297) (xy 71.103386 -140.154688)
			(xy 71.120038 -140.112811) (xy 71.129041 -140.068653) (xy 71.130113 -140.0236) (xy 71.123219 -139.979064)
			(xy 71.108577 -139.936443) (xy 71.086646 -139.897074) (xy 71.072756 -139.879324) (xy 71.056262 -139.858284)
			(xy 71.029178 -139.812195) (xy 71.009478 -139.7625) (xy 70.99763 -139.710371) (xy 70.993913 -139.657043)
			(xy 70.998414 -139.603775) (xy 71.011028 -139.551827) (xy 71.031456 -139.502426) (xy 71.059215 -139.456741)
			(xy 71.09365 -139.415851) (xy 71.133945 -139.380723) (xy 71.17915 -139.352187) (xy 71.228194 -139.330917)
			(xy 71.279919 -139.317418) (xy 71.333103 -139.312007) (xy 71.386487 -139.314813) (xy 71.43881 -139.325769)
			(xy 71.488835 -139.344616) (xy 71.53538 -139.370909) (xy 71.577344 -139.404026) (xy 71.613735 -139.443185)
			(xy 71.643694 -139.487459) (xy 71.666511 -139.535803) (xy 71.681648 -139.587073) (xy 71.688747 -139.640057)
			(xy 71.688342 -139.659614) (xy 73.394059 -139.659614) (xy 73.398134 -139.606533) (xy 73.410264 -139.554697)
			(xy 73.430165 -139.50532) (xy 73.45737 -139.459559) (xy 73.491242 -139.418487) (xy 73.530986 -139.383068)
			(xy 73.575671 -139.35413) (xy 73.62425 -139.332352) (xy 73.675583 -139.318246) (xy 73.728469 -139.31214)
			(xy 73.781667 -139.314179) (xy 73.83393 -139.324315) (xy 73.884033 -139.34231) (xy 73.930802 -139.367742)
			(xy 73.973141 -139.400016) (xy 74.010057 -139.438374) (xy 74.040685 -139.481918) (xy 74.064307 -139.529627)
			(xy 74.08037 -139.580383) (xy 74.088497 -139.632996) (xy 74.089006 -139.659614) (xy 74.088497 -139.686232)
			(xy 74.08037 -139.738845) (xy 74.064307 -139.789601) (xy 74.040685 -139.83731) (xy 74.010057 -139.880854)
			(xy 73.973141 -139.919212) (xy 73.930802 -139.951486) (xy 73.884033 -139.976918) (xy 73.83393 -139.994913)
			(xy 73.781667 -140.005049) (xy 73.728469 -140.007088) (xy 73.675583 -140.000982) (xy 73.62425 -139.986876)
			(xy 73.575671 -139.965098) (xy 73.530986 -139.93616) (xy 73.491242 -139.900741) (xy 73.45737 -139.859669)
			(xy 73.430165 -139.813908) (xy 73.410264 -139.764531) (xy 73.398134 -139.712695) (xy 73.394059 -139.659614)
			(xy 71.688342 -139.659614) (xy 71.68764 -139.693503) (xy 71.678353 -139.746148) (xy 71.661105 -139.796747)
			(xy 71.636305 -139.844104) (xy 71.604539 -139.8871) (xy 71.566557 -139.924718) (xy 71.545196 -139.940792)
			(xy 71.533009 -139.950082) (xy 71.513167 -139.973427) (xy 71.499469 -140.000833) (xy 71.492707 -140.030716)
			(xy 71.493272 -140.061348) (xy 71.501131 -140.090962) (xy 71.515829 -140.117844) (xy 71.536518 -140.140442)
			(xy 71.549006 -140.149326) (xy 71.557011 -140.15475) (xy 71.572513 -140.166313) (xy 71.579994 -140.17244)
			(xy 71.597218 -140.186106) (xy 71.635395 -140.207911) (xy 71.676755 -140.222819) (xy 71.720064 -140.230387)
			(xy 71.764028 -140.230387) (xy 71.807337 -140.222819) (xy 71.848697 -140.207911) (xy 71.886874 -140.186106)
			(xy 71.904098 -140.17244) (xy 71.926521 -140.154518) (xy 71.975789 -140.125066) (xy 72.02899 -140.103517)
			(xy 72.084866 -140.090381) (xy 72.142096 -140.085967) (xy 72.199326 -140.090381) (xy 72.255202 -140.103517)
			(xy 72.308403 -140.125066) (xy 72.357671 -140.154518) (xy 72.380094 -140.17244) (xy 72.397318 -140.186106)
			(xy 72.435495 -140.207911) (xy 72.476855 -140.222819) (xy 72.520164 -140.230387) (xy 72.564128 -140.230387)
			(xy 72.607437 -140.222819) (xy 72.648797 -140.207911) (xy 72.686974 -140.186106) (xy 72.704198 -140.17244)
			(xy 72.725284 -140.155488) (xy 72.771476 -140.127316) (xy 72.821256 -140.106119) (xy 72.873577 -140.092342)
			(xy 72.927341 -140.086275) (xy 72.981417 -140.088045) (xy 73.034669 -140.097616) (xy 73.085977 -140.114785)
			(xy 73.134264 -140.139192) (xy 73.178515 -140.170325) (xy 73.217799 -140.207528) (xy 73.251292 -140.25002)
			(xy 73.278288 -140.296909) (xy 73.298222 -140.347208) (xy 73.310673 -140.39986) (xy 73.315381 -140.45376)
			(xy 73.312246 -140.507774) (xy 73.301335 -140.560767) (xy 73.282876 -140.611626) (xy 73.257257 -140.659281)
			(xy 73.225018 -140.702732) (xy 73.186835 -140.741065) (xy 73.165462 -140.757656) (xy 73.152313 -140.768222)
			(xy 73.131542 -140.794779) (xy 73.118464 -140.825855) (xy 73.113996 -140.859274) (xy 73.117579 -140.886159)
			(xy 74.586328 -140.886159) (xy 74.586328 -140.832861) (xy 74.594271 -140.780157) (xy 74.609981 -140.729227)
			(xy 74.633107 -140.681206) (xy 74.663131 -140.637169) (xy 74.699383 -140.598098) (xy 74.741054 -140.564867)
			(xy 74.787212 -140.538218) (xy 74.836826 -140.518746) (xy 74.888788 -140.506886) (xy 74.941938 -140.502903)
			(xy 74.995088 -140.506886) (xy 75.04705 -140.518746) (xy 75.096664 -140.538218) (xy 75.142822 -140.564867)
			(xy 75.184493 -140.598098) (xy 75.220745 -140.637169) (xy 75.250769 -140.681206) (xy 75.273895 -140.729227)
			(xy 75.289605 -140.780157) (xy 75.297548 -140.832861) (xy 75.298046 -140.85951) (xy 75.297548 -140.886159)
			(xy 75.289605 -140.938863) (xy 75.273895 -140.989793) (xy 75.250769 -141.037814) (xy 75.220745 -141.081851)
			(xy 75.184493 -141.120922) (xy 75.142822 -141.154153) (xy 75.096664 -141.180802) (xy 75.04705 -141.200274)
			(xy 74.995088 -141.212134) (xy 74.941938 -141.216118) (xy 74.888788 -141.212134) (xy 74.836826 -141.200274)
			(xy 74.787212 -141.180802) (xy 74.741054 -141.154153) (xy 74.699383 -141.120922) (xy 74.663131 -141.081851)
			(xy 74.633107 -141.037814) (xy 74.609981 -140.989793) (xy 74.594271 -140.938863) (xy 74.586328 -140.886159)
			(xy 73.117579 -140.886159) (xy 73.11845 -140.892694) (xy 73.131515 -140.923775) (xy 73.152275 -140.950341)
			(xy 73.165462 -140.960856) (xy 73.180194 -140.97254) (xy 73.197418 -140.986206) (xy 73.235595 -141.008011)
			(xy 73.276955 -141.022919) (xy 73.320264 -141.030487) (xy 73.364228 -141.030487) (xy 73.407537 -141.022919)
			(xy 73.448897 -141.008011) (xy 73.487074 -140.986206) (xy 73.504298 -140.97254) (xy 73.525401 -140.955617)
			(xy 73.57159 -140.927461) (xy 73.621364 -140.906279) (xy 73.673677 -140.892517) (xy 73.727431 -140.886464)
			(xy 73.781496 -140.888246) (xy 73.834734 -140.897827) (xy 73.886028 -140.915006) (xy 73.934298 -140.93942)
			(xy 73.978532 -140.970557) (xy 74.017798 -141.007763) (xy 74.051272 -141.050256) (xy 74.07825 -141.097142)
			(xy 74.098165 -141.147436) (xy 74.110599 -141.200081) (xy 74.115291 -141.253971) (xy 74.11214 -141.307973)
			(xy 74.101215 -141.360952) (xy 74.082744 -141.411794) (xy 74.057116 -141.459432) (xy 74.024869 -141.502863)
			(xy 73.986682 -141.541175) (xy 73.965308 -141.557756) (xy 73.952155 -141.568328) (xy 73.931432 -141.594944)
			(xy 73.918391 -141.626053) (xy 73.913939 -141.65949) (xy 73.918386 -141.692927) (xy 73.931422 -141.724038)
			(xy 73.952141 -141.750658) (xy 73.965308 -141.76121) (xy 73.98004 -141.77264) (xy 73.99728 -141.786321)
			(xy 74.035458 -141.808205) (xy 74.076837 -141.823183) (xy 74.120177 -141.830805) (xy 74.164183 -141.830843)
			(xy 74.207537 -141.823296) (xy 74.248941 -141.808391) (xy 74.287157 -141.786572) (xy 74.304398 -141.772894)
			(xy 74.32591 -141.755704) (xy 74.373016 -141.727191) (xy 74.423806 -141.705923) (xy 74.477173 -141.692364)
			(xy 74.531955 -141.686808) (xy 74.586959 -141.689377) (xy 74.640984 -141.700015) (xy 74.692856 -141.71849)
			(xy 74.741442 -141.7444) (xy 74.785685 -141.777179) (xy 74.824621 -141.816115) (xy 74.8574 -141.860358)
			(xy 74.88331 -141.908945) (xy 74.901785 -141.960816) (xy 74.912423 -142.014842) (xy 74.914992 -142.069845)
			(xy 74.909436 -142.124627) (xy 74.895877 -142.177995) (xy 74.874609 -142.228785) (xy 74.846095 -142.275891)
			(xy 74.828908 -142.297404) (xy 74.815255 -142.314658) (xy 74.793446 -142.352864) (xy 74.778534 -142.394253)
			(xy 74.770964 -142.43759) (xy 74.770961 -142.481584) (xy 74.778527 -142.524921) (xy 74.793435 -142.566312)
			(xy 74.81524 -142.604521) (xy 74.828908 -142.621762) (xy 74.846831 -142.644158) (xy 74.876227 -142.693414)
			(xy 74.897733 -142.74659) (xy 74.910841 -142.802434) (xy 74.915243 -142.859625) (xy 74.910834 -142.916817)
			(xy 74.897718 -142.972658) (xy 74.876205 -143.025832) (xy 74.846802 -143.075084) (xy 74.828908 -143.097504)
			(xy 74.815285 -143.114761) (xy 74.793478 -143.15293) (xy 74.778567 -143.194284) (xy 74.770995 -143.237586)
			(xy 74.770989 -143.281546) (xy 74.778549 -143.324851) (xy 74.79345 -143.366208) (xy 74.815246 -143.404383)
			(xy 74.828908 -143.421608) (xy 74.846082 -143.44316) (xy 74.874641 -143.490286) (xy 74.89595 -143.541105)
			(xy 74.909542 -143.594507) (xy 74.915122 -143.649328) (xy 74.912568 -143.704374) (xy 74.901935 -143.758443)
			(xy 74.883455 -143.810357) (xy 74.857532 -143.858983) (xy 74.82473 -143.903262) (xy 74.785765 -143.942227)
			(xy 74.741487 -143.975029) (xy 74.692861 -144.000953) (xy 74.640948 -144.019433) (xy 74.586879 -144.030067)
			(xy 74.531833 -144.032622) (xy 74.477011 -144.027043) (xy 74.423609 -144.013451) (xy 74.372791 -143.992144)
			(xy 74.325664 -143.963584) (xy 74.304144 -143.946372) (xy 74.28692 -143.932706) (xy 74.248743 -143.910901)
			(xy 74.207383 -143.895993) (xy 74.164074 -143.888425) (xy 74.12011 -143.888425) (xy 74.076801 -143.895993)
			(xy 74.035441 -143.910901) (xy 73.997264 -143.932706) (xy 73.98004 -143.946372) (xy 73.957617 -143.964294)
			(xy 73.908349 -143.993746) (xy 73.855148 -144.015295) (xy 73.799272 -144.028431) (xy 73.742042 -144.032845)
			(xy 73.684812 -144.028431) (xy 73.628936 -144.015295) (xy 73.575735 -143.993746) (xy 73.526467 -143.964294)
			(xy 73.504044 -143.946372) (xy 73.48682 -143.932706) (xy 73.448643 -143.910901) (xy 73.407283 -143.895993)
			(xy 73.363974 -143.888425) (xy 73.32001 -143.888425) (xy 73.276701 -143.895993) (xy 73.235341 -143.910901)
			(xy 73.197164 -143.932706) (xy 73.17994 -143.946372) (xy 73.157497 -143.964237) (xy 73.108237 -143.993622)
			(xy 73.055055 -144.015113) (xy 72.99921 -144.028203) (xy 72.942018 -144.032582) (xy 72.88483 -144.028147)
			(xy 72.828997 -144.015003) (xy 72.775837 -143.99346) (xy 72.726605 -143.964026) (xy 72.704198 -143.946118)
			(xy 72.686974 -143.932452) (xy 72.648797 -143.910647) (xy 72.607437 -143.895739) (xy 72.564128 -143.888171)
			(xy 72.520164 -143.888171) (xy 72.476855 -143.895739) (xy 72.435495 -143.910647) (xy 72.397318 -143.932452)
			(xy 72.380094 -143.946118) (xy 72.358958 -143.963003) (xy 72.312771 -143.991164) (xy 72.262999 -144.012353)
			(xy 72.210686 -144.026122) (xy 72.156931 -144.032184) (xy 72.102865 -144.030411) (xy 72.049624 -144.020839)
			(xy 71.998325 -144.003671) (xy 71.950048 -143.979267) (xy 71.905806 -143.948139) (xy 71.86653 -143.910942)
			(xy 71.833043 -143.868457) (xy 71.806051 -143.821578) (xy 71.786121 -143.771288) (xy 71.77367 -143.718645)
			(xy 71.768961 -143.664756) (xy 71.772092 -143.610751) (xy 71.782999 -143.557767) (xy 71.801451 -143.506916)
			(xy 71.827061 -143.459268) (xy 71.859291 -143.415822) (xy 71.897463 -143.377493) (xy 71.91883 -143.360902)
			(xy 71.932021 -143.350385) (xy 71.952794 -143.323817) (xy 71.96587 -143.29273) (xy 71.970333 -143.259301)
			(xy 71.96587 -143.225873) (xy 71.952795 -143.194786) (xy 71.932023 -143.168217) (xy 71.91883 -143.157702)
			(xy 71.904098 -143.146018) (xy 71.886874 -143.132352) (xy 71.848697 -143.110547) (xy 71.807337 -143.095639)
			(xy 71.764028 -143.088071) (xy 71.720064 -143.088071) (xy 71.676755 -143.095639) (xy 71.635395 -143.110547)
			(xy 71.597218 -143.132352) (xy 71.579994 -143.146018) (xy 71.558914 -143.162956) (xy 71.512742 -143.191108)
			(xy 71.462986 -143.21229) (xy 71.41069 -143.226057) (xy 71.356954 -143.23212) (xy 71.302905 -143.230351)
			(xy 71.24968 -143.220788) (xy 71.198396 -143.203632) (xy 71.150131 -143.179243) (xy 71.105898 -143.148132)
			(xy 71.066627 -143.110955) (xy 71.033143 -143.068491) (xy 71.006149 -143.021633) (xy 70.986211 -142.971365)
			(xy 70.97375 -142.918743) (xy 70.969026 -142.864872) (xy 70.972139 -142.810885) (xy 70.983023 -142.757914)
			(xy 71.00145 -142.707073) (xy 71.027033 -142.659429) (xy 71.059234 -142.615985) (xy 71.097377 -142.577651)
			(xy 71.11873 -142.561056) (xy 71.131919 -142.5505) (xy 71.152733 -142.523909) (xy 71.165837 -142.492787)
			(xy 71.170313 -142.459317) (xy 71.165847 -142.425846) (xy 71.152751 -142.394721) (xy 71.131944 -142.368125)
			(xy 71.11873 -142.357602) (xy 71.104252 -142.346172) (xy 71.087025 -142.332471) (xy 71.048827 -142.310606)
			(xy 71.007432 -142.295656) (xy 70.964079 -142.288066) (xy 70.920067 -142.288066) (xy 70.876714 -142.295656)
			(xy 70.835319 -142.310606) (xy 70.797121 -142.332471) (xy 70.779894 -142.346172) (xy 70.758791 -142.363104)
			(xy 70.712586 -142.391252) (xy 70.662795 -142.412421) (xy 70.610466 -142.426166) (xy 70.556699 -142.432197)
			(xy 70.502626 -142.430389) (xy 70.449382 -142.420778) (xy 70.398088 -142.403568) (xy 70.349823 -142.37912)
			(xy 70.305602 -142.347947) (xy 70.266354 -142.310707) (xy 70.232905 -142.268181) (xy 70.205959 -142.221265)
			(xy 70.186082 -142.170944) (xy 70.173692 -142.118278) (xy 70.16905 -142.064373) (xy 70.172253 -142.010364)
			(xy 70.183235 -141.957386) (xy 70.201763 -141.906554) (xy 70.227449 -141.858936) (xy 70.259753 -141.815533)
			(xy 70.297994 -141.77726) (xy 70.319392 -141.760702) (xy 70.332582 -141.750112) (xy 70.353427 -141.723495)
			(xy 70.366552 -141.692338) (xy 70.371037 -141.658829) (xy 70.366567 -141.625317) (xy 70.353456 -141.594155)
			(xy 70.332623 -141.567528) (xy 70.319392 -141.556994) (xy 70.292976 -141.535404) (xy 70.275899 -141.520666)
			(xy 70.237531 -141.496951) (xy 70.195579 -141.48038) (xy 70.151361 -141.471474) (xy 70.106266 -141.470511)
			(xy 70.061708 -141.477522) (xy 70.019087 -141.492287) (xy 69.979742 -141.514342) (xy 69.962014 -141.528292)
			(xy 69.941788 -141.54441) (xy 69.897411 -141.570973) (xy 69.849588 -141.590665) (xy 69.799373 -141.60305)
			(xy 69.747877 -141.607853) (xy 69.696238 -141.60497) (xy 69.645597 -141.594464) (xy 69.597074 -141.576566)
			(xy 69.551739 -141.551672) (xy 69.510596 -141.520333) (xy 69.474553 -141.483242) (xy 69.459094 -141.462506)
			(xy 69.449833 -141.450291) (xy 69.426546 -141.430369) (xy 69.399175 -141.416587) (xy 69.369303 -141.409742)
			(xy 69.338661 -141.410231) (xy 69.309023 -141.418026) (xy 69.282105 -141.432675) (xy 69.259466 -141.453331)
			(xy 69.25056 -141.465808) (xy 69.227446 -141.496542) (xy 69.213754 -141.513817) (xy 69.191863 -141.552072)
			(xy 69.176894 -141.593528) (xy 69.169294 -141.636943) (xy 69.169291 -141.681019) (xy 69.176884 -141.724435)
			(xy 69.191847 -141.765893) (xy 69.213732 -141.804151) (xy 69.227446 -141.821408) (xy 69.245388 -141.843791)
			(xy 69.274911 -141.892973) (xy 69.296548 -141.946099) (xy 69.309789 -142.001913) (xy 69.31432 -142.059096)
			(xy 69.310035 -142.116299) (xy 69.297035 -142.172169) (xy 69.275626 -142.225388) (xy 69.246316 -142.274697)
			(xy 69.228462 -142.29715) (xy 69.214864 -142.314394) (xy 69.193135 -142.35255) (xy 69.178279 -142.393869)
			(xy 69.170738 -142.437126) (xy 69.170734 -142.481035) (xy 69.178269 -142.524293) (xy 69.193119 -142.565615)
			(xy 69.214842 -142.603774) (xy 69.228462 -142.621) (xy 69.24626 -142.643426) (xy 69.275516 -142.692638)
			(xy 69.296901 -142.745746) (xy 69.309913 -142.801499) (xy 69.314244 -142.858586) (xy 69.309795 -142.915664)
			(xy 69.296668 -142.97139) (xy 69.275173 -143.024453) (xy 69.245816 -143.073604) (xy 69.227954 -143.09598)
			(xy 69.214327 -143.113252) (xy 69.19252 -143.151456) (xy 69.17761 -143.192841) (xy 69.170039 -143.236174)
			(xy 69.170033 -143.280163) (xy 69.177593 -143.323498) (xy 69.192494 -143.364886) (xy 69.214291 -143.403096)
			(xy 69.227954 -143.420338) (xy 69.244936 -143.441598) (xy 69.273199 -143.488091) (xy 69.294397 -143.538201)
			(xy 69.30808 -143.590862) (xy 69.313956 -143.644953) (xy 69.3119 -143.699324) (xy 69.301956 -143.752817)
			(xy 69.284335 -143.804294) (xy 69.259413 -143.85266) (xy 69.22772 -143.896886) (xy 69.18993 -143.936031)
			(xy 69.146847 -143.969261) (xy 69.099388 -143.99587) (xy 69.048563 -144.015292) (xy 68.995453 -144.027113)
			(xy 68.941188 -144.031081) (xy 68.886923 -144.027113) (xy 68.833813 -144.015292) (xy 68.782988 -143.99587)
			(xy 68.735529 -143.969261) (xy 68.692446 -143.936031) (xy 68.654656 -143.896886) (xy 68.622963 -143.85266)
			(xy 68.598041 -143.804294) (xy 68.58042 -143.752817) (xy 68.570476 -143.699324) (xy 68.56842 -143.644953)
			(xy 68.574296 -143.590862) (xy 68.587979 -143.538201) (xy 68.609177 -143.488091) (xy 68.63744 -143.441598)
			(xy 68.654422 -143.420338) (xy 68.668163 -143.403141) (xy 68.690026 -143.364937) (xy 68.704974 -143.323536)
			(xy 68.712558 -143.280177) (xy 68.712553 -143.23616) (xy 68.704957 -143.192803) (xy 68.689999 -143.151405)
			(xy 68.668127 -143.113207) (xy 68.654422 -143.09598) (xy 68.637273 -143.074589) (xy 68.608837 -143.027717)
			(xy 68.587577 -142.977182) (xy 68.573955 -142.924078) (xy 68.568265 -142.86955) (xy 68.570628 -142.814776)
			(xy 68.580995 -142.760941) (xy 68.599141 -142.709207) (xy 68.624674 -142.660692) (xy 68.657043 -142.616443)
			(xy 68.695548 -142.577417) (xy 68.71716 -142.560548) (xy 68.730334 -142.550058) (xy 68.751028 -142.523503)
			(xy 68.76405 -142.492457) (xy 68.768491 -142.459085) (xy 68.764042 -142.425714) (xy 68.751013 -142.394671)
			(xy 68.730312 -142.368121) (xy 68.71716 -142.357602) (xy 68.70319 -142.34668) (xy 68.685966 -142.333014)
			(xy 68.647789 -142.311209) (xy 68.606429 -142.296301) (xy 68.56312 -142.288733) (xy 68.519156 -142.288733)
			(xy 68.475847 -142.296301) (xy 68.434487 -142.311209) (xy 68.39631 -142.333014) (xy 68.379086 -142.34668)
			(xy 68.3581 -142.363527) (xy 68.312174 -142.391581) (xy 68.262691 -142.412737) (xy 68.210679 -142.426557)
			(xy 68.15722 -142.432752) (xy 68.103427 -142.431194) (xy 68.050416 -142.421915) (xy 67.999292 -142.405108)
			(xy 67.951116 -142.381123) (xy 67.90689 -142.350459) (xy 67.867535 -142.313752) (xy 67.833869 -142.271767)
			(xy 67.806591 -142.225376) (xy 67.786269 -142.175544) (xy 67.773326 -142.123307) (xy 67.76803 -142.069752)
			(xy 65.313092 -142.069752) (xy 65.309619 -142.114785) (xy 65.296505 -142.170599) (xy 65.274996 -142.223744)
			(xy 65.245598 -142.272967) (xy 65.227708 -142.295372) (xy 65.214086 -142.312649) (xy 65.192274 -142.35085)
			(xy 65.17736 -142.392235) (xy 65.169786 -142.435567) (xy 65.16978 -142.479557) (xy 65.17734 -142.522892)
			(xy 65.192243 -142.564281) (xy 65.214043 -142.602489) (xy 65.227708 -142.61973) (xy 65.245571 -142.642154)
			(xy 65.274966 -142.691373) (xy 65.296473 -142.744513) (xy 65.309585 -142.800322) (xy 65.313993 -142.857474)
			(xy 66.167772 -142.857474) (xy 66.171748 -142.803148) (xy 66.183591 -142.749979) (xy 66.20305 -142.699102)
			(xy 66.22971 -142.6516) (xy 66.263001 -142.608486) (xy 66.302215 -142.570679) (xy 66.346517 -142.538984)
			(xy 66.39496 -142.514078) (xy 66.446514 -142.49649) (xy 66.50008 -142.486596) (xy 66.554515 -142.484606)
			(xy 66.60866 -142.490564) (xy 66.66136 -142.504342) (xy 66.711493 -142.525646) (xy 66.757989 -142.554022)
			(xy 66.799859 -142.588866) (xy 66.836208 -142.629435) (xy 66.866264 -142.674864) (xy 66.889385 -142.724185)
			(xy 66.905078 -142.776347) (xy 66.913009 -142.830238) (xy 66.913506 -142.857474) (xy 66.913009 -142.88471)
			(xy 66.905078 -142.938601) (xy 66.889385 -142.990763) (xy 66.866264 -143.040084) (xy 66.836208 -143.085513)
			(xy 66.799859 -143.126082) (xy 66.757989 -143.160926) (xy 66.711493 -143.189302) (xy 66.66136 -143.210606)
			(xy 66.60866 -143.224384) (xy 66.554515 -143.230342) (xy 66.50008 -143.228352) (xy 66.446514 -143.218458)
			(xy 66.39496 -143.20087) (xy 66.346517 -143.175964) (xy 66.302215 -143.144269) (xy 66.263001 -143.106462)
			(xy 66.22971 -143.063348) (xy 66.20305 -143.015846) (xy 66.183591 -142.964969) (xy 66.171748 -142.9118)
			(xy 66.167772 -142.857474) (xy 65.313993 -142.857474) (xy 65.313993 -142.85748) (xy 65.309591 -142.914639)
			(xy 65.296485 -142.970448) (xy 65.274984 -143.023591) (xy 65.245594 -143.072813) (xy 65.227708 -143.095218)
			(xy 65.214042 -143.112461) (xy 65.192233 -143.15067) (xy 65.177322 -143.192061) (xy 65.169754 -143.2354)
			(xy 65.169753 -143.279395) (xy 65.177321 -143.322734) (xy 65.192231 -143.364125) (xy 65.214039 -143.402335)
			(xy 65.227708 -143.419576) (xy 65.24469 -143.440836) (xy 65.272953 -143.487329) (xy 65.294151 -143.537439)
			(xy 65.307834 -143.5901) (xy 65.31371 -143.644191) (xy 65.311654 -143.698562) (xy 65.30171 -143.752055)
			(xy 65.284089 -143.803532) (xy 65.259167 -143.851898) (xy 65.227474 -143.896124) (xy 65.189684 -143.935269)
			(xy 65.146601 -143.968499) (xy 65.099142 -143.995108) (xy 65.048317 -144.01453) (xy 64.995207 -144.026351)
			(xy 64.940942 -144.030319) (xy 64.886677 -144.026351) (xy 64.833567 -144.01453) (xy 64.782742 -143.995108)
			(xy 64.735283 -143.968499) (xy 64.6922 -143.935269) (xy 64.65441 -143.896124) (xy 64.622717 -143.851898)
			(xy 64.597795 -143.803532) (xy 64.580174 -143.752055) (xy 64.57023 -143.698562) (xy 64.568174 -143.644191)
			(xy 64.57405 -143.5901) (xy 64.587733 -143.537439) (xy 64.608931 -143.487329) (xy 64.637194 -143.440836)
			(xy 64.654176 -143.419576) (xy 64.667878 -143.40235) (xy 64.689738 -143.364151) (xy 64.704686 -143.322756)
			(xy 64.712273 -143.279403) (xy 64.712273 -143.235392) (xy 64.704685 -143.192039) (xy 64.689736 -143.150644)
			(xy 64.667875 -143.112446) (xy 64.654176 -143.095218) (xy 64.636985 -143.073811) (xy 64.608526 -143.026858)
			(xy 64.587267 -142.976237) (xy 64.573669 -142.923044) (xy 64.568025 -142.86843) (xy 64.57046 -142.81358)
			(xy 64.580919 -142.759681) (xy 64.599176 -142.707902) (xy 64.624836 -142.659363) (xy 64.657343 -142.615116)
			(xy 64.695992 -142.57612) (xy 64.717676 -142.559278) (xy 64.730939 -142.548809) (xy 64.751746 -142.522196)
			(xy 64.76484 -142.491056) (xy 64.769304 -142.457571) (xy 64.764824 -142.424087) (xy 64.751716 -142.392953)
			(xy 64.730897 -142.366349) (xy 64.717676 -142.355824) (xy 64.696594 -142.338806) (xy 64.679501 -142.324515)
			(xy 64.64127 -142.301638) (xy 64.599638 -142.285773) (xy 64.555879 -142.277404) (xy 64.51133 -142.276789)
			(xy 64.467356 -142.283945) (xy 64.425301 -142.298655) (xy 64.386454 -142.320468) (xy 64.368934 -142.334234)
			(xy 64.348007 -142.350675) (xy 64.302198 -142.377755) (xy 64.252792 -142.397526) (xy 64.200949 -142.409526)
			(xy 64.147881 -142.413473) (xy 64.094832 -142.409276) (xy 64.043045 -142.397031) (xy 63.993734 -142.377028)
			(xy 63.948053 -142.349733) (xy 63.907072 -142.315786) (xy 63.871752 -142.275983) (xy 63.84292 -142.231256)
			(xy 63.821252 -142.182653) (xy 63.807254 -142.131313) (xy 63.801256 -142.078438) (xy 62.887662 -142.078438)
			(xy 62.887662 -142.083432) (xy 62.88031 -142.133507) (xy 62.865767 -142.181983) (xy 62.84434 -142.227835)
			(xy 62.816483 -142.27009) (xy 62.799976 -142.289276) (xy 62.784998 -142.306889) (xy 62.761009 -142.346406)
			(xy 62.744561 -142.389609) (xy 62.736199 -142.435075) (xy 62.736197 -142.481304) (xy 62.744556 -142.52677)
			(xy 62.760999 -142.569975) (xy 62.784986 -142.609494) (xy 62.799976 -142.627096) (xy 62.817188 -142.647186)
			(xy 62.846004 -142.691547) (xy 62.867757 -142.739766) (xy 62.881942 -142.790727) (xy 62.888231 -142.843251)
			(xy 62.886478 -142.89612) (xy 62.876724 -142.948112) (xy 62.859195 -142.998022) (xy 62.834297 -143.044695)
			(xy 62.802606 -143.08705) (xy 62.764855 -143.124106) (xy 62.72192 -143.155006) (xy 62.674793 -143.179034)
			(xy 62.624567 -143.195634) (xy 62.572403 -143.204422) (xy 62.51951 -143.205193) (xy 62.467112 -143.197931)
			(xy 62.416423 -143.182803) (xy 62.368615 -143.16016) (xy 62.324797 -143.130526) (xy 62.285982 -143.094586)
			(xy 62.253068 -143.053174) (xy 62.226819 -143.007248) (xy 62.207842 -142.95787) (xy 62.196575 -142.906185)
			(xy 62.193281 -142.853389) (xy 62.198035 -142.800705) (xy 62.210727 -142.749351) (xy 62.231064 -142.700518)
			(xy 62.258574 -142.655335) (xy 62.292621 -142.61485) (xy 62.332416 -142.579998) (xy 62.35446 -142.565374)
			(xy 62.367664 -142.556391) (xy 62.389479 -142.53308) (xy 62.404827 -142.505084) (xy 62.412747 -142.474156)
			(xy 62.412746 -142.442229) (xy 62.404821 -142.411302) (xy 62.38947 -142.383308) (xy 62.367653 -142.36)
			(xy 62.35446 -142.350998) (xy 62.342774 -142.343405) (xy 62.320521 -142.326622) (xy 62.31001 -142.31747)
			(xy 62.292412 -142.30243) (xy 62.252879 -142.278357) (xy 62.209636 -142.26185) (xy 62.164116 -142.253457)
			(xy 62.11783 -142.253457) (xy 62.07231 -142.26185) (xy 62.029067 -142.278357) (xy 61.989534 -142.30243)
			(xy 61.971936 -142.31747) (xy 61.951878 -142.334728) (xy 61.90748 -142.363513) (xy 61.859229 -142.38523)
			(xy 61.808243 -142.399378) (xy 61.7557 -142.405629) (xy 61.702818 -142.403838) (xy 61.650818 -142.394046)
			(xy 61.600906 -142.37648) (xy 61.554236 -142.351548) (xy 61.511887 -142.319824) (xy 61.47484 -142.282045)
			(xy 61.443952 -142.239083) (xy 61.419938 -142.191933) (xy 61.403353 -142.141687) (xy 61.394581 -142.089506)
			(xy 61.393826 -142.036598) (xy 57.073292 -142.036598) (xy 57.073292 -142.362174) (xy 57.096406 -142.39494)
			(xy 57.112829 -142.419187) (xy 57.138836 -142.471657) (xy 57.156518 -142.527485) (xy 57.165461 -142.58536)
			(xy 57.165455 -142.643922) (xy 57.156499 -142.701794) (xy 57.138805 -142.757619) (xy 57.112787 -142.810083)
			(xy 57.096406 -142.83436) (xy 57.073292 -142.867126) (xy 57.073292 -143.385032) (xy 57.073753 -143.406943)
			(xy 57.081294 -143.450111) (xy 57.088278 -143.470884) (xy 57.073292 -143.48587) (xy 57.073292 -143.835628)
			(xy 58.35397 -143.835628) (xy 58.357946 -143.781302) (xy 58.369789 -143.728133) (xy 58.389248 -143.677256)
			(xy 58.415908 -143.629754) (xy 58.449199 -143.58664) (xy 58.488413 -143.548833) (xy 58.532715 -143.517138)
			(xy 58.581158 -143.492232) (xy 58.632712 -143.474644) (xy 58.686278 -143.46475) (xy 58.740713 -143.46276)
			(xy 58.794858 -143.468718) (xy 58.847558 -143.482496) (xy 58.897691 -143.5038) (xy 58.944187 -143.532176)
			(xy 58.986057 -143.56702) (xy 59.022406 -143.607589) (xy 59.052462 -143.653018) (xy 59.075583 -143.702339)
			(xy 59.091276 -143.754501) (xy 59.099207 -143.808392) (xy 59.099704 -143.835628) (xy 59.099356 -143.854678)
			(xy 59.420249 -143.854678) (xy 59.424324 -143.801597) (xy 59.436454 -143.749761) (xy 59.456355 -143.700384)
			(xy 59.48356 -143.654623) (xy 59.517432 -143.613551) (xy 59.557176 -143.578132) (xy 59.601861 -143.549194)
			(xy 59.65044 -143.527416) (xy 59.701773 -143.51331) (xy 59.754659 -143.507204) (xy 59.807857 -143.509243)
			(xy 59.86012 -143.519379) (xy 59.910223 -143.537374) (xy 59.956992 -143.562806) (xy 59.999331 -143.59508)
			(xy 60.036247 -143.633438) (xy 60.066875 -143.676982) (xy 60.090497 -143.724691) (xy 60.10656 -143.775447)
			(xy 60.114687 -143.82806) (xy 60.115196 -143.854678) (xy 60.114687 -143.881296) (xy 60.10656 -143.933909)
			(xy 60.090497 -143.984665) (xy 60.066875 -144.032374) (xy 60.036247 -144.075918) (xy 59.999331 -144.114276)
			(xy 59.956992 -144.14655) (xy 59.910223 -144.171982) (xy 59.86012 -144.189977) (xy 59.807857 -144.200113)
			(xy 59.754659 -144.202152) (xy 59.701773 -144.196046) (xy 59.65044 -144.18194) (xy 59.601861 -144.160162)
			(xy 59.557176 -144.131224) (xy 59.517432 -144.095805) (xy 59.48356 -144.054733) (xy 59.456355 -144.008972)
			(xy 59.436454 -143.959595) (xy 59.424324 -143.907759) (xy 59.420249 -143.854678) (xy 59.099356 -143.854678)
			(xy 59.099207 -143.862864) (xy 59.091276 -143.916755) (xy 59.075583 -143.968917) (xy 59.052462 -144.018238)
			(xy 59.022406 -144.063667) (xy 58.986057 -144.104236) (xy 58.944187 -144.13908) (xy 58.897691 -144.167456)
			(xy 58.847558 -144.18876) (xy 58.794858 -144.202538) (xy 58.740713 -144.208496) (xy 58.686278 -144.206506)
			(xy 58.632712 -144.196612) (xy 58.581158 -144.179024) (xy 58.532715 -144.154118) (xy 58.488413 -144.122423)
			(xy 58.449199 -144.084616) (xy 58.415908 -144.041502) (xy 58.389248 -143.994) (xy 58.369789 -143.943123)
			(xy 58.357946 -143.889954) (xy 58.35397 -143.835628) (xy 57.073292 -143.835628) (xy 57.073292 -144.437862)
			(xy 63.094868 -144.437862) (xy 63.098939 -144.38224) (xy 63.111065 -144.327803) (xy 63.130988 -144.275712)
			(xy 63.158284 -144.227077) (xy 63.19237 -144.182934) (xy 63.232519 -144.144225) (xy 63.277877 -144.111774)
			(xy 63.327477 -144.086273) (xy 63.380261 -144.068266) (xy 63.435104 -144.058136) (xy 63.490838 -144.056099)
			(xy 63.546275 -144.062199) (xy 63.600232 -144.076305) (xy 63.651561 -144.098117) (xy 63.699167 -144.127171)
			(xy 63.742035 -144.162846) (xy 63.779252 -144.204383) (xy 63.810025 -144.250896) (xy 63.833697 -144.301393)
			(xy 63.849765 -144.3548) (xy 63.857885 -144.409976) (xy 63.858394 -144.437862) (xy 63.857885 -144.465748)
			(xy 63.849765 -144.520924) (xy 63.844111 -144.539716) (xy 65.956432 -144.539716) (xy 65.960503 -144.484094)
			(xy 65.972629 -144.429657) (xy 65.992552 -144.377566) (xy 66.019848 -144.328931) (xy 66.053934 -144.284788)
			(xy 66.094083 -144.246079) (xy 66.139441 -144.213628) (xy 66.189041 -144.188127) (xy 66.241825 -144.17012)
			(xy 66.296668 -144.15999) (xy 66.352402 -144.157953) (xy 66.407839 -144.164053) (xy 66.461796 -144.178159)
			(xy 66.513125 -144.199971) (xy 66.560731 -144.229025) (xy 66.603599 -144.2647) (xy 66.640816 -144.306237)
			(xy 66.671589 -144.35275) (xy 66.695261 -144.403247) (xy 66.711329 -144.456654) (xy 66.719449 -144.51183)
			(xy 66.719958 -144.539716) (xy 66.719449 -144.567602) (xy 66.711329 -144.622778) (xy 66.695261 -144.676185)
			(xy 66.671589 -144.726682) (xy 66.640816 -144.773195) (xy 66.603599 -144.814732) (xy 66.560731 -144.850407)
			(xy 66.513125 -144.879461) (xy 66.461796 -144.901273) (xy 66.407839 -144.915379) (xy 66.352402 -144.921479)
			(xy 66.296668 -144.919442) (xy 66.241825 -144.909312) (xy 66.189041 -144.891305) (xy 66.139441 -144.865804)
			(xy 66.094083 -144.833353) (xy 66.053934 -144.794644) (xy 66.019848 -144.750501) (xy 65.992552 -144.701866)
			(xy 65.972629 -144.649775) (xy 65.960503 -144.595338) (xy 65.956432 -144.539716) (xy 63.844111 -144.539716)
			(xy 63.833697 -144.574331) (xy 63.810025 -144.624828) (xy 63.779252 -144.671341) (xy 63.742035 -144.712878)
			(xy 63.699167 -144.748553) (xy 63.651561 -144.777607) (xy 63.600232 -144.799419) (xy 63.546275 -144.813525)
			(xy 63.490838 -144.819625) (xy 63.435104 -144.817588) (xy 63.380261 -144.807458) (xy 63.327477 -144.789451)
			(xy 63.277877 -144.76395) (xy 63.232519 -144.731499) (xy 63.19237 -144.69279) (xy 63.158284 -144.648647)
			(xy 63.130988 -144.600012) (xy 63.111065 -144.547921) (xy 63.098939 -144.493484) (xy 63.094868 -144.437862)
			(xy 57.073292 -144.437862) (xy 57.073292 -145.022062) (xy 67.692268 -145.022062) (xy 67.696339 -144.96644)
			(xy 67.708465 -144.912003) (xy 67.728388 -144.859912) (xy 67.755684 -144.811277) (xy 67.78977 -144.767134)
			(xy 67.829919 -144.728425) (xy 67.875277 -144.695974) (xy 67.924877 -144.670473) (xy 67.977661 -144.652466)
			(xy 68.032504 -144.642336) (xy 68.088238 -144.640299) (xy 68.143675 -144.646399) (xy 68.197632 -144.660505)
			(xy 68.248961 -144.682317) (xy 68.296567 -144.711371) (xy 68.339435 -144.747046) (xy 68.376652 -144.788583)
			(xy 68.407425 -144.835096) (xy 68.431097 -144.885593) (xy 68.447165 -144.939) (xy 68.455285 -144.994176)
			(xy 68.455794 -145.022062) (xy 68.455285 -145.049948) (xy 68.447165 -145.105124) (xy 68.431097 -145.158531)
			(xy 68.407425 -145.209028) (xy 68.376652 -145.255541) (xy 68.339435 -145.297078) (xy 68.296567 -145.332753)
			(xy 68.248961 -145.361807) (xy 68.197632 -145.383619) (xy 68.143675 -145.397725) (xy 68.088238 -145.403825)
			(xy 68.032504 -145.401788) (xy 67.977661 -145.391658) (xy 67.924877 -145.373651) (xy 67.875277 -145.34815)
			(xy 67.829919 -145.315699) (xy 67.78977 -145.27699) (xy 67.755684 -145.232847) (xy 67.728388 -145.184212)
			(xy 67.708465 -145.132121) (xy 67.696339 -145.077684) (xy 67.692268 -145.022062) (xy 57.073292 -145.022062)
			(xy 57.073292 -145.895568) (xy 57.611472 -146.433748) (xy 61.318455 -146.433748) (xy 61.32334 -146.379585)
			(xy 61.335868 -146.326665) (xy 61.355782 -146.27606) (xy 61.382681 -146.228796) (xy 61.416018 -146.18583)
			(xy 61.435234 -146.166586) (xy 61.447424 -146.154035) (xy 61.465093 -146.123853) (xy 61.473902 -146.090007)
			(xy 61.473189 -146.055041) (xy 61.463008 -146.021582) (xy 61.45403 -146.006566) (xy 61.439628 -145.983244)
			(xy 61.416928 -145.933353) (xy 61.401602 -145.880727) (xy 61.393965 -145.826449) (xy 61.394174 -145.771637)
			(xy 61.402226 -145.71742) (xy 61.417954 -145.664912) (xy 61.441035 -145.615196) (xy 61.470992 -145.569295)
			(xy 61.507211 -145.528153) (xy 61.548944 -145.492619) (xy 61.595334 -145.463422) (xy 61.645424 -145.441165)
			(xy 61.698184 -145.426306) (xy 61.752527 -145.41915) (xy 61.807335 -145.419845) (xy 61.861479 -145.428377)
			(xy 61.913846 -145.444569) (xy 61.963355 -145.468089) (xy 62.008989 -145.498452) (xy 62.049809 -145.535033)
			(xy 62.084972 -145.57708) (xy 62.113757 -145.623726) (xy 62.125098 -145.64868) (xy 62.132188 -145.663868)
			(xy 62.153083 -145.690067) (xy 62.180085 -145.709914) (xy 62.211327 -145.722035) (xy 62.244649 -145.725593)
			(xy 62.277746 -145.720341) (xy 62.293246 -145.713958) (xy 62.319016 -145.703028) (xy 62.372927 -145.687967)
			(xy 62.42846 -145.680944) (xy 62.484423 -145.682111) (xy 62.539615 -145.691442) (xy 62.592851 -145.708736)
			(xy 62.64299 -145.733623) (xy 62.688954 -145.765569) (xy 62.729757 -145.803887) (xy 62.76437 -145.847562)
			(xy 66.62115 -145.847562) (xy 66.625221 -145.79194) (xy 66.637347 -145.737503) (xy 66.65727 -145.685412)
			(xy 66.684566 -145.636777) (xy 66.718652 -145.592634) (xy 66.758801 -145.553925) (xy 66.804159 -145.521474)
			(xy 66.853759 -145.495973) (xy 66.906543 -145.477966) (xy 66.961386 -145.467836) (xy 67.01712 -145.465799)
			(xy 67.072557 -145.471899) (xy 67.126514 -145.486005) (xy 67.177843 -145.507817) (xy 67.225449 -145.536871)
			(xy 67.268317 -145.572546) (xy 67.305534 -145.614083) (xy 67.336307 -145.660596) (xy 67.359979 -145.711093)
			(xy 67.376047 -145.7645) (xy 67.384167 -145.819676) (xy 67.384676 -145.847562) (xy 67.384167 -145.875448)
			(xy 67.376047 -145.930624) (xy 67.366649 -145.961862) (xy 69.292468 -145.961862) (xy 69.296539 -145.90624)
			(xy 69.308665 -145.851803) (xy 69.328588 -145.799712) (xy 69.355884 -145.751077) (xy 69.38997 -145.706934)
			(xy 69.430119 -145.668225) (xy 69.475477 -145.635774) (xy 69.525077 -145.610273) (xy 69.577861 -145.592266)
			(xy 69.632704 -145.582136) (xy 69.688438 -145.580099) (xy 69.743875 -145.586199) (xy 69.797832 -145.600305)
			(xy 69.849161 -145.622117) (xy 69.896767 -145.651171) (xy 69.939635 -145.686846) (xy 69.976852 -145.728383)
			(xy 70.007625 -145.774896) (xy 70.031297 -145.825393) (xy 70.047365 -145.8788) (xy 70.051739 -145.908522)
			(xy 70.651114 -145.908522) (xy 70.655185 -145.8529) (xy 70.667311 -145.798463) (xy 70.687234 -145.746372)
			(xy 70.71453 -145.697737) (xy 70.748616 -145.653594) (xy 70.788765 -145.614885) (xy 70.834123 -145.582434)
			(xy 70.883723 -145.556933) (xy 70.936507 -145.538926) (xy 70.99135 -145.528796) (xy 71.047084 -145.526759)
			(xy 71.102521 -145.532859) (xy 71.139429 -145.542508) (xy 72.142602 -145.542508) (xy 72.146673 -145.486886)
			(xy 72.158799 -145.432449) (xy 72.178722 -145.380358) (xy 72.206018 -145.331723) (xy 72.240104 -145.28758)
			(xy 72.280253 -145.248871) (xy 72.325611 -145.21642) (xy 72.375211 -145.190919) (xy 72.427995 -145.172912)
			(xy 72.482838 -145.162782) (xy 72.538572 -145.160745) (xy 72.594009 -145.166845) (xy 72.647966 -145.180951)
			(xy 72.699295 -145.202763) (xy 72.746901 -145.231817) (xy 72.789769 -145.267492) (xy 72.826986 -145.309029)
			(xy 72.857759 -145.355542) (xy 72.881431 -145.406039) (xy 72.897499 -145.459446) (xy 72.905619 -145.514622)
			(xy 72.906128 -145.542508) (xy 72.905619 -145.570394) (xy 72.897499 -145.62557) (xy 72.881431 -145.678977)
			(xy 72.857759 -145.729474) (xy 72.826986 -145.775987) (xy 72.789769 -145.817524) (xy 72.746901 -145.853199)
			(xy 72.699295 -145.882253) (xy 72.647966 -145.904065) (xy 72.594009 -145.918171) (xy 72.538572 -145.924271)
			(xy 72.482838 -145.922234) (xy 72.427995 -145.912104) (xy 72.375211 -145.894097) (xy 72.325611 -145.868596)
			(xy 72.280253 -145.836145) (xy 72.240104 -145.797436) (xy 72.206018 -145.753293) (xy 72.178722 -145.704658)
			(xy 72.158799 -145.652567) (xy 72.146673 -145.59813) (xy 72.142602 -145.542508) (xy 71.139429 -145.542508)
			(xy 71.156478 -145.546965) (xy 71.207807 -145.568777) (xy 71.255413 -145.597831) (xy 71.298281 -145.633506)
			(xy 71.335498 -145.675043) (xy 71.366271 -145.721556) (xy 71.389943 -145.772053) (xy 71.406011 -145.82546)
			(xy 71.414131 -145.880636) (xy 71.41464 -145.908522) (xy 71.414131 -145.936408) (xy 71.406011 -145.991584)
			(xy 71.389943 -146.044991) (xy 71.366271 -146.095488) (xy 71.335498 -146.142001) (xy 71.298281 -146.183538)
			(xy 71.255413 -146.219213) (xy 71.207807 -146.248267) (xy 71.156478 -146.270079) (xy 71.102521 -146.284185)
			(xy 71.047084 -146.290285) (xy 70.99135 -146.288248) (xy 70.936507 -146.278118) (xy 70.883723 -146.260111)
			(xy 70.834123 -146.23461) (xy 70.788765 -146.202159) (xy 70.748616 -146.16345) (xy 70.71453 -146.119307)
			(xy 70.687234 -146.070672) (xy 70.667311 -146.018581) (xy 70.655185 -145.964144) (xy 70.651114 -145.908522)
			(xy 70.051739 -145.908522) (xy 70.055485 -145.933976) (xy 70.055994 -145.961862) (xy 70.055485 -145.989748)
			(xy 70.047365 -146.044924) (xy 70.031297 -146.098331) (xy 70.007625 -146.148828) (xy 69.976852 -146.195341)
			(xy 69.939635 -146.236878) (xy 69.896767 -146.272553) (xy 69.849161 -146.301607) (xy 69.797832 -146.323419)
			(xy 69.743875 -146.337525) (xy 69.688438 -146.343625) (xy 69.632704 -146.341588) (xy 69.577861 -146.331458)
			(xy 69.525077 -146.313451) (xy 69.475477 -146.28795) (xy 69.430119 -146.255499) (xy 69.38997 -146.21679)
			(xy 69.355884 -146.172647) (xy 69.328588 -146.124012) (xy 69.308665 -146.071921) (xy 69.296539 -146.017484)
			(xy 69.292468 -145.961862) (xy 67.366649 -145.961862) (xy 67.359979 -145.984031) (xy 67.336307 -146.034528)
			(xy 67.305534 -146.081041) (xy 67.268317 -146.122578) (xy 67.225449 -146.158253) (xy 67.177843 -146.187307)
			(xy 67.126514 -146.209119) (xy 67.072557 -146.223225) (xy 67.01712 -146.229325) (xy 66.961386 -146.227288)
			(xy 66.906543 -146.217158) (xy 66.853759 -146.199151) (xy 66.804159 -146.17365) (xy 66.758801 -146.141199)
			(xy 66.718652 -146.10249) (xy 66.684566 -146.058347) (xy 66.65727 -146.009712) (xy 66.637347 -145.957621)
			(xy 66.625221 -145.903184) (xy 66.62115 -145.847562) (xy 62.76437 -145.847562) (xy 62.764524 -145.847756)
			(xy 62.792509 -145.896234) (xy 62.81311 -145.94828) (xy 62.825885 -146.002778) (xy 62.830561 -146.058558)
			(xy 62.827037 -146.114422) (xy 62.815389 -146.169172) (xy 62.795866 -146.221632) (xy 62.768888 -146.270677)
			(xy 62.735034 -146.315254) (xy 62.69503 -146.354406) (xy 62.649735 -146.387293) (xy 62.608368 -146.408902)
			(xy 68.098668 -146.408902) (xy 68.102739 -146.35328) (xy 68.114865 -146.298843) (xy 68.134788 -146.246752)
			(xy 68.162084 -146.198117) (xy 68.19617 -146.153974) (xy 68.236319 -146.115265) (xy 68.281677 -146.082814)
			(xy 68.331277 -146.057313) (xy 68.384061 -146.039306) (xy 68.438904 -146.029176) (xy 68.494638 -146.027139)
			(xy 68.550075 -146.033239) (xy 68.604032 -146.047345) (xy 68.655361 -146.069157) (xy 68.702967 -146.098211)
			(xy 68.745835 -146.133886) (xy 68.783052 -146.175423) (xy 68.813825 -146.221936) (xy 68.837497 -146.272433)
			(xy 68.853565 -146.32584) (xy 68.861685 -146.381016) (xy 68.862194 -146.408902) (xy 68.861685 -146.436788)
			(xy 68.853565 -146.491964) (xy 68.837497 -146.545371) (xy 68.813825 -146.595868) (xy 68.783052 -146.642381)
			(xy 68.745835 -146.683918) (xy 68.702967 -146.719593) (xy 68.655361 -146.748647) (xy 68.604032 -146.770459)
			(xy 68.550075 -146.784565) (xy 68.494638 -146.790665) (xy 68.438904 -146.788628) (xy 68.384061 -146.778498)
			(xy 68.331277 -146.760491) (xy 68.281677 -146.73499) (xy 68.236319 -146.702539) (xy 68.19617 -146.66383)
			(xy 68.162084 -146.619687) (xy 68.134788 -146.571052) (xy 68.114865 -146.518961) (xy 68.102739 -146.464524)
			(xy 68.098668 -146.408902) (xy 62.608368 -146.408902) (xy 62.600121 -146.41321) (xy 62.547252 -146.431599)
			(xy 62.492265 -146.442067) (xy 62.436338 -146.444388) (xy 62.380672 -146.438513) (xy 62.353444 -146.432016)
			(xy 62.331162 -146.426772) (xy 62.285512 -146.423438) (xy 62.240005 -146.428345) (xy 62.196116 -146.441334)
			(xy 62.155267 -146.461982) (xy 62.118783 -146.489621) (xy 62.087847 -146.523354) (xy 62.063462 -146.562088)
			(xy 62.054486 -146.583146) (xy 62.043843 -146.608174) (xy 62.01661 -146.655246) (xy 61.98297 -146.697975)
			(xy 61.943603 -146.735494) (xy 61.899307 -146.767043) (xy 61.850981 -146.791982) (xy 61.799602 -146.809807)
			(xy 61.746214 -146.820155) (xy 61.691896 -146.822818) (xy 61.637752 -146.81774) (xy 61.584876 -146.805026)
			(xy 61.534342 -146.784932) (xy 61.487174 -146.757867) (xy 61.444326 -146.724378) (xy 61.406668 -146.685144)
			(xy 61.374963 -146.64096) (xy 61.349852 -146.592722) (xy 61.331846 -146.541407) (xy 61.321309 -146.488055)
			(xy 61.318455 -146.433748) (xy 57.611472 -146.433748) (xy 59.52744 -148.349716)
		)
		(stroke
			(width 0)
			(type solid)
		)
		(fill yes)
		(layer "In2.Cu")
		(net "P3V3_NODE1")
	)
	(gr_line
		(start -18.237962 -206.70012)
		(end -18.237962 -1.999996)
		(stroke
			(width 2.032)
			(type default)
		)
		(layer "In3.Cu")
	)
	(gr_arc
		(start -18.237962 -206.70012)
		(mid -17.652177 -208.114331)
		(end -16.237966 -208.700116)
		(stroke
			(width 2.032)
			(type default)
		)
		(layer "In3.Cu")
	)
	(gr_arc
		(start -16.237966 0)
		(mid -17.652177 -0.585785)
		(end -18.237962 -1.999996)
		(stroke
			(width 2.032)
			(type default)
		)
		(layer "In3.Cu")
	)
	(gr_line
		(start -16.237966 0)
		(end -1.999996 0)
		(stroke
			(width 2.032)
			(type default)
		)
		(layer "In3.Cu")
	)
	(gr_line
		(start -1.999996 -160.375092)
		(end -1.999742 -160.375092)
		(stroke
			(width 2.032)
			(type default)
		)
		(layer "In3.Cu")
	)
	(gr_line
		(start -1.999996 0)
		(end -1.999996 -160.375092)
		(stroke
			(width 2.032)
			(type default)
		)
		(layer "In3.Cu")
	)
	(gr_line
		(start -1.999742 -208.700116)
		(end -16.237966 -208.700116)
		(stroke
			(width 2.032)
			(type default)
		)
		(layer "In3.Cu")
	)
	(gr_line
		(start -1.999742 -160.375092)
		(end -1.999742 -208.700116)
		(stroke
			(width 2.032)
			(type default)
		)
		(layer "In3.Cu")
	)
	(gr_arc
		(start 0 -168.699942)
		(mid 0.585785 -170.114153)
		(end 1.999996 -170.699938)
		(stroke
			(width 2.032)
			(type default)
		)
		(layer "In3.Cu")
	)
	(gr_line
		(start 0 -72.300084)
		(end 0 -168.699942)
		(stroke
			(width 2.032)
			(type default)
		)
		(layer "In3.Cu")
	)
	(gr_line
		(start 0 -29.299916)
		(end 0 -1.999996)
		(stroke
			(width 2.032)
			(type default)
		)
		(layer "In3.Cu")
	)
	(gr_arc
		(start 0 -29.299916)
		(mid 0.439376 -30.360664)
		(end 1.500124 -30.80004)
		(stroke
			(width 2.032)
			(type default)
		)
		(layer "In3.Cu")
	)
	(gr_poly
		(pts
			(xy 107.257596 -156.837634)
			(arc
				(start 107.257596 -153.08834)
				(mid 107.220399 -152.998537)
				(end 107.130596 -152.96134)
			)
			(xy 103.559864 -152.96134) (xy 103.496364 -152.89784) (xy 101.62159 -152.89784)
			(arc
				(start 101.589078 -152.920192)
				(mid 101.564617 -152.936015)
				(end 101.539294 -152.950418)
			)
			(xy 101.514402 -152.97531) (xy 101.514402 -153.064972) (xy 101.300026 -153.279348)
			(arc
				(start 99.384358 -153.279348)
				(mid 99.294555 -153.316545)
				(end 99.257358 -153.406348)
			)
			(xy 99.257358 -158.783782) (xy 100.14331 -159.669734) (xy 104.425496 -159.669734)
		)
		(stroke
			(width 0)
			(type solid)
		)
		(fill yes)
		(layer "In3.Cu")
		(net "GND")
	)
	(gr_poly
		(pts
			(arc
				(start 67.399408 -10.000742)
				(mid 67.531488 -9.977147)
				(end 67.663568 -10.000742)
			)
			(xy 67.684904 -10.008616) (xy 68.013072 -10.008616)
			(arc
				(start 68.034408 -10.000742)
				(mid 68.166488 -9.977147)
				(end 68.298568 -10.000742)
			)
			(xy 68.319904 -10.008616) (xy 68.84162 -10.008616)
			(arc
				(start 68.874132 -9.986264)
				(mid 69.09054 -9.918948)
				(end 69.306948 -9.986264)
			)
			(xy 69.33946 -10.008616) (xy 69.435726 -10.008616) (xy 69.607938 -9.836404) (xy 69.607938 -8.403082)
			(xy 69.963284 -8.047736) (xy 73.150222 -8.047736) (xy 73.448926 -7.749032)
			(arc
				(start 73.448926 -1.143)
				(mid 73.411729 -1.053197)
				(end 73.321926 -1.016)
			)
			(arc
				(start 64.876934 -1.016)
				(mid 64.787131 -1.053197)
				(end 64.749934 -1.143)
			)
			(xy 64.749934 -7.89305) (xy 65.581276 -8.724392)
			(arc
				(start 65.581276 -9.881616)
				(mid 65.618473 -9.971419)
				(end 65.708276 -10.008616)
			)
			(xy 67.378072 -10.008616)
		)
		(stroke
			(width 0)
			(type solid)
		)
		(fill yes)
		(layer "In3.Cu")
		(net "GND")
	)
	(gr_poly
		(pts
			(xy 80.094582 -145.735802) (xy 80.111346 -145.666714)
			(arc
				(start 80.100424 -145.632932)
				(mid 80.128395 -145.335919)
				(end 80.361536 -145.149824)
			)
			(arc
				(start 80.361536 -145.149824)
				(mid 80.428596 -145.10438)
				(end 80.4545 -145.02765)
			)
			(xy 80.4545 -142.018004) (xy 80.859884 -141.61262) (xy 81.905348 -141.61262)
			(arc
				(start 81.929478 -141.602206)
				(mid 82.081116 -141.57077)
				(end 82.232754 -141.602206)
			)
			(xy 82.256884 -141.61262) (xy 84.250784 -141.61262) (xy 84.51596 -141.347444) (xy 84.51596 -137.018776)
			(xy 84.024724 -136.52754) (xy 82.617564 -136.52754) (xy 82.1182 -136.028176) (xy 82.1182 -126.244096)
			(xy 81.723484 -125.84938) (xy 57.350152 -125.84938) (xy 57.29224 -125.881892)
			(arc
				(start 57.274968 -125.91034)
				(mid 57.007314 -126.088888)
				(end 56.698388 -125.99924)
			)
			(arc
				(start 56.698388 -125.99924)
				(mid 56.522704 -125.936888)
				(end 56.351678 -126.011178)
			)
			(xy 55.83174 -126.531116) (xy 55.83174 -133.91261) (xy 55.866284 -133.971538)
			(arc
				(start 55.89651 -133.988556)
				(mid 56.090875 -134.321042)
				(end 55.89651 -134.653528)
			)
			(xy 55.866284 -134.670546) (xy 55.83174 -134.729474) (xy 55.83174 -137.872724)
			(arc
				(start 55.858156 -137.90676)
				(mid 55.935502 -138.13409)
				(end 55.858156 -138.36142)
			)
			(xy 55.83174 -138.395456)
			(arc
				(start 55.83174 -143.28648)
				(mid 55.842356 -143.337311)
				(end 55.87238 -143.379698)
			)
			(arc
				(start 55.87238 -143.379698)
				(mid 55.994707 -143.659606)
				(end 55.87238 -143.939514)
			)
			(arc
				(start 55.87238 -143.939514)
				(mid 55.842289 -143.981871)
				(end 55.83174 -144.032732)
			)
			(xy 55.83174 -145.853404) (xy 56.473598 -146.495262) (xy 56.553608 -146.508724)
			(arc
				(start 56.590184 -146.490944)
				(mid 56.836593 -146.460899)
				(end 57.049416 -146.588734)
			)
			(arc
				(start 57.049416 -146.588734)
				(mid 57.093021 -146.622223)
				(end 57.146698 -146.6342)
			)
			(xy 79.196184 -146.6342)
		)
		(stroke
			(width 0)
			(type solid)
		)
		(fill yes)
		(layer "In3.Cu")
		(net "P1V26_BMC_NODE1")
	)
	(gr_poly
		(pts
			(xy 66.961512 -178.18862) (xy 66.977235 -178.188143) (xy 67.007724 -178.180445) (xy 67.035414 -178.165542)
			(xy 67.058632 -178.144334) (xy 67.067684 -178.13147) (xy 67.082889 -178.10923) (xy 67.118561 -178.068856)
			(xy 67.15956 -178.033904) (xy 67.205069 -178.005069) (xy 67.254183 -177.982926) (xy 67.305924 -177.967914)
			(xy 67.359263 -177.960332) (xy 67.413137 -177.960332) (xy 67.466476 -177.967914) (xy 67.518217 -177.982926)
			(xy 67.567331 -178.005069) (xy 67.61284 -178.033904) (xy 67.653839 -178.068856) (xy 67.689511 -178.10923)
			(xy 67.704716 -178.13147) (xy 67.713748 -178.144355) (xy 67.736945 -178.165602) (xy 67.764646 -178.180507)
			(xy 67.795159 -178.188157) (xy 67.810888 -178.18862) (xy 75.116436 -178.18862) (xy 75.15225 -178.157632)
			(xy 75.173158 -178.14018) (xy 75.218989 -178.110762) (xy 75.268537 -178.088158) (xy 75.320795 -178.072829)
			(xy 75.374702 -178.065086) (xy 75.429162 -178.065086) (xy 75.483069 -178.072829) (xy 75.535327 -178.088158)
			(xy 75.584875 -178.110762) (xy 75.630706 -178.14018) (xy 75.651614 -178.157632) (xy 75.687428 -178.18862)
			(xy 76.204572 -178.18862) (xy 76.26731 -178.14798) (xy 76.282804 -178.11369) (xy 76.294469 -178.088899)
			(xy 76.323854 -178.042657) (xy 76.359551 -178.001094) (xy 76.400826 -177.965063) (xy 76.44683 -177.935308)
			(xy 76.496618 -177.912439) (xy 76.549164 -177.896926) (xy 76.60339 -177.889089) (xy 76.658178 -177.889089)
			(xy 76.712404 -177.896926) (xy 76.76495 -177.912439) (xy 76.814738 -177.935308) (xy 76.860742 -177.965063)
			(xy 76.902017 -178.001094) (xy 76.937714 -178.042657) (xy 76.967099 -178.088899) (xy 76.978764 -178.11369)
			(xy 76.985122 -178.126838) (xy 77.002845 -178.150044) (xy 77.025384 -178.168607) (xy 77.051556 -178.181553)
			(xy 77.079988 -178.188201) (xy 77.094588 -178.18862) (xy 78.076806 -178.18862) (xy 79.93253 -176.332896)
			(xy 79.949802 -176.265586) (xy 79.939896 -176.232058) (xy 79.932687 -176.205778) (xy 79.924933 -176.15184)
			(xy 79.924934 -176.097347) (xy 79.93269 -176.043409) (xy 79.948043 -175.991123) (xy 79.97068 -175.941555)
			(xy 80.000141 -175.895712) (xy 80.035826 -175.854529) (xy 80.077009 -175.818844) (xy 80.122851 -175.789382)
			(xy 80.172419 -175.766744) (xy 80.224705 -175.751391) (xy 80.278643 -175.743634) (xy 80.333136 -175.743633)
			(xy 80.387074 -175.751386) (xy 80.413352 -175.758602) (xy 80.429832 -175.762891) (xy 80.463868 -175.763525)
			(xy 80.496856 -175.755121) (xy 80.526439 -175.73828) (xy 80.538828 -175.726598) (xy 84.97824 -171.287186)
			(xy 84.98713 -171.27093) (xy 85.000673 -171.246976) (xy 85.033588 -171.202881) (xy 85.072498 -171.163973)
			(xy 85.116595 -171.131061) (xy 85.140546 -171.117514) (xy 85.156802 -171.108624) (xy 85.691218 -170.574208)
			(xy 85.702065 -170.562631) (xy 85.718223 -170.535343) (xy 85.727174 -170.504918) (xy 85.728366 -170.473226)
			(xy 85.725508 -170.457622) (xy 85.720238 -170.430925) (xy 85.716426 -170.376644) (xy 85.720367 -170.322372)
			(xy 85.73198 -170.26921) (xy 85.751028 -170.218238) (xy 85.777127 -170.17049) (xy 85.809745 -170.126935)
			(xy 85.848221 -170.088457) (xy 85.891775 -170.055837) (xy 85.939522 -170.029736) (xy 85.990493 -170.010685)
			(xy 86.043654 -169.99907) (xy 86.097926 -169.995126) (xy 86.152207 -169.998935) (xy 86.178898 -170.004232)
			(xy 86.210648 -170.01109) (xy 86.272624 -169.992802) (xy 89.055702 -167.209724) (xy 89.057226 -167.207946)
			(xy 89.078308 -167.186864) (xy 89.080086 -167.18534) (xy 92.9513 -163.314126) (xy 92.9513 -148.524976)
			(xy 93.787976 -147.6883) (xy 102.617016 -147.6883) (xy 102.9589 -148.030184) (xy 102.9589 -152.38984)
			(xy 102.959448 -152.406485) (xy 102.968073 -152.438638) (xy 102.984724 -152.467465) (xy 103.008267 -152.491001)
			(xy 103.037099 -152.507643) (xy 103.069255 -152.516257) (xy 103.0859 -152.51684) (xy 103.496364 -152.51684)
			(xy 103.559864 -152.45334) (xy 109.139736 -152.45334) (xy 109.523276 -152.83688) (xy 112.063784 -152.83688)
			(xy 112.84204 -152.058624) (xy 112.84204 -133.724396) (xy 111.263684 -132.14604) (xy 98.731324 -132.14604)
			(xy 97.719134 -131.13385) (xy 97.65284 -131.116578) (xy 97.619566 -131.125722) (xy 97.593307 -131.132576)
			(xy 97.5395 -131.139653) (xy 97.485234 -131.139036) (xy 97.431602 -131.130738) (xy 97.379687 -131.114926)
			(xy 97.354898 -131.103878) (xy 97.329244 -131.09194) (xy 96.767396 -131.09194) (xy 96.021144 -131.838192)
			(xy 96.011031 -131.848945) (xy 95.995566 -131.874081) (xy 95.986292 -131.902098) (xy 95.983706 -131.931496)
			(xy 95.987945 -131.960702) (xy 95.99295 -131.97459) (xy 96.0027 -132.000564) (xy 96.015441 -132.054561)
			(xy 96.020231 -132.109833) (xy 96.016967 -132.165216) (xy 96.005718 -132.219543) (xy 95.986723 -132.271668)
			(xy 95.96038 -132.320495) (xy 95.927246 -132.364992) (xy 95.888018 -132.404224) (xy 95.843523 -132.437362)
			(xy 95.794699 -132.463709) (xy 95.742575 -132.482709) (xy 95.688249 -132.493962) (xy 95.632866 -132.497231)
			(xy 95.577594 -132.492447) (xy 95.523597 -132.47971) (xy 95.49765 -132.46989) (xy 95.483769 -132.464849)
			(xy 95.454554 -132.460588) (xy 95.425143 -132.463167) (xy 95.397115 -132.472449) (xy 95.371978 -132.487934)
			(xy 95.361252 -132.498084) (xy 93.456506 -134.40283) (xy 93.446413 -134.413502) (xy 93.430941 -134.438461)
			(xy 93.42159 -134.466298) (xy 93.418857 -134.495537) (xy 93.422888 -134.524625) (xy 93.427804 -134.538466)
			(xy 93.437317 -134.564333) (xy 93.449645 -134.618049) (xy 93.454113 -134.67298) (xy 93.450629 -134.727982)
			(xy 93.439265 -134.78191) (xy 93.420258 -134.833641) (xy 93.394004 -134.882098) (xy 93.361048 -134.926272)
			(xy 93.322079 -134.965242) (xy 93.277906 -134.998199) (xy 93.229449 -135.024455) (xy 93.177719 -135.043463)
			(xy 93.123791 -135.054828) (xy 93.068789 -135.058313) (xy 93.013858 -135.053846) (xy 92.960141 -135.041519)
			(xy 92.934282 -135.031988) (xy 92.920436 -135.027103) (xy 92.891359 -135.023099) (xy 92.862135 -135.025843)
			(xy 92.834311 -135.035191) (xy 92.809358 -135.050648) (xy 92.798646 -135.06069) (xy 90.691716 -137.16762)
			(xy 85.15096 -137.16762) (xy 85.134316 -137.168168) (xy 85.102165 -137.176793) (xy 85.073341 -137.193445)
			(xy 85.049808 -137.216988) (xy 85.03317 -137.24582) (xy 85.02456 -137.277976) (xy 85.02396 -137.29462)
			(xy 85.02396 -141.557756) (xy 84.461096 -142.12062) (xy 82.464148 -142.12062) (xy 82.409538 -142.148814)
			(xy 82.391758 -142.17396) (xy 82.375135 -142.19641) (xy 82.3364 -142.236659) (xy 82.292212 -142.270833)
			(xy 82.243515 -142.2982) (xy 82.191348 -142.318177) (xy 82.136827 -142.330336) (xy 82.081116 -142.334418)
			(xy 82.025405 -142.330336) (xy 81.970884 -142.318177) (xy 81.918717 -142.2982) (xy 81.87002 -142.270833)
			(xy 81.825832 -142.236659) (xy 81.787097 -142.19641) (xy 81.770474 -142.17396) (xy 81.761343 -142.161896)
			(xy 81.738484 -142.142089) (xy 81.711606 -142.128216) (xy 81.682219 -142.121055) (xy 81.667096 -142.12062)
			(xy 81.070196 -142.12062) (xy 80.9625 -142.228316) (xy 80.9625 -145.586196) (xy 79.406496 -147.1422)
			(xy 56.9849 -147.1422) (xy 56.95442 -147.160488) (xy 56.931997 -147.173536) (xy 56.884374 -147.194115)
			(xy 56.834402 -147.208049) (xy 56.783001 -147.215081) (xy 56.731123 -147.215081) (xy 56.679722 -147.208049)
			(xy 56.62975 -147.194115) (xy 56.582127 -147.173536) (xy 56.559704 -147.160488) (xy 56.529224 -147.1422)
			(xy 56.402224 -147.1422) (xy 55.32374 -146.063716) (xy 55.32374 -143.91132) (xy 55.30088 -143.8783)
			(xy 55.284628 -143.854122) (xy 55.258867 -143.801871) (xy 55.241352 -143.746311) (xy 55.232491 -143.688733)
			(xy 55.23249 -143.630477) (xy 55.24135 -143.572899) (xy 55.258863 -143.517338) (xy 55.284623 -143.465087)
			(xy 55.30088 -143.440912) (xy 55.32374 -143.407892) (xy 55.32374 -138.390122) (xy 55.294784 -138.354816)
			(xy 55.278272 -138.333967) (xy 55.25112 -138.288239) (xy 55.231259 -138.238904) (xy 55.219154 -138.187118)
			(xy 55.215089 -138.134092) (xy 55.219157 -138.081066) (xy 55.231264 -138.029281) (xy 55.251127 -137.979947)
			(xy 55.278281 -137.93422) (xy 55.294784 -137.913364) (xy 55.32374 -137.878058) (xy 55.32374 -134.09676)
			(xy 55.323192 -134.080113) (xy 55.314568 -134.047956) (xy 55.297918 -134.019124) (xy 55.274376 -133.995582)
			(xy 55.245544 -133.978932) (xy 55.213387 -133.970308) (xy 55.19674 -133.96976) (xy 27.179524 -133.96976)
			(xy 26.07056 -132.860796) (xy 26.07056 -119.13362) (xy 26.070068 -119.116965) (xy 26.061449 -119.084791)
			(xy 26.044795 -119.055944) (xy 26.02124 -119.032393) (xy 25.992391 -119.015743) (xy 25.960215 -119.00713)
			(xy 25.94356 -119.00662) (xy 14.20622 -119.00662) (xy 14.189564 -119.007112) (xy 14.157388 -119.01573)
			(xy 14.128539 -119.032384) (xy 14.104984 -119.055939) (xy 14.08833 -119.084788) (xy 14.079712 -119.116964)
			(xy 14.07922 -119.13362) (xy 14.07922 -124.034296) (xy 13.08608 -125.027436) (xy 13.08608 -126.241048)
			(xy 13.105892 -126.27229) (xy 13.119961 -126.295323) (xy 13.142178 -126.344511) (xy 13.15724 -126.39634)
			(xy 13.164847 -126.449774) (xy 13.164847 -126.503746) (xy 13.15724 -126.55718) (xy 13.142178 -126.609009)
			(xy 13.119961 -126.658197) (xy 13.105892 -126.68123) (xy 13.08608 -126.712472) (xy 13.08608 -127.733806)
			(xy 13.105892 -127.765048) (xy 13.11996 -127.788081) (xy 13.142173 -127.837269) (xy 13.157232 -127.889097)
			(xy 13.164836 -127.94253) (xy 13.164834 -127.996501) (xy 13.157226 -128.049933) (xy 13.142162 -128.101759)
			(xy 13.119945 -128.150945) (xy 13.105892 -128.173988) (xy 13.08608 -128.20523) (xy 13.08608 -134.07136)
			(xy 13.086621 -134.088405) (xy 13.095635 -134.121281) (xy 13.113031 -134.150597) (xy 13.124942 -134.1628)
			(xy 13.144649 -134.18252) (xy 13.178708 -134.226657) (xy 13.205981 -134.27528) (xy 13.225887 -134.327354)
			(xy 13.238003 -134.381772) (xy 13.24207 -134.437373) (xy 13.238002 -134.492974) (xy 13.225886 -134.547391)
			(xy 13.205979 -134.599465) (xy 13.178705 -134.648088) (xy 13.144645 -134.692224) (xy 13.124942 -134.711948)
			(xy 13.113051 -134.724169) (xy 13.095648 -134.753477) (xy 13.086623 -134.786345) (xy 13.08608 -134.803388)
			(xy 13.08608 -139.692888) (xy 13.0937 -139.714224) (xy 13.102477 -139.739519) (xy 13.113667 -139.791879)
			(xy 13.117422 -139.845289) (xy 13.11367 -139.898699) (xy 13.102483 -139.951059) (xy 13.0937 -139.976352)
			(xy 13.08608 -139.997688) (xy 13.08608 -140.704824) (xy 22.173438 -149.792182) (xy 81.748381 -149.792182)
			(xy 81.752399 -149.72704) (xy 81.764391 -149.662885) (xy 81.784177 -149.60069) (xy 81.811456 -149.541398)
			(xy 81.845814 -149.485908) (xy 81.886731 -149.435061) (xy 81.933586 -149.389627) (xy 81.985669 -149.350295)
			(xy 82.042191 -149.317662) (xy 82.102295 -149.292222) (xy 82.16507 -149.274362) (xy 82.229563 -149.26435)
			(xy 82.294798 -149.26234) (xy 82.359786 -149.268362) (xy 82.423541 -149.282325) (xy 82.485097 -149.304016)
			(xy 82.543521 -149.333108) (xy 82.597926 -149.369159) (xy 82.64749 -149.411622) (xy 82.691459 -149.459854)
			(xy 82.729168 -149.513124) (xy 82.760045 -149.570624) (xy 82.783622 -149.631483) (xy 82.799541 -149.694778)
			(xy 82.807562 -149.759549) (xy 82.808064 -149.792182) (xy 82.807562 -149.824815) (xy 82.799541 -149.889586)
			(xy 82.783622 -149.952881) (xy 82.760045 -150.01374) (xy 82.729168 -150.07124) (xy 82.691459 -150.12451)
			(xy 82.64749 -150.172742) (xy 82.597926 -150.215205) (xy 82.543521 -150.251256) (xy 82.485097 -150.280348)
			(xy 82.423541 -150.302039) (xy 82.359786 -150.316002) (xy 82.294798 -150.322024) (xy 82.229563 -150.320014)
			(xy 82.16507 -150.310002) (xy 82.102295 -150.292142) (xy 82.042191 -150.266702) (xy 81.985669 -150.234069)
			(xy 81.933586 -150.194737) (xy 81.886731 -150.149303) (xy 81.845814 -150.098456) (xy 81.811456 -150.042966)
			(xy 81.784177 -149.983674) (xy 81.764391 -149.921479) (xy 81.752399 -149.857324) (xy 81.748381 -149.792182)
			(xy 22.173438 -149.792182) (xy 44.64304 -172.261784) (xy 44.64304 -177.666904) (xy 44.962572 -177.986436)
			(xy 45.049186 -177.997104) (xy 45.086524 -177.974498) (xy 45.110872 -177.960493) (xy 45.162767 -177.939004)
			(xy 45.217252 -177.925355) (xy 45.273149 -177.919842) (xy 45.32925 -177.922584) (xy 45.384344 -177.933521)
			(xy 45.437238 -177.952418) (xy 45.48679 -177.978865) (xy 45.53193 -178.012291) (xy 45.571681 -178.051974)
			(xy 45.605184 -178.097056) (xy 45.618908 -178.121564) (xy 45.635418 -178.152552) (xy 45.695616 -178.18862)
		)
		(stroke
			(width 0)
			(type solid)
		)
		(fill yes)
		(layer "In3.Cu")
		(net "P5V_STB_NODE1")
	)
	(gr_poly
		(pts
			(xy 122.01652 -115.322604) (xy 122.01652 -107.584494) (xy 122.015987 -107.567936) (xy 122.007455 -107.535939)
			(xy 121.990969 -107.50722) (xy 121.97969 -107.495086) (xy 121.960885 -107.475495) (xy 121.928443 -107.431948)
			(xy 121.902504 -107.38424) (xy 121.883592 -107.333337) (xy 121.87209 -107.280266) (xy 121.86823 -107.2261)
			(xy 121.87209 -107.171934) (xy 121.883592 -107.118863) (xy 121.902504 -107.06796) (xy 121.928443 -107.020252)
			(xy 121.960885 -106.976705) (xy 121.97969 -106.957114) (xy 121.990972 -106.944982) (xy 122.007455 -106.91626)
			(xy 122.015998 -106.884264) (xy 122.01652 -106.867706) (xy 122.01652 -85.703156) (xy 106.104436 -69.791072)
			(xy 106.096816 -69.78523) (xy 106.074361 -69.767974) (xy 106.034317 -69.727929) (xy 106.01706 -69.705474)
			(xy 106.011218 -69.697854) (xy 105.251504 -68.93814) (xy 102.625144 -68.93814) (xy 102.595172 -68.956174)
			(xy 102.569692 -68.970755) (xy 102.515272 -68.992768) (xy 102.458122 -69.006188) (xy 102.399592 -69.010696)
			(xy 102.341062 -69.006188) (xy 102.283912 -68.992768) (xy 102.229492 -68.970755) (xy 102.204012 -68.956174)
			(xy 102.17404 -68.93814) (xy 80.173576 -68.93814) (xy 79.020416 -70.0913) (xy 75.44689 -70.0913)
			(xy 75.430311 -70.091834) (xy 75.398272 -70.100377) (xy 75.369514 -70.116884) (xy 75.345978 -70.140241)
			(xy 75.337162 -70.154292) (xy 75.322371 -70.178518) (xy 75.286747 -70.222705) (xy 75.244969 -70.261126)
			(xy 75.19796 -70.292933) (xy 75.146757 -70.317424) (xy 75.09249 -70.334058) (xy 75.036357 -70.342467)
			(xy 74.979599 -70.342467) (xy 74.923466 -70.334058) (xy 74.869199 -70.317424) (xy 74.817996 -70.292933)
			(xy 74.770987 -70.261126) (xy 74.729209 -70.222705) (xy 74.693585 -70.178518) (xy 74.678794 -70.154292)
			(xy 74.661522 -70.124828) (xy 74.603102 -70.0913) (xy 66.76644 -70.0913) (xy 66.749782 -70.09179)
			(xy 66.717599 -70.100404) (xy 66.688742 -70.117056) (xy 66.665181 -70.140611) (xy 66.64852 -70.169461)
			(xy 66.639895 -70.201642) (xy 66.63944 -70.2183) (xy 66.63944 -74.330052) (xy 66.000884 -74.968608)
			(xy 65.983612 -75.036426) (xy 65.993772 -75.070208) (xy 66.0014 -75.097379) (xy 66.009489 -75.153228)
			(xy 66.00926 -75.209661) (xy 66.000718 -75.265443) (xy 65.98405 -75.319358) (xy 65.959618 -75.370228)
			(xy 65.927958 -75.416942) (xy 65.889759 -75.458481) (xy 65.845857 -75.493938) (xy 65.797208 -75.522539)
			(xy 65.744877 -75.543659) (xy 65.690004 -75.556837) (xy 65.633789 -75.561785) (xy 65.577458 -75.558395)
			(xy 65.522242 -75.546742) (xy 65.469346 -75.52708) (xy 65.419924 -75.499838) (xy 65.375056 -75.46561)
			(xy 65.335722 -75.425145) (xy 65.30278 -75.379325) (xy 65.276949 -75.329151) (xy 65.267332 -75.302618)
			(xy 65.254124 -75.26401) (xy 65.188084 -75.216512) (xy 64.464184 -75.216512) (xy 63.099442 -76.581254)
			(xy 63.088658 -76.592741) (xy 63.072564 -76.619817) (xy 63.063591 -76.65001) (xy 63.062285 -76.681481)
			(xy 63.068724 -76.712314) (xy 63.082518 -76.740631) (xy 63.09233 -76.752958) (xy 63.109058 -76.773404)
			(xy 63.137312 -76.818039) (xy 63.15914 -76.866145) (xy 63.174125 -76.916802) (xy 63.18198 -76.969041)
			(xy 63.182554 -77.021864) (xy 63.175838 -77.074262) (xy 63.161959 -77.125233) (xy 63.141183 -77.173802)
			(xy 63.113907 -77.219042) (xy 63.097664 -77.239876) (xy 63.084404 -77.256949) (xy 63.063291 -77.294668)
			(xy 63.048869 -77.335417) (xy 63.041556 -77.37802) (xy 63.041561 -77.421246) (xy 63.048886 -77.463846)
			(xy 63.063318 -77.504592) (xy 63.084441 -77.542305) (xy 63.097664 -77.559408) (xy 63.114246 -77.580591)
			(xy 63.14192 -77.62672) (xy 63.16284 -77.676279) (xy 63.176592 -77.728286) (xy 63.182902 -77.781709)
			(xy 63.181646 -77.835488) (xy 63.172849 -77.888558) (xy 63.156684 -77.939866) (xy 63.133473 -77.988394)
			(xy 63.103675 -78.033181) (xy 63.067882 -78.073339) (xy 63.026803 -78.108071) (xy 62.981252 -78.136689)
			(xy 62.932134 -78.158624) (xy 62.906402 -78.166468) (xy 62.890767 -78.171478) (xy 62.862568 -78.188272)
			(xy 62.839597 -78.211714) (xy 62.823378 -78.240247) (xy 62.814988 -78.271978) (xy 62.814454 -78.288388)
			(xy 62.814454 -79.26132) (xy 109.258606 -79.26132) (xy 109.258606 -79.17118) (xy 109.266686 -79.081404)
			(xy 109.282781 -78.992713) (xy 109.306761 -78.905821) (xy 109.338434 -78.82143) (xy 109.377544 -78.740217)
			(xy 109.423776 -78.662837) (xy 109.476759 -78.589912) (xy 109.536065 -78.522031) (xy 109.601218 -78.459739)
			(xy 109.671692 -78.403537) (xy 109.74692 -78.35388) (xy 109.826296 -78.311166) (xy 109.909182 -78.275738)
			(xy 109.99491 -78.247884) (xy 110.082789 -78.227826) (xy 110.172113 -78.215726) (xy 110.262162 -78.211682)
			(xy 110.352211 -78.215726) (xy 110.441535 -78.227826) (xy 110.529414 -78.247884) (xy 110.615142 -78.275738)
			(xy 110.698028 -78.311166) (xy 110.777404 -78.35388) (xy 110.852632 -78.403537) (xy 110.923106 -78.459739)
			(xy 110.988259 -78.522031) (xy 111.047565 -78.589912) (xy 111.100548 -78.662837) (xy 111.14678 -78.740217)
			(xy 111.18589 -78.82143) (xy 111.217563 -78.905821) (xy 111.241543 -78.992713) (xy 111.257638 -79.081404)
			(xy 111.265718 -79.17118) (xy 111.266224 -79.21625) (xy 111.265718 -79.26132) (xy 111.257638 -79.351096)
			(xy 111.241543 -79.439787) (xy 111.217563 -79.526679) (xy 111.18589 -79.61107) (xy 111.14678 -79.692283)
			(xy 111.100548 -79.769663) (xy 111.047565 -79.842588) (xy 110.988259 -79.910469) (xy 110.923106 -79.972761)
			(xy 110.852632 -80.028963) (xy 110.777404 -80.07862) (xy 110.698028 -80.121334) (xy 110.615142 -80.156762)
			(xy 110.529414 -80.184616) (xy 110.441535 -80.204674) (xy 110.352211 -80.216774) (xy 110.262162 -80.220818)
			(xy 110.172113 -80.216774) (xy 110.082789 -80.204674) (xy 109.99491 -80.184616) (xy 109.909182 -80.156762)
			(xy 109.826296 -80.121334) (xy 109.74692 -80.07862) (xy 109.671692 -80.028963) (xy 109.601218 -79.972761)
			(xy 109.536065 -79.910469) (xy 109.476759 -79.842588) (xy 109.423776 -79.769663) (xy 109.377544 -79.692283)
			(xy 109.338434 -79.61107) (xy 109.306761 -79.526679) (xy 109.282781 -79.439787) (xy 109.266686 -79.351096)
			(xy 109.258606 -79.26132) (xy 62.814454 -79.26132) (xy 62.814454 -79.703676) (xy 62.815003 -79.720309)
			(xy 62.823616 -79.752443) (xy 62.840236 -79.781261) (xy 62.863736 -79.804808) (xy 62.89252 -79.821486)
			(xy 62.908434 -79.826358) (xy 62.935085 -79.834039) (xy 62.985996 -79.856046) (xy 63.033183 -79.885194)
			(xy 63.075651 -79.920869) (xy 63.112504 -79.962319) (xy 63.142965 -80.008669) (xy 63.166391 -80.058942)
			(xy 63.18229 -80.112079) (xy 63.190324 -80.166957) (xy 63.190326 -80.222421) (xy 63.182294 -80.2773)
			(xy 63.166399 -80.330437) (xy 63.142975 -80.380712) (xy 63.112517 -80.427064) (xy 63.075667 -80.468516)
			(xy 63.033201 -80.504193) (xy 62.986016 -80.533344) (xy 62.935106 -80.555353) (xy 62.908434 -80.562958)
			(xy 62.892491 -80.567759) (xy 62.863682 -80.584431) (xy 62.84017 -80.607992) (xy 62.823558 -80.636836)
			(xy 62.814977 -80.668997) (xy 62.814454 -80.68564) (xy 62.814454 -82.785966) (xy 62.867032 -82.854292)
			(xy 62.908942 -82.865468) (xy 62.935777 -82.873075) (xy 62.987061 -82.895004) (xy 63.034606 -82.924167)
			(xy 63.077398 -82.959941) (xy 63.114525 -83.001564) (xy 63.145197 -83.04815) (xy 63.168759 -83.098704)
			(xy 63.18471 -83.152151) (xy 63.192709 -83.20735) (xy 63.192587 -83.263126) (xy 63.184345 -83.318289)
			(xy 63.168159 -83.371665) (xy 63.144375 -83.422116) (xy 63.113498 -83.468566) (xy 63.076188 -83.510025)
			(xy 63.054992 -83.528154) (xy 63.042494 -83.539139) (xy 63.023234 -83.566261) (xy 63.011654 -83.597445)
			(xy 63.008547 -83.630564) (xy 63.014122 -83.663359) (xy 63.028001 -83.69359) (xy 63.038228 -83.706716)
			(xy 63.055487 -83.728338) (xy 63.084241 -83.7756) (xy 63.105871 -83.826518) (xy 63.119923 -83.880025)
			(xy 63.126103 -83.935001) (xy 63.124283 -83.990293) (xy 63.114499 -84.044742) (xy 63.096956 -84.097209)
			(xy 63.072024 -84.146594) (xy 63.056516 -84.169504) (xy 63.046916 -84.184152) (xy 63.035348 -84.217193)
			(xy 63.033181 -84.252135) (xy 63.040577 -84.286353) (xy 63.056983 -84.317279) (xy 63.068708 -84.330286)
			(xy 63.087599 -84.350705) (xy 63.11987 -84.396013) (xy 63.145219 -84.445527) (xy 63.16311 -84.498197)
			(xy 63.173161 -84.552907) (xy 63.175161 -84.608497) (xy 63.169067 -84.663788) (xy 63.155008 -84.717608)
			(xy 63.133282 -84.768815) (xy 63.104349 -84.816325) (xy 63.068825 -84.859129) (xy 63.02746 -84.89632)
			(xy 62.981133 -84.927111) (xy 62.930826 -84.950847) (xy 62.90437 -84.959444) (xy 62.864238 -84.971636)
			(xy 62.814454 -85.038946) (xy 62.814454 -85.26653) (xy 62.814906 -85.282092) (xy 62.822451 -85.312288)
			(xy 62.837085 -85.339758) (xy 62.857936 -85.362866) (xy 62.870588 -85.37194) (xy 62.892514 -85.387195)
			(xy 62.932281 -85.422857) (xy 62.966683 -85.463718) (xy 62.995049 -85.508978) (xy 63.016825 -85.557753)
			(xy 63.031583 -85.609088) (xy 63.039036 -85.66198) (xy 63.039038 -85.715395) (xy 63.031588 -85.768288)
			(xy 63.016833 -85.819624) (xy 62.995061 -85.8684) (xy 62.966698 -85.913662) (xy 62.932298 -85.954525)
			(xy 62.892534 -85.99019) (xy 62.870588 -86.005416) (xy 62.844172 -86.023196) (xy 62.814454 -86.079076)
			(xy 62.814454 -87.136478) (xy 64.540968 -88.862992) (xy 87.993207 -88.862992) (xy 87.993207 -88.736856)
			(xy 88.001127 -88.610968) (xy 88.016937 -88.485826) (xy 88.040572 -88.361923) (xy 88.071941 -88.23975)
			(xy 88.110919 -88.119787) (xy 88.157353 -88.002508) (xy 88.21106 -87.888376) (xy 88.271827 -87.777841)
			(xy 88.339414 -87.671341) (xy 88.413555 -87.569294) (xy 88.493958 -87.472104) (xy 88.580304 -87.380154)
			(xy 88.672254 -87.293808) (xy 88.769444 -87.213405) (xy 88.871491 -87.139264) (xy 88.977991 -87.071677)
			(xy 89.088526 -87.01091) (xy 89.202658 -86.957203) (xy 89.319937 -86.910769) (xy 89.4399 -86.871791)
			(xy 89.562073 -86.840422) (xy 89.685976 -86.816787) (xy 89.811118 -86.800977) (xy 89.937006 -86.793057)
			(xy 90.063142 -86.793057) (xy 90.18903 -86.800977) (xy 90.314172 -86.816787) (xy 90.438075 -86.840422)
			(xy 90.560248 -86.871791) (xy 90.680211 -86.910769) (xy 90.79749 -86.957203) (xy 90.911622 -87.01091)
			(xy 91.022157 -87.071677) (xy 91.128657 -87.139264) (xy 91.230704 -87.213405) (xy 91.327894 -87.293808)
			(xy 91.419844 -87.380154) (xy 91.50619 -87.472104) (xy 91.586593 -87.569294) (xy 91.660734 -87.671341)
			(xy 91.728321 -87.777841) (xy 91.789088 -87.888376) (xy 91.842795 -88.002508) (xy 91.889229 -88.119787)
			(xy 91.928207 -88.23975) (xy 91.959576 -88.361923) (xy 91.983211 -88.485826) (xy 91.999021 -88.610968)
			(xy 92.006941 -88.736856) (xy 92.007436 -88.799924) (xy 92.006941 -88.862992) (xy 91.999021 -88.98888)
			(xy 91.983211 -89.114022) (xy 91.959576 -89.237925) (xy 91.928207 -89.360098) (xy 91.889229 -89.480061)
			(xy 91.842795 -89.59734) (xy 91.789088 -89.711472) (xy 91.728321 -89.822007) (xy 91.660734 -89.928507)
			(xy 91.586593 -90.030554) (xy 91.50619 -90.127744) (xy 91.419844 -90.219694) (xy 91.327894 -90.30604)
			(xy 91.230704 -90.386443) (xy 91.128657 -90.460584) (xy 91.022157 -90.528171) (xy 90.911622 -90.588938)
			(xy 90.79749 -90.642645) (xy 90.680211 -90.689079) (xy 90.560248 -90.728057) (xy 90.438075 -90.759426)
			(xy 90.314172 -90.783061) (xy 90.18903 -90.798871) (xy 90.063142 -90.806791) (xy 89.937006 -90.806791)
			(xy 89.811118 -90.798871) (xy 89.685976 -90.783061) (xy 89.562073 -90.759426) (xy 89.4399 -90.728057)
			(xy 89.319937 -90.689079) (xy 89.202658 -90.642645) (xy 89.088526 -90.588938) (xy 88.977991 -90.528171)
			(xy 88.871491 -90.460584) (xy 88.769444 -90.386443) (xy 88.672254 -90.30604) (xy 88.580304 -90.219694)
			(xy 88.493958 -90.127744) (xy 88.413555 -90.030554) (xy 88.339414 -89.928507) (xy 88.271827 -89.822007)
			(xy 88.21106 -89.711472) (xy 88.157353 -89.59734) (xy 88.110919 -89.480061) (xy 88.071941 -89.360098)
			(xy 88.040572 -89.237925) (xy 88.016937 -89.114022) (xy 88.001127 -88.98888) (xy 87.993207 -88.862992)
			(xy 64.540968 -88.862992) (xy 65.338452 -89.660476) (xy 65.354843 -89.676151) (xy 65.392097 -89.702008)
			(xy 65.433347 -89.720848) (xy 65.477284 -89.732073) (xy 65.522516 -89.735326) (xy 65.567607 -89.730506)
			(xy 65.611129 -89.717765) (xy 65.6517 -89.697506) (xy 65.670176 -89.684352) (xy 65.693607 -89.667482)
			(xy 65.744516 -89.640252) (xy 65.798946 -89.621001) (xy 65.855655 -89.610169) (xy 65.913348 -89.608002)
			(xy 65.97071 -89.614552) (xy 66.02643 -89.629667) (xy 66.079238 -89.653003) (xy 66.127927 -89.684028)
			(xy 66.171388 -89.722033) (xy 66.190368 -89.743788) (xy 66.202743 -89.757488) (xy 66.2336 -89.777727)
			(xy 66.268946 -89.78833) (xy 66.287396 -89.789) (xy 80.825848 -89.789) (xy 80.843069 -89.788426)
			(xy 80.876258 -89.779215) (xy 80.905782 -89.761476) (xy 80.91805 -89.749376) (xy 80.937807 -89.729229)
			(xy 80.982197 -89.694397) (xy 81.031235 -89.666484) (xy 81.083849 -89.646099) (xy 81.138893 -89.633688)
			(xy 81.195164 -89.62952) (xy 81.251435 -89.633688) (xy 81.306479 -89.646099) (xy 81.359093 -89.666484)
			(xy 81.408131 -89.694397) (xy 81.452521 -89.729229) (xy 81.472278 -89.749376) (xy 81.484539 -89.761486)
			(xy 81.51406 -89.779238) (xy 81.547256 -89.788438) (xy 81.56448 -89.789) (xy 81.711038 -89.789) (xy 81.726647 -89.788575)
			(xy 81.756938 -89.781035) (xy 81.784481 -89.766345) (xy 81.796382 -89.756234) (xy 81.817522 -89.737793)
			(xy 81.864198 -89.706676) (xy 81.914929 -89.682732) (xy 81.968619 -89.666476) (xy 82.024111 -89.658259)
			(xy 82.080209 -89.658259) (xy 82.135701 -89.666476) (xy 82.189391 -89.682732) (xy 82.240122 -89.706676)
			(xy 82.286798 -89.737793) (xy 82.307938 -89.756234) (xy 82.319827 -89.766359) (xy 82.347381 -89.781035)
			(xy 82.377672 -89.788588) (xy 82.393282 -89.789) (xy 84.338414 -89.789) (xy 84.40166 -89.747598)
			(xy 84.416646 -89.7128) (xy 84.428162 -89.687644) (xy 84.457384 -89.640665) (xy 84.493082 -89.598398)
			(xy 84.53451 -89.561729) (xy 84.580799 -89.531426) (xy 84.630978 -89.508126) (xy 84.683996 -89.492315)
			(xy 84.738741 -89.484326) (xy 84.794067 -89.484326) (xy 84.848812 -89.492315) (xy 84.90183 -89.508126)
			(xy 84.952009 -89.531426) (xy 84.998298 -89.561729) (xy 85.039726 -89.598398) (xy 85.075424 -89.640665)
			(xy 85.104646 -89.687644) (xy 85.116162 -89.7128) (xy 85.122448 -89.726129) (xy 85.140129 -89.749695)
			(xy 85.162747 -89.768574) (xy 85.189094 -89.781758) (xy 85.217764 -89.788544) (xy 85.232494 -89.789)
			(xy 86.185756 -89.789) (xy 91.76766 -95.370904) (xy 91.76766 -97.983294) (xy 99.729544 -97.983294)
			(xy 99.729544 -93.61678) (xy 102.816914 -90.52941) (xy 107.183174 -90.52941) (xy 110.270544 -93.61678)
			(xy 110.270544 -97.983294) (xy 107.183174 -101.070664) (xy 102.816914 -101.070664) (xy 99.729544 -97.983294)
			(xy 91.76766 -97.983294) (xy 91.76766 -98.363532) (xy 91.768054 -98.378079) (xy 91.774641 -98.406418)
			(xy 91.787486 -98.432522) (xy 91.80592 -98.455031) (xy 91.828982 -98.472769) (xy 91.842082 -98.479102)
			(xy 91.866706 -98.490838) (xy 91.912612 -98.520302) (xy 91.953854 -98.556003) (xy 91.989592 -98.597213)
			(xy 92.019098 -98.643093) (xy 92.041769 -98.692706) (xy 92.057145 -98.745042) (xy 92.064912 -98.799034)
			(xy 92.06491 -98.853582) (xy 92.057142 -98.907574) (xy 92.041764 -98.95991) (xy 92.01909 -99.009522)
			(xy 91.989582 -99.0554) (xy 91.953842 -99.096608) (xy 91.912599 -99.132308) (xy 91.866692 -99.16177)
			(xy 91.842082 -99.173538) (xy 91.807792 -99.189032) (xy 91.76766 -99.251516) (xy 91.76766 -100.198428)
			(xy 91.768123 -100.214733) (xy 91.776321 -100.246295) (xy 91.792252 -100.274747) (xy 91.80322 -100.28682)
			(xy 91.821403 -100.306289) (xy 91.852712 -100.349387) (xy 91.877718 -100.396423) (xy 91.895934 -100.446482)
			(xy 91.907006 -100.498589) (xy 91.910717 -100.55173) (xy 91.906997 -100.604871) (xy 91.895917 -100.656976)
			(xy 91.877693 -100.707032) (xy 91.85268 -100.754064) (xy 91.821364 -100.797158) (xy 91.80322 -100.816664)
			(xy 91.792268 -100.828749) (xy 91.776336 -100.857197) (xy 91.768136 -100.888753) (xy 91.76766 -100.905056)
			(xy 91.76766 -109.373924) (xy 99.294696 -116.90096) (xy 120.438164 -116.90096)
		)
		(stroke
			(width 0)
			(type solid)
		)
		(fill yes)
		(layer "In3.Cu")
		(net "PV_VCCP_NODE1")
	)
	(gr_poly
		(pts
			(xy 31.624016 -118.49862) (xy 31.63939 -118.498144) (xy 31.669241 -118.490766) (xy 31.696462 -118.476465)
			(xy 31.719476 -118.456071) (xy 31.736946 -118.430768) (xy 31.742888 -118.416578) (xy 31.752936 -118.391347)
			(xy 31.779145 -118.343783) (xy 31.811835 -118.300416) (xy 31.850344 -118.262122) (xy 31.893894 -118.229677)
			(xy 31.941605 -118.203736) (xy 31.992513 -118.184822) (xy 32.045588 -118.173319) (xy 32.099758 -118.169459)
			(xy 32.153928 -118.173319) (xy 32.207003 -118.184822) (xy 32.257911 -118.203736) (xy 32.305622 -118.229677)
			(xy 32.349172 -118.262122) (xy 32.387681 -118.300416) (xy 32.420371 -118.343783) (xy 32.44658 -118.391347)
			(xy 32.456628 -118.416578) (xy 32.470598 -118.453662) (xy 32.535622 -118.49862) (xy 43.385994 -118.49862)
			(xy 43.41368 -118.484142) (xy 43.432476 -118.474998) (xy 43.453558 -118.465346) (xy 64.071754 -97.84715)
			(xy 64.077342 -97.804478) (xy 64.081487 -97.777084) (xy 64.096663 -97.7238) (xy 64.119386 -97.673272)
			(xy 64.149179 -97.626562) (xy 64.185415 -97.584653) (xy 64.227333 -97.548426) (xy 64.274049 -97.518644)
			(xy 64.324583 -97.495933) (xy 64.37787 -97.48077) (xy 64.405256 -97.476564) (xy 64.447928 -97.470976)
			(xy 65.10782 -96.811084) (xy 65.10782 -91.657932) (xy 65.107388 -91.642889) (xy 65.100321 -91.613644)
			(xy 65.086598 -91.586869) (xy 65.066982 -91.564056) (xy 65.042566 -91.546475) (xy 65.028826 -91.54033)
			(xy 65.002922 -91.529174) (xy 64.954446 -91.500349) (xy 64.910742 -91.464701) (xy 64.872763 -91.423006)
			(xy 64.841336 -91.376175) (xy 64.817147 -91.325227) (xy 64.800722 -91.271273) (xy 64.79242 -91.215488)
			(xy 64.792422 -91.159089) (xy 64.800727 -91.103305) (xy 64.817155 -91.049352) (xy 64.841347 -90.998405)
			(xy 64.872777 -90.951576) (xy 64.910759 -90.909884) (xy 64.954465 -90.874238) (xy 65.002943 -90.845416)
			(xy 65.028826 -90.83421) (xy 65.064894 -90.819478) (xy 65.10782 -90.75547) (xy 65.10782 -90.148156)
			(xy 62.306454 -87.34679) (xy 62.306454 -87.08771) (xy 62.268354 -87.026496) (xy 62.235842 -87.01024)
			(xy 62.210778 -86.997224) (xy 62.164454 -86.964922) (xy 62.123398 -86.926143) (xy 62.088508 -86.881735)
			(xy 62.060548 -86.832667) (xy 62.040127 -86.780014) (xy 62.027694 -86.724925) (xy 62.023518 -86.668604)
			(xy 62.027692 -86.612284) (xy 62.040125 -86.557195) (xy 62.060544 -86.504541) (xy 62.088503 -86.455473)
			(xy 62.123392 -86.411064) (xy 62.164447 -86.372284) (xy 62.210771 -86.339981) (xy 62.235842 -86.32698)
			(xy 62.268354 -86.310724) (xy 62.306454 -86.24951) (xy 62.306454 -85.838538) (xy 62.299088 -85.81771)
			(xy 62.290597 -85.792776) (xy 62.27977 -85.741227) (xy 62.27614 -85.688679) (xy 62.279776 -85.636132)
			(xy 62.290608 -85.584584) (xy 62.299088 -85.559646) (xy 62.306454 -85.538818) (xy 62.306454 -76.65593)
			(xy 63.26886 -75.693524) (xy 63.28156 -75.611736) (xy 63.26251 -75.574652) (xy 63.249946 -75.549235)
			(xy 63.231638 -75.495577) (xy 63.221474 -75.439801) (xy 63.219677 -75.383134) (xy 63.226289 -75.326825)
			(xy 63.241163 -75.272115) (xy 63.26397 -75.22021) (xy 63.29421 -75.172252) (xy 63.331215 -75.129299)
			(xy 63.374171 -75.092296) (xy 63.42213 -75.06206) (xy 63.474037 -75.039255) (xy 63.528748 -75.024385)
			(xy 63.585057 -75.017776) (xy 63.641724 -75.019576) (xy 63.6975 -75.029743) (xy 63.751157 -75.048055)
			(xy 63.776606 -75.060556) (xy 63.81369 -75.079606) (xy 63.895478 -75.066906) (xy 64.253872 -74.708512)
			(xy 65.542668 -74.708512) (xy 66.13144 -74.11974) (xy 66.13144 -70.2183) (xy 66.130897 -70.20165)
			(xy 66.12228 -70.169483) (xy 66.105633 -70.140643) (xy 66.082089 -70.117092) (xy 66.053254 -70.100436)
			(xy 66.02109 -70.091808) (xy 66.00444 -70.0913) (xy 61.420756 -70.0913) (xy 61.390276 -70.109842)
			(xy 61.367702 -70.123149) (xy 61.319685 -70.144128) (xy 61.269248 -70.158337) (xy 61.21734 -70.165509)
			(xy 61.16494 -70.165509) (xy 61.113032 -70.158337) (xy 61.062595 -70.144128) (xy 61.014578 -70.123149)
			(xy 60.992004 -70.109842) (xy 60.961524 -70.0913) (xy 51.357784 -70.0913) (xy 51.338988 -70.097142)
			(xy 51.310834 -70.105526) (xy 51.252788 -70.114532) (xy 51.194048 -70.114532) (xy 51.136002 -70.105526)
			(xy 51.107848 -70.097142) (xy 51.089052 -70.0913) (xy 46.285658 -70.0913) (xy 46.270926 -70.094856)
			(xy 46.241634 -70.101488) (xy 46.181772 -70.106321) (xy 46.12191 -70.101488) (xy 46.092618 -70.094856)
			(xy 46.077886 -70.0913) (xy 45.523658 -70.0913) (xy 45.508926 -70.094856) (xy 45.479634 -70.101488)
			(xy 45.419772 -70.106321) (xy 45.35991 -70.101488) (xy 45.330618 -70.094856) (xy 45.315886 -70.0913)
			(xy 43.760136 -70.0913) (xy 43.742832 -70.091889) (xy 43.7095 -70.101199) (xy 43.679892 -70.119116)
			(xy 43.656182 -70.144326) (xy 43.647614 -70.159372) (xy 43.634334 -70.183697) (xy 43.601818 -70.228575)
			(xy 43.563151 -70.268276) (xy 43.519147 -70.301964) (xy 43.470731 -70.328931) (xy 43.418923 -70.348609)
			(xy 43.364813 -70.360584) (xy 43.30954 -70.364604) (xy 43.254267 -70.360584) (xy 43.200157 -70.348609)
			(xy 43.148349 -70.328931) (xy 43.099933 -70.301964) (xy 43.055929 -70.268276) (xy 43.017262 -70.228575)
			(xy 42.984746 -70.183697) (xy 42.971466 -70.159372) (xy 42.954956 -70.127876) (xy 42.894504 -70.0913)
			(xy 8.978138 -70.0913) (xy 8.962699 -70.091763) (xy 8.932736 -70.099237) (xy 8.905444 -70.113685)
			(xy 8.882417 -70.134262) (xy 8.865003 -70.159764) (xy 8.859266 -70.174104) (xy 8.834665 -70.239141)
			(xy 8.779221 -70.366678) (xy 8.716817 -70.490957) (xy 8.647642 -70.611598) (xy 8.571908 -70.728234)
			(xy 8.489847 -70.840508) (xy 8.401709 -70.948078) (xy 8.307762 -71.050614) (xy 8.208295 -71.147803)
			(xy 8.103611 -71.239349) (xy 7.994029 -71.324973) (xy 7.879884 -71.404411) (xy 7.842448 -71.427504)
			(xy 55.200298 -71.427504) (xy 55.200298 -71.37028) (xy 55.208442 -71.313639) (xy 55.224564 -71.258733)
			(xy 55.248336 -71.20668) (xy 55.279273 -71.15854) (xy 55.316747 -71.115293) (xy 55.359994 -71.077819)
			(xy 55.408134 -71.046882) (xy 55.460187 -71.02311) (xy 55.515093 -71.006988) (xy 55.571734 -70.998844)
			(xy 55.628958 -70.998844) (xy 55.685599 -71.006988) (xy 55.740505 -71.02311) (xy 55.792558 -71.046882)
			(xy 55.840698 -71.077819) (xy 55.883945 -71.115293) (xy 55.921419 -71.15854) (xy 55.952356 -71.20668)
			(xy 55.976128 -71.258733) (xy 55.99225 -71.313639) (xy 56.000394 -71.37028) (xy 56.000904 -71.398892)
			(xy 56.000394 -71.427504) (xy 55.99225 -71.484145) (xy 55.976128 -71.539051) (xy 55.952356 -71.591104)
			(xy 55.921419 -71.639244) (xy 55.883945 -71.682491) (xy 55.840698 -71.719965) (xy 55.792558 -71.750902)
			(xy 55.740505 -71.774674) (xy 55.685599 -71.790796) (xy 55.628958 -71.79894) (xy 55.571734 -71.79894)
			(xy 55.515093 -71.790796) (xy 55.460187 -71.774674) (xy 55.408134 -71.750902) (xy 55.359994 -71.719965)
			(xy 55.316747 -71.682491) (xy 55.279273 -71.639244) (xy 55.248336 -71.591104) (xy 55.224564 -71.539051)
			(xy 55.208442 -71.484145) (xy 55.200298 -71.427504) (xy 7.842448 -71.427504) (xy 7.761525 -71.477423)
			(xy 7.639314 -71.543785) (xy 7.513623 -71.603294) (xy 7.384837 -71.655769) (xy 7.253348 -71.701049)
			(xy 7.119559 -71.738996) (xy 6.983878 -71.769494) (xy 6.846719 -71.79245) (xy 6.708501 -71.807794)
			(xy 6.569647 -71.815479) (xy 6.500114 -71.81596) (xy 1.500124 -71.81596) (xy 1.468427 -71.816479)
			(xy 1.405575 -71.824754) (xy 1.344341 -71.841162) (xy 1.285773 -71.865422) (xy 1.230872 -71.89712)
			(xy 1.180578 -71.935712) (xy 1.135752 -71.980538) (xy 1.09716 -72.030832) (xy 1.065462 -72.085733)
			(xy 1.041202 -72.144301) (xy 1.024794 -72.205535) (xy 1.016519 -72.268387) (xy 1.016 -72.300084)
			(xy 1.016 -77.082841) (xy 4.534904 -77.082841) (xy 4.534904 -76.959015) (xy 4.542837 -76.835444)
			(xy 4.558672 -76.712636) (xy 4.582342 -76.591094) (xy 4.613751 -76.471318) (xy 4.652769 -76.353801)
			(xy 4.699237 -76.239025) (xy 4.752963 -76.127462) (xy 4.813726 -76.019571) (xy 4.881277 -75.915794)
			(xy 4.955339 -75.816559) (xy 5.035606 -75.722272) (xy 5.121749 -75.633322) (xy 5.213414 -75.550074)
			(xy 5.310225 -75.472871) (xy 5.411783 -75.402028) (xy 5.517671 -75.337838) (xy 5.627455 -75.280564)
			(xy 5.740682 -75.230441) (xy 5.856889 -75.187676) (xy 5.975596 -75.152445) (xy 6.096317 -75.124891)
			(xy 6.218555 -75.105128) (xy 6.341808 -75.093238) (xy 6.46557 -75.08927) (xy 6.589332 -75.093238)
			(xy 6.712585 -75.105128) (xy 6.834823 -75.124891) (xy 6.955544 -75.152445) (xy 7.074251 -75.187676)
			(xy 7.190458 -75.230441) (xy 7.303685 -75.280564) (xy 7.413469 -75.337838) (xy 7.519357 -75.402028)
			(xy 7.620915 -75.472871) (xy 7.717726 -75.550074) (xy 7.809391 -75.633322) (xy 7.895534 -75.722272)
			(xy 7.975801 -75.816559) (xy 8.049863 -75.915794) (xy 8.117414 -76.019571) (xy 8.178177 -76.127462)
			(xy 8.231903 -76.239025) (xy 8.278371 -76.353801) (xy 8.317389 -76.471318) (xy 8.348798 -76.591094)
			(xy 8.372468 -76.712636) (xy 8.388303 -76.835444) (xy 8.396236 -76.959015) (xy 8.396732 -77.020928)
			(xy 8.396236 -77.082841) (xy 8.388303 -77.206412) (xy 8.372468 -77.32922) (xy 8.348798 -77.450762)
			(xy 8.317389 -77.570538) (xy 8.278371 -77.688055) (xy 8.231903 -77.802831) (xy 8.178177 -77.914394)
			(xy 8.117414 -78.022285) (xy 8.049863 -78.126062) (xy 7.975801 -78.225297) (xy 7.895534 -78.319584)
			(xy 7.809391 -78.408534) (xy 7.717726 -78.491782) (xy 7.620915 -78.568985) (xy 7.519357 -78.639828)
			(xy 7.413469 -78.704018) (xy 7.303685 -78.761292) (xy 7.190458 -78.811415) (xy 7.074251 -78.85418)
			(xy 6.955544 -78.889411) (xy 6.834823 -78.916965) (xy 6.712585 -78.936728) (xy 6.589332 -78.948618)
			(xy 6.46557 -78.952587) (xy 6.341808 -78.948618) (xy 6.218555 -78.936728) (xy 6.096317 -78.916965)
			(xy 5.975596 -78.889411) (xy 5.856889 -78.85418) (xy 5.740682 -78.811415) (xy 5.627455 -78.761292)
			(xy 5.517671 -78.704018) (xy 5.411783 -78.639828) (xy 5.310225 -78.568985) (xy 5.213414 -78.491782)
			(xy 5.121749 -78.408534) (xy 5.035606 -78.319584) (xy 4.955339 -78.225297) (xy 4.881277 -78.126062)
			(xy 4.813726 -78.022285) (xy 4.752963 -77.914394) (xy 4.699237 -77.802831) (xy 4.652769 -77.688055)
			(xy 4.613751 -77.570538) (xy 4.582342 -77.450762) (xy 4.558672 -77.32922) (xy 4.542837 -77.206412)
			(xy 4.534904 -77.082841) (xy 1.016 -77.082841) (xy 1.016 -90.697241) (xy 4.534904 -90.697241) (xy 4.534904 -90.573415)
			(xy 4.542837 -90.449844) (xy 4.558672 -90.327036) (xy 4.582342 -90.205494) (xy 4.613751 -90.085718)
			(xy 4.652769 -89.968201) (xy 4.699237 -89.853425) (xy 4.752963 -89.741862) (xy 4.813726 -89.633971)
			(xy 4.881277 -89.530194) (xy 4.955339 -89.430959) (xy 5.035606 -89.336672) (xy 5.121749 -89.247722)
			(xy 5.213414 -89.164474) (xy 5.310225 -89.087271) (xy 5.411783 -89.016428) (xy 5.517671 -88.952238)
			(xy 5.627455 -88.894964) (xy 5.740682 -88.844841) (xy 5.856889 -88.802076) (xy 5.975596 -88.766845)
			(xy 6.096317 -88.739291) (xy 6.218555 -88.719528) (xy 6.341808 -88.707638) (xy 6.46557 -88.70367)
			(xy 6.589332 -88.707638) (xy 6.712585 -88.719528) (xy 6.834823 -88.739291) (xy 6.955544 -88.766845)
			(xy 7.074251 -88.802076) (xy 7.190458 -88.844841) (xy 7.231461 -88.862992) (xy 23.993081 -88.862992)
			(xy 23.993081 -88.736856) (xy 24.001001 -88.610968) (xy 24.016811 -88.485826) (xy 24.040446 -88.361923)
			(xy 24.071815 -88.23975) (xy 24.110793 -88.119787) (xy 24.157227 -88.002508) (xy 24.210934 -87.888376)
			(xy 24.271701 -87.777841) (xy 24.339288 -87.671341) (xy 24.413429 -87.569294) (xy 24.493832 -87.472104)
			(xy 24.580178 -87.380154) (xy 24.672128 -87.293808) (xy 24.769318 -87.213405) (xy 24.871365 -87.139264)
			(xy 24.977865 -87.071677) (xy 25.0884 -87.01091) (xy 25.202532 -86.957203) (xy 25.319811 -86.910769)
			(xy 25.439774 -86.871791) (xy 25.561947 -86.840422) (xy 25.68585 -86.816787) (xy 25.810992 -86.800977)
			(xy 25.93688 -86.793057) (xy 26.063016 -86.793057) (xy 26.188904 -86.800977) (xy 26.314046 -86.816787)
			(xy 26.437949 -86.840422) (xy 26.560122 -86.871791) (xy 26.680085 -86.910769) (xy 26.797364 -86.957203)
			(xy 26.911496 -87.01091) (xy 27.022031 -87.071677) (xy 27.128531 -87.139264) (xy 27.230578 -87.213405)
			(xy 27.327768 -87.293808) (xy 27.419718 -87.380154) (xy 27.506064 -87.472104) (xy 27.586467 -87.569294)
			(xy 27.660608 -87.671341) (xy 27.728195 -87.777841) (xy 27.788962 -87.888376) (xy 27.842669 -88.002508)
			(xy 27.889103 -88.119787) (xy 27.928081 -88.23975) (xy 27.95945 -88.361923) (xy 27.983085 -88.485826)
			(xy 27.998895 -88.610968) (xy 28.006815 -88.736856) (xy 28.00731 -88.799924) (xy 28.006815 -88.862992)
			(xy 27.998895 -88.98888) (xy 27.983085 -89.114022) (xy 27.95945 -89.237925) (xy 27.928081 -89.360098)
			(xy 27.889103 -89.480061) (xy 27.842669 -89.59734) (xy 27.788962 -89.711472) (xy 27.728195 -89.822007)
			(xy 27.660608 -89.928507) (xy 27.586467 -90.030554) (xy 27.506064 -90.127744) (xy 27.419718 -90.219694)
			(xy 27.327768 -90.30604) (xy 27.230578 -90.386443) (xy 27.128531 -90.460584) (xy 27.022031 -90.528171)
			(xy 26.911496 -90.588938) (xy 26.797364 -90.642645) (xy 26.680085 -90.689079) (xy 26.560122 -90.728057)
			(xy 26.437949 -90.759426) (xy 26.314046 -90.783061) (xy 26.188904 -90.798871) (xy 26.063016 -90.806791)
			(xy 25.93688 -90.806791) (xy 25.810992 -90.798871) (xy 25.68585 -90.783061) (xy 25.561947 -90.759426)
			(xy 25.439774 -90.728057) (xy 25.319811 -90.689079) (xy 25.202532 -90.642645) (xy 25.0884 -90.588938)
			(xy 24.977865 -90.528171) (xy 24.871365 -90.460584) (xy 24.769318 -90.386443) (xy 24.672128 -90.30604)
			(xy 24.580178 -90.219694) (xy 24.493832 -90.127744) (xy 24.413429 -90.030554) (xy 24.339288 -89.928507)
			(xy 24.271701 -89.822007) (xy 24.210934 -89.711472) (xy 24.157227 -89.59734) (xy 24.110793 -89.480061)
			(xy 24.071815 -89.360098) (xy 24.040446 -89.237925) (xy 24.016811 -89.114022) (xy 24.001001 -88.98888)
			(xy 23.993081 -88.862992) (xy 7.231461 -88.862992) (xy 7.303685 -88.894964) (xy 7.413469 -88.952238)
			(xy 7.519357 -89.016428) (xy 7.620915 -89.087271) (xy 7.717726 -89.164474) (xy 7.809391 -89.247722)
			(xy 7.895534 -89.336672) (xy 7.975801 -89.430959) (xy 8.049863 -89.530194) (xy 8.117414 -89.633971)
			(xy 8.178177 -89.741862) (xy 8.231903 -89.853425) (xy 8.278371 -89.968201) (xy 8.317389 -90.085718)
			(xy 8.348798 -90.205494) (xy 8.372468 -90.327036) (xy 8.388303 -90.449844) (xy 8.396236 -90.573415)
			(xy 8.396732 -90.635328) (xy 8.396236 -90.697241) (xy 8.388303 -90.820812) (xy 8.372468 -90.94362)
			(xy 8.348798 -91.065162) (xy 8.317389 -91.184938) (xy 8.278371 -91.302455) (xy 8.231903 -91.417231)
			(xy 8.178177 -91.528794) (xy 8.117414 -91.636685) (xy 8.049863 -91.740462) (xy 7.975801 -91.839697)
			(xy 7.895534 -91.933984) (xy 7.809391 -92.022934) (xy 7.717726 -92.106182) (xy 7.620915 -92.183385)
			(xy 7.519357 -92.254228) (xy 7.413469 -92.318418) (xy 7.303685 -92.375692) (xy 7.190458 -92.425815)
			(xy 7.074251 -92.46858) (xy 6.955544 -92.503811) (xy 6.834823 -92.531365) (xy 6.712585 -92.551128)
			(xy 6.589332 -92.563018) (xy 6.46557 -92.566987) (xy 6.341808 -92.563018) (xy 6.218555 -92.551128)
			(xy 6.096317 -92.531365) (xy 5.975596 -92.503811) (xy 5.856889 -92.46858) (xy 5.740682 -92.425815)
			(xy 5.627455 -92.375692) (xy 5.517671 -92.318418) (xy 5.411783 -92.254228) (xy 5.310225 -92.183385)
			(xy 5.213414 -92.106182) (xy 5.121749 -92.022934) (xy 5.035606 -91.933984) (xy 4.955339 -91.839697)
			(xy 4.881277 -91.740462) (xy 4.813726 -91.636685) (xy 4.752963 -91.528794) (xy 4.699237 -91.417231)
			(xy 4.652769 -91.302455) (xy 4.613751 -91.184938) (xy 4.582342 -91.065162) (xy 4.558672 -90.94362)
			(xy 4.542837 -90.820812) (xy 4.534904 -90.697241) (xy 1.016 -90.697241) (xy 1.016 -113.67262) (xy 1.016543 -113.689268)
			(xy 1.025161 -113.721431) (xy 1.041809 -113.750266) (xy 1.065354 -113.773811) (xy 1.094189 -113.790459)
			(xy 1.126352 -113.799077) (xy 1.143 -113.79962) (xy 12.203176 -113.79962) (xy 14.07922 -115.675664)
			(xy 14.07922 -118.37162) (xy 14.079766 -118.388266) (xy 14.088387 -118.420421) (xy 14.105037 -118.44925)
			(xy 14.128582 -118.472787) (xy 14.157416 -118.489428) (xy 14.189574 -118.49804) (xy 14.20622 -118.49862)
		)
		(stroke
			(width 0)
			(type solid)
		)
		(fill yes)
		(layer "In3.Cu")
		(net "P1V05_NODE1")
	)
	(gr_poly
		(pts
			(xy 44.117768 -69.543422) (xy 44.133516 -69.509386) (xy 44.145316 -69.484906) (xy 44.174819 -69.43927)
			(xy 44.2105 -69.398283) (xy 44.251638 -69.362775) (xy 44.297398 -69.333466) (xy 44.346856 -69.310949)
			(xy 44.399009 -69.295679) (xy 44.452801 -69.287966) (xy 44.507143 -69.287966) (xy 44.560935 -69.295679)
			(xy 44.613088 -69.310949) (xy 44.662546 -69.333466) (xy 44.708306 -69.362775) (xy 44.749444 -69.398283)
			(xy 44.785125 -69.43927) (xy 44.814628 -69.484906) (xy 44.826428 -69.509386) (xy 44.842176 -69.543422)
			(xy 44.904406 -69.5833) (xy 45.003974 -69.5833) (xy 45.019605 -69.582844) (xy 45.049926 -69.575231)
			(xy 45.077477 -69.560459) (xy 45.100597 -69.539418) (xy 45.109638 -69.526658) (xy 45.125438 -69.503854)
			(xy 45.162692 -69.46275) (xy 45.205627 -69.42762) (xy 45.253294 -69.399241) (xy 45.30464 -69.378239)
			(xy 45.358532 -69.365078) (xy 45.413778 -69.36005) (xy 45.46916 -69.363264) (xy 45.523454 -69.37465)
			(xy 45.575462 -69.393957) (xy 45.624034 -69.420758) (xy 45.64634 -69.43725) (xy 45.665506 -69.451257)
			(xy 45.707895 -69.472618) (xy 45.753512 -69.485739) (xy 45.800772 -69.490164) (xy 45.848032 -69.485739)
			(xy 45.893649 -69.472618) (xy 45.936038 -69.451257) (xy 45.955204 -69.43725) (xy 45.977536 -69.42079)
			(xy 46.026096 -69.393964) (xy 46.078097 -69.374636) (xy 46.13239 -69.363234) (xy 46.187773 -69.36001)
			(xy 46.243021 -69.365036) (xy 46.296914 -69.378199) (xy 46.348258 -69.399209) (xy 46.395919 -69.427602)
			(xy 46.438842 -69.462748) (xy 46.476078 -69.503872) (xy 46.491906 -69.526658) (xy 46.500954 -69.539406)
			(xy 46.524091 -69.560413) (xy 46.551638 -69.575171) (xy 46.581945 -69.582794) (xy 46.59757 -69.5833)
			(xy 50.829464 -69.5833) (xy 50.886106 -69.552566) (xy 50.903632 -69.525642) (xy 50.918808 -69.503185)
			(xy 50.954495 -69.462394) (xy 50.995596 -69.427063) (xy 51.041283 -69.397906) (xy 51.090638 -69.375508)
			(xy 51.142665 -69.36032) (xy 51.196319 -69.35265) (xy 51.250517 -69.35265) (xy 51.304171 -69.36032)
			(xy 51.356198 -69.375508) (xy 51.405553 -69.397906) (xy 51.45124 -69.427063) (xy 51.492341 -69.462394)
			(xy 51.528028 -69.503185) (xy 51.543204 -69.525642) (xy 51.552221 -69.538621) (xy 51.575437 -69.560047)
			(xy 51.60321 -69.575105) (xy 51.633834 -69.582869) (xy 51.64963 -69.5833) (xy 53.703474 -69.5833)
			(xy 53.767736 -69.539612) (xy 53.782214 -69.503036) (xy 53.792441 -69.478452) (xy 53.818728 -69.43215)
			(xy 53.8512 -69.389954) (xy 53.889224 -69.352683) (xy 53.932062 -69.321063) (xy 53.978881 -69.295708)
			(xy 54.028771 -69.277111) (xy 54.080763 -69.265633) (xy 54.133846 -69.261497) (xy 54.186989 -69.264783)
			(xy 54.239158 -69.275429) (xy 54.289339 -69.293226) (xy 54.336558 -69.317829) (xy 54.35854 -69.332856)
			(xy 54.377635 -69.345857) (xy 54.419466 -69.365447) (xy 54.464147 -69.377158) (xy 54.510209 -69.380605)
			(xy 54.556136 -69.375673) (xy 54.600416 -69.362527) (xy 54.641593 -69.341597) (xy 54.660292 -69.32803)
			(xy 54.682418 -69.311749) (xy 54.730418 -69.285034) (xy 54.781754 -69.265481) (xy 54.835363 -69.253493)
			(xy 54.890137 -69.249319) (xy 54.944944 -69.253045) (xy 54.99865 -69.264594) (xy 55.050144 -69.283726)
			(xy 55.09836 -69.310047) (xy 55.142303 -69.343012) (xy 55.181063 -69.38194) (xy 55.213839 -69.426024)
			(xy 55.239952 -69.474354) (xy 55.249826 -69.499988) (xy 55.255572 -69.514419) (xy 55.272972 -69.540141)
			(xy 55.296084 -69.560882) (xy 55.32353 -69.575409) (xy 55.353678 -69.582857) (xy 55.369206 -69.5833)
			(xy 57.648856 -69.5833) (xy 57.663932 -69.582831) (xy 57.693225 -69.575677) (xy 57.720023 -69.561852)
			(xy 57.742831 -69.542127) (xy 57.760377 -69.517602) (xy 57.766458 -69.503798) (xy 57.777008 -69.478809)
			(xy 57.804149 -69.431847) (xy 57.837668 -69.389202) (xy 57.876888 -69.351734) (xy 57.92102 -69.320198)
			(xy 57.969173 -69.29523) (xy 58.020376 -69.277334) (xy 58.073599 -69.26687) (xy 58.127766 -69.264049)
			(xy 58.181788 -69.268928) (xy 58.234573 -69.281409) (xy 58.285059 -69.30124) (xy 58.332228 -69.328021)
			(xy 58.375128 -69.361212) (xy 58.394346 -69.380354) (xy 58.406268 -69.391967) (xy 58.434806 -69.409072)
			(xy 58.466802 -69.418195) (xy 58.500069 -69.418713) (xy 58.532334 -69.410591) (xy 58.561391 -69.394383)
			(xy 58.57367 -69.383148) (xy 58.594428 -69.36383) (xy 58.640605 -69.330922) (xy 58.691145 -69.305212)
			(xy 58.744933 -69.287267) (xy 58.800786 -69.277481) (xy 58.857471 -69.276071) (xy 58.913741 -69.283068)
			(xy 58.968355 -69.298318) (xy 59.02011 -69.321483) (xy 59.067866 -69.352055) (xy 59.11057 -69.38936)
			(xy 59.147281 -69.432575) (xy 59.177191 -69.480748) (xy 59.188858 -69.506592) (xy 59.195116 -69.519998)
			(xy 59.212787 -69.543716) (xy 59.235447 -69.562724) (xy 59.261878 -69.575999) (xy 59.290656 -69.582827)
			(xy 59.305444 -69.5833) (xy 60.830968 -69.5833) (xy 60.881514 -69.559932) (xy 60.899802 -69.538342)
			(xy 60.918016 -69.517544) (xy 60.959416 -69.480907) (xy 61.005673 -69.450631) (xy 61.055815 -69.427351)
			(xy 61.108794 -69.411554) (xy 61.163498 -69.403573) (xy 61.218782 -69.403573) (xy 61.273486 -69.411554)
			(xy 61.326465 -69.427351) (xy 61.376607 -69.450631) (xy 61.422864 -69.480907) (xy 61.464264 -69.517544)
			(xy 61.482478 -69.538342) (xy 61.494851 -69.552028) (xy 61.525714 -69.572214) (xy 61.561066 -69.582717)
			(xy 61.579506 -69.5833) (xy 74.957432 -69.5833) (xy 74.964544 -69.582538) (xy 74.986208 -69.580367)
			(xy 75.029748 -69.580367) (xy 75.051412 -69.582538) (xy 75.058524 -69.5833) (xy 78.810104 -69.5833)
			(xy 79.81442 -68.578984) (xy 79.81442 -65.937638) (xy 79.7941 -65.906142) (xy 79.779568 -65.882859)
			(xy 79.756612 -65.833007) (xy 79.741038 -65.780379) (xy 79.733168 -65.726062) (xy 79.733166 -65.671178)
			(xy 79.741029 -65.616861) (xy 79.756598 -65.564231) (xy 79.779549 -65.514377) (xy 79.7941 -65.491106)
			(xy 79.81442 -65.45961) (xy 79.81442 -55.919624) (xy 84.2264 -51.507644) (xy 84.2264 -31.438342)
			(xy 84.225875 -31.420744) (xy 84.216319 -31.386874) (xy 84.197846 -31.35692) (xy 84.185252 -31.344616)
			(xy 84.164409 -31.324797) (xy 84.128332 -31.280005) (xy 84.099386 -31.230307) (xy 84.078228 -31.176826)
			(xy 84.065337 -31.120776) (xy 84.061005 -31.063426) (xy 84.065329 -31.006075) (xy 84.078213 -30.950023)
			(xy 84.099364 -30.89654) (xy 84.128303 -30.846837) (xy 84.164374 -30.802041) (xy 84.185252 -30.78226)
			(xy 84.197819 -30.76994) (xy 84.216252 -30.739974) (xy 84.225835 -30.706124) (xy 84.2264 -30.688534)
			(xy 84.2264 -14.39418) (xy 84.225854 -14.377533) (xy 84.217233 -14.345376) (xy 84.200583 -14.316544)
			(xy 84.17704 -14.293004) (xy 84.148206 -14.276359) (xy 84.116047 -14.267743) (xy 84.0994 -14.26718)
			(xy 66.249042 -14.26718) (xy 65.073276 -13.091414) (xy 65.073276 -8.934704) (xy 64.241934 -8.103362)
			(xy 64.241934 -1.143) (xy 64.241391 -1.12635) (xy 64.232774 -1.094184) (xy 64.216126 -1.065344) (xy 64.192583 -1.041795)
			(xy 64.163747 -1.025139) (xy 64.131584 -1.016514) (xy 64.114934 -1.016) (xy 1.999996 -1.016) (xy 1.954527 -1.016525)
			(xy 1.863978 -1.024916) (xy 1.77459 -1.041626) (xy 1.687124 -1.066512) (xy 1.602328 -1.099363) (xy 1.520924 -1.139897)
			(xy 1.443608 -1.187769) (xy 1.371039 -1.242571) (xy 1.303835 -1.303835) (xy 1.242571 -1.371039) (xy 1.187769 -1.443608)
			(xy 1.139897 -1.520924) (xy 1.099363 -1.602328) (xy 1.066512 -1.687124) (xy 1.041626 -1.77459) (xy 1.024916 -1.863978)
			(xy 1.016525 -1.954527) (xy 1.016 -1.999996) (xy 1.016 -21.794632) (xy 20.990752 -21.794632) (xy 20.995027 -21.614979)
			(xy 21.007348 -21.435698) (xy 21.027692 -21.257149) (xy 21.056017 -21.079691) (xy 21.092266 -20.90368)
			(xy 21.136367 -20.729471) (xy 21.188231 -20.557414) (xy 21.247753 -20.387854) (xy 21.314815 -20.221131)
			(xy 21.389281 -20.057581) (xy 21.471001 -19.897533) (xy 21.559812 -19.741309) (xy 21.655535 -19.589221)
			(xy 21.757978 -19.441575) (xy 21.866935 -19.29867) (xy 21.982186 -19.16079) (xy 22.103501 -19.028214)
			(xy 22.230636 -18.901209) (xy 22.363334 -18.780028) (xy 22.43201 -18.722086) (xy 22.500626 -18.665453)
			(xy 22.64215 -18.557602) (xy 22.78832 -18.456137) (xy 22.938848 -18.361257) (xy 23.093438 -18.27315)
			(xy 23.251784 -18.191989) (xy 23.413576 -18.117933) (xy 23.578495 -18.05113) (xy 23.746215 -17.991709)
			(xy 23.916407 -17.939789) (xy 24.088734 -17.895471) (xy 24.262859 -17.858844) (xy 24.438437 -17.829978)
			(xy 24.615123 -17.808931) (xy 24.792568 -17.795745) (xy 24.970424 -17.790445) (xy 25.14834 -17.793041)
			(xy 25.325966 -17.80353) (xy 25.502951 -17.821889) (xy 25.678948 -17.848083) (xy 25.853608 -17.88206)
			(xy 26.02659 -17.923753) (xy 26.197551 -17.973081) (xy 26.366154 -18.029946) (xy 26.532069 -18.094236)
			(xy 26.694968 -18.165824) (xy 26.85453 -18.244569) (xy 27.010441 -18.330317) (xy 27.162393 -18.422898)
			(xy 27.310089 -18.52213) (xy 27.453235 -18.627817) (xy 27.591552 -18.739752) (xy 27.724765 -18.857714)
			(xy 27.852614 -18.98147) (xy 27.974845 -19.110778) (xy 28.091219 -19.245381) (xy 28.201505 -19.385015)
			(xy 28.305488 -19.529405) (xy 28.402961 -19.678267) (xy 28.493733 -19.831307) (xy 28.577626 -19.988224)
			(xy 28.654473 -20.148709) (xy 28.724124 -20.312445) (xy 28.786442 -20.479111) (xy 28.841303 -20.648377)
			(xy 28.888599 -20.819911) (xy 28.928238 -20.993375) (xy 28.960141 -21.168426) (xy 28.984246 -21.344721)
			(xy 29.000505 -21.521911) (xy 29.008886 -21.699649) (xy 29.009372 -21.877583) (xy 29.001963 -22.055364)
			(xy 28.986673 -22.232641) (xy 28.963532 -22.409064) (xy 28.932586 -22.584288) (xy 28.893895 -22.757965)
			(xy 28.847537 -22.929755) (xy 28.793602 -23.099319) (xy 28.732197 -23.266323) (xy 28.663442 -23.430437)
			(xy 28.587473 -23.59134) (xy 28.504439 -23.748713) (xy 28.414505 -23.902247) (xy 28.317846 -24.051639)
			(xy 28.214655 -24.196595) (xy 28.105133 -24.33683) (xy 27.989497 -24.472067) (xy 27.867974 -24.602041)
			(xy 27.740804 -24.726494) (xy 27.608237 -24.845182) (xy 27.539696 -24.901906) (xy 27.515948 -24.921923)
			(xy 27.473219 -24.967001) (xy 27.436505 -25.0171) (xy 27.40639 -25.071423) (xy 27.395113 -25.099663)
			(xy 37.367456 -25.099663) (xy 37.367456 -25.000313) (xy 37.37545 -24.901285) (xy 37.391387 -24.803222)
			(xy 37.415163 -24.706759) (xy 37.446624 -24.612522) (xy 37.485566 -24.521123) (xy 37.531736 -24.433153)
			(xy 37.584835 -24.349183) (xy 37.644519 -24.269759) (xy 37.7104 -24.195394) (xy 37.782051 -24.126572)
			(xy 37.859008 -24.063739) (xy 37.940771 -24.007302) (xy 38.026811 -23.957627) (xy 38.116568 -23.915036)
			(xy 38.209462 -23.879807) (xy 38.304889 -23.852166) (xy 38.402231 -23.832293) (xy 38.500857 -23.820318)
			(xy 38.600126 -23.816318) (xy 38.699395 -23.820318) (xy 38.798021 -23.832293) (xy 38.895363 -23.852166)
			(xy 38.99079 -23.879807) (xy 39.083684 -23.915036) (xy 39.173441 -23.957627) (xy 39.259481 -24.007302)
			(xy 39.341244 -24.063739) (xy 39.418201 -24.126572) (xy 39.489852 -24.195394) (xy 39.555733 -24.269759)
			(xy 39.615417 -24.349183) (xy 39.668516 -24.433153) (xy 39.714686 -24.521123) (xy 39.753628 -24.612522)
			(xy 39.785089 -24.706759) (xy 39.808865 -24.803222) (xy 39.824802 -24.901285) (xy 39.832796 -25.000313)
			(xy 39.833296 -25.049988) (xy 39.832796 -25.099663) (xy 39.824802 -25.198691) (xy 39.808865 -25.296754)
			(xy 39.785089 -25.393217) (xy 39.753628 -25.487454) (xy 39.714686 -25.578853) (xy 39.668516 -25.666823)
			(xy 39.615417 -25.750793) (xy 39.555733 -25.830217) (xy 39.489852 -25.904582) (xy 39.418201 -25.973404)
			(xy 39.341244 -26.036237) (xy 39.259481 -26.092674) (xy 39.173441 -26.142349) (xy 39.083684 -26.18494)
			(xy 38.99079 -26.220169) (xy 38.895363 -26.24781) (xy 38.798021 -26.267683) (xy 38.699395 -26.279658)
			(xy 38.600126 -26.283659) (xy 38.500857 -26.279658) (xy 38.402231 -26.267683) (xy 38.304889 -26.24781)
			(xy 38.209462 -26.220169) (xy 38.116568 -26.18494) (xy 38.026811 -26.142349) (xy 37.940771 -26.092674)
			(xy 37.859008 -26.036237) (xy 37.782051 -25.973404) (xy 37.7104 -25.904582) (xy 37.644519 -25.830217)
			(xy 37.584835 -25.750793) (xy 37.531736 -25.666823) (xy 37.485566 -25.578853) (xy 37.446624 -25.487454)
			(xy 37.415163 -25.393217) (xy 37.391387 -25.296754) (xy 37.37545 -25.198691) (xy 37.367456 -25.099663)
			(xy 27.395113 -25.099663) (xy 27.383355 -25.129105) (xy 27.367765 -25.189228) (xy 27.359868 -25.250835)
			(xy 27.359356 -25.28189) (xy 27.359356 -26.79954) (xy 27.358857 -26.868155) (xy 27.350878 -27.005153)
			(xy 27.334946 -27.141455) (xy 27.311117 -27.2766) (xy 27.279469 -27.410131) (xy 27.240111 -27.541596)
			(xy 27.193176 -27.67055) (xy 27.138822 -27.796557) (xy 27.077233 -27.91919) (xy 27.008618 -28.038035)
			(xy 26.933209 -28.152689) (xy 26.851261 -28.262764) (xy 26.763051 -28.367889) (xy 26.668878 -28.467706)
			(xy 26.569061 -28.561879) (xy 26.463936 -28.650089) (xy 26.353861 -28.732037) (xy 26.239207 -28.807446)
			(xy 26.120362 -28.876061) (xy 25.997729 -28.93765) (xy 25.871722 -28.992004) (xy 25.742768 -29.038939)
			(xy 25.611303 -29.078297) (xy 25.477772 -29.109945) (xy 25.342627 -29.133774) (xy 25.206325 -29.149706)
			(xy 25.069327 -29.157685) (xy 24.932097 -29.157685) (xy 24.795099 -29.149706) (xy 24.658797 -29.133774)
			(xy 24.523652 -29.109945) (xy 24.390121 -29.078297) (xy 24.258656 -29.038939) (xy 24.129702 -28.992004)
			(xy 24.003695 -28.93765) (xy 23.881062 -28.876061) (xy 23.762217 -28.807446) (xy 23.647563 -28.732037)
			(xy 23.537488 -28.650089) (xy 23.432363 -28.561879) (xy 23.332546 -28.467706) (xy 23.238373 -28.367889)
			(xy 23.150163 -28.262764) (xy 23.068215 -28.152689) (xy 22.992806 -28.038035) (xy 22.924191 -27.91919)
			(xy 22.862602 -27.796557) (xy 22.808248 -27.67055) (xy 22.761313 -27.541596) (xy 22.721955 -27.410131)
			(xy 22.690307 -27.2766) (xy 22.666478 -27.141455) (xy 22.650546 -27.005153) (xy 22.642567 -26.868155)
			(xy 22.642068 -26.79954) (xy 22.642068 -25.28189) (xy 22.641619 -25.252611) (xy 22.634617 -25.194473)
			(xy 22.620748 -25.137581) (xy 22.600211 -25.082742) (xy 22.573297 -25.030735) (xy 22.540387 -24.9823)
			(xy 22.501949 -24.938122) (xy 22.480524 -24.918162) (xy 22.414674 -24.864344) (xy 22.287047 -24.751911)
			(xy 22.164302 -24.634168) (xy 22.04666 -24.511326) (xy 21.934332 -24.383607) (xy 21.880576 -24.317706)
			(xy 21.876512 -24.312626) (xy 21.8313 -24.26716) (xy 21.8313 -24.25573) (xy 21.805392 -24.221694)
			(xy 21.75151 -24.149789) (xy 21.649473 -24.001863) (xy 21.554168 -23.849512) (xy 21.465787 -23.693044)
			(xy 21.384506 -23.532772) (xy 21.31049 -23.369018) (xy 21.243887 -23.202112) (xy 21.18483 -23.032389)
			(xy 21.13344 -22.86019) (xy 21.089818 -22.68586) (xy 21.054052 -22.509751) (xy 21.026215 -22.332216)
			(xy 21.006362 -22.153612) (xy 20.994533 -21.974297) (xy 20.990752 -21.794632) (xy 1.016 -21.794632)
			(xy 1.016 -29.299916) (xy 1.016518 -29.331613) (xy 1.024793 -29.394465) (xy 1.041201 -29.455699)
			(xy 1.065461 -29.514268) (xy 1.097158 -29.569169) (xy 1.13575 -29.619463) (xy 1.180577 -29.66429)
			(xy 1.230871 -29.702882) (xy 1.285772 -29.734579) (xy 1.344341 -29.758839) (xy 1.405575 -29.775247)
			(xy 1.468427 -29.783522) (xy 1.500124 -29.78404) (xy 6.500114 -29.78404) (xy 6.570689 -29.784535)
			(xy 6.711616 -29.792449) (xy 6.851877 -29.808253) (xy 6.991032 -29.831897) (xy 7.128642 -29.863306)
			(xy 7.264275 -29.902381) (xy 7.397503 -29.949) (xy 7.527908 -30.003015) (xy 7.655078 -30.064258)
			(xy 7.778615 -30.132534) (xy 7.89813 -30.20763) (xy 8.013245 -30.289309) (xy 8.1236 -30.377315) (xy 8.228847 -30.471369)
			(xy 8.328654 -30.571176) (xy 8.422708 -30.676423) (xy 8.510713 -30.786778) (xy 8.592392 -30.901894)
			(xy 8.667488 -31.021408) (xy 8.735764 -31.144945) (xy 8.797006 -31.272116) (xy 8.851022 -31.402521)
			(xy 8.89764 -31.535749) (xy 8.936715 -31.671382) (xy 8.968124 -31.808992) (xy 8.991767 -31.948147)
			(xy 9.007571 -32.088408) (xy 9.015485 -32.229335) (xy 9.015984 -32.29991) (xy 9.015984 -42.857987)
			(xy 9.994378 -42.857987) (xy 9.994378 -42.762365) (xy 10.002274 -42.667069) (xy 10.018013 -42.572751)
			(xy 10.041487 -42.480054) (xy 10.072536 -42.389613) (xy 10.110947 -42.302045) (xy 10.156458 -42.217947)
			(xy 10.208758 -42.137895) (xy 10.267491 -42.062436) (xy 10.332254 -41.992084) (xy 10.402606 -41.927321)
			(xy 10.478065 -41.868588) (xy 10.558117 -41.816288) (xy 10.642215 -41.770777) (xy 10.729783 -41.732366)
			(xy 10.820224 -41.701317) (xy 10.912921 -41.677843) (xy 11.007239 -41.662104) (xy 11.102535 -41.654208)
			(xy 11.198157 -41.654208) (xy 11.293453 -41.662104) (xy 11.387771 -41.677843) (xy 11.480468 -41.701317)
			(xy 11.570909 -41.732366) (xy 11.658477 -41.770777) (xy 11.742575 -41.816288) (xy 11.822627 -41.868588)
			(xy 11.898086 -41.927321) (xy 11.968438 -41.992084) (xy 12.033201 -42.062436) (xy 12.091934 -42.137895)
			(xy 12.144234 -42.217947) (xy 12.189745 -42.302045) (xy 12.228156 -42.389613) (xy 12.259205 -42.480054)
			(xy 12.282679 -42.572751) (xy 12.298418 -42.667069) (xy 12.306314 -42.762365) (xy 12.306808 -42.810176)
			(xy 12.306314 -42.857987) (xy 12.298418 -42.953283) (xy 12.282679 -43.047601) (xy 12.259205 -43.140298)
			(xy 12.228156 -43.230739) (xy 12.189745 -43.318307) (xy 12.144234 -43.402405) (xy 12.091934 -43.482457)
			(xy 12.033201 -43.557916) (xy 11.968438 -43.628268) (xy 11.898086 -43.693031) (xy 11.822627 -43.751764)
			(xy 11.742575 -43.804064) (xy 11.658477 -43.849575) (xy 11.570909 -43.887986) (xy 11.480468 -43.919035)
			(xy 11.387771 -43.942509) (xy 11.293453 -43.958248) (xy 11.198157 -43.966144) (xy 11.102535 -43.966144)
			(xy 11.007239 -43.958248) (xy 10.912921 -43.942509) (xy 10.820224 -43.919035) (xy 10.729783 -43.887986)
			(xy 10.642215 -43.849575) (xy 10.558117 -43.804064) (xy 10.478065 -43.751764) (xy 10.402606 -43.693031)
			(xy 10.332254 -43.628268) (xy 10.267491 -43.557916) (xy 10.208758 -43.482457) (xy 10.156458 -43.402405)
			(xy 10.110947 -43.318307) (xy 10.072536 -43.230739) (xy 10.041487 -43.140298) (xy 10.018013 -43.047601)
			(xy 10.002274 -42.953283) (xy 9.994378 -42.857987) (xy 9.015984 -42.857987) (xy 9.015984 -58.837889)
			(xy 9.994378 -58.837889) (xy 9.994378 -58.742267) (xy 10.002274 -58.646971) (xy 10.018013 -58.552653)
			(xy 10.041487 -58.459956) (xy 10.072536 -58.369515) (xy 10.110947 -58.281947) (xy 10.156458 -58.197849)
			(xy 10.208758 -58.117797) (xy 10.267491 -58.042338) (xy 10.332254 -57.971986) (xy 10.402606 -57.907223)
			(xy 10.478065 -57.84849) (xy 10.558117 -57.79619) (xy 10.642215 -57.750679) (xy 10.729783 -57.712268)
			(xy 10.820224 -57.681219) (xy 10.912921 -57.657745) (xy 11.007239 -57.642006) (xy 11.102535 -57.63411)
			(xy 11.198157 -57.63411) (xy 11.293453 -57.642006) (xy 11.387771 -57.657745) (xy 11.480468 -57.681219)
			(xy 11.570909 -57.712268) (xy 11.658477 -57.750679) (xy 11.742575 -57.79619) (xy 11.822627 -57.84849)
			(xy 11.898086 -57.907223) (xy 11.968438 -57.971986) (xy 12.033201 -58.042338) (xy 12.091934 -58.117797)
			(xy 12.144234 -58.197849) (xy 12.189745 -58.281947) (xy 12.228156 -58.369515) (xy 12.259205 -58.459956)
			(xy 12.282679 -58.552653) (xy 12.298418 -58.646971) (xy 12.306314 -58.742267) (xy 12.306808 -58.790078)
			(xy 12.306314 -58.837889) (xy 12.298418 -58.933185) (xy 12.282679 -59.027503) (xy 12.259205 -59.1202)
			(xy 12.228156 -59.210641) (xy 12.189745 -59.298209) (xy 12.144234 -59.382307) (xy 12.091934 -59.462359)
			(xy 12.033201 -59.537818) (xy 11.968438 -59.60817) (xy 11.898086 -59.672933) (xy 11.822627 -59.731666)
			(xy 11.742575 -59.783966) (xy 11.658477 -59.829477) (xy 11.570909 -59.867888) (xy 11.480468 -59.898937)
			(xy 11.387771 -59.922411) (xy 11.293453 -59.93815) (xy 11.198157 -59.946046) (xy 11.102535 -59.946046)
			(xy 11.007239 -59.93815) (xy 10.912921 -59.922411) (xy 10.820224 -59.898937) (xy 10.729783 -59.867888)
			(xy 10.642215 -59.829477) (xy 10.558117 -59.783966) (xy 10.478065 -59.731666) (xy 10.402606 -59.672933)
			(xy 10.332254 -59.60817) (xy 10.267491 -59.537818) (xy 10.208758 -59.462359) (xy 10.156458 -59.382307)
			(xy 10.110947 -59.298209) (xy 10.072536 -59.210641) (xy 10.041487 -59.1202) (xy 10.018013 -59.027503)
			(xy 10.002274 -58.933185) (xy 9.994378 -58.837889) (xy 9.015984 -58.837889) (xy 9.015984 -62.863044)
			(xy 23.993081 -62.863044) (xy 23.993081 -62.736908) (xy 24.001001 -62.61102) (xy 24.016811 -62.485878)
			(xy 24.040446 -62.361975) (xy 24.071815 -62.239802) (xy 24.110793 -62.119839) (xy 24.157227 -62.00256)
			(xy 24.210934 -61.888428) (xy 24.271701 -61.777893) (xy 24.339288 -61.671393) (xy 24.413429 -61.569346)
			(xy 24.493832 -61.472156) (xy 24.580178 -61.380206) (xy 24.672128 -61.29386) (xy 24.769318 -61.213457)
			(xy 24.871365 -61.139316) (xy 24.977865 -61.071729) (xy 25.0884 -61.010962) (xy 25.202532 -60.957255)
			(xy 25.319811 -60.910821) (xy 25.439774 -60.871843) (xy 25.561947 -60.840474) (xy 25.68585 -60.816839)
			(xy 25.810992 -60.801029) (xy 25.93688 -60.793109) (xy 26.063016 -60.793109) (xy 26.188904 -60.801029)
			(xy 26.314046 -60.816839) (xy 26.437949 -60.840474) (xy 26.560122 -60.871843) (xy 26.680085 -60.910821)
			(xy 26.797364 -60.957255) (xy 26.911496 -61.010962) (xy 27.022031 -61.071729) (xy 27.128531 -61.139316)
			(xy 27.230578 -61.213457) (xy 27.327768 -61.29386) (xy 27.419718 -61.380206) (xy 27.506064 -61.472156)
			(xy 27.586467 -61.569346) (xy 27.660608 -61.671393) (xy 27.728195 -61.777893) (xy 27.788962 -61.888428)
			(xy 27.842669 -62.00256) (xy 27.889103 -62.119839) (xy 27.928081 -62.239802) (xy 27.95945 -62.361975)
			(xy 27.983085 -62.485878) (xy 27.998895 -62.61102) (xy 28.006815 -62.736908) (xy 28.00731 -62.799976)
			(xy 28.006815 -62.863044) (xy 27.998895 -62.988932) (xy 27.983085 -63.114074) (xy 27.95945 -63.237977)
			(xy 27.928081 -63.36015) (xy 27.889103 -63.480113) (xy 27.842669 -63.597392) (xy 27.788962 -63.711524)
			(xy 27.728195 -63.822059) (xy 27.660608 -63.928559) (xy 27.586467 -64.030606) (xy 27.506064 -64.127796)
			(xy 27.419718 -64.219746) (xy 27.327768 -64.306092) (xy 27.230578 -64.386495) (xy 27.128531 -64.460636)
			(xy 27.022031 -64.528223) (xy 26.911496 -64.58899) (xy 26.797364 -64.642697) (xy 26.680085 -64.689131)
			(xy 26.560122 -64.728109) (xy 26.437949 -64.759478) (xy 26.314046 -64.783113) (xy 26.188904 -64.798923)
			(xy 26.063016 -64.806843) (xy 25.93688 -64.806843) (xy 25.810992 -64.798923) (xy 25.68585 -64.783113)
			(xy 25.561947 -64.759478) (xy 25.439774 -64.728109) (xy 25.319811 -64.689131) (xy 25.202532 -64.642697)
			(xy 25.0884 -64.58899) (xy 24.977865 -64.528223) (xy 24.871365 -64.460636) (xy 24.769318 -64.386495)
			(xy 24.672128 -64.306092) (xy 24.580178 -64.219746) (xy 24.493832 -64.127796) (xy 24.413429 -64.030606)
			(xy 24.339288 -63.928559) (xy 24.271701 -63.822059) (xy 24.210934 -63.711524) (xy 24.157227 -63.597392)
			(xy 24.110793 -63.480113) (xy 24.071815 -63.36015) (xy 24.040446 -63.237977) (xy 24.016811 -63.114074)
			(xy 24.001001 -62.988932) (xy 23.993081 -62.863044) (xy 9.015984 -62.863044) (xy 9.015984 -69.30009)
			(xy 9.01573 -69.326506) (xy 9.015953 -69.348847) (xy 9.023281 -69.392918) (xy 9.038202 -69.435028)
			(xy 9.060257 -69.473879) (xy 9.088766 -69.508276) (xy 9.12285 -69.537157) (xy 9.161459 -69.559634)
			(xy 9.203404 -69.575012) (xy 9.247392 -69.582819) (xy 9.26973 -69.5833) (xy 44.055538 -69.5833)
		)
		(stroke
			(width 0)
			(type solid)
		)
		(fill yes)
		(layer "In3.Cu")
		(net "PV_VDDR_NODE1")
	)
	(gr_poly
		(pts
			(xy -3.142742 -207.684116) (xy -3.126087 -207.683622) (xy -3.093913 -207.675001) (xy -3.065066 -207.658346)
			(xy -3.041512 -207.634792) (xy -3.024857 -207.605945) (xy -3.016236 -207.573771) (xy -3.015742 -207.557116)
			(xy -3.015742 -161.391092) (xy -3.015996 -161.391092) (xy -3.015996 -1.143) (xy -3.01649 -1.126345)
			(xy -3.025111 -1.094171) (xy -3.041766 -1.065324) (xy -3.06532 -1.04177) (xy -3.094167 -1.025115)
			(xy -3.126341 -1.016494) (xy -3.142996 -1.016) (xy -16.237966 -1.016) (xy -16.283435 -1.016525) (xy -16.373984 -1.024916)
			(xy -16.463373 -1.041625) (xy -16.550838 -1.066512) (xy -16.635635 -1.099362) (xy -16.717038 -1.139896)
			(xy -16.794355 -1.187769) (xy -16.866924 -1.24257) (xy -16.934128 -1.303834) (xy -16.995392 -1.371038)
			(xy -17.050193 -1.443607) (xy -17.098066 -1.520924) (xy -17.1386 -1.602327) (xy -17.17145 -1.687124)
			(xy -17.196337 -1.774589) (xy -17.213046 -1.863978) (xy -17.221437 -1.954527) (xy -17.221962 -1.999996)
			(xy -17.221962 -31.846463) (xy -12.286746 -31.846463) (xy -12.286746 -31.761741) (xy -12.278693 -31.677404)
			(xy -12.262659 -31.594214) (xy -12.238791 -31.512924) (xy -12.207303 -31.434272) (xy -12.168481 -31.358969)
			(xy -12.122678 -31.287697) (xy -12.070307 -31.221101) (xy -12.011842 -31.159786) (xy -11.947814 -31.104305)
			(xy -11.878802 -31.055162) (xy -11.805432 -31.012802) (xy -11.728367 -30.977607) (xy -11.648305 -30.949898)
			(xy -11.565972 -30.929924) (xy -11.482113 -30.917867) (xy -11.397488 -30.913836) (xy -11.312863 -30.917867)
			(xy -11.229004 -30.929924) (xy -11.146671 -30.949898) (xy -11.066609 -30.977607) (xy -10.989544 -31.012802)
			(xy -10.916174 -31.055162) (xy -10.847162 -31.104305) (xy -10.783134 -31.159786) (xy -10.724669 -31.221101)
			(xy -10.672298 -31.287697) (xy -10.626495 -31.358969) (xy -10.587673 -31.434272) (xy -10.556185 -31.512924)
			(xy -10.532317 -31.594214) (xy -10.516283 -31.677404) (xy -10.50823 -31.761741) (xy -10.507726 -31.804102)
			(xy -10.50823 -31.846463) (xy -7.714746 -31.846463) (xy -7.714746 -31.761741) (xy -7.706693 -31.677404)
			(xy -7.690659 -31.594214) (xy -7.666791 -31.512924) (xy -7.635303 -31.434272) (xy -7.596481 -31.358969)
			(xy -7.550678 -31.287697) (xy -7.498307 -31.221101) (xy -7.439842 -31.159786) (xy -7.375814 -31.104305)
			(xy -7.306802 -31.055162) (xy -7.233432 -31.012802) (xy -7.156367 -30.977607) (xy -7.076305 -30.949898)
			(xy -6.993972 -30.929924) (xy -6.910113 -30.917867) (xy -6.825488 -30.913836) (xy -6.740863 -30.917867)
			(xy -6.657004 -30.929924) (xy -6.574671 -30.949898) (xy -6.494609 -30.977607) (xy -6.417544 -31.012802)
			(xy -6.344174 -31.055162) (xy -6.275162 -31.104305) (xy -6.211134 -31.159786) (xy -6.152669 -31.221101)
			(xy -6.100298 -31.287697) (xy -6.054495 -31.358969) (xy -6.015673 -31.434272) (xy -5.984185 -31.512924)
			(xy -5.960317 -31.594214) (xy -5.944283 -31.677404) (xy -5.93623 -31.761741) (xy -5.935726 -31.804102)
			(xy -5.93623 -31.846463) (xy -5.944283 -31.9308) (xy -5.960317 -32.01399) (xy -5.984185 -32.09528)
			(xy -6.015673 -32.173932) (xy -6.054495 -32.249235) (xy -6.100298 -32.320507) (xy -6.152669 -32.387103)
			(xy -6.211134 -32.448418) (xy -6.275162 -32.503899) (xy -6.344174 -32.553042) (xy -6.417544 -32.595402)
			(xy -6.494609 -32.630597) (xy -6.574671 -32.658306) (xy -6.657004 -32.67828) (xy -6.740863 -32.690337)
			(xy -6.825488 -32.694369) (xy -6.910113 -32.690337) (xy -6.993972 -32.67828) (xy -7.076305 -32.658306)
			(xy -7.156367 -32.630597) (xy -7.233432 -32.595402) (xy -7.306802 -32.553042) (xy -7.375814 -32.503899)
			(xy -7.439842 -32.448418) (xy -7.498307 -32.387103) (xy -7.550678 -32.320507) (xy -7.596481 -32.249235)
			(xy -7.635303 -32.173932) (xy -7.666791 -32.09528) (xy -7.690659 -32.01399) (xy -7.706693 -31.9308)
			(xy -7.714746 -31.846463) (xy -10.50823 -31.846463) (xy -10.516283 -31.9308) (xy -10.532317 -32.01399)
			(xy -10.556185 -32.09528) (xy -10.587673 -32.173932) (xy -10.626495 -32.249235) (xy -10.672298 -32.320507)
			(xy -10.724669 -32.387103) (xy -10.783134 -32.448418) (xy -10.847162 -32.503899) (xy -10.916174 -32.553042)
			(xy -10.989544 -32.595402) (xy -11.066609 -32.630597) (xy -11.146671 -32.658306) (xy -11.229004 -32.67828)
			(xy -11.312863 -32.690337) (xy -11.397488 -32.694369) (xy -11.482113 -32.690337) (xy -11.565972 -32.67828)
			(xy -11.648305 -32.658306) (xy -11.728367 -32.630597) (xy -11.805432 -32.595402) (xy -11.878802 -32.553042)
			(xy -11.947814 -32.503899) (xy -12.011842 -32.448418) (xy -12.070307 -32.387103) (xy -12.122678 -32.320507)
			(xy -12.168481 -32.249235) (xy -12.207303 -32.173932) (xy -12.238791 -32.09528) (xy -12.262659 -32.01399)
			(xy -12.278693 -31.9308) (xy -12.286746 -31.846463) (xy -17.221962 -31.846463) (xy -17.221962 -35.910463)
			(xy -12.286746 -35.910463) (xy -12.286746 -35.825741) (xy -12.278693 -35.741404) (xy -12.262659 -35.658214)
			(xy -12.238791 -35.576924) (xy -12.207303 -35.498272) (xy -12.168481 -35.422969) (xy -12.122678 -35.351697)
			(xy -12.070307 -35.285101) (xy -12.011842 -35.223786) (xy -11.947814 -35.168305) (xy -11.878802 -35.119162)
			(xy -11.805432 -35.076802) (xy -11.728367 -35.041607) (xy -11.648305 -35.013898) (xy -11.565972 -34.993924)
			(xy -11.482113 -34.981867) (xy -11.397488 -34.977836) (xy -11.312863 -34.981867) (xy -11.229004 -34.993924)
			(xy -11.146671 -35.013898) (xy -11.066609 -35.041607) (xy -10.989544 -35.076802) (xy -10.916174 -35.119162)
			(xy -10.847162 -35.168305) (xy -10.783134 -35.223786) (xy -10.724669 -35.285101) (xy -10.672298 -35.351697)
			(xy -10.626495 -35.422969) (xy -10.587673 -35.498272) (xy -10.556185 -35.576924) (xy -10.532317 -35.658214)
			(xy -10.516283 -35.741404) (xy -10.50823 -35.825741) (xy -10.507726 -35.868102) (xy -10.50823 -35.910463)
			(xy -7.714746 -35.910463) (xy -7.714746 -35.825741) (xy -7.706693 -35.741404) (xy -7.690659 -35.658214)
			(xy -7.666791 -35.576924) (xy -7.635303 -35.498272) (xy -7.596481 -35.422969) (xy -7.550678 -35.351697)
			(xy -7.498307 -35.285101) (xy -7.439842 -35.223786) (xy -7.375814 -35.168305) (xy -7.306802 -35.119162)
			(xy -7.233432 -35.076802) (xy -7.156367 -35.041607) (xy -7.076305 -35.013898) (xy -6.993972 -34.993924)
			(xy -6.910113 -34.981867) (xy -6.825488 -34.977836) (xy -6.740863 -34.981867) (xy -6.657004 -34.993924)
			(xy -6.574671 -35.013898) (xy -6.494609 -35.041607) (xy -6.417544 -35.076802) (xy -6.344174 -35.119162)
			(xy -6.275162 -35.168305) (xy -6.211134 -35.223786) (xy -6.152669 -35.285101) (xy -6.100298 -35.351697)
			(xy -6.054495 -35.422969) (xy -6.015673 -35.498272) (xy -5.984185 -35.576924) (xy -5.960317 -35.658214)
			(xy -5.944283 -35.741404) (xy -5.93623 -35.825741) (xy -5.935726 -35.868102) (xy -5.93623 -35.910463)
			(xy -5.944283 -35.9948) (xy -5.960317 -36.07799) (xy -5.984185 -36.15928) (xy -6.015673 -36.237932)
			(xy -6.054495 -36.313235) (xy -6.100298 -36.384507) (xy -6.152669 -36.451103) (xy -6.211134 -36.512418)
			(xy -6.275162 -36.567899) (xy -6.344174 -36.617042) (xy -6.417544 -36.659402) (xy -6.494609 -36.694597)
			(xy -6.574671 -36.722306) (xy -6.657004 -36.74228) (xy -6.740863 -36.754337) (xy -6.825488 -36.758369)
			(xy -6.910113 -36.754337) (xy -6.993972 -36.74228) (xy -7.076305 -36.722306) (xy -7.156367 -36.694597)
			(xy -7.233432 -36.659402) (xy -7.306802 -36.617042) (xy -7.375814 -36.567899) (xy -7.439842 -36.512418)
			(xy -7.498307 -36.451103) (xy -7.550678 -36.384507) (xy -7.596481 -36.313235) (xy -7.635303 -36.237932)
			(xy -7.666791 -36.15928) (xy -7.690659 -36.07799) (xy -7.706693 -35.9948) (xy -7.714746 -35.910463)
			(xy -10.50823 -35.910463) (xy -10.516283 -35.9948) (xy -10.532317 -36.07799) (xy -10.556185 -36.15928)
			(xy -10.587673 -36.237932) (xy -10.626495 -36.313235) (xy -10.672298 -36.384507) (xy -10.724669 -36.451103)
			(xy -10.783134 -36.512418) (xy -10.847162 -36.567899) (xy -10.916174 -36.617042) (xy -10.989544 -36.659402)
			(xy -11.066609 -36.694597) (xy -11.146671 -36.722306) (xy -11.229004 -36.74228) (xy -11.312863 -36.754337)
			(xy -11.397488 -36.758369) (xy -11.482113 -36.754337) (xy -11.565972 -36.74228) (xy -11.648305 -36.722306)
			(xy -11.728367 -36.694597) (xy -11.805432 -36.659402) (xy -11.878802 -36.617042) (xy -11.947814 -36.567899)
			(xy -12.011842 -36.512418) (xy -12.070307 -36.451103) (xy -12.122678 -36.384507) (xy -12.168481 -36.313235)
			(xy -12.207303 -36.237932) (xy -12.238791 -36.15928) (xy -12.262659 -36.07799) (xy -12.278693 -35.9948)
			(xy -12.286746 -35.910463) (xy -17.221962 -35.910463) (xy -17.221962 -59.105743) (xy -12.286746 -59.105743)
			(xy -12.286746 -59.021021) (xy -12.278693 -58.936684) (xy -12.262659 -58.853494) (xy -12.238791 -58.772204)
			(xy -12.207303 -58.693552) (xy -12.168481 -58.618249) (xy -12.122678 -58.546977) (xy -12.070307 -58.480381)
			(xy -12.011842 -58.419066) (xy -11.947814 -58.363585) (xy -11.878802 -58.314442) (xy -11.805432 -58.272082)
			(xy -11.728367 -58.236887) (xy -11.648305 -58.209178) (xy -11.565972 -58.189204) (xy -11.482113 -58.177147)
			(xy -11.397488 -58.173116) (xy -11.312863 -58.177147) (xy -11.229004 -58.189204) (xy -11.146671 -58.209178)
			(xy -11.066609 -58.236887) (xy -10.989544 -58.272082) (xy -10.916174 -58.314442) (xy -10.847162 -58.363585)
			(xy -10.783134 -58.419066) (xy -10.724669 -58.480381) (xy -10.672298 -58.546977) (xy -10.626495 -58.618249)
			(xy -10.587673 -58.693552) (xy -10.556185 -58.772204) (xy -10.532317 -58.853494) (xy -10.516283 -58.936684)
			(xy -10.50823 -59.021021) (xy -10.507726 -59.063382) (xy -10.50823 -59.105743) (xy -7.714746 -59.105743)
			(xy -7.714746 -59.021021) (xy -7.706693 -58.936684) (xy -7.690659 -58.853494) (xy -7.666791 -58.772204)
			(xy -7.635303 -58.693552) (xy -7.596481 -58.618249) (xy -7.550678 -58.546977) (xy -7.498307 -58.480381)
			(xy -7.439842 -58.419066) (xy -7.375814 -58.363585) (xy -7.306802 -58.314442) (xy -7.233432 -58.272082)
			(xy -7.156367 -58.236887) (xy -7.076305 -58.209178) (xy -6.993972 -58.189204) (xy -6.910113 -58.177147)
			(xy -6.825488 -58.173116) (xy -6.740863 -58.177147) (xy -6.657004 -58.189204) (xy -6.574671 -58.209178)
			(xy -6.494609 -58.236887) (xy -6.417544 -58.272082) (xy -6.344174 -58.314442) (xy -6.275162 -58.363585)
			(xy -6.211134 -58.419066) (xy -6.152669 -58.480381) (xy -6.100298 -58.546977) (xy -6.054495 -58.618249)
			(xy -6.015673 -58.693552) (xy -5.984185 -58.772204) (xy -5.960317 -58.853494) (xy -5.944283 -58.936684)
			(xy -5.93623 -59.021021) (xy -5.935726 -59.063382) (xy -5.93623 -59.105743) (xy -5.944283 -59.19008)
			(xy -5.960317 -59.27327) (xy -5.984185 -59.35456) (xy -6.015673 -59.433212) (xy -6.054495 -59.508515)
			(xy -6.100298 -59.579787) (xy -6.152669 -59.646383) (xy -6.211134 -59.707698) (xy -6.275162 -59.763179)
			(xy -6.344174 -59.812322) (xy -6.417544 -59.854682) (xy -6.494609 -59.889877) (xy -6.574671 -59.917586)
			(xy -6.657004 -59.93756) (xy -6.740863 -59.949617) (xy -6.825488 -59.953649) (xy -6.910113 -59.949617)
			(xy -6.993972 -59.93756) (xy -7.076305 -59.917586) (xy -7.156367 -59.889877) (xy -7.233432 -59.854682)
			(xy -7.306802 -59.812322) (xy -7.375814 -59.763179) (xy -7.439842 -59.707698) (xy -7.498307 -59.646383)
			(xy -7.550678 -59.579787) (xy -7.596481 -59.508515) (xy -7.635303 -59.433212) (xy -7.666791 -59.35456)
			(xy -7.690659 -59.27327) (xy -7.706693 -59.19008) (xy -7.714746 -59.105743) (xy -10.50823 -59.105743)
			(xy -10.516283 -59.19008) (xy -10.532317 -59.27327) (xy -10.556185 -59.35456) (xy -10.587673 -59.433212)
			(xy -10.626495 -59.508515) (xy -10.672298 -59.579787) (xy -10.724669 -59.646383) (xy -10.783134 -59.707698)
			(xy -10.847162 -59.763179) (xy -10.916174 -59.812322) (xy -10.989544 -59.854682) (xy -11.066609 -59.889877)
			(xy -11.146671 -59.917586) (xy -11.229004 -59.93756) (xy -11.312863 -59.949617) (xy -11.397488 -59.953649)
			(xy -11.482113 -59.949617) (xy -11.565972 -59.93756) (xy -11.648305 -59.917586) (xy -11.728367 -59.889877)
			(xy -11.805432 -59.854682) (xy -11.878802 -59.812322) (xy -11.947814 -59.763179) (xy -12.011842 -59.707698)
			(xy -12.070307 -59.646383) (xy -12.122678 -59.579787) (xy -12.168481 -59.508515) (xy -12.207303 -59.433212)
			(xy -12.238791 -59.35456) (xy -12.262659 -59.27327) (xy -12.278693 -59.19008) (xy -12.286746 -59.105743)
			(xy -17.221962 -59.105743) (xy -17.221962 -63.169743) (xy -12.286746 -63.169743) (xy -12.286746 -63.085021)
			(xy -12.278693 -63.000684) (xy -12.262659 -62.917494) (xy -12.238791 -62.836204) (xy -12.207303 -62.757552)
			(xy -12.168481 -62.682249) (xy -12.122678 -62.610977) (xy -12.070307 -62.544381) (xy -12.011842 -62.483066)
			(xy -11.947814 -62.427585) (xy -11.878802 -62.378442) (xy -11.805432 -62.336082) (xy -11.728367 -62.300887)
			(xy -11.648305 -62.273178) (xy -11.565972 -62.253204) (xy -11.482113 -62.241147) (xy -11.397488 -62.237116)
			(xy -11.312863 -62.241147) (xy -11.229004 -62.253204) (xy -11.146671 -62.273178) (xy -11.066609 -62.300887)
			(xy -10.989544 -62.336082) (xy -10.916174 -62.378442) (xy -10.847162 -62.427585) (xy -10.783134 -62.483066)
			(xy -10.724669 -62.544381) (xy -10.672298 -62.610977) (xy -10.626495 -62.682249) (xy -10.587673 -62.757552)
			(xy -10.556185 -62.836204) (xy -10.532317 -62.917494) (xy -10.516283 -63.000684) (xy -10.50823 -63.085021)
			(xy -10.507726 -63.127382) (xy -10.50823 -63.169743) (xy -7.714746 -63.169743) (xy -7.714746 -63.085021)
			(xy -7.706693 -63.000684) (xy -7.690659 -62.917494) (xy -7.666791 -62.836204) (xy -7.635303 -62.757552)
			(xy -7.596481 -62.682249) (xy -7.550678 -62.610977) (xy -7.498307 -62.544381) (xy -7.439842 -62.483066)
			(xy -7.375814 -62.427585) (xy -7.306802 -62.378442) (xy -7.233432 -62.336082) (xy -7.156367 -62.300887)
			(xy -7.076305 -62.273178) (xy -6.993972 -62.253204) (xy -6.910113 -62.241147) (xy -6.825488 -62.237116)
			(xy -6.740863 -62.241147) (xy -6.657004 -62.253204) (xy -6.574671 -62.273178) (xy -6.494609 -62.300887)
			(xy -6.417544 -62.336082) (xy -6.344174 -62.378442) (xy -6.275162 -62.427585) (xy -6.211134 -62.483066)
			(xy -6.152669 -62.544381) (xy -6.100298 -62.610977) (xy -6.054495 -62.682249) (xy -6.015673 -62.757552)
			(xy -5.984185 -62.836204) (xy -5.960317 -62.917494) (xy -5.944283 -63.000684) (xy -5.93623 -63.085021)
			(xy -5.935726 -63.127382) (xy -5.93623 -63.169743) (xy -5.944283 -63.25408) (xy -5.960317 -63.33727)
			(xy -5.984185 -63.41856) (xy -6.015673 -63.497212) (xy -6.054495 -63.572515) (xy -6.100298 -63.643787)
			(xy -6.152669 -63.710383) (xy -6.211134 -63.771698) (xy -6.275162 -63.827179) (xy -6.344174 -63.876322)
			(xy -6.417544 -63.918682) (xy -6.494609 -63.953877) (xy -6.574671 -63.981586) (xy -6.657004 -64.00156)
			(xy -6.740863 -64.013617) (xy -6.825488 -64.017649) (xy -6.910113 -64.013617) (xy -6.993972 -64.00156)
			(xy -7.076305 -63.981586) (xy -7.156367 -63.953877) (xy -7.233432 -63.918682) (xy -7.306802 -63.876322)
			(xy -7.375814 -63.827179) (xy -7.439842 -63.771698) (xy -7.498307 -63.710383) (xy -7.550678 -63.643787)
			(xy -7.596481 -63.572515) (xy -7.635303 -63.497212) (xy -7.666791 -63.41856) (xy -7.690659 -63.33727)
			(xy -7.706693 -63.25408) (xy -7.714746 -63.169743) (xy -10.50823 -63.169743) (xy -10.516283 -63.25408)
			(xy -10.532317 -63.33727) (xy -10.556185 -63.41856) (xy -10.587673 -63.497212) (xy -10.626495 -63.572515)
			(xy -10.672298 -63.643787) (xy -10.724669 -63.710383) (xy -10.783134 -63.771698) (xy -10.847162 -63.827179)
			(xy -10.916174 -63.876322) (xy -10.989544 -63.918682) (xy -11.066609 -63.953877) (xy -11.146671 -63.981586)
			(xy -11.229004 -64.00156) (xy -11.312863 -64.013617) (xy -11.397488 -64.017649) (xy -11.482113 -64.013617)
			(xy -11.565972 -64.00156) (xy -11.648305 -63.981586) (xy -11.728367 -63.953877) (xy -11.805432 -63.918682)
			(xy -11.878802 -63.876322) (xy -11.947814 -63.827179) (xy -12.011842 -63.771698) (xy -12.070307 -63.710383)
			(xy -12.122678 -63.643787) (xy -12.168481 -63.572515) (xy -12.207303 -63.497212) (xy -12.238791 -63.41856)
			(xy -12.262659 -63.33727) (xy -12.278693 -63.25408) (xy -12.286746 -63.169743) (xy -17.221962 -63.169743)
			(xy -17.221962 -187.619583) (xy -12.286746 -187.619583) (xy -12.286746 -187.534861) (xy -12.278693 -187.450524)
			(xy -12.262659 -187.367334) (xy -12.238791 -187.286044) (xy -12.207303 -187.207392) (xy -12.168481 -187.132089)
			(xy -12.122678 -187.060817) (xy -12.070307 -186.994221) (xy -12.011842 -186.932906) (xy -11.947814 -186.877425)
			(xy -11.878802 -186.828282) (xy -11.805432 -186.785922) (xy -11.728367 -186.750727) (xy -11.648305 -186.723018)
			(xy -11.565972 -186.703044) (xy -11.482113 -186.690987) (xy -11.397488 -186.686956) (xy -11.312863 -186.690987)
			(xy -11.229004 -186.703044) (xy -11.146671 -186.723018) (xy -11.066609 -186.750727) (xy -10.989544 -186.785922)
			(xy -10.916174 -186.828282) (xy -10.847162 -186.877425) (xy -10.783134 -186.932906) (xy -10.724669 -186.994221)
			(xy -10.672298 -187.060817) (xy -10.626495 -187.132089) (xy -10.587673 -187.207392) (xy -10.556185 -187.286044)
			(xy -10.532317 -187.367334) (xy -10.516283 -187.450524) (xy -10.50823 -187.534861) (xy -10.507726 -187.577222)
			(xy -10.50823 -187.619583) (xy -7.714746 -187.619583) (xy -7.714746 -187.534861) (xy -7.706693 -187.450524)
			(xy -7.690659 -187.367334) (xy -7.666791 -187.286044) (xy -7.635303 -187.207392) (xy -7.596481 -187.132089)
			(xy -7.550678 -187.060817) (xy -7.498307 -186.994221) (xy -7.439842 -186.932906) (xy -7.375814 -186.877425)
			(xy -7.306802 -186.828282) (xy -7.233432 -186.785922) (xy -7.156367 -186.750727) (xy -7.076305 -186.723018)
			(xy -6.993972 -186.703044) (xy -6.910113 -186.690987) (xy -6.825488 -186.686956) (xy -6.740863 -186.690987)
			(xy -6.657004 -186.703044) (xy -6.574671 -186.723018) (xy -6.494609 -186.750727) (xy -6.417544 -186.785922)
			(xy -6.344174 -186.828282) (xy -6.275162 -186.877425) (xy -6.211134 -186.932906) (xy -6.152669 -186.994221)
			(xy -6.100298 -187.060817) (xy -6.054495 -187.132089) (xy -6.015673 -187.207392) (xy -5.984185 -187.286044)
			(xy -5.960317 -187.367334) (xy -5.944283 -187.450524) (xy -5.93623 -187.534861) (xy -5.935726 -187.577222)
			(xy -5.93623 -187.619583) (xy -5.944283 -187.70392) (xy -5.960317 -187.78711) (xy -5.984185 -187.8684)
			(xy -6.015673 -187.947052) (xy -6.054495 -188.022355) (xy -6.100298 -188.093627) (xy -6.152669 -188.160223)
			(xy -6.211134 -188.221538) (xy -6.275162 -188.277019) (xy -6.344174 -188.326162) (xy -6.417544 -188.368522)
			(xy -6.494609 -188.403717) (xy -6.574671 -188.431426) (xy -6.657004 -188.4514) (xy -6.740863 -188.463457)
			(xy -6.825488 -188.467489) (xy -6.910113 -188.463457) (xy -6.993972 -188.4514) (xy -7.076305 -188.431426)
			(xy -7.156367 -188.403717) (xy -7.233432 -188.368522) (xy -7.306802 -188.326162) (xy -7.375814 -188.277019)
			(xy -7.439842 -188.221538) (xy -7.498307 -188.160223) (xy -7.550678 -188.093627) (xy -7.596481 -188.022355)
			(xy -7.635303 -187.947052) (xy -7.666791 -187.8684) (xy -7.690659 -187.78711) (xy -7.706693 -187.70392)
			(xy -7.714746 -187.619583) (xy -10.50823 -187.619583) (xy -10.516283 -187.70392) (xy -10.532317 -187.78711)
			(xy -10.556185 -187.8684) (xy -10.587673 -187.947052) (xy -10.626495 -188.022355) (xy -10.672298 -188.093627)
			(xy -10.724669 -188.160223) (xy -10.783134 -188.221538) (xy -10.847162 -188.277019) (xy -10.916174 -188.326162)
			(xy -10.989544 -188.368522) (xy -11.066609 -188.403717) (xy -11.146671 -188.431426) (xy -11.229004 -188.4514)
			(xy -11.312863 -188.463457) (xy -11.397488 -188.467489) (xy -11.482113 -188.463457) (xy -11.565972 -188.4514)
			(xy -11.648305 -188.431426) (xy -11.728367 -188.403717) (xy -11.805432 -188.368522) (xy -11.878802 -188.326162)
			(xy -11.947814 -188.277019) (xy -12.011842 -188.221538) (xy -12.070307 -188.160223) (xy -12.122678 -188.093627)
			(xy -12.168481 -188.022355) (xy -12.207303 -187.947052) (xy -12.238791 -187.8684) (xy -12.262659 -187.78711)
			(xy -12.278693 -187.70392) (xy -12.286746 -187.619583) (xy -17.221962 -187.619583) (xy -17.221962 -191.683583)
			(xy -12.286746 -191.683583) (xy -12.286746 -191.598861) (xy -12.278693 -191.514524) (xy -12.262659 -191.431334)
			(xy -12.238791 -191.350044) (xy -12.207303 -191.271392) (xy -12.168481 -191.196089) (xy -12.122678 -191.124817)
			(xy -12.070307 -191.058221) (xy -12.011842 -190.996906) (xy -11.947814 -190.941425) (xy -11.878802 -190.892282)
			(xy -11.805432 -190.849922) (xy -11.728367 -190.814727) (xy -11.648305 -190.787018) (xy -11.565972 -190.767044)
			(xy -11.482113 -190.754987) (xy -11.397488 -190.750956) (xy -11.312863 -190.754987) (xy -11.229004 -190.767044)
			(xy -11.146671 -190.787018) (xy -11.066609 -190.814727) (xy -10.989544 -190.849922) (xy -10.916174 -190.892282)
			(xy -10.847162 -190.941425) (xy -10.783134 -190.996906) (xy -10.724669 -191.058221) (xy -10.672298 -191.124817)
			(xy -10.626495 -191.196089) (xy -10.587673 -191.271392) (xy -10.556185 -191.350044) (xy -10.532317 -191.431334)
			(xy -10.516283 -191.514524) (xy -10.50823 -191.598861) (xy -10.507726 -191.641222) (xy -10.50823 -191.683583)
			(xy -7.714746 -191.683583) (xy -7.714746 -191.598861) (xy -7.706693 -191.514524) (xy -7.690659 -191.431334)
			(xy -7.666791 -191.350044) (xy -7.635303 -191.271392) (xy -7.596481 -191.196089) (xy -7.550678 -191.124817)
			(xy -7.498307 -191.058221) (xy -7.439842 -190.996906) (xy -7.375814 -190.941425) (xy -7.306802 -190.892282)
			(xy -7.233432 -190.849922) (xy -7.156367 -190.814727) (xy -7.076305 -190.787018) (xy -6.993972 -190.767044)
			(xy -6.910113 -190.754987) (xy -6.825488 -190.750956) (xy -6.740863 -190.754987) (xy -6.657004 -190.767044)
			(xy -6.574671 -190.787018) (xy -6.494609 -190.814727) (xy -6.417544 -190.849922) (xy -6.344174 -190.892282)
			(xy -6.275162 -190.941425) (xy -6.211134 -190.996906) (xy -6.152669 -191.058221) (xy -6.100298 -191.124817)
			(xy -6.054495 -191.196089) (xy -6.015673 -191.271392) (xy -5.984185 -191.350044) (xy -5.960317 -191.431334)
			(xy -5.944283 -191.514524) (xy -5.93623 -191.598861) (xy -5.935726 -191.641222) (xy -5.93623 -191.683583)
			(xy -5.944283 -191.76792) (xy -5.960317 -191.85111) (xy -5.984185 -191.9324) (xy -6.015673 -192.011052)
			(xy -6.054495 -192.086355) (xy -6.100298 -192.157627) (xy -6.152669 -192.224223) (xy -6.211134 -192.285538)
			(xy -6.275162 -192.341019) (xy -6.344174 -192.390162) (xy -6.417544 -192.432522) (xy -6.494609 -192.467717)
			(xy -6.574671 -192.495426) (xy -6.657004 -192.5154) (xy -6.740863 -192.527457) (xy -6.825488 -192.531489)
			(xy -6.910113 -192.527457) (xy -6.993972 -192.5154) (xy -7.076305 -192.495426) (xy -7.156367 -192.467717)
			(xy -7.233432 -192.432522) (xy -7.306802 -192.390162) (xy -7.375814 -192.341019) (xy -7.439842 -192.285538)
			(xy -7.498307 -192.224223) (xy -7.550678 -192.157627) (xy -7.596481 -192.086355) (xy -7.635303 -192.011052)
			(xy -7.666791 -191.9324) (xy -7.690659 -191.85111) (xy -7.706693 -191.76792) (xy -7.714746 -191.683583)
			(xy -10.50823 -191.683583) (xy -10.516283 -191.76792) (xy -10.532317 -191.85111) (xy -10.556185 -191.9324)
			(xy -10.587673 -192.011052) (xy -10.626495 -192.086355) (xy -10.672298 -192.157627) (xy -10.724669 -192.224223)
			(xy -10.783134 -192.285538) (xy -10.847162 -192.341019) (xy -10.916174 -192.390162) (xy -10.989544 -192.432522)
			(xy -11.066609 -192.467717) (xy -11.146671 -192.495426) (xy -11.229004 -192.5154) (xy -11.312863 -192.527457)
			(xy -11.397488 -192.531489) (xy -11.482113 -192.527457) (xy -11.565972 -192.5154) (xy -11.648305 -192.495426)
			(xy -11.728367 -192.467717) (xy -11.805432 -192.432522) (xy -11.878802 -192.390162) (xy -11.947814 -192.341019)
			(xy -12.011842 -192.285538) (xy -12.070307 -192.224223) (xy -12.122678 -192.157627) (xy -12.168481 -192.086355)
			(xy -12.207303 -192.011052) (xy -12.238791 -191.9324) (xy -12.262659 -191.85111) (xy -12.278693 -191.76792)
			(xy -12.286746 -191.683583) (xy -17.221962 -191.683583) (xy -17.221962 -206.70012) (xy -17.221437 -206.745589)
			(xy -17.213046 -206.836138) (xy -17.196337 -206.925527) (xy -17.17145 -207.012992) (xy -17.1386 -207.097789)
			(xy -17.098066 -207.179192) (xy -17.050193 -207.256509) (xy -16.995392 -207.329078) (xy -16.934128 -207.396282)
			(xy -16.866924 -207.457546) (xy -16.794355 -207.512347) (xy -16.717038 -207.56022) (xy -16.635635 -207.600754)
			(xy -16.550838 -207.633604) (xy -16.463373 -207.658491) (xy -16.373984 -207.6752) (xy -16.283435 -207.683591)
			(xy -16.237966 -207.684116)
		)
		(stroke
			(width 0)
			(type solid)
		)
		(fill yes)
		(layer "In3.Cu")
		(net "GND")
	)
	(gr_poly
		(pts
			(xy 144.234662 -178.02479) (xy 144.264868 -178.017912) (xy 144.32661 -178.012892) (xy 144.388352 -178.017912)
			(xy 144.418558 -178.02479) (xy 144.433544 -178.0286) (xy 158.294324 -178.0286) (xy 162.269424 -174.0535)
			(xy 162.286696 -173.986444) (xy 162.277298 -173.952916) (xy 162.270264 -173.92674) (xy 162.262808 -173.873054)
			(xy 162.263028 -173.818853) (xy 162.27092 -173.76523) (xy 162.286325 -173.713264) (xy 162.308932 -173.664002)
			(xy 162.338286 -173.618438) (xy 162.373796 -173.577489) (xy 162.414746 -173.54198) (xy 162.460311 -173.512627)
			(xy 162.509573 -173.490021) (xy 162.561539 -173.474618) (xy 162.615163 -173.466727) (xy 162.669364 -173.466509)
			(xy 162.723049 -173.473966) (xy 162.74923 -173.480984) (xy 162.765669 -173.485144) (xy 162.799565 -173.485594)
			(xy 162.832388 -173.477125) (xy 162.861834 -173.46033) (xy 162.874198 -173.448726) (xy 176.68748 -159.635444)
			(xy 176.68748 -144.452848) (xy 176.662334 -144.427702) (xy 176.662334 -144.21739) (xy 176.68748 -144.192244)
			(xy 176.68748 -144.118584) (xy 176.836324 -143.96974) (xy 176.909984 -143.96974) (xy 181.578504 -139.30122)
			(xy 181.578504 -133.57479) (xy 181.571138 -133.553962) (xy 181.562642 -133.529028) (xy 181.551807 -133.477478)
			(xy 181.54817 -133.424928) (xy 181.5518 -133.372378) (xy 181.562627 -133.320826) (xy 181.571138 -133.295898)
			(xy 181.578504 -133.27507) (xy 181.578504 -131.55422) (xy 181.555898 -131.521454) (xy 181.539843 -131.497376)
			(xy 181.514414 -131.445392) (xy 181.497129 -131.390165) (xy 181.488384 -131.332959) (xy 181.48838 -131.27509)
			(xy 181.497118 -131.217883) (xy 181.514396 -131.162653) (xy 181.539819 -131.110667) (xy 181.555898 -131.086606)
			(xy 181.578504 -131.05384) (xy 181.578504 -122.652282) (xy 181.577951 -122.635184) (xy 181.568879 -122.602215)
			(xy 181.55139 -122.57283) (xy 181.526735 -122.549135) (xy 181.511956 -122.540522) (xy 181.488116 -122.527102)
			(xy 181.444198 -122.494479) (xy 181.405392 -122.455917) (xy 181.372495 -122.412205) (xy 181.34618 -122.364241)
			(xy 181.326989 -122.31301) (xy 181.315315 -122.259562) (xy 181.311397 -122.204994) (xy 181.315316 -122.150427)
			(xy 181.326992 -122.096979) (xy 181.346185 -122.045748) (xy 181.372501 -121.997785) (xy 181.4054 -121.954075)
			(xy 181.444207 -121.915513) (xy 181.488125 -121.882892) (xy 181.511956 -121.869454) (xy 181.526737 -121.860837)
			(xy 181.551419 -121.837164) (xy 181.568913 -121.807777) (xy 181.577958 -121.774795) (xy 181.578504 -121.757694)
			(xy 181.578504 -119.15521) (xy 178.500024 -116.07673) (xy 178.455066 -116.072158) (xy 178.426237 -116.068699)
			(xy 178.370022 -116.054175) (xy 178.316658 -116.031298) (xy 178.267378 -116.000596) (xy 178.223321 -115.96278)
			(xy 178.185505 -115.918724) (xy 178.154803 -115.869444) (xy 178.131926 -115.81608) (xy 178.117401 -115.759865)
			(xy 178.113944 -115.731036) (xy 178.109372 -115.686078) (xy 176.68748 -114.264186) (xy 176.68748 -28.993846)
			(xy 176.686962 -28.971206) (xy 176.678893 -28.926651) (xy 176.663056 -28.884231) (xy 176.639951 -28.845289)
			(xy 176.610312 -28.811057) (xy 176.575075 -28.782621) (xy 176.535356 -28.760878) (xy 176.492413 -28.746519)
			(xy 176.447605 -28.739998) (xy 176.402351 -28.74152) (xy 176.358082 -28.751038) (xy 176.316201 -28.76825)
			(xy 176.296828 -28.779978) (xy 176.237694 -28.817166) (xy 176.115806 -28.88544) (xy 175.990165 -28.946534)
			(xy 175.861194 -29.000243) (xy 175.729326 -29.046385) (xy 175.595006 -29.084806) (xy 175.458685 -29.115376)
			(xy 175.32082 -29.137993) (xy 175.181877 -29.152581) (xy 175.042321 -29.15909) (xy 174.902623 -29.157499)
			(xy 174.763252 -29.147813) (xy 174.624677 -29.130064) (xy 174.487363 -29.104313) (xy 174.351773 -29.070645)
			(xy 174.218363 -29.029175) (xy 174.087581 -28.980041) (xy 173.959867 -28.923408) (xy 173.83565 -28.859468)
			(xy 173.715348 -28.788436) (xy 173.599367 -28.710549) (xy 173.488094 -28.62607) (xy 173.381906 -28.535284)
			(xy 173.281159 -28.438494) (xy 173.186192 -28.336028) (xy 173.097324 -28.228229) (xy 173.014854 -28.11546)
			(xy 172.93906 -27.998101) (xy 172.870195 -27.876545) (xy 172.808493 -27.751202) (xy 172.75416 -27.622492)
			(xy 172.707378 -27.49085) (xy 172.668307 -27.356718) (xy 172.637076 -27.220546) (xy 172.613791 -27.082793)
			(xy 172.6057 -27.013408) (xy 172.600874 -26.968958) (xy 172.592238 -26.960322) (xy 172.592238 -26.813764)
			(xy 172.591476 -26.75001) (xy 172.591476 -25.190958) (xy 172.591013 -25.16037) (xy 172.583421 -25.099668)
			(xy 172.568349 -25.040379) (xy 172.546029 -24.983421) (xy 172.516807 -24.929677) (xy 172.481136 -24.879978)
			(xy 172.439569 -24.835095) (xy 172.41647 -24.815038) (xy 172.349 -24.757529) (xy 172.218613 -24.637376)
			(xy 172.093666 -24.511576) (xy 171.974403 -24.380375) (xy 171.861059 -24.244028) (xy 171.753854 -24.102803)
			(xy 171.652998 -23.956977) (xy 171.558688 -23.806833) (xy 171.47111 -23.652666) (xy 171.390433 -23.494778)
			(xy 171.316817 -23.333477) (xy 171.250405 -23.169079) (xy 171.191326 -23.001905) (xy 171.139697 -22.832282)
			(xy 171.095619 -22.660543) (xy 171.059177 -22.487022) (xy 171.030443 -22.31206) (xy 171.009473 -22.135999)
			(xy 170.996309 -21.959182) (xy 170.990975 -21.781957) (xy 170.993483 -21.604668) (xy 171.003827 -21.427665)
			(xy 171.021987 -21.251291) (xy 171.047928 -21.075893) (xy 171.081599 -20.901814) (xy 171.122934 -20.729393)
			(xy 171.171853 -20.558969) (xy 171.228258 -20.390875) (xy 171.292042 -20.225439) (xy 171.363077 -20.062985)
			(xy 171.441226 -19.90383) (xy 171.526336 -19.748287) (xy 171.61824 -19.596659) (xy 171.716758 -19.449243)
			(xy 171.821698 -19.306327) (xy 171.932855 -19.168191) (xy 172.050011 -19.035105) (xy 172.172936 -18.907329)
			(xy 172.301391 -18.785113) (xy 172.435125 -18.668697) (xy 172.573874 -18.558307) (xy 172.71737 -18.454161)
			(xy 172.865329 -18.356461) (xy 173.017464 -18.265398) (xy 173.173477 -18.181152) (xy 173.333061 -18.103886)
			(xy 173.495907 -18.033751) (xy 173.661693 -17.970886) (xy 173.830098 -17.915412) (xy 173.915324 -17.890998)
			(xy 173.936435 -17.88459) (xy 173.976216 -17.865527) (xy 174.012106 -17.839879) (xy 174.043026 -17.808416)
			(xy 174.068046 -17.772085) (xy 174.086414 -17.731977) (xy 174.097578 -17.6893) (xy 174.101201 -17.645336)
			(xy 174.097176 -17.601407) (xy 174.085622 -17.558834) (xy 174.066888 -17.518897) (xy 174.041537 -17.482796)
			(xy 174.026322 -17.466818) (xy 170.826684 -14.26718) (xy 84.8614 -14.26718) (xy 84.844751 -14.267723)
			(xy 84.812586 -14.276341) (xy 84.783748 -14.292988) (xy 84.760201 -14.316532) (xy 84.743548 -14.345368)
			(xy 84.734926 -14.377531) (xy 84.7344 -14.39418) (xy 84.7344 -17.571212) (xy 147.308316 -17.571212)
			(xy 147.308773 -17.52685) (xy 147.316505 -17.438465) (xy 147.331911 -17.351089) (xy 147.354874 -17.265389)
			(xy 147.385219 -17.182016) (xy 147.422715 -17.101605) (xy 147.467076 -17.024769) (xy 147.517966 -16.952091)
			(xy 147.574997 -16.884125) (xy 147.637734 -16.821389) (xy 147.7057 -16.764359) (xy 147.778379 -16.71347)
			(xy 147.855216 -16.669109) (xy 147.935627 -16.631614) (xy 148.019 -16.60127) (xy 148.104701 -16.578309)
			(xy 148.192076 -16.562904) (xy 148.280462 -16.555173) (xy 148.324824 -16.554704) (xy 148.370622 -16.555198)
			(xy 148.461827 -16.563651) (xy 148.551863 -16.580484) (xy 148.639962 -16.605552) (xy 148.725372 -16.638643)
			(xy 148.807365 -16.679472) (xy 148.88524 -16.727693) (xy 148.958334 -16.782893) (xy 149.026023 -16.844602)
			(xy 149.08773 -16.912294) (xy 149.142928 -16.98539) (xy 149.191145 -17.063267) (xy 149.231972 -17.145261)
			(xy 149.265059 -17.230672) (xy 149.290124 -17.318772) (xy 149.306954 -17.408809) (xy 149.315404 -17.500014)
			(xy 149.315932 -17.545812) (xy 149.315932 -17.571212) (xy 153.571448 -17.571212) (xy 153.571987 -17.526853)
			(xy 153.579718 -17.438472) (xy 153.595123 -17.351101) (xy 153.618083 -17.265406) (xy 153.648425 -17.182037)
			(xy 153.685918 -17.10163) (xy 153.730275 -17.024797) (xy 153.78116 -16.952122) (xy 153.838185 -16.884158)
			(xy 153.900917 -16.821423) (xy 153.968877 -16.764394) (xy 154.04155 -16.713505) (xy 154.118381 -16.669144)
			(xy 154.198785 -16.631647) (xy 154.282152 -16.6013) (xy 154.367847 -16.578335) (xy 154.455216 -16.562926)
			(xy 154.543597 -16.55519) (xy 154.587956 -16.554704) (xy 154.633754 -16.555247) (xy 154.724958 -16.563695)
			(xy 154.814995 -16.580522) (xy 154.903094 -16.605585) (xy 154.988505 -16.63867) (xy 155.070499 -16.679496)
			(xy 155.148376 -16.727712) (xy 155.221471 -16.782909) (xy 155.289162 -16.844615) (xy 155.35087 -16.912304)
			(xy 155.40607 -16.985398) (xy 155.454289 -17.063273) (xy 155.495117 -17.145266) (xy 155.528205 -17.230676)
			(xy 155.553271 -17.318774) (xy 155.570101 -17.40881) (xy 155.578551 -17.500014) (xy 155.579064 -17.545812)
			(xy 155.579064 -17.571212) (xy 155.578559 -17.61627) (xy 155.570481 -17.706024) (xy 155.55439 -17.794693)
			(xy 155.530415 -17.881562) (xy 155.498751 -17.965933) (xy 155.45965 -18.047125) (xy 155.41343 -18.124486)
			(xy 155.36046 -18.197392) (xy 155.301169 -18.265256) (xy 155.236033 -18.327532) (xy 155.165577 -18.383719)
			(xy 155.090368 -18.433364) (xy 155.011012 -18.476068) (xy 154.928147 -18.511486) (xy 154.842441 -18.539333)
			(xy 154.754583 -18.559386) (xy 154.665282 -18.571483) (xy 154.575256 -18.575526) (xy 154.48523 -18.571483)
			(xy 154.395929 -18.559386) (xy 154.308071 -18.539333) (xy 154.222365 -18.511486) (xy 154.1395 -18.476068)
			(xy 154.060144 -18.433364) (xy 153.984935 -18.383719) (xy 153.914479 -18.327532) (xy 153.849343 -18.265256)
			(xy 153.790052 -18.197392) (xy 153.737082 -18.124486) (xy 153.690862 -18.047125) (xy 153.651761 -17.965933)
			(xy 153.620097 -17.881562) (xy 153.596122 -17.794693) (xy 153.580031 -17.706024) (xy 153.571953 -17.61627)
			(xy 153.571448 -17.571212) (xy 149.315932 -17.571212) (xy 149.315427 -17.61627) (xy 149.307349 -17.706024)
			(xy 149.291258 -17.794693) (xy 149.267283 -17.881562) (xy 149.235619 -17.965933) (xy 149.196518 -18.047125)
			(xy 149.150298 -18.124486) (xy 149.097328 -18.197392) (xy 149.038037 -18.265256) (xy 148.972901 -18.327532)
			(xy 148.902445 -18.383719) (xy 148.827236 -18.433364) (xy 148.74788 -18.476068) (xy 148.665015 -18.511486)
			(xy 148.579309 -18.539333) (xy 148.491451 -18.559386) (xy 148.40215 -18.571483) (xy 148.312124 -18.575526)
			(xy 148.222098 -18.571483) (xy 148.132797 -18.559386) (xy 148.044939 -18.539333) (xy 147.959233 -18.511486)
			(xy 147.876368 -18.476068) (xy 147.797012 -18.433364) (xy 147.721803 -18.383719) (xy 147.651347 -18.327532)
			(xy 147.586211 -18.265256) (xy 147.52692 -18.197392) (xy 147.47395 -18.124486) (xy 147.42773 -18.047125)
			(xy 147.388629 -17.965933) (xy 147.356965 -17.881562) (xy 147.33299 -17.794693) (xy 147.316899 -17.706024)
			(xy 147.308821 -17.61627) (xy 147.308316 -17.571212) (xy 84.7344 -17.571212) (xy 84.7344 -25.094499)
			(xy 104.408977 -25.094499) (xy 104.408977 -25.005477) (xy 104.416957 -24.916813) (xy 104.432853 -24.829222)
			(xy 104.456536 -24.743407) (xy 104.487816 -24.660062) (xy 104.526442 -24.579856) (xy 104.572101 -24.503435)
			(xy 104.624427 -24.431414) (xy 104.682998 -24.364374) (xy 104.747343 -24.302854) (xy 104.816943 -24.24735)
			(xy 104.891239 -24.198308) (xy 104.969631 -24.156123) (xy 105.05149 -24.121135) (xy 105.136155 -24.093626)
			(xy 105.222945 -24.073816) (xy 105.311161 -24.061866) (xy 105.400094 -24.057873) (xy 105.489027 -24.061866)
			(xy 105.577243 -24.073816) (xy 105.664033 -24.093626) (xy 105.748698 -24.121135) (xy 105.830557 -24.156123)
			(xy 105.908949 -24.198308) (xy 105.983245 -24.24735) (xy 106.052845 -24.302854) (xy 106.11719 -24.364374)
			(xy 106.175761 -24.431414) (xy 106.228087 -24.503435) (xy 106.273746 -24.579856) (xy 106.312372 -24.660062)
			(xy 106.343652 -24.743407) (xy 106.367335 -24.829222) (xy 106.383231 -24.916813) (xy 106.391211 -25.005477)
			(xy 106.39171 -25.049988) (xy 106.391211 -25.094499) (xy 106.383231 -25.183163) (xy 106.367335 -25.270754)
			(xy 106.343652 -25.356569) (xy 106.312372 -25.439914) (xy 106.273746 -25.52012) (xy 106.228087 -25.596541)
			(xy 106.175761 -25.668562) (xy 106.11719 -25.735602) (xy 106.052845 -25.797122) (xy 105.983245 -25.852626)
			(xy 105.908949 -25.901668) (xy 105.830557 -25.943853) (xy 105.748698 -25.978841) (xy 105.664033 -26.00635)
			(xy 105.577243 -26.02616) (xy 105.489027 -26.03811) (xy 105.400094 -26.042104) (xy 105.311161 -26.03811)
			(xy 105.222945 -26.02616) (xy 105.136155 -26.00635) (xy 105.05149 -25.978841) (xy 104.969631 -25.943853)
			(xy 104.891239 -25.901668) (xy 104.816943 -25.852626) (xy 104.747343 -25.797122) (xy 104.682998 -25.735602)
			(xy 104.624427 -25.668562) (xy 104.572101 -25.596541) (xy 104.526442 -25.52012) (xy 104.487816 -25.439914)
			(xy 104.456536 -25.356569) (xy 104.432853 -25.270754) (xy 104.416957 -25.183163) (xy 104.408977 -25.094499)
			(xy 84.7344 -25.094499) (xy 84.7344 -30.81401) (xy 84.757006 -30.846522) (xy 84.772971 -30.870562)
			(xy 84.79825 -30.922437) (xy 84.815428 -30.977528) (xy 84.824113 -31.034578) (xy 84.824109 -31.092285)
			(xy 84.815414 -31.149333) (xy 84.798227 -31.204421) (xy 84.77294 -31.256292) (xy 84.757006 -31.280354)
			(xy 84.7344 -31.312866) (xy 84.7344 -47.480982) (xy 154.610308 -47.480982) (xy 154.610308 -45.149516)
			(xy 155.056586 -44.703238) (xy 155.68803 -44.703238) (xy 156.134308 -45.149516) (xy 156.134308 -47.135796)
			(xy 158.3182 -47.135796) (xy 158.3182 -46.99508) (xy 158.3182 -46.961044) (xy 158.3182 -45.72508)
			(xy 158.3182 -45.691044) (xy 158.3182 -45.550328) (xy 158.414974 -45.453554) (xy 158.417006 -45.451268)
			(xy 158.444438 -45.42409) (xy 158.541466 -45.327062) (xy 158.682182 -45.327062) (xy 158.716218 -45.327062)
			(xy 158.856934 -45.327062) (xy 158.953962 -45.42409) (xy 158.981394 -45.451268) (xy 158.983426 -45.453554)
			(xy 159.0802 -45.550328) (xy 159.0802 -45.691044) (xy 159.0802 -45.72508) (xy 159.0802 -46.961044)
			(xy 159.0802 -46.99508) (xy 159.0802 -47.135796) (xy 158.983426 -47.23257) (xy 158.981394 -47.234856)
			(xy 158.953962 -47.262034) (xy 158.856934 -47.359062) (xy 158.716218 -47.359062) (xy 158.682182 -47.359062)
			(xy 158.541466 -47.359062) (xy 158.444438 -47.262034) (xy 158.417006 -47.234856) (xy 158.414974 -47.23257)
			(xy 158.3182 -47.135796) (xy 156.134308 -47.135796) (xy 156.134308 -47.480982) (xy 155.68803 -47.92726)
			(xy 155.056586 -47.92726) (xy 154.610308 -47.480982) (xy 84.7344 -47.480982) (xy 84.7344 -51.290982)
			(xy 154.610308 -51.290982) (xy 154.610308 -48.959516) (xy 155.056586 -48.513238) (xy 155.68803 -48.513238)
			(xy 156.134308 -48.959516) (xy 156.134308 -50.988468) (xy 160.899348 -50.988468) (xy 160.899348 -50.847752)
			(xy 160.899348 -50.813716) (xy 160.899348 -49.577752) (xy 160.899348 -49.543716) (xy 160.899348 -49.403)
			(xy 160.996122 -49.306226) (xy 160.998154 -49.30394) (xy 161.025586 -49.276762) (xy 161.122614 -49.179734)
			(xy 161.26333 -49.179734) (xy 161.297366 -49.179734) (xy 161.438082 -49.179734) (xy 161.53511 -49.276762)
			(xy 161.562542 -49.30394) (xy 161.564574 -49.306226) (xy 161.661348 -49.403) (xy 161.661348 -49.543716)
			(xy 161.661348 -49.577752) (xy 161.661348 -50.813716) (xy 161.661348 -50.847752) (xy 161.661348 -50.988468)
			(xy 161.564574 -51.085242) (xy 161.562542 -51.087528) (xy 161.53511 -51.114706) (xy 161.438082 -51.211734)
			(xy 161.297366 -51.211734) (xy 161.26333 -51.211734) (xy 161.122614 -51.211734) (xy 161.025586 -51.114706)
			(xy 160.998154 -51.087528) (xy 160.996122 -51.085242) (xy 160.899348 -50.988468) (xy 156.134308 -50.988468)
			(xy 156.134308 -51.290982) (xy 155.68803 -51.73726) (xy 155.056586 -51.73726) (xy 154.610308 -51.290982)
			(xy 84.7344 -51.290982) (xy 84.7344 -51.717956) (xy 80.32242 -56.129936) (xy 80.32242 -59.13563)
			(xy 109.258606 -59.13563) (xy 109.258606 -59.04549) (xy 109.266686 -58.955714) (xy 109.282781 -58.867023)
			(xy 109.306761 -58.780131) (xy 109.338434 -58.69574) (xy 109.377544 -58.614527) (xy 109.423776 -58.537147)
			(xy 109.476759 -58.464222) (xy 109.536065 -58.396341) (xy 109.601218 -58.334049) (xy 109.671692 -58.277847)
			(xy 109.74692 -58.22819) (xy 109.826296 -58.185476) (xy 109.909182 -58.150048) (xy 109.99491 -58.122194)
			(xy 110.082789 -58.102136) (xy 110.172113 -58.090036) (xy 110.262162 -58.085992) (xy 110.352211 -58.090036)
			(xy 110.441535 -58.102136) (xy 110.529414 -58.122194) (xy 110.615142 -58.150048) (xy 110.698028 -58.185476)
			(xy 110.777404 -58.22819) (xy 110.852632 -58.277847) (xy 110.923106 -58.334049) (xy 110.988259 -58.396341)
			(xy 111.047565 -58.464222) (xy 111.100548 -58.537147) (xy 111.14678 -58.614527) (xy 111.18589 -58.69574)
			(xy 111.217563 -58.780131) (xy 111.241543 -58.867023) (xy 111.257638 -58.955714) (xy 111.265718 -59.04549)
			(xy 111.266224 -59.09056) (xy 111.265718 -59.13563) (xy 111.257638 -59.225406) (xy 111.241543 -59.314097)
			(xy 111.217563 -59.400989) (xy 111.18589 -59.48538) (xy 111.14678 -59.566593) (xy 111.100548 -59.643973)
			(xy 111.047565 -59.716898) (xy 110.988259 -59.784779) (xy 110.923106 -59.847071) (xy 110.852632 -59.903273)
			(xy 110.777404 -59.95293) (xy 110.698028 -59.995644) (xy 110.615142 -60.031072) (xy 110.529414 -60.058926)
			(xy 110.441535 -60.078984) (xy 110.352211 -60.091084) (xy 110.262162 -60.095128) (xy 110.172113 -60.091084)
			(xy 110.082789 -60.078984) (xy 109.99491 -60.058926) (xy 109.909182 -60.031072) (xy 109.826296 -59.995644)
			(xy 109.74692 -59.95293) (xy 109.671692 -59.903273) (xy 109.601218 -59.847071) (xy 109.536065 -59.784779)
			(xy 109.476759 -59.716898) (xy 109.423776 -59.643973) (xy 109.377544 -59.566593) (xy 109.338434 -59.48538)
			(xy 109.306761 -59.400989) (xy 109.282781 -59.314097) (xy 109.266686 -59.225406) (xy 109.258606 -59.13563)
			(xy 80.32242 -59.13563) (xy 80.32242 -62.863044) (xy 87.993207 -62.863044) (xy 87.993207 -62.736908)
			(xy 88.001127 -62.61102) (xy 88.016937 -62.485878) (xy 88.040572 -62.361975) (xy 88.071941 -62.239802)
			(xy 88.110919 -62.119839) (xy 88.157353 -62.00256) (xy 88.21106 -61.888428) (xy 88.271827 -61.777893)
			(xy 88.339414 -61.671393) (xy 88.413555 -61.569346) (xy 88.493958 -61.472156) (xy 88.580304 -61.380206)
			(xy 88.672254 -61.29386) (xy 88.769444 -61.213457) (xy 88.871491 -61.139316) (xy 88.977991 -61.071729)
			(xy 89.088526 -61.010962) (xy 89.202658 -60.957255) (xy 89.319937 -60.910821) (xy 89.4399 -60.871843)
			(xy 89.562073 -60.840474) (xy 89.685976 -60.816839) (xy 89.811118 -60.801029) (xy 89.937006 -60.793109)
			(xy 90.063142 -60.793109) (xy 90.18903 -60.801029) (xy 90.314172 -60.816839) (xy 90.438075 -60.840474)
			(xy 90.560248 -60.871843) (xy 90.680211 -60.910821) (xy 90.79749 -60.957255) (xy 90.911622 -61.010962)
			(xy 91.022157 -61.071729) (xy 91.128657 -61.139316) (xy 91.230704 -61.213457) (xy 91.327894 -61.29386)
			(xy 91.419844 -61.380206) (xy 91.50619 -61.472156) (xy 91.586593 -61.569346) (xy 91.660734 -61.671393)
			(xy 91.728321 -61.777893) (xy 91.789088 -61.888428) (xy 91.842795 -62.00256) (xy 91.889229 -62.119839)
			(xy 91.928207 -62.239802) (xy 91.959576 -62.361975) (xy 91.983211 -62.485878) (xy 91.999021 -62.61102)
			(xy 92.006941 -62.736908) (xy 92.007436 -62.799976) (xy 92.006941 -62.863044) (xy 91.999021 -62.988932)
			(xy 91.983211 -63.114074) (xy 91.959576 -63.237977) (xy 91.928207 -63.36015) (xy 91.889229 -63.480113)
			(xy 91.842795 -63.597392) (xy 91.789088 -63.711524) (xy 91.728321 -63.822059) (xy 91.660734 -63.928559)
			(xy 91.586593 -64.030606) (xy 91.50619 -64.127796) (xy 91.419844 -64.219746) (xy 91.327894 -64.306092)
			(xy 91.230704 -64.386495) (xy 91.128657 -64.460636) (xy 91.022157 -64.528223) (xy 90.911622 -64.58899)
			(xy 90.79749 -64.642697) (xy 90.680211 -64.689131) (xy 90.560248 -64.728109) (xy 90.438075 -64.759478)
			(xy 90.314172 -64.783113) (xy 90.18903 -64.798923) (xy 90.063142 -64.806843) (xy 89.937006 -64.806843)
			(xy 89.811118 -64.798923) (xy 89.685976 -64.783113) (xy 89.562073 -64.759478) (xy 89.4399 -64.728109)
			(xy 89.319937 -64.689131) (xy 89.202658 -64.642697) (xy 89.088526 -64.58899) (xy 88.977991 -64.528223)
			(xy 88.871491 -64.460636) (xy 88.769444 -64.386495) (xy 88.672254 -64.306092) (xy 88.580304 -64.219746)
			(xy 88.493958 -64.127796) (xy 88.413555 -64.030606) (xy 88.339414 -63.928559) (xy 88.271827 -63.822059)
			(xy 88.21106 -63.711524) (xy 88.157353 -63.597392) (xy 88.110919 -63.480113) (xy 88.071941 -63.36015)
			(xy 88.040572 -63.237977) (xy 88.016937 -63.114074) (xy 88.001127 -62.988932) (xy 87.993207 -62.863044)
			(xy 80.32242 -62.863044) (xy 80.32242 -65.316354) (xy 80.32305 -65.334391) (xy 80.333127 -65.369029)
			(xy 80.352466 -65.399481) (xy 80.3656 -65.411858) (xy 80.385628 -65.430053) (xy 80.420856 -65.471123)
			(xy 80.449926 -65.51676) (xy 80.472255 -65.566047) (xy 80.487393 -65.617995) (xy 80.495038 -65.671561)
			(xy 80.495036 -65.72567) (xy 80.487387 -65.779236) (xy 80.472244 -65.831183) (xy 80.449911 -65.880468)
			(xy 80.420837 -65.926102) (xy 80.385606 -65.96717) (xy 80.3656 -65.98539) (xy 80.352445 -65.997756)
			(xy 80.333061 -66.028195) (xy 80.322992 -66.06285) (xy 80.32242 -66.080894) (xy 80.32242 -68.30314)
			(xy 80.322968 -68.319784) (xy 80.331593 -68.351935) (xy 80.348245 -68.380759) (xy 80.371788 -68.404292)
			(xy 80.40062 -68.42093) (xy 80.432776 -68.42954) (xy 80.44942 -68.43014) (xy 102.037388 -68.43014)
			(xy 102.088188 -68.406264) (xy 102.106476 -68.38442) (xy 102.124701 -68.363328) (xy 102.166226 -68.326143)
			(xy 102.21272 -68.295397) (xy 102.263195 -68.271745) (xy 102.316574 -68.255692) (xy 102.371722 -68.247579)
			(xy 102.427462 -68.247579) (xy 102.48261 -68.255692) (xy 102.535989 -68.271745) (xy 102.586464 -68.295397)
			(xy 102.632958 -68.326143) (xy 102.674483 -68.363328) (xy 102.692708 -68.38442) (xy 102.710996 -68.406264)
			(xy 102.761796 -68.43014) (xy 105.461816 -68.43014) (xy 106.13136 -69.099684) (xy 106.19613 -69.117464)
			(xy 106.228896 -69.109082) (xy 106.256394 -69.102564) (xy 106.312605 -69.096765) (xy 106.369057 -69.099321)
			(xy 106.424515 -69.110174) (xy 106.477765 -69.129089) (xy 106.527643 -69.15565) (xy 106.573059 -69.189278)
			(xy 106.613018 -69.229236) (xy 106.646646 -69.27465) (xy 106.673208 -69.324528) (xy 106.692124 -69.377778)
			(xy 106.702978 -69.433236) (xy 106.705535 -69.489688) (xy 106.699737 -69.545899) (xy 106.693208 -69.573394)
			(xy 106.684826 -69.60616) (xy 106.702606 -69.67093) (xy 122.52452 -85.492844) (xy 122.52452 -106.957368)
			(xy 122.55119 -106.991912) (xy 122.568013 -107.014341) (xy 122.595592 -107.063153) (xy 122.615727 -107.115478)
			(xy 122.627984 -107.170186) (xy 122.632099 -107.2261) (xy 122.627984 -107.282014) (xy 122.615727 -107.336722)
			(xy 122.595592 -107.389047) (xy 122.568013 -107.437859) (xy 122.55119 -107.460288) (xy 122.52452 -107.494832)
			(xy 122.52452 -115.532916) (xy 120.648476 -117.40896) (xy 99.084384 -117.40896) (xy 91.25966 -109.584236)
			(xy 91.25966 -100.825808) (xy 91.23172 -100.790756) (xy 91.214124 -100.768052) (xy 91.185241 -100.718405)
			(xy 91.164129 -100.664987) (xy 91.151266 -100.609008) (xy 91.146942 -100.551733) (xy 91.151256 -100.494457)
			(xy 91.164109 -100.438475) (xy 91.185212 -100.385054) (xy 91.214087 -100.335402) (xy 91.23172 -100.312728)
			(xy 91.25966 -100.277676) (xy 91.25966 -95.581216) (xy 85.975444 -90.297) (xy 82.337402 -90.297)
			(xy 82.301588 -90.327988) (xy 82.280691 -90.3454) (xy 82.234895 -90.374747) (xy 82.185396 -90.397295)
			(xy 82.133197 -90.412585) (xy 82.079356 -90.420308) (xy 82.024964 -90.420308) (xy 81.971123 -90.412585)
			(xy 81.918924 -90.397295) (xy 81.869425 -90.374747) (xy 81.823629 -90.3454) (xy 81.802732 -90.327988)
			(xy 81.766918 -90.297) (xy 81.45145 -90.297) (xy 81.418176 -90.320876) (xy 81.396432 -90.335991)
			(xy 81.349603 -90.360716) (xy 81.299804 -90.378725) (xy 81.247992 -90.38967) (xy 81.195164 -90.393343)
			(xy 81.142336 -90.38967) (xy 81.090524 -90.378725) (xy 81.040725 -90.360716) (xy 80.993896 -90.335991)
			(xy 80.972152 -90.320876) (xy 80.938878 -90.297) (xy 68.88226 -90.297) (xy 68.815966 -90.344244)
			(xy 68.802758 -90.382852) (xy 68.793273 -90.409066) (xy 68.767778 -90.45864) (xy 68.735337 -90.503974)
			(xy 68.696642 -90.544102) (xy 68.652516 -90.57817) (xy 68.603902 -90.60545) (xy 68.551834 -90.625362)
			(xy 68.497421 -90.637481) (xy 68.441824 -90.64155) (xy 68.386227 -90.637481) (xy 68.331814 -90.625362)
			(xy 68.279746 -90.60545) (xy 68.231132 -90.57817) (xy 68.187006 -90.544102) (xy 68.148311 -90.503974)
			(xy 68.11587 -90.45864) (xy 68.090375 -90.409066) (xy 68.08089 -90.382852) (xy 68.067682 -90.344244)
			(xy 68.001388 -90.297) (xy 66.127884 -90.297) (xy 66.097404 -90.315542) (xy 66.072988 -90.329839)
			(xy 66.020868 -90.351849) (xy 65.966065 -90.365909) (xy 65.909786 -90.371712) (xy 65.881504 -90.370914)
			(xy 65.858672 -90.370344) (xy 65.813412 -90.376426) (xy 65.769967 -90.390499) (xy 65.729736 -90.412109)
			(xy 65.694015 -90.440562) (xy 65.663955 -90.474941) (xy 65.640522 -90.514138) (xy 65.624472 -90.556892)
			(xy 65.616321 -90.601826) (xy 65.61582 -90.62466) (xy 65.61582 -97.021396) (xy 64.85636 -97.780856)
			(xy 64.837056 -97.827846) (xy 64.837056 -97.853246) (xy 64.836695 -97.880642) (xy 64.829079 -97.934898)
			(xy 64.813782 -97.987507) (xy 64.791117 -98.037388) (xy 64.761551 -98.083514) (xy 64.725692 -98.124937)
			(xy 64.684276 -98.160804) (xy 64.638156 -98.19038) (xy 64.58828 -98.213055) (xy 64.535674 -98.228363)
			(xy 64.481419 -98.235989) (xy 64.454024 -98.236278) (xy 64.437314 -98.236713) (xy 64.405012 -98.245267)
			(xy 64.376045 -98.261925) (xy 64.363854 -98.273362) (xy 44.000166 -118.63705) (xy 43.989502 -118.648287)
			(xy 43.973479 -118.674791) (xy 43.964331 -118.70438) (xy 43.9626 -118.735303) (xy 43.965114 -118.750588)
			(xy 43.969923 -118.778494) (xy 43.972215 -118.835073) (xy 43.966116 -118.89137) (xy 43.951761 -118.946146)
			(xy 43.929465 -118.998197) (xy 43.899717 -119.04638) (xy 43.863173 -119.089635) (xy 43.820635 -119.127011)
			(xy 43.773039 -119.157687) (xy 43.72143 -119.180989) (xy 43.666943 -119.196404) (xy 43.610775 -119.203593)
			(xy 43.554162 -119.202399) (xy 43.498348 -119.192848) (xy 43.444559 -119.175149) (xy 43.393978 -119.149692)
			(xy 43.347718 -119.117037) (xy 43.306793 -119.0779) (xy 43.288966 -119.055896) (xy 43.279754 -119.044676)
			(xy 43.257238 -119.026363) (xy 43.231169 -119.013604) (xy 43.202894 -119.007058) (xy 43.188382 -119.00662)
			(xy 34.852356 -119.00662) (xy 34.836146 -119.007101) (xy 34.804771 -119.015268) (xy 34.776472 -119.031089)
			(xy 34.753083 -119.053539) (xy 34.736115 -119.081166) (xy 34.730944 -119.096536) (xy 34.722586 -119.122215)
			(xy 34.699642 -119.171101) (xy 34.670033 -119.216263) (xy 34.634351 -119.256797) (xy 34.593309 -119.291895)
			(xy 34.547728 -119.320853) (xy 34.498518 -119.343095) (xy 34.446664 -119.358174) (xy 34.393201 -119.365789)
			(xy 34.339199 -119.365789) (xy 34.285736 -119.358174) (xy 34.233882 -119.343095) (xy 34.184672 -119.320853)
			(xy 34.139091 -119.291895) (xy 34.098049 -119.256797) (xy 34.062367 -119.216263) (xy 34.032758 -119.171101)
			(xy 34.009814 -119.122215) (xy 34.001456 -119.096536) (xy 33.996254 -119.081179) (xy 33.979277 -119.053568)
			(xy 33.955892 -119.031123) (xy 33.927609 -119.015291) (xy 33.89625 -119.007093) (xy 33.880044 -119.00662)
			(xy 26.749756 -119.00662) (xy 26.57856 -119.177816) (xy 26.57856 -132.650484) (xy 27.389836 -133.46176)
			(xy 42.402252 -133.46176) (xy 42.420019 -133.461186) (xy 42.454179 -133.451406) (xy 42.484306 -133.432565)
			(xy 42.508053 -133.406133) (xy 42.516298 -133.390386) (xy 42.528047 -133.36728) (xy 42.55736 -133.32453)
			(xy 42.592702 -133.286612) (xy 42.633287 -133.254368) (xy 42.678215 -133.228515) (xy 42.726485 -133.209627)
			(xy 42.777028 -133.198124) (xy 42.828718 -133.194261) (xy 42.880408 -133.198124) (xy 42.930951 -133.209627)
			(xy 42.979221 -133.228515) (xy 43.024149 -133.254368) (xy 43.064734 -133.286612) (xy 43.100076 -133.32453)
			(xy 43.129389 -133.36728) (xy 43.141138 -133.390386) (xy 43.149457 -133.406082) (xy 43.173216 -133.432471)
			(xy 43.203314 -133.451314) (xy 43.237431 -133.461159) (xy 43.255184 -133.46176) (xy 55.19674 -133.46176)
			(xy 55.213383 -133.461212) (xy 55.245532 -133.452587) (xy 55.274354 -133.435934) (xy 55.297883 -133.41239)
			(xy 55.314517 -133.383558) (xy 55.323122 -133.351403) (xy 55.32374 -133.33476) (xy 55.32374 -126.320804)
			(xy 56.303164 -125.34138) (xy 56.856376 -125.34138) (xy 56.869584 -125.338586) (xy 56.8958 -125.333458)
			(xy 56.949086 -125.329723) (xy 57.002372 -125.333458) (xy 57.028588 -125.338586) (xy 57.041796 -125.34138)
			(xy 81.933796 -125.34138) (xy 82.6262 -126.033784) (xy 82.6262 -135.817864) (xy 82.827876 -136.01954)
			(xy 84.235036 -136.01954) (xy 84.875116 -136.65962) (xy 90.481404 -136.65962) (xy 96.557084 -130.58394)
			(xy 97.137728 -130.58394) (xy 97.191322 -130.556762) (xy 97.209356 -130.532124) (xy 97.226046 -130.510268)
			(xy 97.264671 -130.471124) (xy 97.308514 -130.437929) (xy 97.356667 -130.41137) (xy 97.408133 -130.391996)
			(xy 97.461847 -130.380209) (xy 97.516696 -130.376252) (xy 97.571545 -130.380209) (xy 97.625259 -130.391996)
			(xy 97.676725 -130.41137) (xy 97.724878 -130.437929) (xy 97.768721 -130.471124) (xy 97.807346 -130.510268)
			(xy 97.824036 -130.532124) (xy 97.861882 -130.58394) (xy 97.887536 -130.58394) (xy 98.941636 -131.63804)
			(xy 111.473996 -131.63804) (xy 113.35004 -133.514084) (xy 113.35004 -136.258046) (xy 113.38687 -136.318498)
			(xy 113.41862 -136.335008) (xy 113.443051 -136.348253) (xy 113.48814 -136.380737) (xy 113.528038 -136.419419)
			(xy 113.561901 -136.463481) (xy 113.589012 -136.51199) (xy 113.608799 -136.56392) (xy 113.620841 -136.618171)
			(xy 113.624884 -136.673595) (xy 113.620842 -136.72902) (xy 113.608801 -136.783271) (xy 113.589016 -136.835201)
			(xy 113.561906 -136.883711) (xy 113.528044 -136.927774) (xy 113.488147 -136.966457) (xy 113.443059 -136.998943)
			(xy 113.41862 -137.012172) (xy 113.40343 -137.020644) (xy 113.378018 -137.044373) (xy 113.359955 -137.074082)
			(xy 113.350583 -137.107563) (xy 113.35004 -137.124948) (xy 113.35004 -152.268936) (xy 112.274096 -153.34488)
			(xy 109.79912 -153.34488) (xy 109.782469 -153.345421) (xy 109.7503 -153.354035) (xy 109.721457 -153.370681)
			(xy 109.697906 -153.394226) (xy 109.68125 -153.423063) (xy 109.672626 -153.455229) (xy 109.67212 -153.47188)
			(xy 109.67212 -153.717498) (xy 109.672532 -153.73251) (xy 109.679549 -153.761703) (xy 109.693215 -153.788436)
			(xy 109.71277 -153.81122) (xy 109.737121 -153.828782) (xy 109.75086 -153.834846) (xy 109.776756 -153.846011)
			(xy 109.825214 -153.87485) (xy 109.868901 -153.910507) (xy 109.906864 -153.952206) (xy 109.938277 -153.999037)
			(xy 109.962456 -154.049981) (xy 109.978874 -154.10393) (xy 109.987173 -154.159707) (xy 109.987172 -154.216098)
			(xy 109.978873 -154.271875) (xy 109.962454 -154.325823) (xy 109.938275 -154.376767) (xy 109.906862 -154.423598)
			(xy 109.868898 -154.465296) (xy 109.825211 -154.500952) (xy 109.776751 -154.529791) (xy 109.75086 -154.540966)
			(xy 109.737144 -154.547066) (xy 109.712828 -154.564655) (xy 109.693288 -154.587433) (xy 109.679605 -154.614143)
			(xy 109.672535 -154.643309) (xy 109.67212 -154.658314) (xy 109.67212 -163.0553) (xy 110.060994 -163.444174)
			(xy 110.071263 -163.453929) (xy 110.095192 -163.469069) (xy 110.121879 -163.478539) (xy 110.149999 -163.481869)
			(xy 110.164118 -163.48075) (xy 110.191029 -163.478436) (xy 110.245001 -163.480507) (xy 110.298143 -163.490166)
			(xy 110.349392 -163.50722) (xy 110.397724 -163.531329) (xy 110.442176 -163.562011) (xy 110.481857 -163.598654)
			(xy 110.515977 -163.640525) (xy 110.543853 -163.686787) (xy 110.564928 -163.736518) (xy 110.578782 -163.788723)
			(xy 110.585138 -163.84236) (xy 110.584996 -163.86937) (xy 110.585171 -163.886744) (xy 110.593733 -163.920401)
			(xy 110.61105 -163.950505) (xy 110.635842 -163.974826) (xy 110.666271 -163.991564) (xy 110.68304 -163.996116)
			(xy 110.711222 -164.003223) (xy 110.76518 -164.024814) (xy 110.815235 -164.054346) (xy 110.860228 -164.091134)
			(xy 110.899114 -164.134326) (xy 110.930992 -164.18292) (xy 110.955124 -164.235791) (xy 110.97095 -164.291712)
			(xy 110.97514 -164.320474) (xy 110.980728 -164.363908) (xy 111.079788 -164.462968) (xy 111.131604 -164.463476)
			(xy 111.158459 -164.464237) (xy 111.211563 -164.472373) (xy 111.263001 -164.487877) (xy 111.311756 -164.510444)
			(xy 111.356862 -164.539627) (xy 111.397429 -164.574849) (xy 111.432654 -164.615413) (xy 111.461841 -164.660518)
			(xy 111.484412 -164.70927) (xy 111.49992 -164.760707) (xy 111.508061 -164.813811) (xy 111.508794 -164.840666)
			(xy 111.509302 -164.892482) (xy 113.235994 -166.619174) (xy 113.24887 -166.63121) (xy 113.279668 -166.648322)
			(xy 113.31397 -166.656367) (xy 113.349165 -166.654732) (xy 113.366042 -166.649654) (xy 113.392944 -166.641205)
			(xy 113.448474 -166.631411) (xy 113.50484 -166.629896) (xy 113.560816 -166.636691) (xy 113.615182 -166.65165)
			(xy 113.666755 -166.674447) (xy 113.714412 -166.704585) (xy 113.757115 -166.741407) (xy 113.793934 -166.784113)
			(xy 113.824068 -166.831773) (xy 113.84686 -166.883348) (xy 113.861815 -166.937715) (xy 113.868606 -166.993691)
			(xy 113.867086 -167.050058) (xy 113.857287 -167.105586) (xy 113.848896 -167.132508) (xy 113.843832 -167.149391)
			(xy 113.842184 -167.184585) (xy 113.850221 -167.21889) (xy 113.867329 -167.249691) (xy 113.879376 -167.262556)
			(xy 118.97106 -172.35424) (xy 119.049038 -172.368464) (xy 119.085614 -172.3517) (xy 119.110607 -172.340751)
			(xy 119.162938 -172.325307) (xy 119.216937 -172.317478) (xy 119.2715 -172.317423) (xy 119.325514 -172.325144)
			(xy 119.377876 -172.340484) (xy 119.427519 -172.363128) (xy 119.473428 -172.392615) (xy 119.514667 -172.428343)
			(xy 119.550393 -172.469583) (xy 119.579879 -172.515493) (xy 119.602521 -172.565136) (xy 119.617858 -172.6175)
			(xy 119.625578 -172.671514) (xy 119.625521 -172.726077) (xy 119.61769 -172.780075) (xy 119.602244 -172.832406)
			(xy 119.591328 -172.857414) (xy 119.585299 -172.871652) (xy 119.579582 -172.90203) (xy 119.581328 -172.932893)
			(xy 119.590433 -172.962433) (xy 119.606364 -172.988923) (xy 119.616982 -173.000162) (xy 124.64542 -178.0286)
			(xy 144.219676 -178.0286)
		)
		(stroke
			(width 0)
			(type solid)
		)
		(fill yes)
		(layer "In3.Cu")
		(net "P3V3_STB_NODE1")
	)
	(gr_poly
		(pts
			(xy 82.416904 -207.683608) (xy 82.433552 -207.683064) (xy 82.465714 -207.674446) (xy 82.49455 -207.657798)
			(xy 82.518095 -207.634254) (xy 82.534744 -207.605418) (xy 82.543364 -207.573256) (xy 82.543904 -207.556608)
			(xy 82.543904 -201.250042) (xy 82.544394 -201.187007) (xy 82.552464 -201.061195) (xy 82.568578 -200.936158)
			(xy 82.592671 -200.812411) (xy 82.624642 -200.690462) (xy 82.664362 -200.570812) (xy 82.711667 -200.453952)
			(xy 82.766361 -200.340364) (xy 82.828222 -200.230514) (xy 82.896993 -200.124852) (xy 82.972394 -200.023815)
			(xy 83.054113 -199.927816) (xy 83.141815 -199.83725) (xy 83.23514 -199.75249) (xy 83.333703 -199.673884)
			(xy 83.437101 -199.601754) (xy 83.544908 -199.536397) (xy 83.656681 -199.478083) (xy 83.771961 -199.427049)
			(xy 83.890274 -199.383507) (xy 84.011133 -199.347635) (xy 84.134043 -199.319581) (xy 84.258497 -199.299459)
			(xy 84.383985 -199.287353) (xy 84.509991 -199.283312) (xy 84.635997 -199.287353) (xy 84.761485 -199.299459)
			(xy 84.885939 -199.319581) (xy 85.008849 -199.347635) (xy 85.129708 -199.383507) (xy 85.248021 -199.427049)
			(xy 85.363301 -199.478083) (xy 85.475074 -199.536397) (xy 85.582881 -199.601754) (xy 85.686279 -199.673884)
			(xy 85.784842 -199.75249) (xy 85.878167 -199.83725) (xy 85.965869 -199.927816) (xy 86.047588 -200.023815)
			(xy 86.122989 -200.124852) (xy 86.19176 -200.230514) (xy 86.253621 -200.340364) (xy 86.308315 -200.453952)
			(xy 86.35562 -200.570812) (xy 86.39534 -200.690462) (xy 86.427311 -200.812411) (xy 86.451404 -200.936158)
			(xy 86.467518 -201.061195) (xy 86.475588 -201.187007) (xy 86.476078 -201.250042) (xy 86.476078 -207.556608)
			(xy 86.476622 -207.573257) (xy 86.485241 -207.605419) (xy 86.501889 -207.634256) (xy 86.525433 -207.657802)
			(xy 86.554268 -207.674454) (xy 86.586429 -207.683076) (xy 86.603078 -207.683608) (xy 95.516954 -207.683608)
			(xy 95.533613 -207.683119) (xy 95.565798 -207.674506) (xy 95.594657 -207.657854) (xy 95.618221 -207.6343)
			(xy 95.634885 -207.605449) (xy 95.643512 -207.573267) (xy 95.643954 -207.556608) (xy 95.643954 -201.478388)
			(xy 95.606616 -201.417428) (xy 95.574612 -201.401172) (xy 95.550159 -201.388151) (xy 95.504963 -201.356118)
			(xy 95.464877 -201.317882) (xy 95.430745 -201.274248) (xy 95.403285 -201.226135) (xy 95.383075 -201.174556)
			(xy 95.370541 -201.120595) (xy 95.365946 -201.065388) (xy 95.369387 -201.010098) (xy 95.380791 -200.955887)
			(xy 95.399919 -200.903896) (xy 95.426368 -200.85522) (xy 95.442532 -200.83272) (xy 95.456128 -200.813707)
			(xy 95.476861 -200.771823) (xy 95.489589 -200.726854) (xy 95.493882 -200.680316) (xy 95.489595 -200.633778)
			(xy 95.476873 -200.588807) (xy 95.456145 -200.54692) (xy 95.442532 -200.52792) (xy 95.426328 -200.50545)
			(xy 95.399891 -200.456767) (xy 95.380774 -200.404772) (xy 95.369378 -200.350558) (xy 95.365945 -200.295266)
			(xy 95.370545 -200.24006) (xy 95.383083 -200.186099) (xy 95.403294 -200.134519) (xy 95.430753 -200.086405)
			(xy 95.464884 -200.04277) (xy 95.504967 -200.00453) (xy 95.55016 -199.97249) (xy 95.574612 -199.959468)
			(xy 95.606616 -199.943212) (xy 95.643954 -199.882252) (xy 95.643954 -188.250068) (xy 95.644459 -188.156118)
			(xy 95.652543 -187.968391) (xy 95.668696 -187.781186) (xy 95.692888 -187.594849) (xy 95.725074 -187.409726)
			(xy 95.765195 -187.226159) (xy 95.813176 -187.044487) (xy 95.868928 -186.865049) (xy 95.932349 -186.688175)
			(xy 96.003321 -186.514193) (xy 96.081711 -186.343425) (xy 96.167377 -186.176189) (xy 96.260157 -186.012792)
			(xy 96.359882 -185.853539) (xy 96.466365 -185.698723) (xy 96.579411 -185.548632) (xy 96.698809 -185.403544)
			(xy 96.824339 -185.263726) (xy 96.955767 -185.129438) (xy 97.092851 -185.00093) (xy 97.235338 -184.878437)
			(xy 97.382962 -184.762189) (xy 97.53545 -184.652399) (xy 97.692521 -184.549271) (xy 97.853883 -184.452996)
			(xy 98.019238 -184.363752) (xy 98.188279 -184.281705) (xy 98.360694 -184.207007) (xy 98.536162 -184.139795)
			(xy 98.71436 -184.080195) (xy 98.894957 -184.028316) (xy 99.077618 -183.984255) (xy 99.262007 -183.948093)
			(xy 99.44778 -183.919898) (xy 99.634594 -183.899721) (xy 99.822103 -183.887599) (xy 100.00996 -183.883557)
			(xy 100.197817 -183.887599) (xy 100.385326 -183.899721) (xy 100.57214 -183.919898) (xy 100.757913 -183.948093)
			(xy 100.942302 -183.984255) (xy 101.124963 -184.028316) (xy 101.30556 -184.080195) (xy 101.483758 -184.139795)
			(xy 101.659226 -184.207007) (xy 101.831641 -184.281705) (xy 102.000682 -184.363752) (xy 102.166037 -184.452996)
			(xy 102.327399 -184.549271) (xy 102.48447 -184.652399) (xy 102.636958 -184.762189) (xy 102.784582 -184.878437)
			(xy 102.927069 -185.00093) (xy 103.064153 -185.129438) (xy 103.195581 -185.263726) (xy 103.321111 -185.403544)
			(xy 103.440509 -185.548632) (xy 103.553555 -185.698723) (xy 103.660038 -185.853539) (xy 103.759763 -186.012792)
			(xy 103.852543 -186.176189) (xy 103.938209 -186.343425) (xy 104.016599 -186.514193) (xy 104.087571 -186.688175)
			(xy 104.150992 -186.865049) (xy 104.206744 -187.044487) (xy 104.254725 -187.226159) (xy 104.294846 -187.409726)
			(xy 104.327032 -187.594849) (xy 104.351224 -187.781186) (xy 104.367377 -187.968391) (xy 104.375461 -188.156118)
			(xy 104.375966 -188.250068) (xy 104.375966 -207.556608) (xy 104.37651 -207.573257) (xy 104.385129 -207.605421)
			(xy 104.401777 -207.634259) (xy 104.42532 -207.657808) (xy 104.454155 -207.674461) (xy 104.486317 -207.683087)
			(xy 104.502966 -207.683608) (xy 173.416976 -207.683608) (xy 173.433633 -207.683116) (xy 173.465814 -207.674499)
			(xy 173.494667 -207.657846) (xy 173.518227 -207.634293) (xy 173.534887 -207.605443) (xy 173.543512 -207.573265)
			(xy 173.543976 -207.556608) (xy 173.543976 -201.65695) (xy 173.543541 -201.642063) (xy 173.536581 -201.613113)
			(xy 173.523097 -201.586565) (xy 173.503826 -201.563867) (xy 173.479818 -201.546256) (xy 173.466252 -201.54011)
			(xy 173.440556 -201.528775) (xy 173.392527 -201.499668) (xy 173.349285 -201.463834) (xy 173.311763 -201.422047)
			(xy 173.280774 -201.37521) (xy 173.256986 -201.324337) (xy 173.240914 -201.270525) (xy 173.232905 -201.214938)
			(xy 173.233132 -201.158778) (xy 173.241591 -201.103258) (xy 173.258098 -201.049579) (xy 173.282296 -200.998899)
			(xy 173.313664 -200.952315) (xy 173.351523 -200.910833) (xy 173.395054 -200.87535) (xy 173.443317 -200.846632)
			(xy 173.495268 -200.825301) (xy 173.522386 -200.817988) (xy 173.538622 -200.813423) (xy 173.568077 -200.79702)
			(xy 173.592208 -200.773476) (xy 173.609333 -200.744434) (xy 173.614334 -200.728326) (xy 173.631462 -200.667936)
			(xy 173.672417 -200.549265) (xy 173.72086 -200.433449) (xy 173.776594 -200.32096) (xy 173.839393 -200.212256)
			(xy 173.908999 -200.10778) (xy 173.98513 -200.007959) (xy 174.067474 -199.913199) (xy 174.155698 -199.823886)
			(xy 174.24944 -199.740385) (xy 174.34832 -199.663035) (xy 174.451933 -199.592151) (xy 174.559858 -199.528024)
			(xy 174.671655 -199.470913) (xy 174.786868 -199.421052) (xy 174.905028 -199.378645) (xy 175.025652 -199.343863)
			(xy 175.148251 -199.316848) (xy 175.272323 -199.297711) (xy 175.397364 -199.28653) (xy 175.522863 -199.28335)
			(xy 175.648309 -199.288184) (xy 175.773191 -199.301013) (xy 175.897001 -199.321784) (xy 176.019232 -199.350412)
			(xy 176.139388 -199.386781) (xy 176.256978 -199.430743) (xy 176.371524 -199.482119) (xy 176.482558 -199.540698)
			(xy 176.589629 -199.606243) (xy 176.692298 -199.678486) (xy 176.790149 -199.757133) (xy 176.882783 -199.841863)
			(xy 176.969821 -199.932331) (xy 177.050909 -200.028169) (xy 177.125718 -200.128985) (xy 177.193941 -200.234369)
			(xy 177.2553 -200.343891) (xy 177.309547 -200.457105) (xy 177.356459 -200.57355) (xy 177.395845 -200.692751)
			(xy 177.427546 -200.814222) (xy 177.451431 -200.937468) (xy 177.467404 -201.061988) (xy 177.475398 -201.187272)
			(xy 177.475896 -201.250042) (xy 177.475896 -207.556608) (xy 177.47644 -207.573256) (xy 177.485059 -207.605417)
			(xy 177.501708 -207.634251) (xy 177.525252 -207.657794) (xy 177.554087 -207.674442) (xy 177.586248 -207.68306)
			(xy 177.602896 -207.683608) (xy 186.517026 -207.683608) (xy 186.533672 -207.683062) (xy 186.56583 -207.67444)
			(xy 186.594661 -207.65779) (xy 186.618201 -207.634246) (xy 186.634847 -207.605413) (xy 186.643464 -207.573255)
			(xy 186.644026 -207.556608) (xy 186.644026 -172.699934) (xy 186.644533 -172.62097) (xy 186.652797 -172.463259)
			(xy 186.669303 -172.306197) (xy 186.694007 -172.150214) (xy 186.726841 -171.995737) (xy 186.767714 -171.843191)
			(xy 186.816515 -171.692992) (xy 186.87311 -171.545554) (xy 186.937344 -171.40128) (xy 187.009041 -171.260565)
			(xy 187.088004 -171.123796) (xy 187.174017 -170.991346) (xy 187.266844 -170.86358) (xy 187.36623 -170.740847)
			(xy 187.471904 -170.623484) (xy 187.583575 -170.511812) (xy 187.700938 -170.406138) (xy 187.82367 -170.306751)
			(xy 187.951436 -170.213923) (xy 188.083885 -170.12791) (xy 188.220655 -170.048947) (xy 188.361369 -169.977249)
			(xy 188.505643 -169.913015) (xy 188.653081 -169.856419) (xy 188.803279 -169.807617) (xy 188.955825 -169.766743)
			(xy 189.110302 -169.733909) (xy 189.266285 -169.709205) (xy 189.423347 -169.692698) (xy 189.581058 -169.684434)
			(xy 189.660022 -169.683938) (xy 198.000112 -169.683938) (xy 198.045581 -169.683412) (xy 198.136131 -169.675021)
			(xy 198.22552 -169.658311) (xy 198.312987 -169.633424) (xy 198.397784 -169.600574) (xy 198.479188 -169.560039)
			(xy 198.556506 -169.512167) (xy 198.629076 -169.457366) (xy 198.696281 -169.396102) (xy 198.757547 -169.328899)
			(xy 198.81235 -169.25633) (xy 198.860225 -169.179014) (xy 198.900761 -169.097611) (xy 198.933615 -169.012815)
			(xy 198.958504 -168.92535) (xy 198.975217 -168.835961) (xy 198.983611 -168.745411) (xy 198.984108 -168.699942)
			(xy 198.984108 -75.65009) (xy 198.983611 -75.618392) (xy 198.975335 -75.555539) (xy 198.958926 -75.494304)
			(xy 198.934664 -75.435734) (xy 198.902965 -75.380833) (xy 198.86437 -75.330539) (xy 198.819542 -75.285712)
			(xy 198.769245 -75.247121) (xy 198.714342 -75.215425) (xy 198.655771 -75.191166) (xy 198.594535 -75.17476)
			(xy 198.531682 -75.166487) (xy 198.499984 -75.165966) (xy 198.20001 -75.165966) (xy 198.129432 -75.165471)
			(xy 197.988499 -75.157558) (xy 197.84823 -75.141755) (xy 197.709069 -75.118113) (xy 197.571451 -75.086706)
			(xy 197.435812 -75.047632) (xy 197.302576 -75.001015) (xy 197.172163 -74.947001) (xy 197.044984 -74.885761)
			(xy 196.921439 -74.817486) (xy 196.801916 -74.742392) (xy 196.686791 -74.660715) (xy 196.576426 -74.572712)
			(xy 196.471169 -74.478659) (xy 196.371351 -74.378853) (xy 196.277286 -74.273608) (xy 196.189269 -74.163254)
			(xy 196.107578 -74.048139) (xy 196.032469 -73.928625) (xy 195.96418 -73.805088) (xy 195.902924 -73.677916)
			(xy 195.848894 -73.54751) (xy 195.802261 -73.41428) (xy 195.763171 -73.278645) (xy 195.731747 -73.141032)
			(xy 195.708088 -73.001873) (xy 195.692268 -72.861606) (xy 195.684337 -72.720674) (xy 195.683886 -72.650096)
			(xy 195.683886 -33.64992) (xy 195.684389 -33.579343) (xy 195.692318 -33.438413) (xy 195.708137 -33.298149)
			(xy 195.731795 -33.158992) (xy 195.763218 -33.021381) (xy 195.802306 -32.885748) (xy 195.848938 -32.75252)
			(xy 195.902966 -32.622116) (xy 195.964221 -32.494946) (xy 196.032509 -32.371411) (xy 196.107615 -32.251898)
			(xy 196.189305 -32.136785) (xy 196.27732 -32.026433) (xy 196.371383 -31.921188) (xy 196.471199 -31.821384)
			(xy 196.576454 -31.727332) (xy 196.686817 -31.63933) (xy 196.801939 -31.557654) (xy 196.921461 -31.482561)
			(xy 197.045004 -31.414287) (xy 197.172181 -31.353048) (xy 197.302591 -31.299035) (xy 197.435824 -31.252418)
			(xy 197.571462 -31.213345) (xy 197.709077 -31.181938) (xy 197.848236 -31.158296) (xy 197.988502 -31.142494)
			(xy 198.129433 -31.134581) (xy 198.20001 -31.13405) (xy 198.499984 -31.13405) (xy 198.531683 -31.133533)
			(xy 198.594537 -31.12526) (xy 198.655775 -31.108854) (xy 198.714347 -31.084595) (xy 198.769252 -31.052899)
			(xy 198.819549 -31.014307) (xy 198.86438 -30.969481) (xy 198.902976 -30.919186) (xy 198.934677 -30.864285)
			(xy 198.95894 -30.805715) (xy 198.975352 -30.744479) (xy 198.98363 -30.681624) (xy 198.984108 -30.649926)
			(xy 198.984108 -1.999996) (xy 198.983583 -1.954527) (xy 198.975192 -1.863978) (xy 198.958482 -1.774589)
			(xy 198.933596 -1.687123) (xy 198.900745 -1.602326) (xy 198.860211 -1.520923) (xy 198.812339 -1.443606)
			(xy 198.757537 -1.371036) (xy 198.696273 -1.303833) (xy 198.62907 -1.242568) (xy 198.556501 -1.187766)
			(xy 198.479184 -1.139893) (xy 198.397781 -1.099358) (xy 198.312985 -1.066507) (xy 198.225519 -1.04162)
			(xy 198.13613 -1.024909) (xy 198.045581 -1.016518) (xy 198.000112 -1.016) (xy 74.083926 -1.016) (xy 74.067269 -1.016491)
			(xy 74.035089 -1.025108) (xy 74.006236 -1.041761) (xy 73.982677 -1.065315) (xy 73.966018 -1.094165)
			(xy 73.957395 -1.126343) (xy 73.956926 -1.143) (xy 73.956926 -7.959344) (xy 73.360534 -8.555736)
			(xy 70.173596 -8.555736) (xy 70.115938 -8.613394) (xy 70.115938 -9.750405) (xy 89.064349 -9.750405)
			(xy 89.072055 -9.665303) (xy 89.08745 -9.58125) (xy 89.110408 -9.498942) (xy 89.140739 -9.419055)
			(xy 89.178194 -9.342251) (xy 89.222464 -9.269162) (xy 89.273182 -9.20039) (xy 89.329931 -9.136505)
			(xy 89.360756 -9.106916) (xy 89.44864 -9.106916) (xy 89.465307 -9.106475) (xy 89.497514 -9.097891)
			(xy 89.526391 -9.081243) (xy 89.549958 -9.057672) (xy 89.5666 -9.028792) (xy 89.575178 -8.996583)
			(xy 89.57564 -8.979916) (xy 89.57564 -8.955532) (xy 89.615755 -8.935545) (xy 89.69906 -8.902468)
			(xy 89.785135 -8.877468) (xy 89.873199 -8.860773) (xy 89.962451 -8.852535) (xy 90.052082 -8.852827)
			(xy 90.141279 -8.861648) (xy 90.229232 -8.878917) (xy 90.315142 -8.904478) (xy 90.398229 -8.938099)
			(xy 90.438224 -8.958326) (xy 90.438224 -8.979408) (xy 90.438881 -8.996035) (xy 90.447554 -9.028141)
			(xy 90.464208 -9.056928) (xy 90.487718 -9.08045) (xy 90.516496 -9.09712) (xy 90.548598 -9.10581)
			(xy 90.565224 -9.106408) (xy 90.647266 -9.106408) (xy 90.678125 -9.135996) (xy 90.734975 -9.199856)
			(xy 90.785794 -9.268611) (xy 90.830163 -9.341696) (xy 90.867716 -9.418505) (xy 90.898142 -9.498406)
			(xy 90.921191 -9.580739) (xy 90.936672 -9.664824) (xy 90.944458 -9.749967) (xy 90.944463 -9.750405)
			(xy 99.064304 -9.750405) (xy 99.07201 -9.665301) (xy 99.087407 -9.581247) (xy 99.110367 -9.498937)
			(xy 99.140701 -9.41905) (xy 99.178159 -9.342246) (xy 99.222432 -9.269157) (xy 99.273155 -9.200387)
			(xy 99.329909 -9.136503) (xy 99.360736 -9.106916) (xy 99.44862 -9.106916) (xy 99.465286 -9.106457)
			(xy 99.497493 -9.097878) (xy 99.526369 -9.081234) (xy 99.549936 -9.057666) (xy 99.566579 -9.028789)
			(xy 99.575157 -8.996582) (xy 99.57562 -8.979916) (xy 99.57562 -8.955532) (xy 99.615743 -8.935561)
			(xy 99.699047 -8.902482) (xy 99.78512 -8.877481) (xy 99.873182 -8.860785) (xy 99.962434 -8.852545)
			(xy 100.052064 -8.852835) (xy 100.14126 -8.861655) (xy 100.229212 -8.878922) (xy 100.315122 -8.904481)
			(xy 100.398209 -8.9381) (xy 100.438204 -8.958326) (xy 100.438204 -8.979408) (xy 100.438782 -8.996041)
			(xy 100.447462 -9.028159) (xy 100.464129 -9.056954) (xy 100.487655 -9.080479) (xy 100.516452 -9.097143)
			(xy 100.548571 -9.10582) (xy 100.565204 -9.106408) (xy 100.647246 -9.106408) (xy 100.678101 -9.136)
			(xy 100.734952 -9.199859) (xy 100.785772 -9.268614) (xy 100.830141 -9.341697) (xy 100.867694 -9.418507)
			(xy 100.898121 -9.498407) (xy 100.92117 -9.58074) (xy 100.936652 -9.664824) (xy 100.944438 -9.749967)
			(xy 100.944934 -9.792716) (xy 100.94442 -9.835465) (xy 100.936641 -9.920609) (xy 100.921165 -10.004695)
			(xy 100.898121 -10.08703) (xy 100.867699 -10.166933) (xy 100.83015 -10.243745) (xy 100.785784 -10.316831)
			(xy 100.734968 -10.38559) (xy 100.67812 -10.449452) (xy 100.647246 -10.479024) (xy 100.565204 -10.479024)
			(xy 100.548566 -10.479581) (xy 100.516434 -10.488245) (xy 100.487627 -10.504909) (xy 100.464097 -10.528443)
			(xy 100.447438 -10.557252) (xy 100.438779 -10.589386) (xy 100.438204 -10.606024) (xy 100.438204 -10.627106)
			(xy 100.39822 -10.647284) (xy 100.315185 -10.680859) (xy 100.229335 -10.706392) (xy 100.141446 -10.72365)
			(xy 100.052316 -10.732478) (xy 99.96275 -10.732795) (xy 99.873559 -10.724599) (xy 99.78555 -10.707965)
			(xy 99.699521 -10.683041) (xy 99.61625 -10.650055) (xy 99.576128 -10.630154) (xy 99.576128 -10.606024)
			(xy 99.575536 -10.589379) (xy 99.566926 -10.557222) (xy 99.550287 -10.528389) (xy 99.526753 -10.504845)
			(xy 99.497926 -10.488194) (xy 99.465773 -10.479571) (xy 99.449128 -10.479024) (xy 99.361498 -10.479024)
			(xy 99.33065 -10.449458) (xy 99.273824 -10.385638) (xy 99.223024 -10.316926) (xy 99.178669 -10.243887)
			(xy 99.141124 -10.167125) (xy 99.110699 -10.087272) (xy 99.087646 -10.004988) (xy 99.072154 -9.920952)
			(xy 99.064352 -9.835857) (xy 99.064304 -9.750405) (xy 90.944463 -9.750405) (xy 90.944954 -9.792716)
			(xy 90.944434 -9.835465) (xy 90.936654 -9.920608) (xy 90.921179 -10.004694) (xy 90.898135 -10.087029)
			(xy 90.867714 -10.166931) (xy 90.830166 -10.243743) (xy 90.785801 -10.31683) (xy 90.734986 -10.385589)
			(xy 90.67814 -10.449451) (xy 90.647266 -10.479024) (xy 90.565224 -10.479024) (xy 90.548586 -10.479599)
			(xy 90.516455 -10.488258) (xy 90.487648 -10.504918) (xy 90.464118 -10.528448) (xy 90.447458 -10.557255)
			(xy 90.438799 -10.589386) (xy 90.438224 -10.606024) (xy 90.438224 -10.627106) (xy 90.398233 -10.647268)
			(xy 90.315199 -10.680845) (xy 90.22935 -10.706379) (xy 90.141463 -10.723638) (xy 90.052333 -10.732468)
			(xy 89.962768 -10.732787) (xy 89.873578 -10.724593) (xy 89.78557 -10.70796) (xy 89.699541 -10.683038)
			(xy 89.61627 -10.650054) (xy 89.576148 -10.630154) (xy 89.576148 -10.606024) (xy 89.575536 -10.589381)
			(xy 89.566928 -10.557227) (xy 89.550292 -10.528395) (xy 89.526762 -10.504852) (xy 89.49794 -10.488199)
			(xy 89.465791 -10.479573) (xy 89.449148 -10.479024) (xy 89.361518 -10.479024) (xy 89.330672 -10.449456)
			(xy 89.273851 -10.385635) (xy 89.223055 -10.316921) (xy 89.178703 -10.243882) (xy 89.141162 -10.16712)
			(xy 89.11074 -10.087268) (xy 89.087689 -10.004985) (xy 89.072199 -9.92095) (xy 89.064398 -9.835856)
			(xy 89.064349 -9.750405) (xy 70.115938 -9.750405) (xy 70.115938 -10.046716) (xy 70.091046 -10.071608)
			(xy 70.074536 -10.14222) (xy 70.086474 -10.176764) (xy 70.09489 -10.202749) (xy 70.105055 -10.256414)
			(xy 70.107464 -10.31098) (xy 70.102066 -10.365332) (xy 70.088972 -10.418359) (xy 70.06845 -10.468976)
			(xy 70.040918 -10.516149) (xy 70.006941 -10.558913) (xy 69.967212 -10.596395) (xy 69.922543 -10.627828)
			(xy 69.873849 -10.652569) (xy 69.822124 -10.670112) (xy 69.768425 -10.6801) (xy 69.713851 -10.682327)
			(xy 69.659517 -10.676749) (xy 69.606535 -10.663479) (xy 69.555986 -10.642788) (xy 69.508905 -10.6151)
			(xy 69.487288 -10.598404) (xy 69.47354 -10.588148) (xy 69.442015 -10.574668) (xy 69.40804 -10.570064)
			(xy 69.374065 -10.574668) (xy 69.34254 -10.588148) (xy 69.328792 -10.598404) (xy 69.306047 -10.615928)
			(xy 69.256337 -10.644662) (xy 69.202883 -10.665624) (xy 69.146892 -10.678339) (xy 69.089628 -10.682522)
			(xy 69.032383 -10.678078) (xy 68.976451 -10.665107) (xy 68.923093 -10.643902) (xy 68.873516 -10.614941)
			(xy 68.828836 -10.578879) (xy 68.809108 -10.558018) (xy 68.796808 -10.545403) (xy 68.766857 -10.526872)
			(xy 68.732991 -10.517202) (xy 68.715382 -10.516616) (xy 68.58762 -10.516616) (xy 68.572104 -10.517059)
			(xy 68.541993 -10.524563) (xy 68.514592 -10.539131) (xy 68.491531 -10.559896) (xy 68.482464 -10.572496)
			(xy 68.46599 -10.595927) (xy 68.427161 -10.638032) (xy 68.382474 -10.67386) (xy 68.332934 -10.702605)
			(xy 68.279653 -10.723621) (xy 68.223829 -10.736436) (xy 68.166716 -10.740761) (xy 68.109599 -10.7365)
			(xy 68.053761 -10.723749) (xy 68.000456 -10.702793) (xy 67.950883 -10.674104) (xy 67.928236 -10.65657)
			(xy 67.914488 -10.646314) (xy 67.882963 -10.632834) (xy 67.848988 -10.62823) (xy 67.815013 -10.632834)
			(xy 67.783488 -10.646314) (xy 67.76974 -10.65657) (xy 67.747055 -10.674045) (xy 67.697486 -10.702711)
			(xy 67.64419 -10.723649) (xy 67.588364 -10.736388) (xy 67.531261 -10.740642) (xy 67.474163 -10.736317)
			(xy 67.418353 -10.723508) (xy 67.365083 -10.702503) (xy 67.31555 -10.673775) (xy 67.270865 -10.637968)
			(xy 67.232033 -10.595886) (xy 67.215512 -10.572496) (xy 67.20645 -10.559897) (xy 67.183371 -10.539159)
			(xy 67.155971 -10.5246) (xy 67.125869 -10.517079) (xy 67.110356 -10.516616) (xy 65.708276 -10.516616)
			(xy 65.691631 -10.517162) (xy 65.659475 -10.525784) (xy 65.630647 -10.542435) (xy 65.60711 -10.565979)
			(xy 65.590469 -10.594812) (xy 65.581857 -10.62697) (xy 65.581276 -10.643616) (xy 65.581276 -12.881102)
			(xy 66.459354 -13.75918) (xy 171.036996 -13.75918) (xy 175.018954 -17.741138) (xy 175.070262 -17.7419)
			(xy 175.160209 -17.743968) (xy 175.339797 -17.755178) (xy 175.518702 -17.774435) (xy 175.696562 -17.8017)
			(xy 175.87302 -17.836919) (xy 176.04772 -17.88002) (xy 176.22031 -17.930916) (xy 176.390442 -17.989505)
			(xy 176.557775 -18.05567) (xy 176.721969 -18.129276) (xy 176.882696 -18.210175) (xy 177.03963 -18.298205)
			(xy 177.192457 -18.393188) (xy 177.340867 -18.494933) (xy 177.484563 -18.603235) (xy 177.623255 -18.717875)
			(xy 177.756662 -18.838623) (xy 177.884518 -18.965236) (xy 178.006563 -19.097458) (xy 178.122552 -19.235023)
			(xy 178.232252 -19.377655) (xy 178.335442 -19.525064) (xy 178.431913 -19.676956) (xy 178.521471 -19.833023)
			(xy 178.603937 -19.992952) (xy 178.679143 -20.15642) (xy 178.746938 -20.323098) (xy 178.807187 -20.49265)
			(xy 178.859766 -20.664734) (xy 178.904571 -20.839005) (xy 178.941512 -21.015111) (xy 178.970513 -21.192696)
			(xy 178.991516 -21.371404) (xy 179.004479 -21.550875) (xy 179.009377 -21.730746) (xy 179.006198 -21.910656)
			(xy 178.99495 -22.090243) (xy 178.975655 -22.269143) (xy 178.948352 -22.446998) (xy 178.913097 -22.623448)
			(xy 178.869959 -22.798139) (xy 178.819026 -22.970718) (xy 178.7604 -23.140838) (xy 178.694201 -23.308156)
			(xy 178.62056 -23.472335) (xy 178.539626 -23.633045) (xy 178.451563 -23.789961) (xy 178.356548 -23.942767)
			(xy 178.254771 -24.091156) (xy 178.146439 -24.234829) (xy 178.031769 -24.373496) (xy 177.910993 -24.506878)
			(xy 177.784353 -24.634707) (xy 177.652106 -24.756724) (xy 177.583592 -24.815038) (xy 177.560507 -24.835097)
			(xy 177.51899 -24.880003) (xy 177.483367 -24.929714) (xy 177.454189 -24.983461) (xy 177.431906 -25.040414)
			(xy 177.416863 -25.099693) (xy 177.409293 -25.160379) (xy 177.40884 -25.190958) (xy 177.40884 -26.75001)
			(xy 177.408078 -26.803858) (xy 177.408078 -26.960322) (xy 177.399188 -26.969212) (xy 177.394362 -27.013662)
			(xy 177.385491 -27.088852) (xy 177.359483 -27.23802) (xy 177.324153 -27.385258) (xy 177.279639 -27.529985)
			(xy 177.226119 -27.671629) (xy 177.19548 -27.740864) (xy 177.19548 -114.053874) (xy 178.451764 -115.310158)
			(xy 178.502564 -115.311174) (xy 178.528972 -115.312257) (xy 178.58113 -115.320806) (xy 178.631609 -115.33647)
			(xy 178.679444 -115.358949) (xy 178.723719 -115.387815) (xy 178.763588 -115.422514) (xy 178.798286 -115.462382)
			(xy 178.827152 -115.506658) (xy 178.849631 -115.554493) (xy 178.865295 -115.604972) (xy 178.873843 -115.65713)
			(xy 178.874928 -115.683538) (xy 178.875944 -115.734338) (xy 182.086504 -118.944898) (xy 182.086504 -130.929634)
			(xy 182.087062 -130.947187) (xy 182.096644 -130.98096) (xy 182.115097 -131.010825) (xy 182.127652 -131.023106)
			(xy 182.148436 -131.042927) (xy 182.184404 -131.0877) (xy 182.213256 -131.137356) (xy 182.234343 -131.190776)
			(xy 182.247187 -131.246752) (xy 182.251499 -131.30402) (xy 182.247181 -131.361288) (xy 182.234331 -131.417263)
			(xy 182.213239 -131.47068) (xy 182.184381 -131.520334) (xy 182.148408 -131.565103) (xy 182.127652 -131.584954)
			(xy 182.115113 -131.597242) (xy 182.096707 -131.627123) (xy 182.087106 -131.66088) (xy 182.086504 -131.678426)
			(xy 182.086504 -133.002782) (xy 182.08695 -133.018348) (xy 182.094484 -133.048554) (xy 182.109109 -133.076037)
			(xy 182.129954 -133.09916) (xy 182.142638 -133.108192) (xy 182.164558 -133.123449) (xy 182.204313 -133.159112)
			(xy 182.238704 -133.199972) (xy 182.267059 -133.245229) (xy 182.288825 -133.293999) (xy 182.303576 -133.345328)
			(xy 182.311023 -133.398213) (xy 182.311021 -133.45162) (xy 182.303569 -133.504504) (xy 182.288814 -133.555832)
			(xy 182.267044 -133.6046) (xy 182.238684 -133.649855) (xy 182.204289 -133.690712) (xy 182.164532 -133.726372)
			(xy 182.142638 -133.741668) (xy 182.129969 -133.750721) (xy 182.10911 -133.77383) (xy 182.094478 -133.801307)
			(xy 182.086946 -133.831513) (xy 182.086504 -133.847078) (xy 182.086504 -139.511532) (xy 177.19548 -144.402556)
			(xy 177.19548 -159.845756) (xy 168.009824 -169.031412) (xy 167.992552 -169.097452) (xy 168.00195 -169.13098)
			(xy 168.008744 -169.157032) (xy 168.01579 -169.210407) (xy 168.015264 -169.264243) (xy 168.007176 -169.31747)
			(xy 167.991687 -169.369033) (xy 167.969105 -169.417906) (xy 167.939878 -169.46312) (xy 167.904586 -169.503778)
			(xy 167.863929 -169.539071) (xy 167.818716 -169.5683) (xy 167.769843 -169.590883) (xy 167.718281 -169.606374)
			(xy 167.665054 -169.614463) (xy 167.611218 -169.614991) (xy 167.557843 -169.607946) (xy 167.531796 -169.601134)
			(xy 167.498268 -169.591736) (xy 167.432228 -169.609008) (xy 159.319104 -177.722132) (xy 170.990983 -177.722132)
			(xy 170.996242 -177.542809) (xy 171.009518 -177.363901) (xy 171.030784 -177.185766) (xy 171.059997 -177.008761)
			(xy 171.0971 -176.83324) (xy 171.142017 -176.659555) (xy 171.19466 -176.488052) (xy 171.254922 -176.319077)
			(xy 171.322682 -176.152966) (xy 171.397806 -175.990053) (xy 171.480143 -175.830664) (xy 171.569527 -175.675118)
			(xy 171.665781 -175.523726) (xy 171.76871 -175.376791) (xy 171.87811 -175.234608) (xy 171.993761 -175.097462)
			(xy 172.115431 -174.965626) (xy 172.242877 -174.839366) (xy 172.375844 -174.718933) (xy 172.514065 -174.604569)
			(xy 172.657264 -174.496503) (xy 172.805154 -174.394951) (xy 172.957439 -174.300116) (xy 173.113814 -174.21219)
			(xy 173.273966 -174.131346) (xy 173.437574 -174.057748) (xy 173.60431 -173.991543) (xy 173.773842 -173.932863)
			(xy 173.945828 -173.881825) (xy 174.119926 -173.838533) (xy 174.295786 -173.803072) (xy 174.473057 -173.775514)
			(xy 174.651382 -173.755914) (xy 174.830406 -173.744311) (xy 175.00977 -173.740728) (xy 175.189115 -173.745172)
			(xy 175.368081 -173.757635) (xy 175.546311 -173.778092) (xy 175.723447 -173.806501) (xy 175.899134 -173.842807)
			(xy 176.073022 -173.886935) (xy 176.244762 -173.938798) (xy 176.414009 -173.998292) (xy 176.580426 -174.065297)
			(xy 176.743678 -174.13968) (xy 176.90344 -174.221292) (xy 177.059391 -174.309969) (xy 177.211218 -174.405534)
			(xy 177.358619 -174.507796) (xy 177.501297 -174.616548) (xy 177.638967 -174.731575) (xy 177.771354 -174.852645)
			(xy 177.898192 -174.979517) (xy 178.019227 -175.111935) (xy 178.134218 -175.249636) (xy 178.242933 -175.392342)
			(xy 178.345156 -175.53977) (xy 178.440681 -175.691622) (xy 178.529317 -175.847596) (xy 178.610887 -176.007379)
			(xy 178.685227 -176.170651) (xy 178.752189 -176.337085) (xy 178.811639 -176.506349) (xy 178.863457 -176.678102)
			(xy 178.907539 -176.852001) (xy 178.943798 -177.027698) (xy 178.972161 -177.204842) (xy 178.992571 -177.383077)
			(xy 179.004987 -177.562046) (xy 179.009385 -177.741392) (xy 179.005755 -177.920755) (xy 178.994105 -178.099776)
			(xy 178.974457 -178.278096) (xy 178.946853 -178.45536) (xy 178.911346 -178.63121) (xy 178.868008 -178.805297)
			(xy 178.816925 -178.97727) (xy 178.758201 -179.146786) (xy 178.691952 -179.313505) (xy 178.618311 -179.477094)
			(xy 178.537425 -179.637225) (xy 178.449457 -179.793576) (xy 178.354583 -179.945836) (xy 178.252992 -180.0937)
			(xy 178.144889 -180.23687) (xy 178.030488 -180.375062) (xy 177.910021 -180.507997) (xy 177.783727 -180.63541)
			(xy 177.651859 -180.757045) (xy 177.583592 -180.815234) (xy 177.560538 -180.835301) (xy 177.51903 -180.880166)
			(xy 177.483412 -180.929836) (xy 177.454233 -180.983542) (xy 177.431944 -181.040453) (xy 177.416891 -181.099691)
			(xy 177.409305 -181.16034) (xy 177.40884 -181.1909) (xy 177.40884 -182.749952) (xy 177.408078 -182.8038)
			(xy 177.408078 -182.960264) (xy 177.399188 -182.969154) (xy 177.394362 -183.013604) (xy 177.386323 -183.082148)
			(xy 177.363383 -183.218252) (xy 177.332686 -183.352819) (xy 177.294334 -183.485408) (xy 177.248451 -183.615582)
			(xy 177.195189 -183.742915) (xy 177.134722 -183.866989) (xy 177.067249 -183.987397) (xy 176.992992 -184.103743)
			(xy 176.912193 -184.215646) (xy 176.825119 -184.322737) (xy 176.732055 -184.424667) (xy 176.633306 -184.5211)
			(xy 176.529197 -184.611719) (xy 176.420069 -184.696228) (xy 176.30628 -184.774348) (xy 176.188205 -184.845824)
			(xy 176.06623 -184.910421) (xy 175.940756 -184.967927) (xy 175.812195 -185.018152) (xy 175.680969 -185.060933)
			(xy 175.547508 -185.096129) (xy 175.41225 -185.123624) (xy 175.27564 -185.143328) (xy 175.138125 -185.155176)
			(xy 175.000158 -185.15913) (xy 174.862191 -185.155176) (xy 174.724676 -185.143328) (xy 174.588066 -185.123624)
			(xy 174.452808 -185.096129) (xy 174.319347 -185.060933) (xy 174.188121 -185.018152) (xy 174.05956 -184.967927)
			(xy 173.934086 -184.910421) (xy 173.812111 -184.845824) (xy 173.694036 -184.774348) (xy 173.580247 -184.696228)
			(xy 173.471119 -184.611719) (xy 173.36701 -184.5211) (xy 173.268261 -184.424667) (xy 173.175197 -184.322737)
			(xy 173.088123 -184.215646) (xy 173.007324 -184.103743) (xy 172.933067 -183.987397) (xy 172.865594 -183.866989)
			(xy 172.805127 -183.742915) (xy 172.751865 -183.615582) (xy 172.705982 -183.485408) (xy 172.66763 -183.352819)
			(xy 172.636933 -183.218252) (xy 172.613993 -183.082148) (xy 172.605954 -183.013604) (xy 172.601128 -182.969154)
			(xy 172.592238 -182.960264) (xy 172.592238 -182.8038) (xy 172.591476 -182.749952) (xy 172.591476 -181.1909)
			(xy 172.59098 -181.157843) (xy 172.582132 -181.092325) (xy 172.564569 -181.028588) (xy 172.538608 -180.967786)
			(xy 172.504721 -180.911018) (xy 172.484542 -180.88483) (xy 172.406056 -180.80609) (xy 172.401992 -180.802788)
			(xy 172.334005 -180.744272) (xy 172.202724 -180.622004) (xy 172.077043 -180.493986) (xy 171.957216 -180.360473)
			(xy 171.843481 -180.221734) (xy 171.736066 -180.078046) (xy 171.635187 -179.929696) (xy 171.541045 -179.776982)
			(xy 171.453829 -179.62021) (xy 171.373714 -179.459692) (xy 171.30086 -179.295752) (xy 171.235412 -179.128716)
			(xy 171.177503 -178.95892) (xy 171.127247 -178.786703) (xy 171.084746 -178.612411) (xy 171.050084 -178.436391)
			(xy 171.023331 -178.258998) (xy 171.004541 -178.080585) (xy 170.993751 -177.90151) (xy 170.990983 -177.722132)
			(xy 159.319104 -177.722132) (xy 158.504636 -178.5366) (xy 144.72539 -178.5366) (xy 144.667986 -178.568604)
			(xy 144.650714 -178.596544) (xy 144.635689 -178.619786) (xy 144.599994 -178.662078) (xy 144.558563 -178.698769)
			(xy 144.512267 -178.729091) (xy 144.462076 -178.752407) (xy 144.409043 -178.768229) (xy 144.354281 -178.776223)
			(xy 144.298939 -178.776223) (xy 144.244177 -178.768229) (xy 144.191144 -178.752407) (xy 144.140953 -178.729091)
			(xy 144.094657 -178.698769) (xy 144.053226 -178.662078) (xy 144.017531 -178.619786) (xy 144.002506 -178.596544)
			(xy 143.985234 -178.568604) (xy 143.92783 -178.5366) (xy 124.435108 -178.5366) (xy 111.12754 -165.229032)
			(xy 111.083598 -165.223952) (xy 111.055407 -165.220172) (xy 111.0005 -165.20534) (xy 110.948403 -165.182519)
			(xy 110.900272 -165.152216) (xy 110.857174 -165.115102) (xy 110.820065 -165.072001) (xy 110.789766 -165.023867)
			(xy 110.766949 -164.971769) (xy 110.752121 -164.91686) (xy 110.748318 -164.888672) (xy 110.743238 -164.84473)
			(xy 110.647988 -164.74948) (xy 110.59541 -164.749226) (xy 110.568276 -164.748657) (xy 110.514579 -164.740785)
			(xy 110.462539 -164.725383) (xy 110.413207 -164.702761) (xy 110.367578 -164.673378) (xy 110.326573 -164.637825)
			(xy 110.291021 -164.59682) (xy 110.261638 -164.551192) (xy 110.239017 -164.501859) (xy 110.223615 -164.449819)
			(xy 110.215743 -164.396122) (xy 110.215172 -164.368988) (xy 110.214918 -164.31641) (xy 110.13567 -164.237162)
			(xy 110.103158 -164.228272) (xy 110.075978 -164.220328) (xy 110.02415 -164.197524) (xy 109.976261 -164.16731)
			(xy 109.933364 -164.130349) (xy 109.896401 -164.087453) (xy 109.866184 -164.039566) (xy 109.843378 -163.987738)
			(xy 109.835442 -163.960556) (xy 109.826552 -163.928044) (xy 109.16412 -163.265612) (xy 109.16412 -153.196036)
			(xy 108.929424 -152.96134) (xy 107.892596 -152.96134) (xy 107.875943 -152.961835) (xy 107.843774 -152.970458)
			(xy 107.814933 -152.987114) (xy 107.791387 -153.010668) (xy 107.774741 -153.039515) (xy 107.766129 -153.071687)
			(xy 107.765596 -153.08834) (xy 107.765596 -157.047946) (xy 107.605068 -157.208474) (xy 107.589066 -157.280864)
			(xy 107.60202 -157.315916) (xy 107.610949 -157.341554) (xy 107.622294 -157.394644) (xy 107.625996 -157.448806)
			(xy 107.62198 -157.502945) (xy 107.610329 -157.555969) (xy 107.591276 -157.606804) (xy 107.565208 -157.654424)
			(xy 107.532651 -157.697867) (xy 107.494263 -157.736255) (xy 107.45082 -157.768811) (xy 107.4032 -157.794878)
			(xy 107.352364 -157.81393) (xy 107.299341 -157.825581) (xy 107.245201 -157.829596) (xy 107.191039 -157.825893)
			(xy 107.137949 -157.814548) (xy 107.112308 -157.805628) (xy 107.077256 -157.792674) (xy 107.004866 -157.808676)
			(xy 104.635808 -160.177734) (xy 99.932998 -160.177734) (xy 98.749358 -158.994094) (xy 98.749358 -153.069036)
			(xy 99.047046 -152.771348) (xy 101.089714 -152.771348) (xy 101.155246 -152.705816) (xy 101.244908 -152.705816)
			(xy 101.433884 -152.51684) (xy 102.3239 -152.51684) (xy 102.34055 -152.516297) (xy 102.372717 -152.50768)
			(xy 102.401557 -152.491033) (xy 102.425108 -152.467489) (xy 102.441764 -152.438654) (xy 102.450392 -152.40649)
			(xy 102.4509 -152.38984) (xy 102.4509 -148.240496) (xy 102.406704 -148.1963) (xy 93.998288 -148.1963)
			(xy 93.4593 -148.735288) (xy 93.4593 -163.524438) (xy 93.349318 -163.63442) (xy 93.339341 -163.64491)
			(xy 93.323981 -163.669441) (xy 93.314568 -163.69681) (xy 93.31159 -163.725599) (xy 93.315201 -163.754316)
			(xy 93.319854 -163.768024) (xy 93.328719 -163.793643) (xy 93.339948 -163.846678) (xy 93.343558 -163.900769)
			(xy 93.339475 -163.954826) (xy 93.327784 -164.00776) (xy 93.308717 -164.058508) (xy 93.282661 -164.106046)
			(xy 93.250138 -164.149417) (xy 93.211805 -164.187749) (xy 93.168432 -164.22027) (xy 93.120893 -164.246324)
			(xy 93.070144 -164.265388) (xy 93.017209 -164.277078) (xy 92.963152 -164.281158) (xy 92.909062 -164.277546)
			(xy 92.856027 -164.266314) (xy 92.830396 -164.257482) (xy 92.795598 -164.244528) (xy 92.723208 -164.26053)
			(xy 89.714324 -167.269414) (xy 89.696798 -167.334692) (xy 89.705688 -167.367966) (xy 89.712615 -167.395685)
			(xy 89.719055 -167.452455) (xy 89.716954 -167.50955) (xy 89.70636 -167.565694) (xy 89.687509 -167.619628)
			(xy 89.660824 -167.670147) (xy 89.626901 -167.71612) (xy 89.5865 -167.756519) (xy 89.540525 -167.790438)
			(xy 89.490003 -167.81712) (xy 89.436068 -167.835967) (xy 89.379924 -167.846557) (xy 89.322828 -167.848654)
			(xy 89.266059 -167.84221) (xy 89.238328 -167.835326) (xy 89.222073 -167.831463) (xy 89.188672 -167.831444)
			(xy 89.156413 -167.840103) (xy 89.127512 -167.856847) (xy 89.115392 -167.868346) (xy 86.444074 -170.539664)
			(xy 86.435184 -170.556428) (xy 86.421449 -170.581135) (xy 86.387811 -170.626563) (xy 86.347839 -170.666532)
			(xy 86.302407 -170.700166) (xy 86.277704 -170.713908) (xy 86.26094 -170.722798) (xy 85.706204 -171.277534)
			(xy 85.68817 -171.33951) (xy 85.695028 -171.37126) (xy 85.700405 -171.39801) (xy 85.704355 -171.45243)
			(xy 85.700511 -171.506857) (xy 85.68895 -171.560181) (xy 85.66991 -171.611314) (xy 85.643778 -171.659212)
			(xy 85.611088 -171.702898) (xy 85.572507 -171.74148) (xy 85.528822 -171.774171) (xy 85.480925 -171.800305)
			(xy 85.429793 -171.819347) (xy 85.376469 -171.830909) (xy 85.322042 -171.834755) (xy 85.267622 -171.830807)
			(xy 85.240876 -171.825412) (xy 85.225242 -171.822533) (xy 85.193485 -171.823694) (xy 85.162995 -171.832652)
			(xy 85.135655 -171.848851) (xy 85.124036 -171.859702) (xy 78.287118 -178.69662) (xy 75.7428 -178.69662)
			(xy 75.727234 -178.697071) (xy 75.697033 -178.704629) (xy 75.669569 -178.719292) (xy 75.65771 -178.729386)
			(xy 75.636564 -178.747816) (xy 75.589882 -178.778912) (xy 75.539151 -178.802841) (xy 75.485464 -178.819085)
			(xy 75.429977 -178.827296) (xy 75.373887 -178.827296) (xy 75.3184 -178.819085) (xy 75.264713 -178.802841)
			(xy 75.213982 -178.778912) (xy 75.1673 -178.747816) (xy 75.146154 -178.729386) (xy 75.134301 -178.719285)
			(xy 75.106831 -178.70463) (xy 75.076631 -178.697058) (xy 75.061064 -178.69662) (xy 74.942192 -178.69662)
			(xy 74.87412 -178.74869) (xy 74.86269 -178.790346) (xy 74.854939 -178.816905) (xy 74.83283 -178.867621)
			(xy 74.803627 -178.914611) (xy 74.767943 -178.956889) (xy 74.726525 -178.993569) (xy 74.680243 -179.023882)
			(xy 74.630068 -179.047191) (xy 74.577051 -179.063007) (xy 74.522307 -179.070999) (xy 74.466981 -179.070999)
			(xy 74.412237 -179.063007) (xy 74.35922 -179.047191) (xy 74.309045 -179.023882) (xy 74.262763 -178.993569)
			(xy 74.221345 -178.956889) (xy 74.185661 -178.914611) (xy 74.156458 -178.867621) (xy 74.134349 -178.816905)
			(xy 74.126598 -178.790346) (xy 74.121731 -178.774448) (xy 74.105038 -178.745711) (xy 74.081478 -178.72227)
			(xy 74.052656 -178.705723) (xy 74.020534 -178.697196) (xy 74.003916 -178.69662) (xy 67.526662 -178.69662)
			(xy 67.507104 -178.703224) (xy 67.477728 -178.712418) (xy 67.416975 -178.722296) (xy 67.355425 -178.722296)
			(xy 67.294672 -178.712418) (xy 67.265296 -178.703224) (xy 67.245738 -178.69662) (xy 64.158622 -178.69662)
			(xy 64.140884 -178.697203) (xy 64.106776 -178.706962) (xy 64.076672 -178.725733) (xy 64.052898 -178.752065)
			(xy 64.044576 -178.76774) (xy 64.031632 -178.793011) (xy 63.999396 -178.83975) (xy 63.960589 -178.881194)
			(xy 63.916067 -178.916428) (xy 63.866814 -178.944674) (xy 63.813919 -178.965307) (xy 63.75855 -178.977873)
			(xy 63.70193 -178.982092) (xy 63.64531 -178.977873) (xy 63.589941 -178.965307) (xy 63.537046 -178.944674)
			(xy 63.487793 -178.916428) (xy 63.443271 -178.881194) (xy 63.404464 -178.83975) (xy 63.372228 -178.793011)
			(xy 63.359284 -178.76774) (xy 63.350957 -178.752065) (xy 63.327187 -178.725723) (xy 63.297086 -178.70694)
			(xy 63.262978 -178.697165) (xy 63.245238 -178.69662) (xy 50.631598 -178.69662) (xy 50.564288 -178.74742)
			(xy 50.55235 -178.788314) (xy 50.544308 -178.814453) (xy 50.521779 -178.864286) (xy 50.492365 -178.910391)
			(xy 50.45667 -178.951824) (xy 50.415424 -178.987736) (xy 50.369473 -179.01739) (xy 50.319759 -179.04018)
			(xy 50.267301 -179.055637) (xy 50.213172 -179.063446) (xy 50.158484 -179.063446) (xy 50.104355 -179.055637)
			(xy 50.051897 -179.04018) (xy 50.002183 -179.01739) (xy 49.956232 -178.987736) (xy 49.914986 -178.951824)
			(xy 49.879291 -178.910391) (xy 49.849877 -178.864286) (xy 49.827348 -178.814453) (xy 49.819306 -178.788314)
			(xy 49.807368 -178.74742) (xy 49.740058 -178.69662) (xy 44.954444 -178.69662) (xy 44.13504 -177.877216)
			(xy 44.13504 -172.472096) (xy 12.57808 -140.915136) (xy 12.57808 -140.266674) (xy 12.577643 -140.251155)
			(xy 12.570149 -140.221035) (xy 12.555587 -140.193625) (xy 12.534825 -140.170554) (xy 12.5222 -140.161518)
			(xy 12.498708 -140.14504) (xy 12.456488 -140.106181) (xy 12.420565 -140.061436) (xy 12.391748 -140.011816)
			(xy 12.370687 -139.95844) (xy 12.357858 -139.902512) (xy 12.35355 -139.845293) (xy 12.35786 -139.788075)
			(xy 12.370691 -139.732147) (xy 12.391754 -139.678771) (xy 12.420572 -139.629153) (xy 12.456497 -139.58441)
			(xy 12.498718 -139.545552) (xy 12.5222 -139.529058) (xy 12.534795 -139.519994) (xy 12.555524 -139.496913)
			(xy 12.570072 -139.469513) (xy 12.57758 -139.439413) (xy 12.57808 -139.423902) (xy 12.57808 -134.697724)
			(xy 12.553188 -134.664196) (xy 12.537515 -134.642206) (xy 12.511859 -134.594691) (xy 12.49316 -134.544032)
			(xy 12.48179 -134.491244) (xy 12.477976 -134.437379) (xy 12.481795 -134.383515) (xy 12.493171 -134.330727)
			(xy 12.511877 -134.280071) (xy 12.537537 -134.232558) (xy 12.553188 -134.210552) (xy 12.57808 -134.177024)
			(xy 12.57808 -132.635498) (xy 12.538202 -132.573268) (xy 12.504166 -132.55752) (xy 12.479686 -132.54572)
			(xy 12.434049 -132.516217) (xy 12.393062 -132.480535) (xy 12.357554 -132.439398) (xy 12.328245 -132.393636)
			(xy 12.305727 -132.344179) (xy 12.290457 -132.292026) (xy 12.282744 -132.238233) (xy 12.282743 -132.18389)
			(xy 12.290456 -132.130098) (xy 12.305726 -132.077944) (xy 12.328243 -132.028486) (xy 12.357552 -131.982725)
			(xy 12.39306 -131.941587) (xy 12.434047 -131.905905) (xy 12.479683 -131.876402) (xy 12.504166 -131.864608)
			(xy 12.538202 -131.84886) (xy 12.57808 -131.78663) (xy 12.57808 -128.354074) (xy 12.577502 -128.33588)
			(xy 12.567244 -128.300969) (xy 12.547542 -128.270377) (xy 12.534138 -128.258062) (xy 12.513811 -128.239861)
			(xy 12.478056 -128.198649) (xy 12.448534 -128.152765) (xy 12.42585 -128.103143) (xy 12.410464 -128.050797)
			(xy 12.402691 -127.996792) (xy 12.402689 -127.942231) (xy 12.410459 -127.888226) (xy 12.425841 -127.835879)
			(xy 12.448523 -127.786256) (xy 12.478042 -127.74037) (xy 12.513795 -127.699155) (xy 12.534138 -127.680974)
			(xy 12.55522 -127.66294) (xy 12.57808 -127.612902) (xy 12.57808 -126.861316) (xy 12.577494 -126.843126)
			(xy 12.567224 -126.808225) (xy 12.547514 -126.777646) (xy 12.534138 -126.765304) (xy 12.513814 -126.747103)
			(xy 12.478062 -126.70589) (xy 12.448545 -126.660006) (xy 12.425864 -126.610386) (xy 12.410481 -126.558041)
			(xy 12.402711 -126.504039) (xy 12.402711 -126.449481) (xy 12.410481 -126.395479) (xy 12.425864 -126.343134)
			(xy 12.448545 -126.293514) (xy 12.478062 -126.24763) (xy 12.513814 -126.206417) (xy 12.534138 -126.188216)
			(xy 12.55522 -126.170182) (xy 12.57808 -126.120144) (xy 12.57808 -125.401324) (xy 12.577587 -125.385382)
			(xy 12.569682 -125.354495) (xy 12.554359 -125.326535) (xy 12.532578 -125.303251) (xy 12.505701 -125.2861)
			(xy 12.490704 -125.280674) (xy 12.464809 -125.271666) (xy 12.41571 -125.247271) (xy 12.370609 -125.2161)
			(xy 12.330433 -125.178793) (xy 12.296012 -125.13612) (xy 12.268054 -125.088959) (xy 12.247134 -125.038282)
			(xy 12.233684 -124.985132) (xy 12.227981 -124.930604) (xy 12.230142 -124.875821) (xy 12.240122 -124.821912)
			(xy 12.257717 -124.769986) (xy 12.282563 -124.721114) (xy 12.314149 -124.676302) (xy 12.351824 -124.636472)
			(xy 12.394813 -124.602446) (xy 12.44223 -124.574924) (xy 12.493098 -124.554473) (xy 12.546369 -124.541513)
			(xy 12.600947 -124.536313) (xy 12.655708 -124.538979) (xy 12.709523 -124.549456) (xy 12.73556 -124.558044)
			(xy 12.752621 -124.563375) (xy 12.788295 -124.565366) (xy 12.823123 -124.55739) (xy 12.854375 -124.540073)
			(xy 12.867386 -124.527818) (xy 13.57122 -123.823984) (xy 13.57122 -115.885976) (xy 11.992864 -114.30762)
			(xy 1.143 -114.30762) (xy 1.126346 -114.308115) (xy 1.094174 -114.316736) (xy 1.065329 -114.333391)
			(xy 1.041779 -114.356945) (xy 1.025128 -114.385792) (xy 1.016512 -114.417966) (xy 1.016 -114.43462)
			(xy 1.016 -168.699942) (xy 1.016525 -168.745411) (xy 1.024916 -168.83596) (xy 1.041626 -168.925349)
			(xy 1.066512 -169.012814) (xy 1.099362 -169.097611) (xy 1.139897 -169.179015) (xy 1.187769 -169.256331)
			(xy 1.242571 -169.3289) (xy 1.303835 -169.396104) (xy 1.371038 -169.457368) (xy 1.443607 -169.51217)
			(xy 1.520924 -169.560043) (xy 1.602327 -169.600577) (xy 1.687124 -169.633427) (xy 1.774589 -169.658314)
			(xy 1.863978 -169.675024) (xy 1.954527 -169.683415) (xy 1.999996 -169.683938) (xy 10.359898 -169.683938)
			(xy 10.438861 -169.684446) (xy 10.596572 -169.692711) (xy 10.753633 -169.709219) (xy 10.909615 -169.733924)
			(xy 11.064091 -169.766759) (xy 11.216636 -169.807633) (xy 11.366834 -169.856435) (xy 11.514271 -169.913031)
			(xy 11.658544 -169.977266) (xy 11.799258 -170.048963) (xy 11.936026 -170.127926) (xy 12.068475 -170.213939)
			(xy 12.19624 -170.306766) (xy 12.318972 -170.406153) (xy 12.436334 -170.511826) (xy 12.548005 -170.623497)
			(xy 12.653679 -170.74086) (xy 12.753065 -170.863592) (xy 12.845892 -170.991357) (xy 12.931905 -171.123806)
			(xy 13.010868 -171.260574) (xy 13.082565 -171.401288) (xy 13.1468 -171.545561) (xy 13.203395 -171.692998)
			(xy 13.252197 -171.843196) (xy 13.293072 -171.995741) (xy 13.325906 -172.150217) (xy 13.350611 -172.306199)
			(xy 13.367119 -172.46326) (xy 13.375384 -172.620971) (xy 13.375894 -172.699934) (xy 13.375894 -177.52949)
			(xy 20.336002 -177.52949) (xy 20.336002 -177.319178) (xy 20.535392 -177.119788) (xy 20.541996 -177.079148)
			(xy 20.557625 -176.985567) (xy 20.595756 -176.799685) (xy 20.64166 -176.615568) (xy 20.695258 -176.433543)
			(xy 20.756454 -176.253929) (xy 20.825141 -176.077044) (xy 20.901197 -175.903201) (xy 20.984487 -175.732706)
			(xy 21.074866 -175.565859) (xy 21.172173 -175.402956) (xy 21.276237 -175.244285) (xy 21.386874 -175.090124)
			(xy 21.503889 -174.940746) (xy 21.627074 -174.796416) (xy 21.756214 -174.657387) (xy 21.891079 -174.523905)
			(xy 22.031432 -174.396206) (xy 22.177025 -174.274515) (xy 22.327601 -174.159047) (xy 22.482894 -174.050005)
			(xy 22.64263 -173.947583) (xy 22.806528 -173.85196) (xy 22.974297 -173.763306) (xy 23.145642 -173.681778)
			(xy 23.320261 -173.607518) (xy 23.497844 -173.540659) (xy 23.678079 -173.481318) (xy 23.860648 -173.4296)
			(xy 24.045227 -173.385596) (xy 24.231493 -173.349384) (xy 24.419114 -173.321028) (xy 24.607762 -173.300578)
			(xy 24.797102 -173.288069) (xy 24.9868 -173.283525) (xy 25.176521 -173.286953) (xy 25.365931 -173.298347)
			(xy 25.554696 -173.317686) (xy 25.742481 -173.344938) (xy 25.928956 -173.380053) (xy 26.113792 -173.42297)
			(xy 26.296662 -173.473613) (xy 26.477243 -173.531892) (xy 26.655217 -173.597705) (xy 26.830269 -173.670935)
			(xy 27.002091 -173.751454) (xy 27.170379 -173.839119) (xy 27.334837 -173.933775) (xy 27.495173 -174.035256)
			(xy 27.651105 -174.143382) (xy 27.802358 -174.257962) (xy 27.948665 -174.378794) (xy 28.089767 -174.505665)
			(xy 28.225415 -174.638351) (xy 28.355371 -174.776617) (xy 28.479404 -174.92022) (xy 28.597295 -175.068906)
			(xy 28.708837 -175.222413) (xy 28.813833 -175.38047) (xy 28.912098 -175.542797) (xy 29.003457 -175.709109)
			(xy 29.087749 -175.879111) (xy 29.164827 -176.052504) (xy 29.234553 -176.228981) (xy 29.296806 -176.408232)
			(xy 29.351474 -176.589939) (xy 29.398461 -176.773782) (xy 29.437685 -176.959436) (xy 29.469076 -177.146574)
			(xy 29.492578 -177.334865) (xy 29.508151 -177.523978) (xy 29.515767 -177.713578) (xy 29.515412 -177.90333)
			(xy 29.507088 -178.0929) (xy 29.490807 -178.281952) (xy 29.466601 -178.470155) (xy 29.43451 -178.657174)
			(xy 29.394592 -178.84268) (xy 29.346918 -179.026346) (xy 29.291571 -179.207848) (xy 29.228648 -179.386864)
			(xy 29.158263 -179.563079) (xy 29.080537 -179.736183) (xy 28.995609 -179.905868) (xy 28.903629 -180.071837)
			(xy 28.804758 -180.233796) (xy 28.699172 -180.391459) (xy 28.587056 -180.544547) (xy 28.468609 -180.692792)
			(xy 28.34404 -180.83593) (xy 28.213568 -180.973709) (xy 28.077425 -181.105887) (xy 27.935849 -181.232229)
			(xy 27.862784 -181.292754) (xy 27.852155 -181.301964) (xy 27.834864 -181.324138) (xy 27.822845 -181.349558)
			(xy 27.816681 -181.376993) (xy 27.816302 -181.391052) (xy 27.816302 -183.220868) (xy 27.778964 -183.258206)
			(xy 27.772106 -183.297322) (xy 27.758285 -183.371507) (xy 27.723714 -183.518413) (xy 27.681325 -183.663258)
			(xy 27.631239 -183.805623) (xy 27.573599 -183.945102) (xy 27.508571 -184.081293) (xy 27.436342 -184.213806)
			(xy 27.357118 -184.34226) (xy 27.271129 -184.466286) (xy 27.17862 -184.585528) (xy 27.079857 -184.699644)
			(xy 26.975123 -184.808307) (xy 26.86472 -184.911204) (xy 26.748964 -185.008039) (xy 26.628187 -185.098536)
			(xy 26.502736 -185.182434) (xy 26.372972 -185.259492) (xy 26.239267 -185.329489) (xy 26.102005 -185.392224)
			(xy 25.961579 -185.447517) (xy 25.818393 -185.495209) (xy 25.672859 -185.535164) (xy 25.525393 -185.567266)
			(xy 25.37642 -185.591424) (xy 25.226366 -185.607568) (xy 25.075664 -185.615651) (xy 24.924744 -185.615651)
			(xy 24.774042 -185.607568) (xy 24.623988 -185.591424) (xy 24.475015 -185.567266) (xy 24.327549 -185.535164)
			(xy 24.182015 -185.495209) (xy 24.038829 -185.447517) (xy 23.898403 -185.392224) (xy 23.761141 -185.329489)
			(xy 23.627436 -185.259492) (xy 23.497672 -185.182434) (xy 23.372221 -185.098536) (xy 23.251444 -185.008039)
			(xy 23.135688 -184.911204) (xy 23.025285 -184.808307) (xy 22.920551 -184.699644) (xy 22.821788 -184.585528)
			(xy 22.729279 -184.466286) (xy 22.64329 -184.34226) (xy 22.564066 -184.213806) (xy 22.491837 -184.081293)
			(xy 22.426809 -183.945102) (xy 22.369169 -183.805623) (xy 22.319083 -183.663258) (xy 22.276694 -183.518413)
			(xy 22.242123 -183.371507) (xy 22.228302 -183.297322) (xy 22.221444 -183.258206) (xy 22.184106 -183.220868)
			(xy 22.184106 -181.391052) (xy 22.183733 -181.376989) (xy 22.177601 -181.349541) (xy 22.165583 -181.324114)
			(xy 22.148267 -181.301953) (xy 22.137624 -181.292754) (xy 22.063175 -181.231073) (xy 21.919015 -181.102209)
			(xy 21.780503 -180.967293) (xy 21.647892 -180.826572) (xy 21.521425 -180.680305) (xy 21.401334 -180.528759)
			(xy 21.28784 -180.372212) (xy 21.181149 -180.210951) (xy 21.081458 -180.045272) (xy 20.98895 -179.875478)
			(xy 20.903793 -179.70188) (xy 20.826144 -179.524796) (xy 20.756146 -179.344551) (xy 20.693926 -179.161476)
			(xy 20.639598 -178.975905) (xy 20.593263 -178.788179) (xy 20.555004 -178.598642) (xy 20.524893 -178.407642)
			(xy 20.502984 -178.215527) (xy 20.489318 -178.022651) (xy 20.483919 -177.829367) (xy 20.484846 -177.73269)
			(xy 20.4851 -177.707036) (xy 20.465796 -177.659284) (xy 20.336002 -177.52949) (xy 13.375894 -177.52949)
			(xy 13.375894 -207.556608) (xy 13.376438 -207.573256) (xy 13.385057 -207.605417) (xy 13.401706 -207.634252)
			(xy 13.42525 -207.657795) (xy 13.454085 -207.674444) (xy 13.486246 -207.683062) (xy 13.502894 -207.683608)
		)
		(stroke
			(width 0)
			(type solid)
		)
		(fill yes)
		(layer "In3.Cu")
		(net "P12V_AUX")
	)
	(gr_line
		(start 0.36322 -114.05362)
		(end 12.09802 -114.05362)
		(stroke
			(width 0.508)
			(type default)
		)
		(layer "In3.Cu")
	)
	(gr_arc
		(start 1.500124 -70.79996)
		(mid 0.439376 -71.239336)
		(end 0 -72.300084)
		(stroke
			(width 2.032)
			(type default)
		)
		(layer "In3.Cu")
	)
	(gr_line
		(start 1.500124 -70.79996)
		(end 6.500114 -70.79996)
		(stroke
			(width 2.032)
			(type default)
		)
		(layer "In3.Cu")
	)
	(gr_line
		(start 1.999996 -170.699938)
		(end 10.359898 -170.699938)
		(stroke
			(width 2.032)
			(type default)
		)
		(layer "In3.Cu")
	)
	(gr_arc
		(start 1.999996 0)
		(mid 0.585785 -0.585785)
		(end 0 -1.999996)
		(stroke
			(width 2.032)
			(type default)
		)
		(layer "In3.Cu")
	)
	(gr_line
		(start 1.999996 0)
		(end 198.000112 0)
		(stroke
			(width 2.032)
			(type default)
		)
		(layer "In3.Cu")
	)
	(gr_arc
		(start 6.500114 -70.79996)
		(mid 7.560682 -70.360658)
		(end 7.999984 -69.30009)
		(stroke
			(width 2.032)
			(type default)
		)
		(layer "In3.Cu")
	)
	(gr_line
		(start 6.500114 -30.80004)
		(end 1.500124 -30.80004)
		(stroke
			(width 2.032)
			(type default)
		)
		(layer "In3.Cu")
	)
	(gr_line
		(start 7.74954 -69.77126)
		(end 7.81558 -69.8373)
		(stroke
			(width 0.508)
			(type default)
		)
		(layer "In3.Cu")
	)
	(gr_line
		(start 7.81558 -69.8373)
		(end 78.91526 -69.8373)
		(stroke
			(width 0.508)
			(type default)
		)
		(layer "In3.Cu")
	)
	(gr_line
		(start 7.999984 -69.30009)
		(end 7.999984 -32.29991)
		(stroke
			(width 2.032)
			(type default)
		)
		(layer "In3.Cu")
	)
	(gr_arc
		(start 7.999984 -32.29991)
		(mid 7.560682 -31.239342)
		(end 6.500114 -30.80004)
		(stroke
			(width 2.032)
			(type default)
		)
		(layer "In3.Cu")
	)
	(gr_line
		(start 12.09802 -114.05362)
		(end 13.82522 -115.78082)
		(stroke
			(width 0.508)
			(type default)
		)
		(layer "In3.Cu")
	)
	(gr_line
		(start 12.359894 -208.197196)
		(end 12.497054 -208.334356)
		(stroke
			(width 2.032)
			(type default)
		)
		(layer "In3.Cu")
	)
	(gr_arc
		(start 12.359894 -172.699934)
		(mid 11.774121 -171.285702)
		(end 10.359898 -170.699938)
		(stroke
			(width 2.032)
			(type default)
		)
		(layer "In3.Cu")
	)
	(gr_line
		(start 12.359894 -172.699934)
		(end 12.359894 -208.197196)
		(stroke
			(width 2.032)
			(type default)
		)
		(layer "In3.Cu")
	)
	(gr_line
		(start 12.497054 -208.334356)
		(end 12.864084 -208.699608)
		(stroke
			(width 2.032)
			(type default)
		)
		(layer "In3.Cu")
	)
	(gr_line
		(start 12.83208 -140.80998)
		(end 44.38904 -172.36694)
		(stroke
			(width 0.508)
			(type default)
		)
		(layer "In3.Cu")
	)
	(gr_line
		(start 12.83208 -124.92228)
		(end 12.83208 -140.80998)
		(stroke
			(width 0.508)
			(type default)
		)
		(layer "In3.Cu")
	)
	(gr_line
		(start 13.82522 -123.92914)
		(end 12.83208 -124.92228)
		(stroke
			(width 0.508)
			(type default)
		)
		(layer "In3.Cu")
	)
	(gr_line
		(start 13.82522 -115.78082)
		(end 13.82522 -123.92914)
		(stroke
			(width 0.508)
			(type default)
		)
		(layer "In3.Cu")
	)
	(gr_line
		(start 13.98524 -118.75262)
		(end 43.52544 -118.75262)
		(stroke
			(width 0.508)
			(type default)
		)
		(layer "In3.Cu")
	)
	(gr_line
		(start 21.633942 -178.468274)
		(end 20.590002 -177.424334)
		(stroke
			(width 0.508)
			(type default)
		)
		(layer "In3.Cu")
	)
	(gr_line
		(start 22.3393 -24.056848)
		(end 22.822408 -24.539956)
		(stroke
			(width 1.016)
			(type default)
		)
		(layer "In3.Cu")
	)
	(gr_line
		(start 22.3393 -20.73656)
		(end 22.3393 -24.056848)
		(stroke
			(width 1.016)
			(type default)
		)
		(layer "In3.Cu")
	)
	(gr_line
		(start 22.3393 -20.73656)
		(end 23.89124 -19.18462)
		(stroke
			(width 1.016)
			(type default)
		)
		(layer "In3.Cu")
	)
	(gr_line
		(start 22.67585 -182.537862)
		(end 22.734778 -182.478934)
		(stroke
			(width 0.1524)
			(type default)
		)
		(layer "In3.Cu")
	)
	(gr_line
		(start 22.67585 -182.537862)
		(end 23.003256 -182.865268)
		(stroke
			(width 0.1524)
			(type default)
		)
		(layer "In3.Cu")
	)
	(gr_line
		(start 22.67585 -181.90464)
		(end 22.67585 -182.537862)
		(stroke
			(width 0.1524)
			(type default)
		)
		(layer "In3.Cu")
	)
	(gr_line
		(start 22.67585 -180.979064)
		(end 22.67585 -182.537862)
		(stroke
			(width 0.1524)
			(type default)
		)
		(layer "In3.Cu")
	)
	(gr_line
		(start 22.67585 -180.979064)
		(end 22.67585 -181.90464)
		(stroke
			(width 0.1524)
			(type default)
		)
		(layer "In3.Cu")
	)
	(gr_line
		(start 22.72284 -182.425848)
		(end 22.734778 -182.437786)
		(stroke
			(width 0.1524)
			(type default)
		)
		(layer "In3.Cu")
	)
	(gr_line
		(start 22.72284 -182.395622)
		(end 23.192486 -182.865268)
		(stroke
			(width 0.1524)
			(type default)
		)
		(layer "In3.Cu")
	)
	(gr_line
		(start 22.72284 -181.014116)
		(end 22.72284 -182.425848)
		(stroke
			(width 0.1524)
			(type default)
		)
		(layer "In3.Cu")
	)
	(gr_line
		(start 22.72284 -181.014116)
		(end 22.72284 -182.395622)
		(stroke
			(width 0.1524)
			(type default)
		)
		(layer "In3.Cu")
	)
	(gr_line
		(start 22.734778 -182.478934)
		(end 22.734778 -180.685186)
		(stroke
			(width 0.1524)
			(type default)
		)
		(layer "In3.Cu")
	)
	(gr_line
		(start 22.734778 -182.437786)
		(end 22.734778 -180.920136)
		(stroke
			(width 0.1524)
			(type default)
		)
		(layer "In3.Cu")
	)
	(gr_line
		(start 22.734778 -182.437786)
		(end 23.16226 -182.865268)
		(stroke
			(width 0.1524)
			(type default)
		)
		(layer "In3.Cu")
	)
	(gr_line
		(start 22.734778 -182.40756)
		(end 22.734778 -180.920136)
		(stroke
			(width 0.1524)
			(type default)
		)
		(layer "In3.Cu")
	)
	(gr_line
		(start 22.734778 -182.40756)
		(end 23.192486 -182.865268)
		(stroke
			(width 0.1524)
			(type default)
		)
		(layer "In3.Cu")
	)
	(gr_line
		(start 22.734778 -180.920136)
		(end 22.67585 -180.979064)
		(stroke
			(width 0.1524)
			(type default)
		)
		(layer "In3.Cu")
	)
	(gr_line
		(start 22.734778 -180.920136)
		(end 22.734778 -182.40756)
		(stroke
			(width 0.1524)
			(type default)
		)
		(layer "In3.Cu")
	)
	(gr_line
		(start 22.734778 -180.920136)
		(end 22.987762 -180.667152)
		(stroke
			(width 0.1524)
			(type default)
		)
		(layer "In3.Cu")
	)
	(gr_line
		(start 22.734778 -180.920136)
		(end 24.84755 -180.920136)
		(stroke
			(width 0.1524)
			(type default)
		)
		(layer "In3.Cu")
	)
	(gr_line
		(start 22.734778 -180.685186)
		(end 22.734778 -182.437786)
		(stroke
			(width 0.1524)
			(type default)
		)
		(layer "In3.Cu")
	)
	(gr_line
		(start 22.734778 -180.685186)
		(end 23.192486 -181.142894)
		(stroke
			(width 0.1524)
			(type default)
		)
		(layer "In3.Cu")
	)
	(gr_line
		(start 22.814788 -182.48757)
		(end 22.814788 -181.000146)
		(stroke
			(width 0.1524)
			(type default)
		)
		(layer "In3.Cu")
	)
	(gr_line
		(start 22.814788 -182.48757)
		(end 22.814788 -180.605176)
		(stroke
			(width 0.1524)
			(type default)
		)
		(layer "In3.Cu")
	)
	(gr_line
		(start 22.814788 -182.48757)
		(end 23.192486 -182.865268)
		(stroke
			(width 0.1524)
			(type default)
		)
		(layer "In3.Cu")
	)
	(gr_line
		(start 22.814788 -181.000146)
		(end 22.734778 -180.920136)
		(stroke
			(width 0.1524)
			(type default)
		)
		(layer "In3.Cu")
	)
	(gr_line
		(start 22.814788 -180.605176)
		(end 22.734778 -180.685186)
		(stroke
			(width 0.1524)
			(type default)
		)
		(layer "In3.Cu")
	)
	(gr_line
		(start 22.814788 -180.605176)
		(end 22.814788 -182.48757)
		(stroke
			(width 0.1524)
			(type default)
		)
		(layer "In3.Cu")
	)
	(gr_line
		(start 22.814788 -180.605176)
		(end 23.192486 -180.982874)
		(stroke
			(width 0.1524)
			(type default)
		)
		(layer "In3.Cu")
	)
	(gr_line
		(start 22.822408 -24.539956)
		(end 22.822408 -21.219668)
		(stroke
			(width 1.016)
			(type default)
		)
		(layer "In3.Cu")
	)
	(gr_line
		(start 22.822408 -21.219668)
		(end 22.3393 -20.73656)
		(stroke
			(width 1.016)
			(type default)
		)
		(layer "In3.Cu")
	)
	(gr_line
		(start 22.987762 -180.667152)
		(end 23.192486 -180.871876)
		(stroke
			(width 0.1524)
			(type default)
		)
		(layer "In3.Cu")
	)
	(gr_line
		(start 23.003256 -182.865268)
		(end 23.192486 -182.865268)
		(stroke
			(width 0.1524)
			(type default)
		)
		(layer "In3.Cu")
	)
	(gr_line
		(start 23.16226 -182.865268)
		(end 23.192486 -182.865268)
		(stroke
			(width 0.1524)
			(type default)
		)
		(layer "In3.Cu")
	)
	(gr_line
		(start 23.192486 -182.865268)
		(end 22.734778 -182.40756)
		(stroke
			(width 0.1524)
			(type default)
		)
		(layer "In3.Cu")
	)
	(gr_line
		(start 23.192486 -182.865268)
		(end 22.814788 -182.48757)
		(stroke
			(width 0.1524)
			(type default)
		)
		(layer "In3.Cu")
	)
	(gr_line
		(start 23.192486 -182.865268)
		(end 23.192486 -181.483762)
		(stroke
			(width 0.1524)
			(type default)
		)
		(layer "In3.Cu")
	)
	(gr_line
		(start 23.192486 -182.865268)
		(end 23.192486 -181.388004)
		(stroke
			(width 0.1524)
			(type default)
		)
		(layer "In3.Cu")
	)
	(gr_line
		(start 23.192486 -182.865268)
		(end 23.192486 -181.388004)
		(stroke
			(width 1.016)
			(type default)
		)
		(layer "In3.Cu")
	)
	(gr_line
		(start 23.192486 -182.865268)
		(end 23.192486 -181.377844)
		(stroke
			(width 0.1524)
			(type default)
		)
		(layer "In3.Cu")
	)
	(gr_line
		(start 23.192486 -182.865268)
		(end 23.192486 -180.982874)
		(stroke
			(width 0.1524)
			(type default)
		)
		(layer "In3.Cu")
	)
	(gr_arc
		(start 23.192486 -182.865268)
		(mid 24.992584 -184.665366)
		(end 26.792682 -182.865268)
		(stroke
			(width 1.016)
			(type default)
		)
		(layer "In3.Cu")
	)
	(gr_line
		(start 23.192486 -181.483762)
		(end 22.72284 -181.014116)
		(stroke
			(width 0.1524)
			(type default)
		)
		(layer "In3.Cu")
	)
	(gr_line
		(start 23.192486 -181.388004)
		(end 22.67585 -181.90464)
		(stroke
			(width 0.1524)
			(type default)
		)
		(layer "In3.Cu")
	)
	(gr_arc
		(start 23.192486 -181.388004)
		(mid 23.093118 -180.953422)
		(end 22.814788 -180.605176)
		(stroke
			(width 1.016)
			(type default)
		)
		(layer "In3.Cu")
	)
	(gr_arc
		(start 23.192486 -181.388004)
		(mid 23.09314 -180.953412)
		(end 22.814788 -180.605176)
		(stroke
			(width 1.016)
			(type default)
		)
		(layer "In3.Cu")
	)
	(gr_line
		(start 23.192486 -181.388004)
		(end 23.192486 -182.865268)
		(stroke
			(width 1.016)
			(type default)
		)
		(layer "In3.Cu")
	)
	(gr_line
		(start 23.192486 -181.377844)
		(end 22.734778 -180.920136)
		(stroke
			(width 0.1524)
			(type default)
		)
		(layer "In3.Cu")
	)
	(gr_line
		(start 23.192486 -181.142894)
		(end 23.192486 -182.865268)
		(stroke
			(width 0.1524)
			(type default)
		)
		(layer "In3.Cu")
	)
	(gr_line
		(start 23.192486 -180.982874)
		(end 22.814788 -180.605176)
		(stroke
			(width 0.1524)
			(type default)
		)
		(layer "In3.Cu")
	)
	(gr_line
		(start 23.192486 -180.982874)
		(end 23.192486 -182.865268)
		(stroke
			(width 0.1524)
			(type default)
		)
		(layer "In3.Cu")
	)
	(gr_line
		(start 23.192486 -180.871876)
		(end 23.192486 -182.865268)
		(stroke
			(width 0.1524)
			(type default)
		)
		(layer "In3.Cu")
	)
	(gr_line
		(start 23.199344 -182.79872)
		(end 23.199344 -181.32044)
		(stroke
			(width 0.2)
			(type default)
		)
		(layer "In3.Cu")
	)
	(gr_arc
		(start 23.199344 -182.79872)
		(mid 25.000204 -184.59958)
		(end 26.801064 -182.79872)
		(stroke
			(width 0.2)
			(type default)
		)
		(layer "In3.Cu")
	)
	(gr_arc
		(start 23.199344 -181.32044)
		(mid 23.100653 -180.886389)
		(end 22.823424 -180.53812)
		(stroke
			(width 0.2)
			(type default)
		)
		(layer "In3.Cu")
	)
	(gr_line
		(start 23.200106 -182.79999)
		(end 23.200106 -181.322726)
		(stroke
			(width 0.2)
			(type default)
		)
		(layer "In3.Cu")
	)
	(gr_arc
		(start 23.200106 -182.79999)
		(mid 25.000077 -184.599834)
		(end 26.800048 -182.79999)
		(stroke
			(width 0.2)
			(type default)
		)
		(layer "In3.Cu")
	)
	(gr_arc
		(start 23.200106 -182.79999)
		(mid 25.000204 -184.600088)
		(end 26.800302 -182.79999)
		(stroke
			(width 1.016)
			(type default)
		)
		(layer "In3.Cu")
	)
	(gr_arc
		(start 23.200106 -182.79999)
		(mid 25.000204 -184.600088)
		(end 26.800302 -182.79999)
		(stroke
			(width 2.032)
			(type default)
		)
		(layer "In3.Cu")
	)
	(gr_arc
		(start 23.200106 -181.322726)
		(mid 23.100769 -180.888126)
		(end 22.822408 -180.539898)
		(stroke
			(width 0.2)
			(type default)
		)
		(layer "In3.Cu")
	)
	(gr_arc
		(start 23.200106 -181.322726)
		(mid 23.100769 -180.888126)
		(end 22.822408 -180.539898)
		(stroke
			(width 1.016)
			(type default)
		)
		(layer "In3.Cu")
	)
	(gr_arc
		(start 23.200106 -181.322726)
		(mid 23.100769 -180.888126)
		(end 22.822408 -180.539898)
		(stroke
			(width 2.032)
			(type default)
		)
		(layer "In3.Cu")
	)
	(gr_line
		(start 23.200106 -181.322726)
		(end 23.200106 -182.79999)
		(stroke
			(width 1.016)
			(type default)
		)
		(layer "In3.Cu")
	)
	(gr_line
		(start 23.200106 -181.322726)
		(end 23.200106 -182.79999)
		(stroke
			(width 2.032)
			(type default)
		)
		(layer "In3.Cu")
	)
	(gr_line
		(start 23.200106 -26.800048)
		(end 23.200106 -25.322784)
		(stroke
			(width 1.016)
			(type default)
		)
		(layer "In3.Cu")
	)
	(gr_arc
		(start 23.200106 -26.800048)
		(mid 25.000204 -28.600146)
		(end 26.800048 -26.800048)
		(stroke
			(width 1.016)
			(type default)
		)
		(layer "In3.Cu")
	)
	(gr_arc
		(start 23.200106 -25.322784)
		(mid 23.100754 -24.888195)
		(end 22.822408 -24.539956)
		(stroke
			(width 1.016)
			(type default)
		)
		(layer "In3.Cu")
	)
	(gr_line
		(start 23.200106 -20.312634)
		(end 23.200106 -26.800048)
		(stroke
			(width 1.016)
			(type default)
		)
		(layer "In3.Cu")
	)
	(gr_line
		(start 23.30704 -24.45258)
		(end 23.30704 -20.2057)
		(stroke
			(width 1.016)
			(type default)
		)
		(layer "In3.Cu")
	)
	(gr_line
		(start 23.30704 -20.2057)
		(end 23.200106 -20.312634)
		(stroke
			(width 1.016)
			(type default)
		)
		(layer "In3.Cu")
	)
	(gr_line
		(start 23.70582 -24.85136)
		(end 23.30704 -24.45258)
		(stroke
			(width 1.016)
			(type default)
		)
		(layer "In3.Cu")
	)
	(gr_line
		(start 23.89124 -19.18462)
		(end 22.3393 -20.73656)
		(stroke
			(width 1.016)
			(type default)
		)
		(layer "In3.Cu")
	)
	(gr_line
		(start 23.89124 -19.18462)
		(end 23.89378 -19.18716)
		(stroke
			(width 1.016)
			(type default)
		)
		(layer "In3.Cu")
	)
	(gr_line
		(start 23.89378 -24.85136)
		(end 23.70582 -24.85136)
		(stroke
			(width 1.016)
			(type default)
		)
		(layer "In3.Cu")
	)
	(gr_line
		(start 23.89378 -19.18716)
		(end 23.89378 -24.85136)
		(stroke
			(width 1.016)
			(type default)
		)
		(layer "In3.Cu")
	)
	(gr_line
		(start 24.08428 -27.71648)
		(end 24.08428 -23.14448)
		(stroke
			(width 1.016)
			(type default)
		)
		(layer "In3.Cu")
	)
	(gr_line
		(start 24.08428 -23.14448)
		(end 24.25446 -23.31466)
		(stroke
			(width 1.016)
			(type default)
		)
		(layer "In3.Cu")
	)
	(gr_line
		(start 24.25446 -23.31466)
		(end 24.25446 -27.3558)
		(stroke
			(width 1.016)
			(type default)
		)
		(layer "In3.Cu")
	)
	(gr_line
		(start 24.511508 -183.343296)
		(end 24.511508 -180.974238)
		(stroke
			(width 2.54)
			(type default)
		)
		(layer "In3.Cu")
	)
	(gr_line
		(start 24.519128 -183.278018)
		(end 24.519128 -180.90896)
		(stroke
			(width 2.54)
			(type default)
		)
		(layer "In3.Cu")
	)
	(gr_line
		(start 24.65324 -28.28544)
		(end 24.08428 -27.71648)
		(stroke
			(width 1.016)
			(type default)
		)
		(layer "In3.Cu")
	)
	(gr_line
		(start 24.65324 -19.18462)
		(end 23.89124 -19.18462)
		(stroke
			(width 1.016)
			(type default)
		)
		(layer "In3.Cu")
	)
	(gr_line
		(start 24.65324 -19.18462)
		(end 24.65324 -28.28544)
		(stroke
			(width 1.016)
			(type default)
		)
		(layer "In3.Cu")
	)
	(gr_line
		(start 24.84755 -180.920136)
		(end 26.792682 -182.865268)
		(stroke
			(width 0.1524)
			(type default)
		)
		(layer "In3.Cu")
	)
	(gr_line
		(start 24.95804 -18.87982)
		(end 24.65324 -19.18462)
		(stroke
			(width 1.016)
			(type default)
		)
		(layer "In3.Cu")
	)
	(gr_circle
		(center 24.989028 -182.872126)
		(end 26.759154 -182.872126)
		(stroke
			(width 1.27)
			(type default)
		)
		(fill no)
		(layer "In3.Cu")
	)
	(gr_circle
		(center 24.989536 -177.87239)
		(end 27.868372 -177.87239)
		(stroke
			(width 2.54)
			(type default)
		)
		(fill no)
		(layer "In3.Cu")
	)
	(gr_circle
		(center 24.992584 -177.865278)
		(end 27.12085 -177.865278)
		(stroke
			(width 2.54)
			(type default)
		)
		(fill no)
		(layer "In3.Cu")
	)
	(gr_circle
		(center 25.000204 -177.8)
		(end 27.12847 -177.8)
		(stroke
			(width 2.54)
			(type default)
		)
		(fill no)
		(layer "In3.Cu")
	)
	(gr_line
		(start 25.140666 -183.046878)
		(end 25.251664 -183.046878)
		(stroke
			(width 2.54)
			(type default)
		)
		(layer "In3.Cu")
	)
	(gr_line
		(start 25.140666 -176.754536)
		(end 25.140666 -183.046878)
		(stroke
			(width 2.54)
			(type default)
		)
		(layer "In3.Cu")
	)
	(gr_line
		(start 25.148286 -182.9816)
		(end 25.259284 -182.9816)
		(stroke
			(width 2.54)
			(type default)
		)
		(layer "In3.Cu")
	)
	(gr_line
		(start 25.148286 -176.689258)
		(end 25.148286 -182.9816)
		(stroke
			(width 2.54)
			(type default)
		)
		(layer "In3.Cu")
	)
	(gr_line
		(start 25.251664 -183.343296)
		(end 24.511508 -183.343296)
		(stroke
			(width 2.54)
			(type default)
		)
		(layer "In3.Cu")
	)
	(gr_line
		(start 25.251664 -183.046878)
		(end 25.251664 -183.343296)
		(stroke
			(width 2.54)
			(type default)
		)
		(layer "In3.Cu")
	)
	(gr_line
		(start 25.259284 -183.278018)
		(end 24.519128 -183.278018)
		(stroke
			(width 2.54)
			(type default)
		)
		(layer "In3.Cu")
	)
	(gr_line
		(start 25.259284 -182.9816)
		(end 25.259284 -183.278018)
		(stroke
			(width 2.54)
			(type default)
		)
		(layer "In3.Cu")
	)
	(gr_line
		(start 25.2603 -28.26512)
		(end 25.35428 -28.17114)
		(stroke
			(width 1.016)
			(type default)
		)
		(layer "In3.Cu")
	)
	(gr_line
		(start 25.2603 -28.07462)
		(end 25.2603 -28.26512)
		(stroke
			(width 1.016)
			(type default)
		)
		(layer "In3.Cu")
	)
	(gr_line
		(start 25.2603 -18.87982)
		(end 24.95804 -18.87982)
		(stroke
			(width 1.016)
			(type default)
		)
		(layer "In3.Cu")
	)
	(gr_line
		(start 25.35428 -28.17114)
		(end 25.35428 -18.9738)
		(stroke
			(width 1.016)
			(type default)
		)
		(layer "In3.Cu")
	)
	(gr_line
		(start 25.35428 -18.9738)
		(end 25.2603 -18.87982)
		(stroke
			(width 1.016)
			(type default)
		)
		(layer "In3.Cu")
	)
	(gr_line
		(start 25.90546 -19.05254)
		(end 25.90546 -19.03222)
		(stroke
			(width 1.016)
			(type default)
		)
		(layer "In3.Cu")
	)
	(gr_line
		(start 25.90546 -19.03222)
		(end 25.92324 -19.05)
		(stroke
			(width 1.016)
			(type default)
		)
		(layer "In3.Cu")
	)
	(gr_line
		(start 25.92324 -27.41168)
		(end 25.2603 -28.07462)
		(stroke
			(width 1.016)
			(type default)
		)
		(layer "In3.Cu")
	)
	(gr_line
		(start 25.92324 -19.05)
		(end 25.92324 -27.41168)
		(stroke
			(width 1.016)
			(type default)
		)
		(layer "In3.Cu")
	)
	(gr_line
		(start 26.32456 -132.75564)
		(end 26.32456 -119.07266)
		(stroke
			(width 0.508)
			(type default)
		)
		(layer "In3.Cu")
	)
	(gr_line
		(start 26.32456 -119.07266)
		(end 26.5811 -118.81612)
		(stroke
			(width 0.508)
			(type default)
		)
		(layer "In3.Cu")
	)
	(gr_line
		(start 26.792682 -182.865268)
		(end 26.792682 -181.388004)
		(stroke
			(width 1.016)
			(type default)
		)
		(layer "In3.Cu")
	)
	(gr_line
		(start 26.792682 -182.865268)
		(end 26.792682 -180.982874)
		(stroke
			(width 0.1524)
			(type default)
		)
		(layer "In3.Cu")
	)
	(gr_line
		(start 26.792682 -182.865268)
		(end 27.17038 -182.48757)
		(stroke
			(width 0.1524)
			(type default)
		)
		(layer "In3.Cu")
	)
	(gr_line
		(start 26.792682 -182.865268)
		(end 27.264868 -182.393082)
		(stroke
			(width 0.1524)
			(type default)
		)
		(layer "In3.Cu")
	)
	(gr_line
		(start 26.792682 -182.865268)
		(end 27.276552 -182.381398)
		(stroke
			(width 0.1524)
			(type default)
		)
		(layer "In3.Cu")
	)
	(gr_line
		(start 26.792682 -182.865268)
		(end 27.294332 -182.363618)
		(stroke
			(width 0.1524)
			(type default)
		)
		(layer "In3.Cu")
	)
	(gr_line
		(start 26.792682 -181.25694)
		(end 26.792682 -182.865268)
		(stroke
			(width 0.1524)
			(type default)
		)
		(layer "In3.Cu")
	)
	(gr_line
		(start 26.792682 -181.239414)
		(end 26.792682 -182.865268)
		(stroke
			(width 0.1524)
			(type default)
		)
		(layer "In3.Cu")
	)
	(gr_line
		(start 26.792682 -181.151022)
		(end 26.792682 -182.865268)
		(stroke
			(width 0.1524)
			(type default)
		)
		(layer "In3.Cu")
	)
	(gr_line
		(start 26.792682 -180.982874)
		(end 26.792682 -182.865268)
		(stroke
			(width 0.1524)
			(type default)
		)
		(layer "In3.Cu")
	)
	(gr_line
		(start 26.792682 -180.982874)
		(end 27.17038 -180.605176)
		(stroke
			(width 0.1524)
			(type default)
		)
		(layer "In3.Cu")
	)
	(gr_line
		(start 26.800048 -181.322726)
		(end 26.800048 -182.79999)
		(stroke
			(width 0.2)
			(type default)
		)
		(layer "In3.Cu")
	)
	(gr_line
		(start 26.800048 -25.322784)
		(end 26.800048 -26.800048)
		(stroke
			(width 1.016)
			(type default)
		)
		(layer "In3.Cu")
	)
	(gr_line
		(start 26.800048 -25.322784)
		(end 26.800048 -19.947128)
		(stroke
			(width 1.016)
			(type default)
		)
		(layer "In3.Cu")
	)
	(gr_line
		(start 26.800048 -19.947128)
		(end 25.90546 -19.05254)
		(stroke
			(width 1.016)
			(type default)
		)
		(layer "In3.Cu")
	)
	(gr_line
		(start 26.800302 -182.79999)
		(end 26.800302 -181.322726)
		(stroke
			(width 1.016)
			(type default)
		)
		(layer "In3.Cu")
	)
	(gr_line
		(start 26.800302 -182.79999)
		(end 26.800302 -181.322726)
		(stroke
			(width 2.032)
			(type default)
		)
		(layer "In3.Cu")
	)
	(gr_line
		(start 26.801064 -181.32044)
		(end 26.801064 -182.79872)
		(stroke
			(width 0.2)
			(type default)
		)
		(layer "In3.Cu")
	)
	(gr_line
		(start 27.17038 -182.48757)
		(end 26.792682 -182.865268)
		(stroke
			(width 0.1524)
			(type default)
		)
		(layer "In3.Cu")
	)
	(gr_line
		(start 27.17038 -182.48757)
		(end 27.17038 -180.605176)
		(stroke
			(width 0.1524)
			(type default)
		)
		(layer "In3.Cu")
	)
	(gr_line
		(start 27.17038 -182.455312)
		(end 27.17038 -180.605176)
		(stroke
			(width 0.1524)
			(type default)
		)
		(layer "In3.Cu")
	)
	(gr_arc
		(start 27.17038 -180.605176)
		(mid 24.992584 -174.365301)
		(end 22.814788 -180.605176)
		(stroke
			(width 1.016)
			(type default)
		)
		(layer "In3.Cu")
	)
	(gr_arc
		(start 27.17038 -180.605176)
		(mid 26.892013 -180.953405)
		(end 26.792682 -181.388004)
		(stroke
			(width 1.016)
			(type default)
		)
		(layer "In3.Cu")
	)
	(gr_arc
		(start 27.17038 -180.605176)
		(mid 26.892039 -180.953416)
		(end 26.792682 -181.388004)
		(stroke
			(width 1.016)
			(type default)
		)
		(layer "In3.Cu")
	)
	(gr_line
		(start 27.17038 -180.605176)
		(end 26.792682 -180.982874)
		(stroke
			(width 0.1524)
			(type default)
		)
		(layer "In3.Cu")
	)
	(gr_line
		(start 27.17038 -180.605176)
		(end 27.17038 -182.48757)
		(stroke
			(width 0.1524)
			(type default)
		)
		(layer "In3.Cu")
	)
	(gr_line
		(start 27.17038 -180.605176)
		(end 27.288236 -180.723032)
		(stroke
			(width 0.1524)
			(type default)
		)
		(layer "In3.Cu")
	)
	(gr_arc
		(start 27.176984 -180.53812)
		(mid 26.89979 -180.886397)
		(end 26.801064 -181.32044)
		(stroke
			(width 0.2)
			(type default)
		)
		(layer "In3.Cu")
	)
	(gr_arc
		(start 27.178 -180.539898)
		(mid 25.000077 -174.299864)
		(end 22.822154 -180.539898)
		(stroke
			(width 0.2)
			(type default)
		)
		(layer "In3.Cu")
	)
	(gr_arc
		(start 27.178 -180.539898)
		(mid 25.000204 -174.300023)
		(end 22.822408 -180.539898)
		(stroke
			(width 1.016)
			(type default)
		)
		(layer "In3.Cu")
	)
	(gr_arc
		(start 27.178 -180.539898)
		(mid 25.000204 -174.300023)
		(end 22.822408 -180.539898)
		(stroke
			(width 2.032)
			(type default)
		)
		(layer "In3.Cu")
	)
	(gr_arc
		(start 27.178 -180.539898)
		(mid 26.899555 -180.888117)
		(end 26.800048 -181.322726)
		(stroke
			(width 0.2)
			(type default)
		)
		(layer "In3.Cu")
	)
	(gr_arc
		(start 27.178 -180.539898)
		(mid 26.899661 -180.888138)
		(end 26.800302 -181.322726)
		(stroke
			(width 1.016)
			(type default)
		)
		(layer "In3.Cu")
	)
	(gr_arc
		(start 27.178 -180.539898)
		(mid 26.899661 -180.888138)
		(end 26.800302 -181.322726)
		(stroke
			(width 2.032)
			(type default)
		)
		(layer "In3.Cu")
	)
	(gr_arc
		(start 27.178 -24.539956)
		(mid 25.000077 -18.299922)
		(end 22.822154 -24.539956)
		(stroke
			(width 1.016)
			(type default)
		)
		(layer "In3.Cu")
	)
	(gr_arc
		(start 27.178 -24.539956)
		(mid 26.899475 -24.888146)
		(end 26.800048 -25.322784)
		(stroke
			(width 1.016)
			(type default)
		)
		(layer "In3.Cu")
	)
	(gr_arc
		(start 27.179524 -180.53812)
		(mid 25.000204 -174.298655)
		(end 22.820884 -180.53812)
		(stroke
			(width 0.2)
			(type default)
		)
		(layer "In3.Cu")
	)
	(gr_line
		(start 27.264868 -182.393082)
		(end 27.264868 -180.767228)
		(stroke
			(width 0.1524)
			(type default)
		)
		(layer "In3.Cu")
	)
	(gr_line
		(start 27.264868 -180.767228)
		(end 26.792682 -181.239414)
		(stroke
			(width 0.1524)
			(type default)
		)
		(layer "In3.Cu")
	)
	(gr_line
		(start 27.276552 -182.381398)
		(end 27.276552 -180.667152)
		(stroke
			(width 0.1524)
			(type default)
		)
		(layer "In3.Cu")
	)
	(gr_line
		(start 27.276552 -180.667152)
		(end 26.792682 -181.151022)
		(stroke
			(width 0.1524)
			(type default)
		)
		(layer "In3.Cu")
	)
	(gr_line
		(start 27.28468 -133.71576)
		(end 26.32456 -132.75564)
		(stroke
			(width 0.508)
			(type default)
		)
		(layer "In3.Cu")
	)
	(gr_line
		(start 27.288236 -182.573168)
		(end 27.17038 -182.455312)
		(stroke
			(width 0.1524)
			(type default)
		)
		(layer "In3.Cu")
	)
	(gr_line
		(start 27.288236 -180.723032)
		(end 27.288236 -182.573168)
		(stroke
			(width 0.1524)
			(type default)
		)
		(layer "In3.Cu")
	)
	(gr_line
		(start 27.294332 -182.363618)
		(end 27.294332 -180.75529)
		(stroke
			(width 0.1524)
			(type default)
		)
		(layer "In3.Cu")
	)
	(gr_line
		(start 27.294332 -180.75529)
		(end 26.792682 -181.25694)
		(stroke
			(width 0.1524)
			(type default)
		)
		(layer "In3.Cu")
	)
	(gr_line
		(start 27.30754 -24.410416)
		(end 27.178 -24.539956)
		(stroke
			(width 1.016)
			(type default)
		)
		(layer "In3.Cu")
	)
	(gr_line
		(start 27.30754 -20.22602)
		(end 27.30754 -24.410416)
		(stroke
			(width 1.016)
			(type default)
		)
		(layer "In3.Cu")
	)
	(gr_line
		(start 27.8003 -22.67204)
		(end 27.8003 -20.71878)
		(stroke
			(width 1.016)
			(type default)
		)
		(layer "In3.Cu")
	)
	(gr_line
		(start 27.8003 -20.71878)
		(end 27.30754 -20.22602)
		(stroke
			(width 1.016)
			(type default)
		)
		(layer "In3.Cu")
	)
	(gr_line
		(start 43.52544 -118.75262)
		(end 65.36182 -96.91624)
		(stroke
			(width 0.508)
			(type default)
		)
		(layer "In3.Cu")
	)
	(gr_line
		(start 44.38904 -177.77206)
		(end 45.0596 -178.44262)
		(stroke
			(width 0.508)
			(type default)
		)
		(layer "In3.Cu")
	)
	(gr_line
		(start 44.38904 -172.36694)
		(end 44.38904 -177.77206)
		(stroke
			(width 0.508)
			(type default)
		)
		(layer "In3.Cu")
	)
	(gr_line
		(start 45.0596 -178.44262)
		(end 78.181962 -178.44262)
		(stroke
			(width 0.508)
			(type default)
		)
		(layer "In3.Cu")
	)
	(gr_line
		(start 47.39894 -0.27432)
		(end 47.57166 -0.1016)
		(stroke
			(width 0.508)
			(type default)
		)
		(layer "In3.Cu")
	)
	(gr_line
		(start 55.45074 -133.71576)
		(end 27.28468 -133.71576)
		(stroke
			(width 0.508)
			(type default)
		)
		(layer "In3.Cu")
	)
	(gr_line
		(start 55.57774 -145.95856)
		(end 56.50738 -146.8882)
		(stroke
			(width 0.508)
			(type default)
		)
		(layer "In3.Cu")
	)
	(gr_line
		(start 55.57774 -126.42596)
		(end 55.57774 -145.95856)
		(stroke
			(width 0.508)
			(type default)
		)
		(layer "In3.Cu")
	)
	(gr_circle
		(center 55.600346 -71.398892)
		(end 56.000904 -71.398892)
		(stroke
			(width 0.2)
			(type default)
		)
		(fill no)
		(layer "In3.Cu")
	)
	(gr_line
		(start 56.40832 -125.59538)
		(end 55.57774 -126.42596)
		(stroke
			(width 0.508)
			(type default)
		)
		(layer "In3.Cu")
	)
	(gr_line
		(start 56.50738 -146.8882)
		(end 57.658 -146.8882)
		(stroke
			(width 0.508)
			(type default)
		)
		(layer "In3.Cu")
	)
	(gr_line
		(start 57.658 -146.8882)
		(end 79.30134 -146.8882)
		(stroke
			(width 0.508)
			(type default)
		)
		(layer "In3.Cu")
	)
	(gr_line
		(start 62.560454 -87.241634)
		(end 65.36182 -90.043)
		(stroke
			(width 0.508)
			(type default)
		)
		(layer "In3.Cu")
	)
	(gr_line
		(start 62.560454 -76.761086)
		(end 62.560454 -87.241634)
		(stroke
			(width 0.508)
			(type default)
		)
		(layer "In3.Cu")
	)
	(gr_line
		(start 64.359028 -74.962512)
		(end 62.560454 -76.761086)
		(stroke
			(width 0.508)
			(type default)
		)
		(layer "In3.Cu")
	)
	(gr_line
		(start 64.495934 -7.998206)
		(end 64.495934 -0.848106)
		(stroke
			(width 0.508)
			(type default)
		)
		(layer "In3.Cu")
	)
	(gr_line
		(start 64.495934 -0.848106)
		(end 64.805052 -0.538988)
		(stroke
			(width 0.508)
			(type default)
		)
		(layer "In3.Cu")
	)
	(gr_line
		(start 65.327276 -12.986258)
		(end 65.327276 -8.829548)
		(stroke
			(width 0.508)
			(type default)
		)
		(layer "In3.Cu")
	)
	(gr_line
		(start 65.327276 -8.829548)
		(end 64.495934 -7.998206)
		(stroke
			(width 0.508)
			(type default)
		)
		(layer "In3.Cu")
	)
	(gr_line
		(start 65.36182 -96.91624)
		(end 65.36182 -90.043)
		(stroke
			(width 0.508)
			(type default)
		)
		(layer "In3.Cu")
	)
	(gr_line
		(start 65.36182 -90.043)
		(end 86.0806 -90.043)
		(stroke
			(width 0.508)
			(type default)
		)
		(layer "In3.Cu")
	)
	(gr_line
		(start 65.401444 -10.262616)
		(end 69.540882 -10.262616)
		(stroke
			(width 0.508)
			(type default)
		)
		(layer "In3.Cu")
	)
	(gr_line
		(start 65.647824 -74.962512)
		(end 64.359028 -74.962512)
		(stroke
			(width 0.508)
			(type default)
		)
		(layer "In3.Cu")
	)
	(gr_line
		(start 66.354198 -14.01318)
		(end 65.327276 -12.986258)
		(stroke
			(width 0.508)
			(type default)
		)
		(layer "In3.Cu")
	)
	(gr_line
		(start 66.38544 -74.224896)
		(end 65.647824 -74.962512)
		(stroke
			(width 0.508)
			(type default)
		)
		(layer "In3.Cu")
	)
	(gr_line
		(start 66.38544 -69.88302)
		(end 66.38544 -74.224896)
		(stroke
			(width 0.508)
			(type default)
		)
		(layer "In3.Cu")
	)
	(gr_line
		(start 69.540882 -10.262616)
		(end 69.861938 -9.94156)
		(stroke
			(width 0.508)
			(type default)
		)
		(layer "In3.Cu")
	)
	(gr_line
		(start 69.861938 -9.94156)
		(end 69.861938 -8.508238)
		(stroke
			(width 0.508)
			(type default)
		)
		(layer "In3.Cu")
	)
	(gr_line
		(start 69.861938 -8.508238)
		(end 70.06844 -8.301736)
		(stroke
			(width 0.508)
			(type default)
		)
		(layer "In3.Cu")
	)
	(gr_line
		(start 70.06844 -8.301736)
		(end 73.255378 -8.301736)
		(stroke
			(width 0.508)
			(type default)
		)
		(layer "In3.Cu")
	)
	(gr_line
		(start 73.255378 -8.301736)
		(end 73.702926 -7.854188)
		(stroke
			(width 0.508)
			(type default)
		)
		(layer "In3.Cu")
	)
	(gr_line
		(start 73.702926 -7.854188)
		(end 73.702926 -0.584962)
		(stroke
			(width 0.508)
			(type default)
		)
		(layer "In3.Cu")
	)
	(gr_line
		(start 78.181962 -178.44262)
		(end 93.2053 -163.419282)
		(stroke
			(width 0.508)
			(type default)
		)
		(layer "In3.Cu")
	)
	(gr_line
		(start 78.91526 -69.8373)
		(end 80.06842 -68.68414)
		(stroke
			(width 0.508)
			(type default)
		)
		(layer "In3.Cu")
	)
	(gr_line
		(start 79.30134 -146.8882)
		(end 80.7085 -145.48104)
		(stroke
			(width 0.508)
			(type default)
		)
		(layer "In3.Cu")
	)
	(gr_line
		(start 80.06842 -68.68414)
		(end 80.06842 -56.02478)
		(stroke
			(width 0.508)
			(type default)
		)
		(layer "In3.Cu")
	)
	(gr_line
		(start 80.06842 -56.02478)
		(end 84.4804 -51.6128)
		(stroke
			(width 0.508)
			(type default)
		)
		(layer "In3.Cu")
	)
	(gr_line
		(start 80.7085 -145.48104)
		(end 80.7085 -142.12316)
		(stroke
			(width 0.508)
			(type default)
		)
		(layer "In3.Cu")
	)
	(gr_line
		(start 80.7085 -142.12316)
		(end 80.96504 -141.86662)
		(stroke
			(width 0.508)
			(type default)
		)
		(layer "In3.Cu")
	)
	(gr_line
		(start 80.96504 -141.86662)
		(end 84.35594 -141.86662)
		(stroke
			(width 0.508)
			(type default)
		)
		(layer "In3.Cu")
	)
	(gr_line
		(start 81.82864 -125.59538)
		(end 56.40832 -125.59538)
		(stroke
			(width 0.508)
			(type default)
		)
		(layer "In3.Cu")
	)
	(gr_circle
		(center 82.278474 -149.792182)
		(end 82.807302 -149.792182)
		(stroke
			(width 0.2)
			(type default)
		)
		(fill no)
		(layer "In3.Cu")
	)
	(gr_line
		(start 82.3722 -135.92302)
		(end 82.3722 -126.13894)
		(stroke
			(width 0.508)
			(type default)
		)
		(layer "In3.Cu")
	)
	(gr_line
		(start 82.3722 -126.13894)
		(end 81.82864 -125.59538)
		(stroke
			(width 0.508)
			(type default)
		)
		(layer "In3.Cu")
	)
	(gr_line
		(start 82.72272 -136.27354)
		(end 82.3722 -135.92302)
		(stroke
			(width 0.508)
			(type default)
		)
		(layer "In3.Cu")
	)
	(gr_line
		(start 83.064604 -208.699608)
		(end 12.864084 -208.699608)
		(stroke
			(width 2.032)
			(type default)
		)
		(layer "In3.Cu")
	)
	(gr_line
		(start 83.064604 -208.699608)
		(end 83.54441 -208.222342)
		(stroke
			(width 2.032)
			(type default)
		)
		(layer "In3.Cu")
	)
	(gr_line
		(start 83.54441 -208.222342)
		(end 83.559904 -208.206848)
		(stroke
			(width 2.032)
			(type default)
		)
		(layer "In3.Cu")
	)
	(gr_line
		(start 83.559904 -208.206848)
		(end 83.559904 -201.250042)
		(stroke
			(width 2.032)
			(type default)
		)
		(layer "In3.Cu")
	)
	(gr_line
		(start 84.12988 -136.27354)
		(end 82.72272 -136.27354)
		(stroke
			(width 0.508)
			(type default)
		)
		(layer "In3.Cu")
	)
	(gr_line
		(start 84.35594 -141.86662)
		(end 84.76996 -141.4526)
		(stroke
			(width 0.508)
			(type default)
		)
		(layer "In3.Cu")
	)
	(gr_line
		(start 84.4804 -51.6128)
		(end 84.4804 -14.26972)
		(stroke
			(width 0.508)
			(type default)
		)
		(layer "In3.Cu")
	)
	(gr_line
		(start 84.76996 -141.4526)
		(end 84.76996 -136.91362)
		(stroke
			(width 0.508)
			(type default)
		)
		(layer "In3.Cu")
	)
	(gr_line
		(start 84.76996 -136.91362)
		(end 84.12988 -136.27354)
		(stroke
			(width 0.508)
			(type default)
		)
		(layer "In3.Cu")
	)
	(gr_line
		(start 85.460078 -208.196942)
		(end 85.464904 -208.201768)
		(stroke
			(width 2.032)
			(type default)
		)
		(layer "In3.Cu")
	)
	(gr_arc
		(start 85.460078 -201.250042)
		(mid 84.509991 -200.299828)
		(end 83.559904 -201.250042)
		(stroke
			(width 2.032)
			(type default)
		)
		(layer "In3.Cu")
	)
	(gr_line
		(start 85.460078 -201.250042)
		(end 85.460078 -208.196942)
		(stroke
			(width 2.032)
			(type default)
		)
		(layer "In3.Cu")
	)
	(gr_line
		(start 85.464904 -208.201768)
		(end 85.965284 -208.699608)
		(stroke
			(width 2.032)
			(type default)
		)
		(layer "In3.Cu")
	)
	(gr_line
		(start 86.0806 -90.043)
		(end 91.51366 -95.47606)
		(stroke
			(width 0.508)
			(type default)
		)
		(layer "In3.Cu")
	)
	(gr_line
		(start 90.58656 -136.91362)
		(end 84.76996 -136.91362)
		(stroke
			(width 0.508)
			(type default)
		)
		(layer "In3.Cu")
	)
	(gr_line
		(start 91.51366 -109.47908)
		(end 99.18954 -117.15496)
		(stroke
			(width 0.508)
			(type default)
		)
		(layer "In3.Cu")
	)
	(gr_line
		(start 91.51366 -95.47606)
		(end 91.51366 -109.47908)
		(stroke
			(width 0.508)
			(type default)
		)
		(layer "In3.Cu")
	)
	(gr_line
		(start 93.2053 -163.419282)
		(end 93.2053 -148.630132)
		(stroke
			(width 0.508)
			(type default)
		)
		(layer "In3.Cu")
	)
	(gr_line
		(start 93.2053 -148.630132)
		(end 93.893132 -147.9423)
		(stroke
			(width 0.508)
			(type default)
		)
		(layer "In3.Cu")
	)
	(gr_line
		(start 93.893132 -147.9423)
		(end 102.51186 -147.9423)
		(stroke
			(width 0.508)
			(type default)
		)
		(layer "In3.Cu")
	)
	(gr_line
		(start 96.165924 -208.699608)
		(end 85.965284 -208.699608)
		(stroke
			(width 2.032)
			(type default)
		)
		(layer "In3.Cu")
	)
	(gr_line
		(start 96.165924 -208.699608)
		(end 96.659954 -208.205578)
		(stroke
			(width 2.032)
			(type default)
		)
		(layer "In3.Cu")
	)
	(gr_line
		(start 96.659954 -208.205578)
		(end 96.659954 -188.250068)
		(stroke
			(width 2.032)
			(type default)
		)
		(layer "In3.Cu")
	)
	(gr_line
		(start 96.66224 -130.83794)
		(end 90.58656 -136.91362)
		(stroke
			(width 0.508)
			(type default)
		)
		(layer "In3.Cu")
	)
	(gr_line
		(start 97.78238 -130.83794)
		(end 96.66224 -130.83794)
		(stroke
			(width 0.508)
			(type default)
		)
		(layer "In3.Cu")
	)
	(gr_line
		(start 98.83648 -131.89204)
		(end 97.78238 -130.83794)
		(stroke
			(width 0.508)
			(type default)
		)
		(layer "In3.Cu")
	)
	(gr_line
		(start 99.003358 -158.888938)
		(end 100.038154 -159.923734)
		(stroke
			(width 0.508)
			(type default)
		)
		(layer "In3.Cu")
	)
	(gr_line
		(start 99.003358 -153.174192)
		(end 99.003358 -158.888938)
		(stroke
			(width 0.508)
			(type default)
		)
		(layer "In3.Cu")
	)
	(gr_line
		(start 99.152202 -153.025348)
		(end 99.003358 -153.174192)
		(stroke
			(width 0.508)
			(type default)
		)
		(layer "In3.Cu")
	)
	(gr_line
		(start 99.18954 -117.15496)
		(end 120.54332 -117.15496)
		(stroke
			(width 0.508)
			(type default)
		)
		(layer "In3.Cu")
	)
	(gr_line
		(start 100.038154 -159.923734)
		(end 104.530652 -159.923734)
		(stroke
			(width 0.508)
			(type default)
		)
		(layer "In3.Cu")
	)
	(gr_line
		(start 101.19487 -153.025348)
		(end 99.152202 -153.025348)
		(stroke
			(width 0.508)
			(type default)
		)
		(layer "In3.Cu")
	)
	(gr_line
		(start 101.260402 -152.959816)
		(end 101.19487 -153.025348)
		(stroke
			(width 0.508)
			(type default)
		)
		(layer "In3.Cu")
	)
	(gr_line
		(start 101.512878 -152.70734)
		(end 101.260402 -152.959816)
		(stroke
			(width 0.381)
			(type default)
		)
		(layer "In3.Cu")
	)
	(gr_line
		(start 102.51186 -147.9423)
		(end 102.7049 -148.13534)
		(stroke
			(width 0.508)
			(type default)
		)
		(layer "In3.Cu")
	)
	(gr_line
		(start 102.7049 -152.605232)
		(end 102.710488 -152.61082)
		(stroke
			(width 0.508)
			(type default)
		)
		(layer "In3.Cu")
	)
	(gr_line
		(start 102.7049 -148.13534)
		(end 102.7049 -152.605232)
		(stroke
			(width 0.508)
			(type default)
		)
		(layer "In3.Cu")
	)
	(gr_line
		(start 103.359966 -208.19745)
		(end 103.364284 -208.201768)
		(stroke
			(width 2.032)
			(type default)
		)
		(layer "In3.Cu")
	)
	(gr_arc
		(start 103.359966 -188.250068)
		(mid 100.00996 -184.900062)
		(end 96.659954 -188.250068)
		(stroke
			(width 2.032)
			(type default)
		)
		(layer "In3.Cu")
	)
	(gr_line
		(start 103.359966 -188.250068)
		(end 103.359966 -208.19745)
		(stroke
			(width 2.032)
			(type default)
		)
		(layer "In3.Cu")
	)
	(gr_line
		(start 103.364284 -208.201768)
		(end 103.864664 -208.699608)
		(stroke
			(width 2.032)
			(type default)
		)
		(layer "In3.Cu")
	)
	(gr_line
		(start 103.66502 -152.70734)
		(end 101.512878 -152.70734)
		(stroke
			(width 0.381)
			(type default)
		)
		(layer "In3.Cu")
	)
	(gr_line
		(start 104.530652 -159.923734)
		(end 107.511596 -156.94279)
		(stroke
			(width 0.508)
			(type default)
		)
		(layer "In3.Cu")
	)
	(gr_line
		(start 105.000044 -95.79991)
		(end 105.000044 -95.800164)
		(stroke
			(width 10.541)
			(type default)
		)
		(layer "In3.Cu")
	)
	(gr_line
		(start 105.35666 -68.68414)
		(end 80.06842 -68.68414)
		(stroke
			(width 0.508)
			(type default)
		)
		(layer "In3.Cu")
	)
	(gr_line
		(start 107.511596 -156.94279)
		(end 107.511596 -152.959562)
		(stroke
			(width 0.508)
			(type default)
		)
		(layer "In3.Cu")
	)
	(gr_line
		(start 109.03458 -152.70734)
		(end 103.66502 -152.70734)
		(stroke
			(width 0.508)
			(type default)
		)
		(layer "In3.Cu")
	)
	(gr_line
		(start 109.41812 -163.160456)
		(end 109.41812 -153.09088)
		(stroke
			(width 0.508)
			(type default)
		)
		(layer "In3.Cu")
	)
	(gr_line
		(start 109.41812 -153.09088)
		(end 109.03458 -152.70734)
		(stroke
			(width 0.508)
			(type default)
		)
		(layer "In3.Cu")
	)
	(gr_line
		(start 109.41812 -153.09088)
		(end 112.16894 -153.09088)
		(stroke
			(width 0.508)
			(type default)
		)
		(layer "In3.Cu")
	)
	(gr_line
		(start 111.36884 -131.89204)
		(end 98.83648 -131.89204)
		(stroke
			(width 0.508)
			(type default)
		)
		(layer "In3.Cu")
	)
	(gr_line
		(start 112.16894 -153.09088)
		(end 113.09604 -152.16378)
		(stroke
			(width 0.508)
			(type default)
		)
		(layer "In3.Cu")
	)
	(gr_line
		(start 113.09604 -152.16378)
		(end 113.09604 -133.61924)
		(stroke
			(width 0.508)
			(type default)
		)
		(layer "In3.Cu")
	)
	(gr_line
		(start 113.09604 -133.61924)
		(end 111.36884 -131.89204)
		(stroke
			(width 0.508)
			(type default)
		)
		(layer "In3.Cu")
	)
	(gr_line
		(start 120.54332 -117.15496)
		(end 122.27052 -115.42776)
		(stroke
			(width 0.508)
			(type default)
		)
		(layer "In3.Cu")
	)
	(gr_line
		(start 122.27052 -115.42776)
		(end 122.27052 -85.598)
		(stroke
			(width 0.508)
			(type default)
		)
		(layer "In3.Cu")
	)
	(gr_line
		(start 122.27052 -85.598)
		(end 105.35666 -68.68414)
		(stroke
			(width 0.508)
			(type default)
		)
		(layer "In3.Cu")
	)
	(gr_line
		(start 124.540264 -178.2826)
		(end 109.41812 -163.160456)
		(stroke
			(width 0.508)
			(type default)
		)
		(layer "In3.Cu")
	)
	(gr_line
		(start 158.39948 -178.2826)
		(end 124.540264 -178.2826)
		(stroke
			(width 0.508)
			(type default)
		)
		(layer "In3.Cu")
	)
	(gr_line
		(start 170.93184 -14.01318)
		(end 66.354198 -14.01318)
		(stroke
			(width 0.508)
			(type default)
		)
		(layer "In3.Cu")
	)
	(gr_line
		(start 172.1739 -179.02682)
		(end 172.1739 -176.44618)
		(stroke
			(width 1.016)
			(type default)
		)
		(layer "In3.Cu")
	)
	(gr_line
		(start 172.1739 -176.44618)
		(end 172.744638 -175.875442)
		(stroke
			(width 1.016)
			(type default)
		)
		(layer "In3.Cu")
	)
	(gr_line
		(start 172.212 -23.1267)
		(end 172.212 -20.33778)
		(stroke
			(width 1.016)
			(type default)
		)
		(layer "In3.Cu")
	)
	(gr_line
		(start 172.212 -20.33778)
		(end 172.744638 -19.805142)
		(stroke
			(width 1.016)
			(type default)
		)
		(layer "In3.Cu")
	)
	(gr_line
		(start 172.744638 -180.42636)
		(end 172.744638 -179.597558)
		(stroke
			(width 1.016)
			(type default)
		)
		(layer "In3.Cu")
	)
	(gr_line
		(start 172.744638 -179.597558)
		(end 172.1739 -179.02682)
		(stroke
			(width 1.016)
			(type default)
		)
		(layer "In3.Cu")
	)
	(gr_line
		(start 172.744638 -175.875442)
		(end 172.744638 -180.42636)
		(stroke
			(width 1.016)
			(type default)
		)
		(layer "In3.Cu")
	)
	(gr_line
		(start 172.744638 -24.426164)
		(end 172.744638 -19.805142)
		(stroke
			(width 1.016)
			(type default)
		)
		(layer "In3.Cu")
	)
	(gr_line
		(start 172.744638 -19.805142)
		(end 173.38548 -19.1643)
		(stroke
			(width 1.016)
			(type default)
		)
		(layer "In3.Cu")
	)
	(gr_line
		(start 172.744638 -19.805142)
		(end 176.900078 -23.960582)
		(stroke
			(width 1.016)
			(type default)
		)
		(layer "In3.Cu")
	)
	(gr_line
		(start 173.100238 -182.749952)
		(end 173.100238 -181.1909)
		(stroke
			(width 1.016)
			(type default)
		)
		(layer "In3.Cu")
	)
	(gr_arc
		(start 173.100238 -182.749952)
		(mid 175.000158 -184.649872)
		(end 176.900078 -182.749952)
		(stroke
			(width 1.016)
			(type default)
		)
		(layer "In3.Cu")
	)
	(gr_arc
		(start 173.100238 -181.1909)
		(mid 173.006986 -180.769307)
		(end 172.744638 -180.42636)
		(stroke
			(width 1.016)
			(type default)
		)
		(layer "In3.Cu")
	)
	(gr_arc
		(start 173.100238 -26.75001)
		(mid 175.000158 -28.64993)
		(end 176.900078 -26.75001)
		(stroke
			(width 1.016)
			(type default)
		)
		(layer "In3.Cu")
	)
	(gr_arc
		(start 173.100238 -25.190958)
		(mid 173.006976 -24.769264)
		(end 172.744638 -24.426164)
		(stroke
			(width 1.016)
			(type default)
		)
		(layer "In3.Cu")
	)
	(gr_line
		(start 173.100238 -25.190958)
		(end 173.100238 -26.75001)
		(stroke
			(width 1.016)
			(type default)
		)
		(layer "In3.Cu")
	)
	(gr_line
		(start 173.38548 -24.905716)
		(end 173.100238 -25.190958)
		(stroke
			(width 1.016)
			(type default)
		)
		(layer "In3.Cu")
	)
	(gr_line
		(start 173.38548 -19.1643)
		(end 173.38548 -24.905716)
		(stroke
			(width 1.016)
			(type default)
		)
		(layer "In3.Cu")
	)
	(gr_line
		(start 173.53788 -183.00954)
		(end 173.53788 -175.0822)
		(stroke
			(width 1.016)
			(type default)
		)
		(layer "In3.Cu")
	)
	(gr_line
		(start 173.53788 -175.0822)
		(end 172.744638 -175.875442)
		(stroke
			(width 1.016)
			(type default)
		)
		(layer "In3.Cu")
	)
	(gr_line
		(start 174.05096 -28.05684)
		(end 174.05096 -18.91792)
		(stroke
			(width 1.016)
			(type default)
		)
		(layer "In3.Cu")
	)
	(gr_line
		(start 174.05096 -18.91792)
		(end 174.08906 -18.87982)
		(stroke
			(width 1.016)
			(type default)
		)
		(layer "In3.Cu")
	)
	(gr_line
		(start 174.065184 -208.699608)
		(end 103.864664 -208.699608)
		(stroke
			(width 2.032)
			(type default)
		)
		(layer "In3.Cu")
	)
	(gr_line
		(start 174.08906 -18.87982)
		(end 174.76978 -18.87982)
		(stroke
			(width 1.016)
			(type default)
		)
		(layer "In3.Cu")
	)
	(gr_line
		(start 174.10684 -183.5785)
		(end 173.53788 -183.00954)
		(stroke
			(width 1.016)
			(type default)
		)
		(layer "In3.Cu")
	)
	(gr_line
		(start 174.10684 -174.8917)
		(end 174.10684 -183.5785)
		(stroke
			(width 1.016)
			(type default)
		)
		(layer "In3.Cu")
	)
	(gr_line
		(start 174.27702 -175.72736)
		(end 174.27702 -174.72152)
		(stroke
			(width 1.016)
			(type default)
		)
		(layer "In3.Cu")
	)
	(gr_line
		(start 174.27702 -174.72152)
		(end 174.10684 -174.8917)
		(stroke
			(width 1.016)
			(type default)
		)
		(layer "In3.Cu")
	)
	(gr_line
		(start 174.342552 -208.423764)
		(end 174.065184 -208.699608)
		(stroke
			(width 2.032)
			(type default)
		)
		(layer "In3.Cu")
	)
	(gr_line
		(start 174.559976 -208.20634)
		(end 174.342552 -208.423764)
		(stroke
			(width 2.032)
			(type default)
		)
		(layer "In3.Cu")
	)
	(gr_line
		(start 174.559976 -201.250042)
		(end 174.559976 -208.20634)
		(stroke
			(width 2.032)
			(type default)
		)
		(layer "In3.Cu")
	)
	(gr_line
		(start 174.7139 -27.86634)
		(end 174.7139 -19.60118)
		(stroke
			(width 1.016)
			(type default)
		)
		(layer "In3.Cu")
	)
	(gr_line
		(start 174.7139 -19.60118)
		(end 175.35906 -18.95602)
		(stroke
			(width 1.016)
			(type default)
		)
		(layer "In3.Cu")
	)
	(gr_line
		(start 174.752 -184.43194)
		(end 174.752 -176.10582)
		(stroke
			(width 1.016)
			(type default)
		)
		(layer "In3.Cu")
	)
	(gr_line
		(start 174.752 -184.43194)
		(end 174.752 -174.66564)
		(stroke
			(width 1.016)
			(type default)
		)
		(layer "In3.Cu")
	)
	(gr_line
		(start 174.752 -176.10582)
		(end 175.9458 -174.91202)
		(stroke
			(width 1.016)
			(type default)
		)
		(layer "In3.Cu")
	)
	(gr_line
		(start 174.752 -174.66564)
		(end 174.9806 -174.66564)
		(stroke
			(width 1.016)
			(type default)
		)
		(layer "In3.Cu")
	)
	(gr_line
		(start 174.76978 -18.87982)
		(end 174.80788 -18.91792)
		(stroke
			(width 1.016)
			(type default)
		)
		(layer "In3.Cu")
	)
	(gr_line
		(start 174.80788 -27.77236)
		(end 174.7139 -27.86634)
		(stroke
			(width 1.016)
			(type default)
		)
		(layer "In3.Cu")
	)
	(gr_line
		(start 174.80788 -18.91792)
		(end 174.80788 -27.77236)
		(stroke
			(width 1.016)
			(type default)
		)
		(layer "In3.Cu")
	)
	(gr_line
		(start 174.9806 -174.66564)
		(end 175.39716 -175.0822)
		(stroke
			(width 1.016)
			(type default)
		)
		(layer "In3.Cu")
	)
	(gr_line
		(start 175.35906 -18.95602)
		(end 175.45304 -19.05)
		(stroke
			(width 1.016)
			(type default)
		)
		(layer "In3.Cu")
	)
	(gr_line
		(start 175.39716 -183.78678)
		(end 174.752 -184.43194)
		(stroke
			(width 1.016)
			(type default)
		)
		(layer "In3.Cu")
	)
	(gr_line
		(start 175.39716 -175.0822)
		(end 175.39716 -183.78678)
		(stroke
			(width 1.016)
			(type default)
		)
		(layer "In3.Cu")
	)
	(gr_line
		(start 175.45304 -27.96286)
		(end 175.92802 -27.48788)
		(stroke
			(width 1.016)
			(type default)
		)
		(layer "In3.Cu")
	)
	(gr_line
		(start 175.45304 -19.05)
		(end 175.45304 -27.96286)
		(stroke
			(width 1.016)
			(type default)
		)
		(layer "In3.Cu")
	)
	(gr_line
		(start 175.92802 -27.48788)
		(end 175.92802 -19.14398)
		(stroke
			(width 1.016)
			(type default)
		)
		(layer "In3.Cu")
	)
	(gr_line
		(start 175.92802 -19.14398)
		(end 176.19218 -18.87982)
		(stroke
			(width 1.016)
			(type default)
		)
		(layer "In3.Cu")
	)
	(gr_line
		(start 175.9458 -174.91202)
		(end 175.96612 -174.93234)
		(stroke
			(width 1.016)
			(type default)
		)
		(layer "In3.Cu")
	)
	(gr_line
		(start 175.96612 -183.40578)
		(end 176.53508 -182.83682)
		(stroke
			(width 1.016)
			(type default)
		)
		(layer "In3.Cu")
	)
	(gr_line
		(start 175.96612 -174.93234)
		(end 175.96612 -183.40578)
		(stroke
			(width 1.016)
			(type default)
		)
		(layer "In3.Cu")
	)
	(gr_line
		(start 176.19218 -18.87982)
		(end 176.900078 -19.587718)
		(stroke
			(width 1.016)
			(type default)
		)
		(layer "In3.Cu")
	)
	(gr_line
		(start 176.459896 -208.19618)
		(end 176.459896 -201.250042)
		(stroke
			(width 2.032)
			(type default)
		)
		(layer "In3.Cu")
	)
	(gr_arc
		(start 176.459896 -201.250042)
		(mid 175.509936 -200.300082)
		(end 174.559976 -201.250042)
		(stroke
			(width 2.032)
			(type default)
		)
		(layer "In3.Cu")
	)
	(gr_line
		(start 176.465484 -208.201768)
		(end 176.459896 -208.19618)
		(stroke
			(width 2.032)
			(type default)
		)
		(layer "In3.Cu")
	)
	(gr_line
		(start 176.53508 -182.83682)
		(end 176.53508 -175.387)
		(stroke
			(width 1.016)
			(type default)
		)
		(layer "In3.Cu")
	)
	(gr_line
		(start 176.53508 -175.387)
		(end 177.00752 -175.85944)
		(stroke
			(width 1.016)
			(type default)
		)
		(layer "In3.Cu")
	)
	(gr_line
		(start 176.900078 -181.1909)
		(end 176.900078 -182.749952)
		(stroke
			(width 1.016)
			(type default)
		)
		(layer "In3.Cu")
	)
	(gr_line
		(start 176.900078 -25.190958)
		(end 176.900078 -26.75001)
		(stroke
			(width 1.016)
			(type default)
		)
		(layer "In3.Cu")
	)
	(gr_line
		(start 176.900078 -24.071072)
		(end 177.255424 -24.426418)
		(stroke
			(width 1.016)
			(type default)
		)
		(layer "In3.Cu")
	)
	(gr_line
		(start 176.900078 -24.071072)
		(end 177.57648 -23.39467)
		(stroke
			(width 1.016)
			(type default)
		)
		(layer "In3.Cu")
	)
	(gr_line
		(start 176.900078 -23.960582)
		(end 176.900078 -24.071072)
		(stroke
			(width 1.016)
			(type default)
		)
		(layer "In3.Cu")
	)
	(gr_line
		(start 176.900078 -19.587718)
		(end 176.900078 -25.190958)
		(stroke
			(width 1.016)
			(type default)
		)
		(layer "In3.Cu")
	)
	(gr_line
		(start 176.900078 -19.587718)
		(end 176.900078 -24.071072)
		(stroke
			(width 1.016)
			(type default)
		)
		(layer "In3.Cu")
	)
	(gr_line
		(start 176.916334 -144.322546)
		(end 181.832504 -139.406376)
		(stroke
			(width 0.508)
			(type default)
		)
		(layer "In3.Cu")
	)
	(gr_line
		(start 176.94148 -159.7406)
		(end 158.39948 -178.2826)
		(stroke
			(width 0.508)
			(type default)
		)
		(layer "In3.Cu")
	)
	(gr_line
		(start 176.94148 -144.22374)
		(end 176.94148 -159.7406)
		(stroke
			(width 0.508)
			(type default)
		)
		(layer "In3.Cu")
	)
	(gr_line
		(start 176.94148 -114.15903)
		(end 176.94148 -20.02282)
		(stroke
			(width 0.508)
			(type default)
		)
		(layer "In3.Cu")
	)
	(gr_line
		(start 176.94148 -20.02282)
		(end 170.93184 -14.01318)
		(stroke
			(width 0.508)
			(type default)
		)
		(layer "In3.Cu")
	)
	(gr_line
		(start 176.965864 -208.699608)
		(end 176.465484 -208.201768)
		(stroke
			(width 2.032)
			(type default)
		)
		(layer "In3.Cu")
	)
	(gr_line
		(start 177.00752 -179.74818)
		(end 177.72888 -179.02682)
		(stroke
			(width 1.016)
			(type default)
		)
		(layer "In3.Cu")
	)
	(gr_line
		(start 177.00752 -175.85944)
		(end 177.00752 -179.74818)
		(stroke
			(width 1.016)
			(type default)
		)
		(layer "In3.Cu")
	)
	(gr_arc
		(start 177.255424 -180.42636)
		(mid 175.000031 -174.249895)
		(end 172.744638 -180.42636)
		(stroke
			(width 1.016)
			(type default)
		)
		(layer "In3.Cu")
	)
	(gr_arc
		(start 177.255424 -24.426418)
		(mid 175.000255 -18.250116)
		(end 172.744638 -24.426418)
		(stroke
			(width 1.016)
			(type default)
		)
		(layer "In3.Cu")
	)
	(gr_arc
		(start 177.255678 -180.42636)
		(mid 176.993377 -180.769332)
		(end 176.900078 -181.1909)
		(stroke
			(width 1.016)
			(type default)
		)
		(layer "In3.Cu")
	)
	(gr_arc
		(start 177.255678 -24.426164)
		(mid 176.993325 -24.769252)
		(end 176.900078 -25.190958)
		(stroke
			(width 1.016)
			(type default)
		)
		(layer "In3.Cu")
	)
	(gr_line
		(start 177.42408 -20.34032)
		(end 177.42408 -22.88032)
		(stroke
			(width 1.016)
			(type default)
		)
		(layer "In3.Cu")
	)
	(gr_line
		(start 177.57648 -23.39467)
		(end 177.57648 -20.18792)
		(stroke
			(width 1.016)
			(type default)
		)
		(layer "In3.Cu")
	)
	(gr_line
		(start 177.57648 -20.18792)
		(end 177.42408 -20.34032)
		(stroke
			(width 1.016)
			(type default)
		)
		(layer "In3.Cu")
	)
	(gr_line
		(start 177.65268 -179.10302)
		(end 174.27702 -175.72736)
		(stroke
			(width 1.016)
			(type default)
		)
		(layer "In3.Cu")
	)
	(gr_line
		(start 177.65268 -176.10836)
		(end 177.65268 -179.10302)
		(stroke
			(width 1.016)
			(type default)
		)
		(layer "In3.Cu")
	)
	(gr_line
		(start 177.72888 -179.02682)
		(end 177.72888 -176.03216)
		(stroke
			(width 1.016)
			(type default)
		)
		(layer "In3.Cu")
	)
	(gr_line
		(start 177.72888 -176.03216)
		(end 177.65268 -176.10836)
		(stroke
			(width 1.016)
			(type default)
		)
		(layer "In3.Cu")
	)
	(gr_line
		(start 181.832504 -139.406376)
		(end 181.832504 -119.050054)
		(stroke
			(width 0.508)
			(type default)
		)
		(layer "In3.Cu")
	)
	(gr_line
		(start 181.832504 -119.050054)
		(end 176.94148 -114.15903)
		(stroke
			(width 0.508)
			(type default)
		)
		(layer "In3.Cu")
	)
	(gr_line
		(start 187.163964 -208.699608)
		(end 176.965864 -208.699608)
		(stroke
			(width 2.032)
			(type default)
		)
		(layer "In3.Cu")
	)
	(gr_line
		(start 187.62853 -208.237328)
		(end 187.163964 -208.699608)
		(stroke
			(width 2.032)
			(type default)
		)
		(layer "In3.Cu")
	)
	(gr_line
		(start 187.660026 -208.205832)
		(end 187.62853 -208.237328)
		(stroke
			(width 2.032)
			(type default)
		)
		(layer "In3.Cu")
	)
	(gr_line
		(start 187.660026 -172.699934)
		(end 187.660026 -208.205832)
		(stroke
			(width 2.032)
			(type default)
		)
		(layer "In3.Cu")
	)
	(gr_arc
		(start 189.660022 -170.699938)
		(mid 188.245811 -171.285723)
		(end 187.660026 -172.699934)
		(stroke
			(width 2.032)
			(type default)
		)
		(layer "In3.Cu")
	)
	(gr_arc
		(start 196.699886 -72.650096)
		(mid 197.139352 -73.71068)
		(end 198.20001 -74.149966)
		(stroke
			(width 2.032)
			(type default)
		)
		(layer "In3.Cu")
	)
	(gr_line
		(start 196.699886 -33.64992)
		(end 196.699886 -72.650096)
		(stroke
			(width 2.032)
			(type default)
		)
		(layer "In3.Cu")
	)
	(gr_line
		(start 198.000112 -170.699938)
		(end 189.660022 -170.699938)
		(stroke
			(width 2.032)
			(type default)
		)
		(layer "In3.Cu")
	)
	(gr_arc
		(start 198.000112 -170.699938)
		(mid 199.41433 -170.114151)
		(end 200.000108 -168.699942)
		(stroke
			(width 2.032)
			(type default)
		)
		(layer "In3.Cu")
	)
	(gr_line
		(start 198.20001 -74.149966)
		(end 198.499984 -74.149966)
		(stroke
			(width 2.032)
			(type default)
		)
		(layer "In3.Cu")
	)
	(gr_arc
		(start 198.20001 -32.15005)
		(mid 197.139352 -32.589336)
		(end 196.699886 -33.64992)
		(stroke
			(width 2.032)
			(type default)
		)
		(layer "In3.Cu")
	)
	(gr_line
		(start 198.499984 -32.15005)
		(end 198.20001 -32.15005)
		(stroke
			(width 2.032)
			(type default)
		)
		(layer "In3.Cu")
	)
	(gr_arc
		(start 198.499984 -32.15005)
		(mid 199.560751 -31.710681)
		(end 200.000108 -30.649926)
		(stroke
			(width 2.032)
			(type default)
		)
		(layer "In3.Cu")
	)
	(gr_arc
		(start 200.000108 -75.65009)
		(mid 199.560727 -74.589354)
		(end 198.499984 -74.149966)
		(stroke
			(width 2.032)
			(type default)
		)
		(layer "In3.Cu")
	)
	(gr_line
		(start 200.000108 -75.65009)
		(end 200.000108 -168.699942)
		(stroke
			(width 2.032)
			(type default)
		)
		(layer "In3.Cu")
	)
	(gr_arc
		(start 200.000108 -1.999996)
		(mid 199.414322 -0.585784)
		(end 198.000112 0)
		(stroke
			(width 2.032)
			(type default)
		)
		(layer "In3.Cu")
	)
	(gr_line
		(start 200.000108 -1.999996)
		(end 200.000108 -30.649926)
		(stroke
			(width 2.032)
			(type default)
		)
		(layer "In3.Cu")
	)
	(gr_line
		(start -18.237962 -206.70012)
		(end -18.237962 -1.999996)
		(stroke
			(width 2.032)
			(type default)
		)
		(layer "In4.Cu")
	)
	(gr_arc
		(start -18.237962 -206.70012)
		(mid -17.652177 -208.114331)
		(end -16.237966 -208.700116)
		(stroke
			(width 2.032)
			(type default)
		)
		(layer "In4.Cu")
	)
	(gr_arc
		(start -16.237966 0)
		(mid -17.652177 -0.585785)
		(end -18.237962 -1.999996)
		(stroke
			(width 2.032)
			(type default)
		)
		(layer "In4.Cu")
	)
	(gr_line
		(start -16.237966 0)
		(end -1.999996 0)
		(stroke
			(width 2.032)
			(type default)
		)
		(layer "In4.Cu")
	)
	(gr_line
		(start -1.999996 -160.375092)
		(end -1.999742 -160.375092)
		(stroke
			(width 2.032)
			(type default)
		)
		(layer "In4.Cu")
	)
	(gr_line
		(start -1.999996 0)
		(end -1.999996 -160.375092)
		(stroke
			(width 2.032)
			(type default)
		)
		(layer "In4.Cu")
	)
	(gr_line
		(start -1.999742 -208.700116)
		(end -16.237966 -208.700116)
		(stroke
			(width 2.032)
			(type default)
		)
		(layer "In4.Cu")
	)
	(gr_line
		(start -1.999742 -160.375092)
		(end -1.999742 -208.700116)
		(stroke
			(width 2.032)
			(type default)
		)
		(layer "In4.Cu")
	)
	(gr_arc
		(start 0 -168.699942)
		(mid 0.585785 -170.114153)
		(end 1.999996 -170.699938)
		(stroke
			(width 2.032)
			(type default)
		)
		(layer "In4.Cu")
	)
	(gr_line
		(start 0 -72.300084)
		(end 0 -168.699942)
		(stroke
			(width 2.032)
			(type default)
		)
		(layer "In4.Cu")
	)
	(gr_line
		(start 0 -29.299916)
		(end 0 -1.999996)
		(stroke
			(width 2.032)
			(type default)
		)
		(layer "In4.Cu")
	)
	(gr_arc
		(start 0 -29.299916)
		(mid 0.439376 -30.360664)
		(end 1.500124 -30.80004)
		(stroke
			(width 2.032)
			(type default)
		)
		(layer "In4.Cu")
	)
	(gr_poly
		(pts
			(xy 107.230164 -156.907484)
			(arc
				(start 107.230164 -154.24658)
				(mid 107.204526 -154.169809)
				(end 107.137708 -154.124152)
			)
			(arc
				(start 107.137708 -154.124152)
				(mid 106.85996 -153.757122)
				(end 107.137708 -153.390092)
			)
			(arc
				(start 107.137708 -153.390092)
				(mid 107.204497 -153.344413)
				(end 107.230164 -153.267664)
			)
			(arc
				(start 107.230164 -153.070814)
				(mid 107.192967 -152.981011)
				(end 107.103164 -152.943814)
			)
			(xy 103.614728 -152.943814) (xy 103.551228 -152.880314) (xy 101.655372 -152.880314) (xy 101.574092 -152.961594)
			(xy 101.574092 -153.051256) (xy 101.360986 -153.264362) (xy 99.37369 -153.264362) (xy 99.284282 -153.35377)
			(xy 99.284282 -158.729934) (xy 100.243894 -159.689546) (xy 104.448102 -159.689546)
		)
		(stroke
			(width 0)
			(type solid)
		)
		(fill yes)
		(layer "In4.Cu")
		(net "GND")
	)
	(gr_poly
		(pts
			(arc
				(start 95.72244 -158.64332)
				(mid 95.812243 -158.606123)
				(end 95.84944 -158.51632)
			)
			(xy 95.84944 -148.037804) (xy 96.6851 -147.202144) (xy 96.6851 -129.843276) (xy 95.365824 -128.524)
			(xy 89.864946 -128.524)
			(arc
				(start 89.852754 -128.526286)
				(mid 89.77884 -128.533517)
				(end 89.704926 -128.526286)
			)
			(xy 89.692734 -128.524) (xy 88.205564 -128.524) (xy 79.9338 -120.252236) (xy 79.9338 -120.122442)
			(arc
				(start 79.91983 -120.09501)
				(mid 79.877565 -119.920512)
				(end 79.91983 -119.746014)
			)
			(xy 79.9338 -119.718582) (xy 79.9338 -111.496348)
			(arc
				(start 79.91729 -111.467138)
				(mid 79.867331 -111.278416)
				(end 79.91729 -111.089694)
			)
			(xy 79.9338 -111.060484) (xy 79.9338 -106.922316) (xy 78.098904 -105.08742) (xy 67.890136 -105.08742)
			(xy 67.36588 -105.611676) (xy 67.36588 -110.323884) (xy 67.953636 -110.91164) (xy 70.287896 -110.91164)
			(xy 70.9803 -111.604044) (xy 70.9803 -112.593882) (xy 71.020178 -112.656112)
			(arc
				(start 71.054214 -112.67186)
				(mid 71.275967 -113.018316)
				(end 71.054214 -113.364772)
			)
			(arc
				(start 71.054214 -113.364772)
				(mid 71.0004 -113.411616)
				(end 70.9803 -113.480088)
			)
			(xy 70.9803 -117.646196) (xy 71.01586 -117.705886)
			(arc
				(start 71.04634 -117.72265)
				(mid 71.244927 -118.057422)
				(end 71.04634 -118.392194)
			)
			(xy 71.01586 -118.408958) (xy 70.9803 -118.468648) (xy 70.9803 -123.498864)
			(arc
				(start 72.989694 -125.508258)
				(mid 73.040137 -125.539286)
				(end 73.099168 -125.544072)
			)
			(arc
				(start 73.099168 -125.544072)
				(mid 73.406074 -125.644074)
				(end 73.506076 -125.95098)
			)
			(arc
				(start 73.506076 -125.95098)
				(mid 73.510852 -126.010014)
				(end 73.54189 -126.060454)
			)
			(xy 74.346816 -126.86538) (xy 78.761336 -126.86538) (xy 88.68918 -136.793224) (xy 88.68918 -146.023076)
			(xy 88.5952 -146.117056) (xy 88.5952 -158.345124) (xy 88.893396 -158.64332)
		)
		(stroke
			(width 0)
			(type solid)
		)
		(fill yes)
		(layer "In4.Cu")
		(net "P1V8_STB_NODE1")
	)
	(gr_poly
		(pts
			(xy 99.779328 -163.22548) (xy 99.793355 -163.225075) (xy 99.820718 -163.218882) (xy 99.84607 -163.206867)
			(xy 99.86819 -163.189609) (xy 99.877372 -163.178998) (xy 99.895591 -163.157553) (xy 99.937257 -163.119735)
			(xy 99.984027 -163.088447) (xy 100.034884 -163.064368) (xy 100.088726 -163.048019) (xy 100.144385 -163.039754)
			(xy 100.200655 -163.039754) (xy 100.256314 -163.048019) (xy 100.310156 -163.064368) (xy 100.361013 -163.088447)
			(xy 100.407783 -163.119735) (xy 100.449449 -163.157553) (xy 100.467668 -163.178998) (xy 100.485702 -163.201096)
			(xy 100.537264 -163.22548) (xy 109.917738 -163.22548) (xy 109.934372 -163.224935) (xy 109.966508 -163.216327)
			(xy 109.995327 -163.199707) (xy 110.018872 -163.176203) (xy 110.035542 -163.147413) (xy 110.04042 -163.1315)
			(xy 110.048123 -163.104653) (xy 110.070299 -163.053392) (xy 110.099712 -163.005912) (xy 110.135733 -162.963228)
			(xy 110.177594 -162.926253) (xy 110.224398 -162.895776) (xy 110.275145 -162.872449) (xy 110.328752 -162.856771)
			(xy 110.384072 -162.849077) (xy 110.439922 -162.849531) (xy 110.495109 -162.858123) (xy 110.548454 -162.874671)
			(xy 110.598816 -162.898819) (xy 110.645118 -162.930053) (xy 110.686372 -162.967704) (xy 110.721695 -163.010968)
			(xy 110.750332 -163.058919) (xy 110.761526 -163.08451) (xy 110.767872 -163.098709) (xy 110.786347 -163.12372)
			(xy 110.81033 -163.143509) (xy 110.838393 -163.156898) (xy 110.868864 -163.163089) (xy 110.899927 -163.161713)
			(xy 110.914942 -163.157662) (xy 110.941606 -163.150268) (xy 110.996369 -163.142363) (xy 111.0517 -163.142455)
			(xy 111.106437 -163.150542) (xy 111.15943 -163.166454) (xy 111.209569 -163.189856) (xy 111.23295 -163.204652)
			(xy 111.2647 -163.22548) (xy 120.628664 -163.22548) (xy 121.97842 -161.875724) (xy 121.97842 -150.957534)
			(xy 121.953528 -150.924006) (xy 121.937856 -150.902015) (xy 121.912203 -150.854499) (xy 121.893505 -150.80384)
			(xy 121.882136 -150.751051) (xy 121.878322 -150.697187) (xy 121.88214 -150.643323) (xy 121.893513 -150.590535)
			(xy 121.912214 -150.539878) (xy 121.93787 -150.492363) (xy 121.953528 -150.470362) (xy 121.97842 -150.436834)
			(xy 121.97842 -145.924016) (xy 121.9581 -145.89252) (xy 121.94357 -145.869237) (xy 121.920616 -145.819385)
			(xy 121.905046 -145.766758) (xy 121.897179 -145.712443) (xy 121.897179 -145.657561) (xy 121.905045 -145.603245)
			(xy 121.920615 -145.550618) (xy 121.943568 -145.500766) (xy 121.9581 -145.477484) (xy 121.97842 -145.445988)
			(xy 121.97842 -140.764006) (xy 121.956068 -140.731494) (xy 121.940213 -140.707516) (xy 121.915119 -140.6558)
			(xy 121.898065 -140.600906) (xy 121.889438 -140.544074) (xy 121.889433 -140.486592) (xy 121.89805 -140.429759)
			(xy 121.915094 -140.374861) (xy 121.94018 -140.323141) (xy 121.956068 -140.299186) (xy 121.97842 -140.266674)
			(xy 121.97842 -127.923036) (xy 121.121424 -127.06604) (xy 116.940076 -127.06604) (xy 116.3193 -127.686816)
			(xy 116.3193 -134.279894) (xy 116.336572 -134.309612) (xy 116.350675 -134.33478) (xy 116.371963 -134.388399)
			(xy 116.38493 -134.444612) (xy 116.389282 -134.502138) (xy 116.384919 -134.559663) (xy 116.37194 -134.615874)
			(xy 116.350642 -134.669489) (xy 116.336572 -134.694676) (xy 116.3193 -134.724394) (xy 116.3193 -145.662396)
			(xy 114.420396 -147.5613) (xy 97.044256 -147.5613) (xy 96.35744 -148.248116) (xy 96.35744 -158.940246)
			(xy 98.776282 -158.940246) (xy 98.776282 -153.143458) (xy 99.163378 -152.756362) (xy 101.150674 -152.756362)
			(xy 101.214936 -152.6921) (xy 101.304598 -152.6921) (xy 101.497384 -152.499314) (xy 103.551228 -152.499314)
			(xy 103.614728 -152.435814) (xy 107.443016 -152.435814) (xy 107.738164 -152.730962) (xy 107.738164 -157.117796)
			(xy 107.61726 -157.2387) (xy 107.599988 -157.30601) (xy 107.610148 -157.339792) (xy 107.617428 -157.366096)
			(xy 107.625245 -157.420112) (xy 107.625288 -157.47469) (xy 107.617555 -157.528718) (xy 107.602205 -157.581093)
			(xy 107.57955 -157.630747) (xy 107.550052 -157.676667) (xy 107.514314 -157.717917) (xy 107.473063 -157.753655)
			(xy 107.427142 -157.783152) (xy 107.377488 -157.805807) (xy 107.325113 -157.821156) (xy 107.271085 -157.828888)
			(xy 107.216506 -157.828845) (xy 107.162491 -157.821027) (xy 107.136184 -157.813756) (xy 107.102402 -157.803596)
			(xy 107.035092 -157.820868) (xy 104.658414 -160.197546) (xy 100.033582 -160.197546) (xy 98.776282 -158.940246)
			(xy 96.35744 -158.940246) (xy 96.35744 -162.861244) (xy 96.721676 -163.22548)
		)
		(stroke
			(width 0)
			(type solid)
		)
		(fill yes)
		(layer "In4.Cu")
		(net "P12V_AUX")
	)
	(gr_poly
		(pts
			(arc
				(start 66.305684 -69.774308)
				(mid 66.3956 -69.811627)
				(end 66.485516 -69.774308)
			)
			(xy 66.546984 -69.71284)
			(arc
				(start 74.665332 -69.71284)
				(mid 74.711263 -69.704243)
				(end 74.75093 -69.679566)
			)
			(arc
				(start 74.75093 -69.679566)
				(mid 75.007978 -69.579978)
				(end 75.265026 -69.679566)
			)
			(arc
				(start 75.265026 -69.679566)
				(mid 75.304718 -69.704179)
				(end 75.350624 -69.71284)
			)
			(arc
				(start 80.44942 -69.71284)
				(mid 80.539223 -69.675643)
				(end 80.57642 -69.58584)
			)
			(xy 80.57642 -26.168604) (xy 83.91906 -22.825964) (xy 83.91906 -17.168876) (xy 83.168744 -16.41856)
			(xy 82.9691 -16.41856)
			(arc
				(start 82.958432 -16.420338)
				(mid 82.893662 -16.425877)
				(end 82.828892 -16.420338)
			)
			(xy 82.818224 -16.41856) (xy 82.04454 -16.41856)
			(arc
				(start 82.033872 -16.420338)
				(mid 81.969102 -16.425877)
				(end 81.904332 -16.420338)
			)
			(xy 81.893664 -16.41856) (xy 80.98536 -16.41856)
			(arc
				(start 80.974692 -16.420338)
				(mid 80.909922 -16.425877)
				(end 80.845152 -16.420338)
			)
			(xy 80.834484 -16.41856) (xy 79.993998 -16.41856)
			(arc
				(start 79.98333 -16.420338)
				(mid 79.91856 -16.425877)
				(end 79.85379 -16.420338)
			)
			(xy 79.843122 -16.41856) (xy 78.93812 -16.41856)
			(arc
				(start 78.927452 -16.420338)
				(mid 78.862682 -16.425877)
				(end 78.797912 -16.420338)
			)
			(xy 78.787244 -16.41856) (xy 77.97546 -16.41856)
			(arc
				(start 77.964792 -16.420338)
				(mid 77.900022 -16.425877)
				(end 77.835252 -16.420338)
			)
			(xy 77.824584 -16.41856) (xy 77.0509 -16.41856)
			(arc
				(start 77.040232 -16.420338)
				(mid 76.975462 -16.425877)
				(end 76.910692 -16.420338)
			)
			(xy 76.900024 -16.41856) (xy 75.99172 -16.41856)
			(arc
				(start 75.981052 -16.420338)
				(mid 75.916282 -16.425877)
				(end 75.851512 -16.420338)
			)
			(xy 75.840844 -16.41856) (xy 74.9808 -16.41856)
			(arc
				(start 74.970132 -16.420338)
				(mid 74.905362 -16.425877)
				(end 74.840592 -16.420338)
			)
			(xy 74.829924 -16.41856) (xy 73.94448 -16.41856)
			(arc
				(start 73.933812 -16.420338)
				(mid 73.869042 -16.425877)
				(end 73.804272 -16.420338)
			)
			(xy 73.793604 -16.41856) (xy 71.70928 -16.41856)
			(arc
				(start 71.698612 -16.420338)
				(mid 71.633842 -16.425877)
				(end 71.569072 -16.420338)
			)
			(xy 71.558404 -16.41856) (xy 70.6501 -16.41856)
			(arc
				(start 70.639432 -16.420338)
				(mid 70.574662 -16.425877)
				(end 70.509892 -16.420338)
			)
			(xy 70.499224 -16.41856) (xy 69.63918 -16.41856)
			(arc
				(start 69.628512 -16.420338)
				(mid 69.563742 -16.425877)
				(end 69.498972 -16.420338)
			)
			(xy 69.488304 -16.41856) (xy 68.60286 -16.41856)
			(arc
				(start 68.592192 -16.420338)
				(mid 68.527422 -16.425877)
				(end 68.462652 -16.420338)
			)
			(xy 68.451984 -16.41856) (xy 64.60998 -16.41856)
			(arc
				(start 64.590168 -16.425164)
				(mid 64.46774 -16.445349)
				(end 64.345312 -16.425164)
			)
			(xy 64.3255 -16.41856) (xy 50.094896 -16.41856) (xy 49.10836 -17.405096) (xy 49.10836 -22.347936)
			(arc
				(start 49.114202 -22.366478)
				(mid 49.131727 -22.480778)
				(end 49.114202 -22.595078)
			)
			(xy 49.10836 -22.61362) (xy 49.10836 -68.551806)
			(arc
				(start 49.10963 -68.561204)
				(mid 49.113822 -68.617592)
				(end 49.10963 -68.67398)
			)
			(xy 49.10836 -68.683378) (xy 49.10836 -69.048884) (xy 49.386236 -69.32676) (xy 53.921914 -69.32676)
			(arc
				(start 53.950616 -69.310504)
				(mid 54.137052 -69.261865)
				(end 54.323488 -69.310504)
			)
			(xy 54.35219 -69.32676) (xy 54.659022 -69.32676)
			(arc
				(start 54.69001 -69.307456)
				(mid 54.891686 -69.249793)
				(end 55.093362 -69.307456)
			)
			(xy 55.12435 -69.32676) (xy 56.557418 -69.32676) (xy 56.620918 -69.28485)
			(arc
				(start 56.635904 -69.249798)
				(mid 56.986678 -69.018367)
				(end 57.337452 -69.249798)
			)
			(xy 57.352438 -69.28485) (xy 57.415938 -69.32676) (xy 57.909206 -69.32676)
			(arc
				(start 57.937654 -69.311266)
				(mid 58.120534 -69.264571)
				(end 58.303414 -69.311266)
			)
			(xy 58.331862 -69.32676) (xy 58.646568 -69.32676)
			(arc
				(start 58.67273 -69.31406)
				(mid 58.838592 -69.276128)
				(end 59.004454 -69.31406)
			)
			(xy 59.030616 -69.32676) (xy 65.858136 -69.32676)
		)
		(stroke
			(width 0)
			(type solid)
		)
		(fill yes)
		(layer "In4.Cu")
		(net "PV_VDDR_NODE1")
	)
	(gr_poly
		(pts
			(xy 37.101526 -113.915698) (xy 37.11956 -113.852706)
			(arc
				(start 37.112448 -113.820702)
				(mid 37.214606 -113.466168)
				(end 37.56914 -113.36401)
			)
			(xy 37.601144 -113.371122) (xy 37.664136 -113.353088)
			(arc
				(start 42.953178 -108.064046)
				(mid 42.989245 -107.991917)
				(end 42.974514 -107.912662)
			)
			(arc
				(start 42.974514 -107.912662)
				(mid 43.038739 -107.458473)
				(end 43.492928 -107.394248)
			)
			(arc
				(start 43.492928 -107.394248)
				(mid 43.572169 -107.40888)
				(end 43.644312 -107.372912)
			)
			(arc
				(start 48.523652 -102.493572)
				(mid 48.553504 -102.446382)
				(end 48.560228 -102.390956)
			)
			(arc
				(start 48.560228 -102.390956)
				(mid 48.669971 -102.082361)
				(end 48.978566 -101.972618)
			)
			(xy 49.007268 -101.975412) (xy 49.060862 -101.956362) (xy 55.4101 -95.607124) (xy 55.4101 -81.085944)
			(xy 55.945024 -80.55102)
			(arc
				(start 62.055502 -80.55102)
				(mid 62.145305 -80.513823)
				(end 62.182502 -80.42402)
			)
			(xy 62.182502 -76.924662) (xy 64.483488 -74.623676) (xy 65.590166 -74.623676) (xy 66.16192 -74.051922)
			(xy 66.16192 -70.348856) (xy 65.647824 -69.83476) (xy 61.627766 -69.83476) (xy 61.562742 -69.879972)
			(arc
				(start 61.548772 -69.917564)
				(mid 61.19114 -70.166064)
				(end 60.833508 -69.917564)
			)
			(xy 60.819538 -69.879972) (xy 60.754514 -69.83476) (xy 59.216036 -69.83476) (xy 59.162442 -69.861684)
			(arc
				(start 59.144408 -69.885814)
				(mid 58.863277 -70.038432)
				(end 58.56478 -69.923406)
			)
			(arc
				(start 58.56478 -69.923406)
				(mid 58.475661 -69.884819)
				(end 58.385456 -69.920612)
			)
			(arc
				(start 58.385456 -69.920612)
				(mid 58.095177 -70.026737)
				(end 57.821576 -69.88302)
			)
			(arc
				(start 57.821576 -69.88302)
				(mid 57.777319 -69.847504)
				(end 57.722008 -69.83476)
			)
			(xy 55.25008 -69.83476) (xy 55.199788 -69.857874)
			(arc
				(start 55.181754 -69.87921)
				(mid 54.938163 -70.010035)
				(end 54.670198 -69.941948)
			)
			(arc
				(start 54.670198 -69.941948)
				(mid 54.518535 -69.894717)
				(end 54.368446 -69.946774)
			)
			(arc
				(start 54.368446 -69.946774)
				(mid 54.090887 -70.022164)
				(end 53.839618 -69.882258)
			)
			(arc
				(start 53.839618 -69.882258)
				(mid 53.795491 -69.847236)
				(end 53.740558 -69.83476)
			)
			(xy 51.641756 -69.83476) (xy 51.580542 -69.872352)
			(arc
				(start 51.564286 -69.904864)
				(mid 51.223418 -70.115111)
				(end 50.88255 -69.904864)
			)
			(xy 50.866294 -69.872352) (xy 50.80508 -69.83476)
			(arc
				(start 46.626018 -69.83476)
				(mid 46.559879 -69.853341)
				(end 46.512988 -69.903594)
			)
			(arc
				(start 46.512988 -69.903594)
				(mid 46.263444 -70.09659)
				(end 45.955204 -70.02907)
			)
			(arc
				(start 45.955204 -70.02907)
				(mid 45.800772 -69.976733)
				(end 45.64634 -70.02907)
			)
			(arc
				(start 45.64634 -70.02907)
				(mid 45.338057 -70.096779)
				(end 45.088556 -69.903594)
			)
			(arc
				(start 45.088556 -69.903594)
				(mid 45.041727 -69.85324)
				(end 44.975526 -69.83476)
			)
			(xy 44.864528 -69.83476) (xy 44.809664 -69.863208)
			(arc
				(start 44.791884 -69.888608)
				(mid 44.479972 -70.050423)
				(end 44.16806 -69.888608)
			)
			(arc
				(start 44.16806 -69.888608)
				(mid 44.122693 -69.848981)
				(end 44.064174 -69.83476)
			)
			(xy 28.570936 -69.83476) (xy 25.8064 -72.599296)
			(arc
				(start 25.8064 -86.539578)
				(mid 25.878476 -86.71658)
				(end 26.053542 -86.793324)
			)
			(arc
				(start 26.053542 -86.793324)
				(mid 27.987 -89.084422)
				(end 25.488392 -90.740738)
			)
			(arc
				(start 25.488392 -90.740738)
				(mid 25.42292 -90.740993)
				(end 25.366218 -90.773758)
			)
			(xy 15.73784 -100.402136) (xy 15.73784 -116.938044) (xy 15.931896 -117.1321) (xy 33.885124 -117.1321)
		)
		(stroke
			(width 0)
			(type solid)
		)
		(fill yes)
		(layer "In4.Cu")
		(net "P1V05_NODE1")
	)
	(gr_poly
		(pts
			(xy 122.15114 -115.182904) (xy 122.15114 -107.681522) (xy 122.150568 -107.663853) (xy 122.140888 -107.629866)
			(xy 122.122264 -107.599834) (xy 122.096121 -107.576056) (xy 122.080528 -107.56773) (xy 122.055466 -107.554713)
			(xy 122.009144 -107.522411) (xy 121.968091 -107.483632) (xy 121.933204 -107.439224) (xy 121.905246 -107.390157)
			(xy 121.884828 -107.337505) (xy 121.872395 -107.282418) (xy 121.868221 -107.2261) (xy 121.872395 -107.169782)
			(xy 121.884828 -107.114695) (xy 121.905246 -107.062043) (xy 121.933204 -107.012976) (xy 121.968091 -106.968568)
			(xy 122.009144 -106.929789) (xy 122.055466 -106.897487) (xy 122.080528 -106.88447) (xy 122.11304 -106.868214)
			(xy 122.15114 -106.807) (xy 122.15114 -86.264496) (xy 107.17022 -71.283576) (xy 107.117642 -71.283322)
			(xy 107.090507 -71.282755) (xy 107.036806 -71.274886) (xy 106.984763 -71.259487) (xy 106.935427 -71.236868)
			(xy 106.889794 -71.207485) (xy 106.848786 -71.171932) (xy 106.813231 -71.130927) (xy 106.783845 -71.085296)
			(xy 106.761222 -71.035962) (xy 106.745819 -70.983919) (xy 106.737947 -70.930219) (xy 106.737404 -70.903084)
			(xy 106.73715 -70.850506) (xy 106.107484 -70.22084) (xy 101.714808 -70.22084) (xy 101.686106 -70.236842)
			(xy 101.661653 -70.249898) (xy 101.609837 -70.269585) (xy 101.555716 -70.281565) (xy 101.500432 -70.285587)
			(xy 101.445148 -70.281565) (xy 101.391027 -70.269585) (xy 101.339211 -70.249898) (xy 101.314758 -70.236842)
			(xy 101.286056 -70.22084) (xy 100.065586 -70.22084) (xy 100.048409 -70.221445) (xy 100.015317 -70.230682)
			(xy 99.985884 -70.248403) (xy 99.973638 -70.260464) (xy 99.953886 -70.280517) (xy 99.909539 -70.315176)
			(xy 99.860583 -70.342946) (xy 99.808078 -70.363224) (xy 99.753164 -70.375569) (xy 99.697032 -70.379714)
			(xy 99.6409 -70.375569) (xy 99.585986 -70.363224) (xy 99.533481 -70.342946) (xy 99.484525 -70.315176)
			(xy 99.440178 -70.280517) (xy 99.420426 -70.260464) (xy 99.4082 -70.248377) (xy 99.378764 -70.230643)
			(xy 99.34566 -70.221416) (xy 99.328478 -70.22084) (xy 75.291696 -70.22084) (xy 75.256136 -70.25132)
			(xy 75.235299 -70.268543) (xy 75.189684 -70.297556) (xy 75.140431 -70.319839) (xy 75.088526 -70.334948)
			(xy 75.035008 -70.342578) (xy 74.980948 -70.342578) (xy 74.92743 -70.334948) (xy 74.875525 -70.319839)
			(xy 74.826272 -70.297556) (xy 74.780657 -70.268543) (xy 74.75982 -70.25132) (xy 74.72426 -70.22084)
			(xy 73.062592 -70.22084) (xy 73.001886 -70.257924) (xy 72.98563 -70.289674) (xy 72.972407 -70.314192)
			(xy 72.939934 -70.359452) (xy 72.901226 -70.399509) (xy 72.857105 -70.433512) (xy 72.808509 -70.460739)
			(xy 72.75647 -70.480612) (xy 72.702096 -70.492706) (xy 72.64654 -70.496767) (xy 72.590984 -70.492706)
			(xy 72.53661 -70.480612) (xy 72.484571 -70.460739) (xy 72.435975 -70.433512) (xy 72.391854 -70.399509)
			(xy 72.353146 -70.359452) (xy 72.320673 -70.314192) (xy 72.30745 -70.289674) (xy 72.29894 -70.274495)
			(xy 72.275232 -70.249041) (xy 72.245541 -70.230921) (xy 72.212065 -70.221473) (xy 72.194674 -70.22084)
			(xy 66.757296 -70.22084) (xy 66.66992 -70.308216) (xy 66.66992 -74.262234) (xy 65.800478 -75.131676)
			(xy 64.6938 -75.131676) (xy 63.15837 -76.667106) (xy 63.147153 -76.678978) (xy 63.13063 -76.707138)
			(xy 63.12182 -76.738576) (xy 63.121302 -76.771222) (xy 63.129111 -76.802924) (xy 63.136526 -76.817474)
			(xy 63.149342 -76.842105) (xy 63.168501 -76.894217) (xy 63.179901 -76.948557) (xy 63.183302 -77.003975)
			(xy 63.178633 -77.0593) (xy 63.165991 -77.113364) (xy 63.145643 -77.165024) (xy 63.118021 -77.213188)
			(xy 63.083707 -77.256838) (xy 63.043427 -77.295051) (xy 62.998033 -77.327021) (xy 62.948482 -77.352071)
			(xy 62.895823 -77.369671) (xy 62.841169 -77.379451) (xy 62.813438 -77.380846) (xy 62.79715 -77.381868)
			(xy 62.765874 -77.391156) (xy 62.737981 -77.408079) (xy 62.715297 -77.431527) (xy 62.699309 -77.459967)
			(xy 62.691063 -77.491533) (xy 62.690502 -77.507846) (xy 62.690502 -79.26132) (xy 109.258606 -79.26132)
			(xy 109.258606 -79.17118) (xy 109.266686 -79.081404) (xy 109.282781 -78.992713) (xy 109.306761 -78.905821)
			(xy 109.338434 -78.82143) (xy 109.377544 -78.740217) (xy 109.423776 -78.662837) (xy 109.476759 -78.589912)
			(xy 109.536065 -78.522031) (xy 109.601218 -78.459739) (xy 109.671692 -78.403537) (xy 109.74692 -78.35388)
			(xy 109.826296 -78.311166) (xy 109.909182 -78.275738) (xy 109.99491 -78.247884) (xy 110.082789 -78.227826)
			(xy 110.172113 -78.215726) (xy 110.262162 -78.211682) (xy 110.352211 -78.215726) (xy 110.441535 -78.227826)
			(xy 110.529414 -78.247884) (xy 110.615142 -78.275738) (xy 110.698028 -78.311166) (xy 110.777404 -78.35388)
			(xy 110.852632 -78.403537) (xy 110.923106 -78.459739) (xy 110.988259 -78.522031) (xy 111.047565 -78.589912)
			(xy 111.100548 -78.662837) (xy 111.14678 -78.740217) (xy 111.18589 -78.82143) (xy 111.217563 -78.905821)
			(xy 111.241543 -78.992713) (xy 111.257638 -79.081404) (xy 111.265718 -79.17118) (xy 111.266224 -79.21625)
			(xy 111.265718 -79.26132) (xy 111.257638 -79.351096) (xy 111.241543 -79.439787) (xy 111.217563 -79.526679)
			(xy 111.18589 -79.61107) (xy 111.14678 -79.692283) (xy 111.100548 -79.769663) (xy 111.047565 -79.842588)
			(xy 110.988259 -79.910469) (xy 110.923106 -79.972761) (xy 110.852632 -80.028963) (xy 110.777404 -80.07862)
			(xy 110.698028 -80.121334) (xy 110.615142 -80.156762) (xy 110.529414 -80.184616) (xy 110.441535 -80.204674)
			(xy 110.352211 -80.216774) (xy 110.262162 -80.220818) (xy 110.172113 -80.216774) (xy 110.082789 -80.204674)
			(xy 109.99491 -80.184616) (xy 109.909182 -80.156762) (xy 109.826296 -80.121334) (xy 109.74692 -80.07862)
			(xy 109.671692 -80.028963) (xy 109.601218 -79.972761) (xy 109.536065 -79.910469) (xy 109.476759 -79.842588)
			(xy 109.423776 -79.769663) (xy 109.377544 -79.692283) (xy 109.338434 -79.61107) (xy 109.306761 -79.526679)
			(xy 109.282781 -79.439787) (xy 109.266686 -79.351096) (xy 109.258606 -79.26132) (xy 62.690502 -79.26132)
			(xy 62.690502 -80.42402) (xy 62.691048 -80.440667) (xy 62.699669 -80.472824) (xy 62.716319 -80.501655)
			(xy 62.739862 -80.525195) (xy 62.768696 -80.54184) (xy 62.800855 -80.550455) (xy 62.817502 -80.55102)
			(xy 64.442594 -80.55102) (xy 65.42786 -81.536286) (xy 65.42786 -81.766664) (xy 65.439798 -81.792318)
			(xy 65.451084 -81.817693) (xy 65.467018 -81.870892) (xy 65.475069 -81.92584) (xy 65.475068 -81.981374)
			(xy 65.467015 -82.036322) (xy 65.451079 -82.089521) (xy 65.439798 -82.114898) (xy 65.42786 -82.140552)
			(xy 65.42786 -88.862992) (xy 87.993207 -88.862992) (xy 87.993207 -88.736856) (xy 88.001127 -88.610968)
			(xy 88.016937 -88.485826) (xy 88.040572 -88.361923) (xy 88.071941 -88.23975) (xy 88.110919 -88.119787)
			(xy 88.157353 -88.002508) (xy 88.21106 -87.888376) (xy 88.271827 -87.777841) (xy 88.339414 -87.671341)
			(xy 88.413555 -87.569294) (xy 88.493958 -87.472104) (xy 88.580304 -87.380154) (xy 88.672254 -87.293808)
			(xy 88.769444 -87.213405) (xy 88.871491 -87.139264) (xy 88.977991 -87.071677) (xy 89.088526 -87.01091)
			(xy 89.202658 -86.957203) (xy 89.319937 -86.910769) (xy 89.4399 -86.871791) (xy 89.562073 -86.840422)
			(xy 89.685976 -86.816787) (xy 89.811118 -86.800977) (xy 89.937006 -86.793057) (xy 90.063142 -86.793057)
			(xy 90.18903 -86.800977) (xy 90.314172 -86.816787) (xy 90.438075 -86.840422) (xy 90.560248 -86.871791)
			(xy 90.680211 -86.910769) (xy 90.79749 -86.957203) (xy 90.911622 -87.01091) (xy 91.022157 -87.071677)
			(xy 91.128657 -87.139264) (xy 91.230704 -87.213405) (xy 91.327894 -87.293808) (xy 91.419844 -87.380154)
			(xy 91.50619 -87.472104) (xy 91.586593 -87.569294) (xy 91.660734 -87.671341) (xy 91.728321 -87.777841)
			(xy 91.789088 -87.888376) (xy 91.842795 -88.002508) (xy 91.889229 -88.119787) (xy 91.928207 -88.23975)
			(xy 91.959576 -88.361923) (xy 91.983211 -88.485826) (xy 91.999021 -88.610968) (xy 92.006941 -88.736856)
			(xy 92.007436 -88.799924) (xy 92.006941 -88.862992) (xy 91.999021 -88.98888) (xy 91.983211 -89.114022)
			(xy 91.959576 -89.237925) (xy 91.928207 -89.360098) (xy 91.889229 -89.480061) (xy 91.842795 -89.59734)
			(xy 91.789088 -89.711472) (xy 91.728321 -89.822007) (xy 91.660734 -89.928507) (xy 91.586593 -90.030554)
			(xy 91.50619 -90.127744) (xy 91.419844 -90.219694) (xy 91.327894 -90.30604) (xy 91.230704 -90.386443)
			(xy 91.128657 -90.460584) (xy 91.022157 -90.528171) (xy 90.911622 -90.588938) (xy 90.79749 -90.642645)
			(xy 90.680211 -90.689079) (xy 90.560248 -90.728057) (xy 90.438075 -90.759426) (xy 90.314172 -90.783061)
			(xy 90.18903 -90.798871) (xy 90.063142 -90.806791) (xy 89.937006 -90.806791) (xy 89.811118 -90.798871)
			(xy 89.685976 -90.783061) (xy 89.562073 -90.759426) (xy 89.4399 -90.728057) (xy 89.319937 -90.689079)
			(xy 89.202658 -90.642645) (xy 89.088526 -90.588938) (xy 88.977991 -90.528171) (xy 88.871491 -90.460584)
			(xy 88.769444 -90.386443) (xy 88.672254 -90.30604) (xy 88.580304 -90.219694) (xy 88.493958 -90.127744)
			(xy 88.413555 -90.030554) (xy 88.339414 -89.928507) (xy 88.271827 -89.822007) (xy 88.21106 -89.711472)
			(xy 88.157353 -89.59734) (xy 88.110919 -89.480061) (xy 88.071941 -89.360098) (xy 88.040572 -89.237925)
			(xy 88.016937 -89.114022) (xy 88.001127 -88.98888) (xy 87.993207 -88.862992) (xy 65.42786 -88.862992)
			(xy 65.42786 -89.584784) (xy 65.543938 -89.700862) (xy 65.637156 -89.708228) (xy 65.675002 -89.680796)
			(xy 65.696964 -89.665481) (xy 65.744315 -89.640492) (xy 65.794694 -89.622365) (xy 65.847111 -89.611454)
			(xy 65.900539 -89.607975) (xy 65.953929 -89.611996) (xy 66.006233 -89.623438) (xy 66.056425 -89.642075)
			(xy 66.10352 -89.667544) (xy 66.146595 -89.699343) (xy 66.184804 -89.736849) (xy 66.217397 -89.779326)
			(xy 66.243735 -89.825941) (xy 66.253868 -89.850722) (xy 66.259866 -89.86472) (xy 66.277428 -89.889589)
			(xy 66.300383 -89.909589) (xy 66.327423 -89.923579) (xy 66.357009 -89.930763) (xy 66.372232 -89.93124)
			(xy 68.245482 -89.93124) (xy 68.272152 -89.918032) (xy 68.298652 -89.90547) (xy 68.354549 -89.88773)
			(xy 68.412502 -89.878755) (xy 68.471146 -89.878755) (xy 68.529099 -89.88773) (xy 68.584996 -89.90547)
			(xy 68.611496 -89.918032) (xy 68.638166 -89.93124) (xy 80.768444 -89.93124) (xy 80.831436 -89.890346)
			(xy 80.846676 -89.856056) (xy 80.858649 -89.830457) (xy 80.889025 -89.782801) (xy 80.926098 -89.740148)
			(xy 80.969058 -89.703431) (xy 81.016965 -89.673454) (xy 81.06877 -89.650872) (xy 81.12334 -89.63618)
			(xy 81.17948 -89.629699) (xy 81.235962 -89.631571) (xy 81.291549 -89.641756) (xy 81.345026 -89.660029)
			(xy 81.395222 -89.685992) (xy 81.441039 -89.719076) (xy 81.46161 -89.738454) (xy 81.478805 -89.754518)
			(xy 81.517957 -89.780615) (xy 81.561247 -89.79905) (xy 81.607193 -89.809194) (xy 81.654221 -89.810698)
			(xy 81.700721 -89.803511) (xy 81.745101 -89.787879) (xy 81.78584 -89.764338) (xy 81.804002 -89.749376)
			(xy 81.826062 -89.731159) (xy 81.874588 -89.700854) (xy 81.927095 -89.678136) (xy 81.982407 -89.663515)
			(xy 82.039281 -89.657319) (xy 82.096443 -89.659687) (xy 82.152611 -89.670564) (xy 82.206524 -89.689709)
			(xy 82.256973 -89.71669) (xy 82.302826 -89.750904) (xy 82.343056 -89.791581) (xy 82.376759 -89.837811)
			(xy 82.390488 -89.862914) (xy 82.399022 -89.878002) (xy 82.422718 -89.903281) (xy 82.452331 -89.92127)
			(xy 82.485687 -89.930649) (xy 82.50301 -89.93124) (xy 86.419436 -89.93124) (xy 91.7956 -95.307404)
			(xy 91.7956 -97.983294) (xy 99.729544 -97.983294) (xy 99.729544 -93.61678) (xy 102.816914 -90.52941)
			(xy 107.183174 -90.52941) (xy 110.270544 -93.61678) (xy 110.270544 -97.983294) (xy 107.183174 -101.070664)
			(xy 102.816914 -101.070664) (xy 99.729544 -97.983294) (xy 91.7956 -97.983294) (xy 91.7956 -98.377248)
			(xy 91.796127 -98.394472) (xy 91.80527 -98.427682) (xy 91.822981 -98.457225) (xy 91.847965 -98.480937)
			(xy 91.86291 -98.489516) (xy 91.886989 -98.502869) (xy 91.931378 -98.535442) (xy 91.970623 -98.574059)
			(xy 92.003908 -98.617916) (xy 92.030543 -98.666104) (xy 92.049972 -98.71762) (xy 92.061793 -98.771394)
			(xy 92.06576 -98.826309) (xy 92.06179 -98.881224) (xy 92.049967 -98.934998) (xy 92.030535 -98.986513)
			(xy 92.003898 -99.0347) (xy 91.970611 -99.078556) (xy 91.931364 -99.11717) (xy 91.886973 -99.149741)
			(xy 91.86291 -99.163124) (xy 91.831668 -99.179888) (xy 91.7956 -99.239832) (xy 91.7956 -100.275136)
			(xy 91.824302 -100.310188) (xy 91.842282 -100.333043) (xy 91.871831 -100.383125) (xy 91.893439 -100.437112)
			(xy 91.906605 -100.493751) (xy 91.911025 -100.551733) (xy 91.906595 -100.609713) (xy 91.893419 -100.666351)
			(xy 91.871802 -100.720333) (xy 91.842245 -100.77041) (xy 91.824302 -100.793296) (xy 91.7956 -100.828348)
			(xy 91.7956 -109.528864) (xy 99.099116 -116.83238) (xy 120.501664 -116.83238)
		)
		(stroke
			(width 0)
			(type solid)
		)
		(fill yes)
		(layer "In4.Cu")
		(net "PV_VCCP_NODE1")
	)
	(gr_poly
		(pts
			(xy -3.142742 -207.684116) (xy -3.126087 -207.683622) (xy -3.093913 -207.675001) (xy -3.065066 -207.658346)
			(xy -3.041512 -207.634792) (xy -3.024857 -207.605945) (xy -3.016236 -207.573771) (xy -3.015742 -207.557116)
			(xy -3.015742 -161.391092) (xy -3.015996 -161.391092) (xy -3.015996 -1.143) (xy -3.01649 -1.126345)
			(xy -3.025111 -1.094171) (xy -3.041766 -1.065324) (xy -3.06532 -1.04177) (xy -3.094167 -1.025115)
			(xy -3.126341 -1.016494) (xy -3.142996 -1.016) (xy -16.237966 -1.016) (xy -16.283435 -1.016525) (xy -16.373984 -1.024916)
			(xy -16.463373 -1.041625) (xy -16.550838 -1.066512) (xy -16.635635 -1.099362) (xy -16.717038 -1.139896)
			(xy -16.794355 -1.187769) (xy -16.866924 -1.24257) (xy -16.934128 -1.303834) (xy -16.995392 -1.371038)
			(xy -17.050193 -1.443607) (xy -17.098066 -1.520924) (xy -17.1386 -1.602327) (xy -17.17145 -1.687124)
			(xy -17.196337 -1.774589) (xy -17.213046 -1.863978) (xy -17.221437 -1.954527) (xy -17.221962 -1.999996)
			(xy -17.221962 -31.846463) (xy -12.286746 -31.846463) (xy -12.286746 -31.761741) (xy -12.278693 -31.677404)
			(xy -12.262659 -31.594214) (xy -12.238791 -31.512924) (xy -12.207303 -31.434272) (xy -12.168481 -31.358969)
			(xy -12.122678 -31.287697) (xy -12.070307 -31.221101) (xy -12.011842 -31.159786) (xy -11.947814 -31.104305)
			(xy -11.878802 -31.055162) (xy -11.805432 -31.012802) (xy -11.728367 -30.977607) (xy -11.648305 -30.949898)
			(xy -11.565972 -30.929924) (xy -11.482113 -30.917867) (xy -11.397488 -30.913836) (xy -11.312863 -30.917867)
			(xy -11.229004 -30.929924) (xy -11.146671 -30.949898) (xy -11.066609 -30.977607) (xy -10.989544 -31.012802)
			(xy -10.916174 -31.055162) (xy -10.847162 -31.104305) (xy -10.783134 -31.159786) (xy -10.724669 -31.221101)
			(xy -10.672298 -31.287697) (xy -10.626495 -31.358969) (xy -10.587673 -31.434272) (xy -10.556185 -31.512924)
			(xy -10.532317 -31.594214) (xy -10.516283 -31.677404) (xy -10.50823 -31.761741) (xy -10.507726 -31.804102)
			(xy -10.50823 -31.846463) (xy -7.714746 -31.846463) (xy -7.714746 -31.761741) (xy -7.706693 -31.677404)
			(xy -7.690659 -31.594214) (xy -7.666791 -31.512924) (xy -7.635303 -31.434272) (xy -7.596481 -31.358969)
			(xy -7.550678 -31.287697) (xy -7.498307 -31.221101) (xy -7.439842 -31.159786) (xy -7.375814 -31.104305)
			(xy -7.306802 -31.055162) (xy -7.233432 -31.012802) (xy -7.156367 -30.977607) (xy -7.076305 -30.949898)
			(xy -6.993972 -30.929924) (xy -6.910113 -30.917867) (xy -6.825488 -30.913836) (xy -6.740863 -30.917867)
			(xy -6.657004 -30.929924) (xy -6.574671 -30.949898) (xy -6.494609 -30.977607) (xy -6.417544 -31.012802)
			(xy -6.344174 -31.055162) (xy -6.275162 -31.104305) (xy -6.211134 -31.159786) (xy -6.152669 -31.221101)
			(xy -6.100298 -31.287697) (xy -6.054495 -31.358969) (xy -6.015673 -31.434272) (xy -5.984185 -31.512924)
			(xy -5.960317 -31.594214) (xy -5.944283 -31.677404) (xy -5.93623 -31.761741) (xy -5.935726 -31.804102)
			(xy -5.93623 -31.846463) (xy -5.944283 -31.9308) (xy -5.960317 -32.01399) (xy -5.984185 -32.09528)
			(xy -6.015673 -32.173932) (xy -6.054495 -32.249235) (xy -6.100298 -32.320507) (xy -6.152669 -32.387103)
			(xy -6.211134 -32.448418) (xy -6.275162 -32.503899) (xy -6.344174 -32.553042) (xy -6.417544 -32.595402)
			(xy -6.494609 -32.630597) (xy -6.574671 -32.658306) (xy -6.657004 -32.67828) (xy -6.740863 -32.690337)
			(xy -6.825488 -32.694369) (xy -6.910113 -32.690337) (xy -6.993972 -32.67828) (xy -7.076305 -32.658306)
			(xy -7.156367 -32.630597) (xy -7.233432 -32.595402) (xy -7.306802 -32.553042) (xy -7.375814 -32.503899)
			(xy -7.439842 -32.448418) (xy -7.498307 -32.387103) (xy -7.550678 -32.320507) (xy -7.596481 -32.249235)
			(xy -7.635303 -32.173932) (xy -7.666791 -32.09528) (xy -7.690659 -32.01399) (xy -7.706693 -31.9308)
			(xy -7.714746 -31.846463) (xy -10.50823 -31.846463) (xy -10.516283 -31.9308) (xy -10.532317 -32.01399)
			(xy -10.556185 -32.09528) (xy -10.587673 -32.173932) (xy -10.626495 -32.249235) (xy -10.672298 -32.320507)
			(xy -10.724669 -32.387103) (xy -10.783134 -32.448418) (xy -10.847162 -32.503899) (xy -10.916174 -32.553042)
			(xy -10.989544 -32.595402) (xy -11.066609 -32.630597) (xy -11.146671 -32.658306) (xy -11.229004 -32.67828)
			(xy -11.312863 -32.690337) (xy -11.397488 -32.694369) (xy -11.482113 -32.690337) (xy -11.565972 -32.67828)
			(xy -11.648305 -32.658306) (xy -11.728367 -32.630597) (xy -11.805432 -32.595402) (xy -11.878802 -32.553042)
			(xy -11.947814 -32.503899) (xy -12.011842 -32.448418) (xy -12.070307 -32.387103) (xy -12.122678 -32.320507)
			(xy -12.168481 -32.249235) (xy -12.207303 -32.173932) (xy -12.238791 -32.09528) (xy -12.262659 -32.01399)
			(xy -12.278693 -31.9308) (xy -12.286746 -31.846463) (xy -17.221962 -31.846463) (xy -17.221962 -35.910463)
			(xy -12.286746 -35.910463) (xy -12.286746 -35.825741) (xy -12.278693 -35.741404) (xy -12.262659 -35.658214)
			(xy -12.238791 -35.576924) (xy -12.207303 -35.498272) (xy -12.168481 -35.422969) (xy -12.122678 -35.351697)
			(xy -12.070307 -35.285101) (xy -12.011842 -35.223786) (xy -11.947814 -35.168305) (xy -11.878802 -35.119162)
			(xy -11.805432 -35.076802) (xy -11.728367 -35.041607) (xy -11.648305 -35.013898) (xy -11.565972 -34.993924)
			(xy -11.482113 -34.981867) (xy -11.397488 -34.977836) (xy -11.312863 -34.981867) (xy -11.229004 -34.993924)
			(xy -11.146671 -35.013898) (xy -11.066609 -35.041607) (xy -10.989544 -35.076802) (xy -10.916174 -35.119162)
			(xy -10.847162 -35.168305) (xy -10.783134 -35.223786) (xy -10.724669 -35.285101) (xy -10.672298 -35.351697)
			(xy -10.626495 -35.422969) (xy -10.587673 -35.498272) (xy -10.556185 -35.576924) (xy -10.532317 -35.658214)
			(xy -10.516283 -35.741404) (xy -10.50823 -35.825741) (xy -10.507726 -35.868102) (xy -10.50823 -35.910463)
			(xy -7.714746 -35.910463) (xy -7.714746 -35.825741) (xy -7.706693 -35.741404) (xy -7.690659 -35.658214)
			(xy -7.666791 -35.576924) (xy -7.635303 -35.498272) (xy -7.596481 -35.422969) (xy -7.550678 -35.351697)
			(xy -7.498307 -35.285101) (xy -7.439842 -35.223786) (xy -7.375814 -35.168305) (xy -7.306802 -35.119162)
			(xy -7.233432 -35.076802) (xy -7.156367 -35.041607) (xy -7.076305 -35.013898) (xy -6.993972 -34.993924)
			(xy -6.910113 -34.981867) (xy -6.825488 -34.977836) (xy -6.740863 -34.981867) (xy -6.657004 -34.993924)
			(xy -6.574671 -35.013898) (xy -6.494609 -35.041607) (xy -6.417544 -35.076802) (xy -6.344174 -35.119162)
			(xy -6.275162 -35.168305) (xy -6.211134 -35.223786) (xy -6.152669 -35.285101) (xy -6.100298 -35.351697)
			(xy -6.054495 -35.422969) (xy -6.015673 -35.498272) (xy -5.984185 -35.576924) (xy -5.960317 -35.658214)
			(xy -5.944283 -35.741404) (xy -5.93623 -35.825741) (xy -5.935726 -35.868102) (xy -5.93623 -35.910463)
			(xy -5.944283 -35.9948) (xy -5.960317 -36.07799) (xy -5.984185 -36.15928) (xy -6.015673 -36.237932)
			(xy -6.054495 -36.313235) (xy -6.100298 -36.384507) (xy -6.152669 -36.451103) (xy -6.211134 -36.512418)
			(xy -6.275162 -36.567899) (xy -6.344174 -36.617042) (xy -6.417544 -36.659402) (xy -6.494609 -36.694597)
			(xy -6.574671 -36.722306) (xy -6.657004 -36.74228) (xy -6.740863 -36.754337) (xy -6.825488 -36.758369)
			(xy -6.910113 -36.754337) (xy -6.993972 -36.74228) (xy -7.076305 -36.722306) (xy -7.156367 -36.694597)
			(xy -7.233432 -36.659402) (xy -7.306802 -36.617042) (xy -7.375814 -36.567899) (xy -7.439842 -36.512418)
			(xy -7.498307 -36.451103) (xy -7.550678 -36.384507) (xy -7.596481 -36.313235) (xy -7.635303 -36.237932)
			(xy -7.666791 -36.15928) (xy -7.690659 -36.07799) (xy -7.706693 -35.9948) (xy -7.714746 -35.910463)
			(xy -10.50823 -35.910463) (xy -10.516283 -35.9948) (xy -10.532317 -36.07799) (xy -10.556185 -36.15928)
			(xy -10.587673 -36.237932) (xy -10.626495 -36.313235) (xy -10.672298 -36.384507) (xy -10.724669 -36.451103)
			(xy -10.783134 -36.512418) (xy -10.847162 -36.567899) (xy -10.916174 -36.617042) (xy -10.989544 -36.659402)
			(xy -11.066609 -36.694597) (xy -11.146671 -36.722306) (xy -11.229004 -36.74228) (xy -11.312863 -36.754337)
			(xy -11.397488 -36.758369) (xy -11.482113 -36.754337) (xy -11.565972 -36.74228) (xy -11.648305 -36.722306)
			(xy -11.728367 -36.694597) (xy -11.805432 -36.659402) (xy -11.878802 -36.617042) (xy -11.947814 -36.567899)
			(xy -12.011842 -36.512418) (xy -12.070307 -36.451103) (xy -12.122678 -36.384507) (xy -12.168481 -36.313235)
			(xy -12.207303 -36.237932) (xy -12.238791 -36.15928) (xy -12.262659 -36.07799) (xy -12.278693 -35.9948)
			(xy -12.286746 -35.910463) (xy -17.221962 -35.910463) (xy -17.221962 -59.105743) (xy -12.286746 -59.105743)
			(xy -12.286746 -59.021021) (xy -12.278693 -58.936684) (xy -12.262659 -58.853494) (xy -12.238791 -58.772204)
			(xy -12.207303 -58.693552) (xy -12.168481 -58.618249) (xy -12.122678 -58.546977) (xy -12.070307 -58.480381)
			(xy -12.011842 -58.419066) (xy -11.947814 -58.363585) (xy -11.878802 -58.314442) (xy -11.805432 -58.272082)
			(xy -11.728367 -58.236887) (xy -11.648305 -58.209178) (xy -11.565972 -58.189204) (xy -11.482113 -58.177147)
			(xy -11.397488 -58.173116) (xy -11.312863 -58.177147) (xy -11.229004 -58.189204) (xy -11.146671 -58.209178)
			(xy -11.066609 -58.236887) (xy -10.989544 -58.272082) (xy -10.916174 -58.314442) (xy -10.847162 -58.363585)
			(xy -10.783134 -58.419066) (xy -10.724669 -58.480381) (xy -10.672298 -58.546977) (xy -10.626495 -58.618249)
			(xy -10.587673 -58.693552) (xy -10.556185 -58.772204) (xy -10.532317 -58.853494) (xy -10.516283 -58.936684)
			(xy -10.50823 -59.021021) (xy -10.507726 -59.063382) (xy -10.50823 -59.105743) (xy -7.714746 -59.105743)
			(xy -7.714746 -59.021021) (xy -7.706693 -58.936684) (xy -7.690659 -58.853494) (xy -7.666791 -58.772204)
			(xy -7.635303 -58.693552) (xy -7.596481 -58.618249) (xy -7.550678 -58.546977) (xy -7.498307 -58.480381)
			(xy -7.439842 -58.419066) (xy -7.375814 -58.363585) (xy -7.306802 -58.314442) (xy -7.233432 -58.272082)
			(xy -7.156367 -58.236887) (xy -7.076305 -58.209178) (xy -6.993972 -58.189204) (xy -6.910113 -58.177147)
			(xy -6.825488 -58.173116) (xy -6.740863 -58.177147) (xy -6.657004 -58.189204) (xy -6.574671 -58.209178)
			(xy -6.494609 -58.236887) (xy -6.417544 -58.272082) (xy -6.344174 -58.314442) (xy -6.275162 -58.363585)
			(xy -6.211134 -58.419066) (xy -6.152669 -58.480381) (xy -6.100298 -58.546977) (xy -6.054495 -58.618249)
			(xy -6.015673 -58.693552) (xy -5.984185 -58.772204) (xy -5.960317 -58.853494) (xy -5.944283 -58.936684)
			(xy -5.93623 -59.021021) (xy -5.935726 -59.063382) (xy -5.93623 -59.105743) (xy -5.944283 -59.19008)
			(xy -5.960317 -59.27327) (xy -5.984185 -59.35456) (xy -6.015673 -59.433212) (xy -6.054495 -59.508515)
			(xy -6.100298 -59.579787) (xy -6.152669 -59.646383) (xy -6.211134 -59.707698) (xy -6.275162 -59.763179)
			(xy -6.344174 -59.812322) (xy -6.417544 -59.854682) (xy -6.494609 -59.889877) (xy -6.574671 -59.917586)
			(xy -6.657004 -59.93756) (xy -6.740863 -59.949617) (xy -6.825488 -59.953649) (xy -6.910113 -59.949617)
			(xy -6.993972 -59.93756) (xy -7.076305 -59.917586) (xy -7.156367 -59.889877) (xy -7.233432 -59.854682)
			(xy -7.306802 -59.812322) (xy -7.375814 -59.763179) (xy -7.439842 -59.707698) (xy -7.498307 -59.646383)
			(xy -7.550678 -59.579787) (xy -7.596481 -59.508515) (xy -7.635303 -59.433212) (xy -7.666791 -59.35456)
			(xy -7.690659 -59.27327) (xy -7.706693 -59.19008) (xy -7.714746 -59.105743) (xy -10.50823 -59.105743)
			(xy -10.516283 -59.19008) (xy -10.532317 -59.27327) (xy -10.556185 -59.35456) (xy -10.587673 -59.433212)
			(xy -10.626495 -59.508515) (xy -10.672298 -59.579787) (xy -10.724669 -59.646383) (xy -10.783134 -59.707698)
			(xy -10.847162 -59.763179) (xy -10.916174 -59.812322) (xy -10.989544 -59.854682) (xy -11.066609 -59.889877)
			(xy -11.146671 -59.917586) (xy -11.229004 -59.93756) (xy -11.312863 -59.949617) (xy -11.397488 -59.953649)
			(xy -11.482113 -59.949617) (xy -11.565972 -59.93756) (xy -11.648305 -59.917586) (xy -11.728367 -59.889877)
			(xy -11.805432 -59.854682) (xy -11.878802 -59.812322) (xy -11.947814 -59.763179) (xy -12.011842 -59.707698)
			(xy -12.070307 -59.646383) (xy -12.122678 -59.579787) (xy -12.168481 -59.508515) (xy -12.207303 -59.433212)
			(xy -12.238791 -59.35456) (xy -12.262659 -59.27327) (xy -12.278693 -59.19008) (xy -12.286746 -59.105743)
			(xy -17.221962 -59.105743) (xy -17.221962 -63.169743) (xy -12.286746 -63.169743) (xy -12.286746 -63.085021)
			(xy -12.278693 -63.000684) (xy -12.262659 -62.917494) (xy -12.238791 -62.836204) (xy -12.207303 -62.757552)
			(xy -12.168481 -62.682249) (xy -12.122678 -62.610977) (xy -12.070307 -62.544381) (xy -12.011842 -62.483066)
			(xy -11.947814 -62.427585) (xy -11.878802 -62.378442) (xy -11.805432 -62.336082) (xy -11.728367 -62.300887)
			(xy -11.648305 -62.273178) (xy -11.565972 -62.253204) (xy -11.482113 -62.241147) (xy -11.397488 -62.237116)
			(xy -11.312863 -62.241147) (xy -11.229004 -62.253204) (xy -11.146671 -62.273178) (xy -11.066609 -62.300887)
			(xy -10.989544 -62.336082) (xy -10.916174 -62.378442) (xy -10.847162 -62.427585) (xy -10.783134 -62.483066)
			(xy -10.724669 -62.544381) (xy -10.672298 -62.610977) (xy -10.626495 -62.682249) (xy -10.587673 -62.757552)
			(xy -10.556185 -62.836204) (xy -10.532317 -62.917494) (xy -10.516283 -63.000684) (xy -10.50823 -63.085021)
			(xy -10.507726 -63.127382) (xy -10.50823 -63.169743) (xy -7.714746 -63.169743) (xy -7.714746 -63.085021)
			(xy -7.706693 -63.000684) (xy -7.690659 -62.917494) (xy -7.666791 -62.836204) (xy -7.635303 -62.757552)
			(xy -7.596481 -62.682249) (xy -7.550678 -62.610977) (xy -7.498307 -62.544381) (xy -7.439842 -62.483066)
			(xy -7.375814 -62.427585) (xy -7.306802 -62.378442) (xy -7.233432 -62.336082) (xy -7.156367 -62.300887)
			(xy -7.076305 -62.273178) (xy -6.993972 -62.253204) (xy -6.910113 -62.241147) (xy -6.825488 -62.237116)
			(xy -6.740863 -62.241147) (xy -6.657004 -62.253204) (xy -6.574671 -62.273178) (xy -6.494609 -62.300887)
			(xy -6.417544 -62.336082) (xy -6.344174 -62.378442) (xy -6.275162 -62.427585) (xy -6.211134 -62.483066)
			(xy -6.152669 -62.544381) (xy -6.100298 -62.610977) (xy -6.054495 -62.682249) (xy -6.015673 -62.757552)
			(xy -5.984185 -62.836204) (xy -5.960317 -62.917494) (xy -5.944283 -63.000684) (xy -5.93623 -63.085021)
			(xy -5.935726 -63.127382) (xy -5.93623 -63.169743) (xy -5.944283 -63.25408) (xy -5.960317 -63.33727)
			(xy -5.984185 -63.41856) (xy -6.015673 -63.497212) (xy -6.054495 -63.572515) (xy -6.100298 -63.643787)
			(xy -6.152669 -63.710383) (xy -6.211134 -63.771698) (xy -6.275162 -63.827179) (xy -6.344174 -63.876322)
			(xy -6.417544 -63.918682) (xy -6.494609 -63.953877) (xy -6.574671 -63.981586) (xy -6.657004 -64.00156)
			(xy -6.740863 -64.013617) (xy -6.825488 -64.017649) (xy -6.910113 -64.013617) (xy -6.993972 -64.00156)
			(xy -7.076305 -63.981586) (xy -7.156367 -63.953877) (xy -7.233432 -63.918682) (xy -7.306802 -63.876322)
			(xy -7.375814 -63.827179) (xy -7.439842 -63.771698) (xy -7.498307 -63.710383) (xy -7.550678 -63.643787)
			(xy -7.596481 -63.572515) (xy -7.635303 -63.497212) (xy -7.666791 -63.41856) (xy -7.690659 -63.33727)
			(xy -7.706693 -63.25408) (xy -7.714746 -63.169743) (xy -10.50823 -63.169743) (xy -10.516283 -63.25408)
			(xy -10.532317 -63.33727) (xy -10.556185 -63.41856) (xy -10.587673 -63.497212) (xy -10.626495 -63.572515)
			(xy -10.672298 -63.643787) (xy -10.724669 -63.710383) (xy -10.783134 -63.771698) (xy -10.847162 -63.827179)
			(xy -10.916174 -63.876322) (xy -10.989544 -63.918682) (xy -11.066609 -63.953877) (xy -11.146671 -63.981586)
			(xy -11.229004 -64.00156) (xy -11.312863 -64.013617) (xy -11.397488 -64.017649) (xy -11.482113 -64.013617)
			(xy -11.565972 -64.00156) (xy -11.648305 -63.981586) (xy -11.728367 -63.953877) (xy -11.805432 -63.918682)
			(xy -11.878802 -63.876322) (xy -11.947814 -63.827179) (xy -12.011842 -63.771698) (xy -12.070307 -63.710383)
			(xy -12.122678 -63.643787) (xy -12.168481 -63.572515) (xy -12.207303 -63.497212) (xy -12.238791 -63.41856)
			(xy -12.262659 -63.33727) (xy -12.278693 -63.25408) (xy -12.286746 -63.169743) (xy -17.221962 -63.169743)
			(xy -17.221962 -187.619583) (xy -12.286746 -187.619583) (xy -12.286746 -187.534861) (xy -12.278693 -187.450524)
			(xy -12.262659 -187.367334) (xy -12.238791 -187.286044) (xy -12.207303 -187.207392) (xy -12.168481 -187.132089)
			(xy -12.122678 -187.060817) (xy -12.070307 -186.994221) (xy -12.011842 -186.932906) (xy -11.947814 -186.877425)
			(xy -11.878802 -186.828282) (xy -11.805432 -186.785922) (xy -11.728367 -186.750727) (xy -11.648305 -186.723018)
			(xy -11.565972 -186.703044) (xy -11.482113 -186.690987) (xy -11.397488 -186.686956) (xy -11.312863 -186.690987)
			(xy -11.229004 -186.703044) (xy -11.146671 -186.723018) (xy -11.066609 -186.750727) (xy -10.989544 -186.785922)
			(xy -10.916174 -186.828282) (xy -10.847162 -186.877425) (xy -10.783134 -186.932906) (xy -10.724669 -186.994221)
			(xy -10.672298 -187.060817) (xy -10.626495 -187.132089) (xy -10.587673 -187.207392) (xy -10.556185 -187.286044)
			(xy -10.532317 -187.367334) (xy -10.516283 -187.450524) (xy -10.50823 -187.534861) (xy -10.507726 -187.577222)
			(xy -10.50823 -187.619583) (xy -7.714746 -187.619583) (xy -7.714746 -187.534861) (xy -7.706693 -187.450524)
			(xy -7.690659 -187.367334) (xy -7.666791 -187.286044) (xy -7.635303 -187.207392) (xy -7.596481 -187.132089)
			(xy -7.550678 -187.060817) (xy -7.498307 -186.994221) (xy -7.439842 -186.932906) (xy -7.375814 -186.877425)
			(xy -7.306802 -186.828282) (xy -7.233432 -186.785922) (xy -7.156367 -186.750727) (xy -7.076305 -186.723018)
			(xy -6.993972 -186.703044) (xy -6.910113 -186.690987) (xy -6.825488 -186.686956) (xy -6.740863 -186.690987)
			(xy -6.657004 -186.703044) (xy -6.574671 -186.723018) (xy -6.494609 -186.750727) (xy -6.417544 -186.785922)
			(xy -6.344174 -186.828282) (xy -6.275162 -186.877425) (xy -6.211134 -186.932906) (xy -6.152669 -186.994221)
			(xy -6.100298 -187.060817) (xy -6.054495 -187.132089) (xy -6.015673 -187.207392) (xy -5.984185 -187.286044)
			(xy -5.960317 -187.367334) (xy -5.944283 -187.450524) (xy -5.93623 -187.534861) (xy -5.935726 -187.577222)
			(xy -5.93623 -187.619583) (xy -5.944283 -187.70392) (xy -5.960317 -187.78711) (xy -5.984185 -187.8684)
			(xy -6.015673 -187.947052) (xy -6.054495 -188.022355) (xy -6.100298 -188.093627) (xy -6.152669 -188.160223)
			(xy -6.211134 -188.221538) (xy -6.275162 -188.277019) (xy -6.344174 -188.326162) (xy -6.417544 -188.368522)
			(xy -6.494609 -188.403717) (xy -6.574671 -188.431426) (xy -6.657004 -188.4514) (xy -6.740863 -188.463457)
			(xy -6.825488 -188.467489) (xy -6.910113 -188.463457) (xy -6.993972 -188.4514) (xy -7.076305 -188.431426)
			(xy -7.156367 -188.403717) (xy -7.233432 -188.368522) (xy -7.306802 -188.326162) (xy -7.375814 -188.277019)
			(xy -7.439842 -188.221538) (xy -7.498307 -188.160223) (xy -7.550678 -188.093627) (xy -7.596481 -188.022355)
			(xy -7.635303 -187.947052) (xy -7.666791 -187.8684) (xy -7.690659 -187.78711) (xy -7.706693 -187.70392)
			(xy -7.714746 -187.619583) (xy -10.50823 -187.619583) (xy -10.516283 -187.70392) (xy -10.532317 -187.78711)
			(xy -10.556185 -187.8684) (xy -10.587673 -187.947052) (xy -10.626495 -188.022355) (xy -10.672298 -188.093627)
			(xy -10.724669 -188.160223) (xy -10.783134 -188.221538) (xy -10.847162 -188.277019) (xy -10.916174 -188.326162)
			(xy -10.989544 -188.368522) (xy -11.066609 -188.403717) (xy -11.146671 -188.431426) (xy -11.229004 -188.4514)
			(xy -11.312863 -188.463457) (xy -11.397488 -188.467489) (xy -11.482113 -188.463457) (xy -11.565972 -188.4514)
			(xy -11.648305 -188.431426) (xy -11.728367 -188.403717) (xy -11.805432 -188.368522) (xy -11.878802 -188.326162)
			(xy -11.947814 -188.277019) (xy -12.011842 -188.221538) (xy -12.070307 -188.160223) (xy -12.122678 -188.093627)
			(xy -12.168481 -188.022355) (xy -12.207303 -187.947052) (xy -12.238791 -187.8684) (xy -12.262659 -187.78711)
			(xy -12.278693 -187.70392) (xy -12.286746 -187.619583) (xy -17.221962 -187.619583) (xy -17.221962 -191.683583)
			(xy -12.286746 -191.683583) (xy -12.286746 -191.598861) (xy -12.278693 -191.514524) (xy -12.262659 -191.431334)
			(xy -12.238791 -191.350044) (xy -12.207303 -191.271392) (xy -12.168481 -191.196089) (xy -12.122678 -191.124817)
			(xy -12.070307 -191.058221) (xy -12.011842 -190.996906) (xy -11.947814 -190.941425) (xy -11.878802 -190.892282)
			(xy -11.805432 -190.849922) (xy -11.728367 -190.814727) (xy -11.648305 -190.787018) (xy -11.565972 -190.767044)
			(xy -11.482113 -190.754987) (xy -11.397488 -190.750956) (xy -11.312863 -190.754987) (xy -11.229004 -190.767044)
			(xy -11.146671 -190.787018) (xy -11.066609 -190.814727) (xy -10.989544 -190.849922) (xy -10.916174 -190.892282)
			(xy -10.847162 -190.941425) (xy -10.783134 -190.996906) (xy -10.724669 -191.058221) (xy -10.672298 -191.124817)
			(xy -10.626495 -191.196089) (xy -10.587673 -191.271392) (xy -10.556185 -191.350044) (xy -10.532317 -191.431334)
			(xy -10.516283 -191.514524) (xy -10.50823 -191.598861) (xy -10.507726 -191.641222) (xy -10.50823 -191.683583)
			(xy -7.714746 -191.683583) (xy -7.714746 -191.598861) (xy -7.706693 -191.514524) (xy -7.690659 -191.431334)
			(xy -7.666791 -191.350044) (xy -7.635303 -191.271392) (xy -7.596481 -191.196089) (xy -7.550678 -191.124817)
			(xy -7.498307 -191.058221) (xy -7.439842 -190.996906) (xy -7.375814 -190.941425) (xy -7.306802 -190.892282)
			(xy -7.233432 -190.849922) (xy -7.156367 -190.814727) (xy -7.076305 -190.787018) (xy -6.993972 -190.767044)
			(xy -6.910113 -190.754987) (xy -6.825488 -190.750956) (xy -6.740863 -190.754987) (xy -6.657004 -190.767044)
			(xy -6.574671 -190.787018) (xy -6.494609 -190.814727) (xy -6.417544 -190.849922) (xy -6.344174 -190.892282)
			(xy -6.275162 -190.941425) (xy -6.211134 -190.996906) (xy -6.152669 -191.058221) (xy -6.100298 -191.124817)
			(xy -6.054495 -191.196089) (xy -6.015673 -191.271392) (xy -5.984185 -191.350044) (xy -5.960317 -191.431334)
			(xy -5.944283 -191.514524) (xy -5.93623 -191.598861) (xy -5.935726 -191.641222) (xy -5.93623 -191.683583)
			(xy -5.944283 -191.76792) (xy -5.960317 -191.85111) (xy -5.984185 -191.9324) (xy -6.015673 -192.011052)
			(xy -6.054495 -192.086355) (xy -6.100298 -192.157627) (xy -6.152669 -192.224223) (xy -6.211134 -192.285538)
			(xy -6.275162 -192.341019) (xy -6.344174 -192.390162) (xy -6.417544 -192.432522) (xy -6.494609 -192.467717)
			(xy -6.574671 -192.495426) (xy -6.657004 -192.5154) (xy -6.740863 -192.527457) (xy -6.825488 -192.531489)
			(xy -6.910113 -192.527457) (xy -6.993972 -192.5154) (xy -7.076305 -192.495426) (xy -7.156367 -192.467717)
			(xy -7.233432 -192.432522) (xy -7.306802 -192.390162) (xy -7.375814 -192.341019) (xy -7.439842 -192.285538)
			(xy -7.498307 -192.224223) (xy -7.550678 -192.157627) (xy -7.596481 -192.086355) (xy -7.635303 -192.011052)
			(xy -7.666791 -191.9324) (xy -7.690659 -191.85111) (xy -7.706693 -191.76792) (xy -7.714746 -191.683583)
			(xy -10.50823 -191.683583) (xy -10.516283 -191.76792) (xy -10.532317 -191.85111) (xy -10.556185 -191.9324)
			(xy -10.587673 -192.011052) (xy -10.626495 -192.086355) (xy -10.672298 -192.157627) (xy -10.724669 -192.224223)
			(xy -10.783134 -192.285538) (xy -10.847162 -192.341019) (xy -10.916174 -192.390162) (xy -10.989544 -192.432522)
			(xy -11.066609 -192.467717) (xy -11.146671 -192.495426) (xy -11.229004 -192.5154) (xy -11.312863 -192.527457)
			(xy -11.397488 -192.531489) (xy -11.482113 -192.527457) (xy -11.565972 -192.5154) (xy -11.648305 -192.495426)
			(xy -11.728367 -192.467717) (xy -11.805432 -192.432522) (xy -11.878802 -192.390162) (xy -11.947814 -192.341019)
			(xy -12.011842 -192.285538) (xy -12.070307 -192.224223) (xy -12.122678 -192.157627) (xy -12.168481 -192.086355)
			(xy -12.207303 -192.011052) (xy -12.238791 -191.9324) (xy -12.262659 -191.85111) (xy -12.278693 -191.76792)
			(xy -12.286746 -191.683583) (xy -17.221962 -191.683583) (xy -17.221962 -206.70012) (xy -17.221437 -206.745589)
			(xy -17.213046 -206.836138) (xy -17.196337 -206.925527) (xy -17.17145 -207.012992) (xy -17.1386 -207.097789)
			(xy -17.098066 -207.179192) (xy -17.050193 -207.256509) (xy -16.995392 -207.329078) (xy -16.934128 -207.396282)
			(xy -16.866924 -207.457546) (xy -16.794355 -207.512347) (xy -16.717038 -207.56022) (xy -16.635635 -207.600754)
			(xy -16.550838 -207.633604) (xy -16.463373 -207.658491) (xy -16.373984 -207.6752) (xy -16.283435 -207.683591)
			(xy -16.237966 -207.684116)
		)
		(stroke
			(width 0)
			(type solid)
		)
		(fill yes)
		(layer "In4.Cu")
		(net "GND")
	)
	(gr_arc
		(start 1.500124 -70.79996)
		(mid 0.439376 -71.239336)
		(end 0 -72.300084)
		(stroke
			(width 2.032)
			(type default)
		)
		(layer "In4.Cu")
	)
	(gr_line
		(start 1.500124 -70.79996)
		(end 6.500114 -70.79996)
		(stroke
			(width 2.032)
			(type default)
		)
		(layer "In4.Cu")
	)
	(gr_line
		(start 1.999996 -170.699938)
		(end 10.359898 -170.699938)
		(stroke
			(width 2.032)
			(type default)
		)
		(layer "In4.Cu")
	)
	(gr_arc
		(start 1.999996 0)
		(mid 0.585785 -0.585785)
		(end 0 -1.999996)
		(stroke
			(width 2.032)
			(type default)
		)
		(layer "In4.Cu")
	)
	(gr_line
		(start 1.999996 0)
		(end 198.000112 0)
		(stroke
			(width 2.032)
			(type default)
		)
		(layer "In4.Cu")
	)
	(gr_arc
		(start 6.500114 -70.79996)
		(mid 7.560682 -70.360658)
		(end 7.999984 -69.30009)
		(stroke
			(width 2.032)
			(type default)
		)
		(layer "In4.Cu")
	)
	(gr_line
		(start 6.500114 -30.80004)
		(end 1.500124 -30.80004)
		(stroke
			(width 2.032)
			(type default)
		)
		(layer "In4.Cu")
	)
	(gr_line
		(start 7.999984 -69.30009)
		(end 7.999984 -32.29991)
		(stroke
			(width 2.032)
			(type default)
		)
		(layer "In4.Cu")
	)
	(gr_arc
		(start 7.999984 -32.29991)
		(mid 7.560682 -31.239342)
		(end 6.500114 -30.80004)
		(stroke
			(width 2.032)
			(type default)
		)
		(layer "In4.Cu")
	)
	(gr_line
		(start 12.359894 -208.197196)
		(end 12.497054 -208.334356)
		(stroke
			(width 2.032)
			(type default)
		)
		(layer "In4.Cu")
	)
	(gr_arc
		(start 12.359894 -172.699934)
		(mid 11.774121 -171.285702)
		(end 10.359898 -170.699938)
		(stroke
			(width 2.032)
			(type default)
		)
		(layer "In4.Cu")
	)
	(gr_line
		(start 12.359894 -172.699934)
		(end 12.359894 -208.197196)
		(stroke
			(width 2.032)
			(type default)
		)
		(layer "In4.Cu")
	)
	(gr_line
		(start 12.497054 -208.334356)
		(end 12.864084 -208.699608)
		(stroke
			(width 2.032)
			(type default)
		)
		(layer "In4.Cu")
	)
	(gr_line
		(start 15.48384 -117.0432)
		(end 15.82674 -117.3861)
		(stroke
			(width 0.508)
			(type default)
		)
		(layer "In4.Cu")
	)
	(gr_line
		(start 15.48384 -100.29698)
		(end 15.48384 -117.0432)
		(stroke
			(width 0.508)
			(type default)
		)
		(layer "In4.Cu")
	)
	(gr_line
		(start 15.82674 -117.3861)
		(end 33.99028 -117.3861)
		(stroke
			(width 0.508)
			(type default)
		)
		(layer "In4.Cu")
	)
	(gr_line
		(start 22.3393 -24.056848)
		(end 22.822408 -24.539956)
		(stroke
			(width 1.016)
			(type default)
		)
		(layer "In4.Cu")
	)
	(gr_line
		(start 22.3393 -20.73656)
		(end 22.3393 -24.056848)
		(stroke
			(width 1.016)
			(type default)
		)
		(layer "In4.Cu")
	)
	(gr_line
		(start 22.3393 -20.73656)
		(end 23.89124 -19.18462)
		(stroke
			(width 1.016)
			(type default)
		)
		(layer "In4.Cu")
	)
	(gr_line
		(start 22.67585 -182.537862)
		(end 22.734778 -182.478934)
		(stroke
			(width 0.1524)
			(type default)
		)
		(layer "In4.Cu")
	)
	(gr_line
		(start 22.67585 -182.537862)
		(end 23.003256 -182.865268)
		(stroke
			(width 0.1524)
			(type default)
		)
		(layer "In4.Cu")
	)
	(gr_line
		(start 22.67585 -181.90464)
		(end 22.67585 -182.537862)
		(stroke
			(width 0.1524)
			(type default)
		)
		(layer "In4.Cu")
	)
	(gr_line
		(start 22.67585 -180.979064)
		(end 22.67585 -182.537862)
		(stroke
			(width 0.1524)
			(type default)
		)
		(layer "In4.Cu")
	)
	(gr_line
		(start 22.67585 -180.979064)
		(end 22.67585 -181.90464)
		(stroke
			(width 0.1524)
			(type default)
		)
		(layer "In4.Cu")
	)
	(gr_line
		(start 22.72284 -182.425848)
		(end 22.734778 -182.437786)
		(stroke
			(width 0.1524)
			(type default)
		)
		(layer "In4.Cu")
	)
	(gr_line
		(start 22.72284 -182.395622)
		(end 23.192486 -182.865268)
		(stroke
			(width 0.1524)
			(type default)
		)
		(layer "In4.Cu")
	)
	(gr_line
		(start 22.72284 -181.014116)
		(end 22.72284 -182.425848)
		(stroke
			(width 0.1524)
			(type default)
		)
		(layer "In4.Cu")
	)
	(gr_line
		(start 22.72284 -181.014116)
		(end 22.72284 -182.395622)
		(stroke
			(width 0.1524)
			(type default)
		)
		(layer "In4.Cu")
	)
	(gr_line
		(start 22.734778 -182.478934)
		(end 22.734778 -180.685186)
		(stroke
			(width 0.1524)
			(type default)
		)
		(layer "In4.Cu")
	)
	(gr_line
		(start 22.734778 -182.437786)
		(end 22.734778 -180.920136)
		(stroke
			(width 0.1524)
			(type default)
		)
		(layer "In4.Cu")
	)
	(gr_line
		(start 22.734778 -182.437786)
		(end 23.16226 -182.865268)
		(stroke
			(width 0.1524)
			(type default)
		)
		(layer "In4.Cu")
	)
	(gr_line
		(start 22.734778 -182.40756)
		(end 22.734778 -180.920136)
		(stroke
			(width 0.1524)
			(type default)
		)
		(layer "In4.Cu")
	)
	(gr_line
		(start 22.734778 -182.40756)
		(end 23.192486 -182.865268)
		(stroke
			(width 0.1524)
			(type default)
		)
		(layer "In4.Cu")
	)
	(gr_line
		(start 22.734778 -180.920136)
		(end 22.67585 -180.979064)
		(stroke
			(width 0.1524)
			(type default)
		)
		(layer "In4.Cu")
	)
	(gr_line
		(start 22.734778 -180.920136)
		(end 22.734778 -182.40756)
		(stroke
			(width 0.1524)
			(type default)
		)
		(layer "In4.Cu")
	)
	(gr_line
		(start 22.734778 -180.920136)
		(end 22.987762 -180.667152)
		(stroke
			(width 0.1524)
			(type default)
		)
		(layer "In4.Cu")
	)
	(gr_line
		(start 22.734778 -180.920136)
		(end 24.84755 -180.920136)
		(stroke
			(width 0.1524)
			(type default)
		)
		(layer "In4.Cu")
	)
	(gr_line
		(start 22.734778 -180.685186)
		(end 22.734778 -182.437786)
		(stroke
			(width 0.1524)
			(type default)
		)
		(layer "In4.Cu")
	)
	(gr_line
		(start 22.734778 -180.685186)
		(end 23.192486 -181.142894)
		(stroke
			(width 0.1524)
			(type default)
		)
		(layer "In4.Cu")
	)
	(gr_line
		(start 22.814788 -182.48757)
		(end 22.814788 -181.000146)
		(stroke
			(width 0.1524)
			(type default)
		)
		(layer "In4.Cu")
	)
	(gr_line
		(start 22.814788 -182.48757)
		(end 22.814788 -180.605176)
		(stroke
			(width 0.1524)
			(type default)
		)
		(layer "In4.Cu")
	)
	(gr_line
		(start 22.814788 -182.48757)
		(end 23.192486 -182.865268)
		(stroke
			(width 0.1524)
			(type default)
		)
		(layer "In4.Cu")
	)
	(gr_line
		(start 22.814788 -181.000146)
		(end 22.734778 -180.920136)
		(stroke
			(width 0.1524)
			(type default)
		)
		(layer "In4.Cu")
	)
	(gr_line
		(start 22.814788 -180.605176)
		(end 22.734778 -180.685186)
		(stroke
			(width 0.1524)
			(type default)
		)
		(layer "In4.Cu")
	)
	(gr_line
		(start 22.814788 -180.605176)
		(end 22.814788 -182.48757)
		(stroke
			(width 0.1524)
			(type default)
		)
		(layer "In4.Cu")
	)
	(gr_line
		(start 22.814788 -180.605176)
		(end 23.192486 -180.982874)
		(stroke
			(width 0.1524)
			(type default)
		)
		(layer "In4.Cu")
	)
	(gr_line
		(start 22.822408 -24.539956)
		(end 22.822408 -21.219668)
		(stroke
			(width 1.016)
			(type default)
		)
		(layer "In4.Cu")
	)
	(gr_line
		(start 22.822408 -21.219668)
		(end 22.3393 -20.73656)
		(stroke
			(width 1.016)
			(type default)
		)
		(layer "In4.Cu")
	)
	(gr_line
		(start 22.987762 -180.667152)
		(end 23.192486 -180.871876)
		(stroke
			(width 0.1524)
			(type default)
		)
		(layer "In4.Cu")
	)
	(gr_line
		(start 23.003256 -182.865268)
		(end 23.192486 -182.865268)
		(stroke
			(width 0.1524)
			(type default)
		)
		(layer "In4.Cu")
	)
	(gr_line
		(start 23.16226 -182.865268)
		(end 23.192486 -182.865268)
		(stroke
			(width 0.1524)
			(type default)
		)
		(layer "In4.Cu")
	)
	(gr_line
		(start 23.192486 -182.865268)
		(end 22.734778 -182.40756)
		(stroke
			(width 0.1524)
			(type default)
		)
		(layer "In4.Cu")
	)
	(gr_line
		(start 23.192486 -182.865268)
		(end 22.814788 -182.48757)
		(stroke
			(width 0.1524)
			(type default)
		)
		(layer "In4.Cu")
	)
	(gr_line
		(start 23.192486 -182.865268)
		(end 23.192486 -181.483762)
		(stroke
			(width 0.1524)
			(type default)
		)
		(layer "In4.Cu")
	)
	(gr_line
		(start 23.192486 -182.865268)
		(end 23.192486 -181.388004)
		(stroke
			(width 0.1524)
			(type default)
		)
		(layer "In4.Cu")
	)
	(gr_line
		(start 23.192486 -182.865268)
		(end 23.192486 -181.388004)
		(stroke
			(width 1.016)
			(type default)
		)
		(layer "In4.Cu")
	)
	(gr_line
		(start 23.192486 -182.865268)
		(end 23.192486 -181.377844)
		(stroke
			(width 0.1524)
			(type default)
		)
		(layer "In4.Cu")
	)
	(gr_line
		(start 23.192486 -182.865268)
		(end 23.192486 -180.982874)
		(stroke
			(width 0.1524)
			(type default)
		)
		(layer "In4.Cu")
	)
	(gr_arc
		(start 23.192486 -182.865268)
		(mid 24.992584 -184.665366)
		(end 26.792682 -182.865268)
		(stroke
			(width 1.016)
			(type default)
		)
		(layer "In4.Cu")
	)
	(gr_line
		(start 23.192486 -181.483762)
		(end 22.72284 -181.014116)
		(stroke
			(width 0.1524)
			(type default)
		)
		(layer "In4.Cu")
	)
	(gr_line
		(start 23.192486 -181.388004)
		(end 22.67585 -181.90464)
		(stroke
			(width 0.1524)
			(type default)
		)
		(layer "In4.Cu")
	)
	(gr_arc
		(start 23.192486 -181.388004)
		(mid 23.093118 -180.953422)
		(end 22.814788 -180.605176)
		(stroke
			(width 1.016)
			(type default)
		)
		(layer "In4.Cu")
	)
	(gr_arc
		(start 23.192486 -181.388004)
		(mid 23.09314 -180.953412)
		(end 22.814788 -180.605176)
		(stroke
			(width 1.016)
			(type default)
		)
		(layer "In4.Cu")
	)
	(gr_line
		(start 23.192486 -181.388004)
		(end 23.192486 -182.865268)
		(stroke
			(width 1.016)
			(type default)
		)
		(layer "In4.Cu")
	)
	(gr_line
		(start 23.192486 -181.377844)
		(end 22.734778 -180.920136)
		(stroke
			(width 0.1524)
			(type default)
		)
		(layer "In4.Cu")
	)
	(gr_line
		(start 23.192486 -181.142894)
		(end 23.192486 -182.865268)
		(stroke
			(width 0.1524)
			(type default)
		)
		(layer "In4.Cu")
	)
	(gr_line
		(start 23.192486 -180.982874)
		(end 22.814788 -180.605176)
		(stroke
			(width 0.1524)
			(type default)
		)
		(layer "In4.Cu")
	)
	(gr_line
		(start 23.192486 -180.982874)
		(end 23.192486 -182.865268)
		(stroke
			(width 0.1524)
			(type default)
		)
		(layer "In4.Cu")
	)
	(gr_line
		(start 23.192486 -180.871876)
		(end 23.192486 -182.865268)
		(stroke
			(width 0.1524)
			(type default)
		)
		(layer "In4.Cu")
	)
	(gr_line
		(start 23.199344 -182.79872)
		(end 23.199344 -181.32044)
		(stroke
			(width 0.2)
			(type default)
		)
		(layer "In4.Cu")
	)
	(gr_arc
		(start 23.199344 -182.79872)
		(mid 25.000204 -184.59958)
		(end 26.801064 -182.79872)
		(stroke
			(width 0.2)
			(type default)
		)
		(layer "In4.Cu")
	)
	(gr_arc
		(start 23.199344 -181.32044)
		(mid 23.100653 -180.886389)
		(end 22.823424 -180.53812)
		(stroke
			(width 0.2)
			(type default)
		)
		(layer "In4.Cu")
	)
	(gr_line
		(start 23.200106 -182.79999)
		(end 23.200106 -181.322726)
		(stroke
			(width 0.2)
			(type default)
		)
		(layer "In4.Cu")
	)
	(gr_arc
		(start 23.200106 -182.79999)
		(mid 25.000077 -184.599834)
		(end 26.800048 -182.79999)
		(stroke
			(width 0.2)
			(type default)
		)
		(layer "In4.Cu")
	)
	(gr_arc
		(start 23.200106 -182.79999)
		(mid 25.000204 -184.600088)
		(end 26.800302 -182.79999)
		(stroke
			(width 1.016)
			(type default)
		)
		(layer "In4.Cu")
	)
	(gr_arc
		(start 23.200106 -182.79999)
		(mid 25.000204 -184.600088)
		(end 26.800302 -182.79999)
		(stroke
			(width 2.032)
			(type default)
		)
		(layer "In4.Cu")
	)
	(gr_arc
		(start 23.200106 -181.322726)
		(mid 23.100769 -180.888126)
		(end 22.822408 -180.539898)
		(stroke
			(width 0.2)
			(type default)
		)
		(layer "In4.Cu")
	)
	(gr_arc
		(start 23.200106 -181.322726)
		(mid 23.100769 -180.888126)
		(end 22.822408 -180.539898)
		(stroke
			(width 1.016)
			(type default)
		)
		(layer "In4.Cu")
	)
	(gr_arc
		(start 23.200106 -181.322726)
		(mid 23.100769 -180.888126)
		(end 22.822408 -180.539898)
		(stroke
			(width 2.032)
			(type default)
		)
		(layer "In4.Cu")
	)
	(gr_line
		(start 23.200106 -181.322726)
		(end 23.200106 -182.79999)
		(stroke
			(width 1.016)
			(type default)
		)
		(layer "In4.Cu")
	)
	(gr_line
		(start 23.200106 -181.322726)
		(end 23.200106 -182.79999)
		(stroke
			(width 2.032)
			(type default)
		)
		(layer "In4.Cu")
	)
	(gr_line
		(start 23.200106 -26.800048)
		(end 23.200106 -25.322784)
		(stroke
			(width 1.016)
			(type default)
		)
		(layer "In4.Cu")
	)
	(gr_arc
		(start 23.200106 -26.800048)
		(mid 25.000204 -28.600146)
		(end 26.800048 -26.800048)
		(stroke
			(width 1.016)
			(type default)
		)
		(layer "In4.Cu")
	)
	(gr_arc
		(start 23.200106 -25.322784)
		(mid 23.100754 -24.888195)
		(end 22.822408 -24.539956)
		(stroke
			(width 1.016)
			(type default)
		)
		(layer "In4.Cu")
	)
	(gr_line
		(start 23.200106 -20.312634)
		(end 23.200106 -26.800048)
		(stroke
			(width 1.016)
			(type default)
		)
		(layer "In4.Cu")
	)
	(gr_line
		(start 23.30704 -26.40838)
		(end 24.25446 -27.3558)
		(stroke
			(width 0.508)
			(type default)
		)
		(layer "In4.Cu")
	)
	(gr_line
		(start 23.30704 -24.45258)
		(end 23.30704 -20.2057)
		(stroke
			(width 1.016)
			(type default)
		)
		(layer "In4.Cu")
	)
	(gr_line
		(start 23.30704 -20.2057)
		(end 23.200106 -20.312634)
		(stroke
			(width 1.016)
			(type default)
		)
		(layer "In4.Cu")
	)
	(gr_line
		(start 23.30704 -20.2057)
		(end 23.30704 -26.40838)
		(stroke
			(width 0.508)
			(type default)
		)
		(layer "In4.Cu")
	)
	(gr_line
		(start 23.494238 -20.018502)
		(end 23.30704 -20.2057)
		(stroke
			(width 0.508)
			(type default)
		)
		(layer "In4.Cu")
	)
	(gr_line
		(start 23.70582 -24.85136)
		(end 23.30704 -24.45258)
		(stroke
			(width 1.016)
			(type default)
		)
		(layer "In4.Cu")
	)
	(gr_line
		(start 23.89124 -19.18462)
		(end 22.3393 -20.73656)
		(stroke
			(width 1.016)
			(type default)
		)
		(layer "In4.Cu")
	)
	(gr_line
		(start 23.89124 -19.18462)
		(end 23.89378 -19.18716)
		(stroke
			(width 1.016)
			(type default)
		)
		(layer "In4.Cu")
	)
	(gr_line
		(start 23.89378 -24.85136)
		(end 23.70582 -24.85136)
		(stroke
			(width 1.016)
			(type default)
		)
		(layer "In4.Cu")
	)
	(gr_line
		(start 23.89378 -19.18716)
		(end 23.89378 -24.85136)
		(stroke
			(width 1.016)
			(type default)
		)
		(layer "In4.Cu")
	)
	(gr_line
		(start 24.08428 -27.71648)
		(end 24.65324 -28.28544)
		(stroke
			(width 1.016)
			(type default)
		)
		(layer "In4.Cu")
	)
	(gr_line
		(start 24.08428 -23.14448)
		(end 24.08428 -27.71648)
		(stroke
			(width 1.016)
			(type default)
		)
		(layer "In4.Cu")
	)
	(gr_line
		(start 24.25446 -27.3558)
		(end 24.25446 -23.31466)
		(stroke
			(width 1.016)
			(type default)
		)
		(layer "In4.Cu")
	)
	(gr_line
		(start 24.25446 -23.31466)
		(end 24.08428 -23.14448)
		(stroke
			(width 1.016)
			(type default)
		)
		(layer "In4.Cu")
	)
	(gr_line
		(start 24.511508 -183.343296)
		(end 24.511508 -180.974238)
		(stroke
			(width 2.54)
			(type default)
		)
		(layer "In4.Cu")
	)
	(gr_line
		(start 24.519128 -183.278018)
		(end 24.519128 -180.90896)
		(stroke
			(width 2.54)
			(type default)
		)
		(layer "In4.Cu")
	)
	(gr_line
		(start 24.65324 -28.28544)
		(end 24.65324 -19.18462)
		(stroke
			(width 1.016)
			(type default)
		)
		(layer "In4.Cu")
	)
	(gr_line
		(start 24.65324 -19.18462)
		(end 23.89124 -19.18462)
		(stroke
			(width 1.016)
			(type default)
		)
		(layer "In4.Cu")
	)
	(gr_line
		(start 24.65324 -19.18462)
		(end 24.95804 -18.87982)
		(stroke
			(width 1.016)
			(type default)
		)
		(layer "In4.Cu")
	)
	(gr_line
		(start 24.84755 -180.920136)
		(end 26.792682 -182.865268)
		(stroke
			(width 0.1524)
			(type default)
		)
		(layer "In4.Cu")
	)
	(gr_line
		(start 24.95804 -18.87982)
		(end 25.2603 -18.87982)
		(stroke
			(width 1.016)
			(type default)
		)
		(layer "In4.Cu")
	)
	(gr_circle
		(center 24.989028 -182.872126)
		(end 26.759154 -182.872126)
		(stroke
			(width 1.27)
			(type default)
		)
		(fill no)
		(layer "In4.Cu")
	)
	(gr_circle
		(center 24.989536 -177.87239)
		(end 27.868372 -177.87239)
		(stroke
			(width 2.54)
			(type default)
		)
		(fill no)
		(layer "In4.Cu")
	)
	(gr_circle
		(center 24.992584 -177.865278)
		(end 27.12085 -177.865278)
		(stroke
			(width 2.54)
			(type default)
		)
		(fill no)
		(layer "In4.Cu")
	)
	(gr_circle
		(center 25.000204 -177.8)
		(end 27.12847 -177.8)
		(stroke
			(width 2.54)
			(type default)
		)
		(fill no)
		(layer "In4.Cu")
	)
	(gr_line
		(start 25.140666 -183.046878)
		(end 25.251664 -183.046878)
		(stroke
			(width 2.54)
			(type default)
		)
		(layer "In4.Cu")
	)
	(gr_line
		(start 25.140666 -176.754536)
		(end 25.140666 -183.046878)
		(stroke
			(width 2.54)
			(type default)
		)
		(layer "In4.Cu")
	)
	(gr_line
		(start 25.148286 -182.9816)
		(end 25.259284 -182.9816)
		(stroke
			(width 2.54)
			(type default)
		)
		(layer "In4.Cu")
	)
	(gr_line
		(start 25.148286 -176.689258)
		(end 25.148286 -182.9816)
		(stroke
			(width 2.54)
			(type default)
		)
		(layer "In4.Cu")
	)
	(gr_line
		(start 25.251664 -183.343296)
		(end 24.511508 -183.343296)
		(stroke
			(width 2.54)
			(type default)
		)
		(layer "In4.Cu")
	)
	(gr_line
		(start 25.251664 -183.046878)
		(end 25.251664 -183.343296)
		(stroke
			(width 2.54)
			(type default)
		)
		(layer "In4.Cu")
	)
	(gr_line
		(start 25.259284 -183.278018)
		(end 24.519128 -183.278018)
		(stroke
			(width 2.54)
			(type default)
		)
		(layer "In4.Cu")
	)
	(gr_line
		(start 25.259284 -182.9816)
		(end 25.259284 -183.278018)
		(stroke
			(width 2.54)
			(type default)
		)
		(layer "In4.Cu")
	)
	(gr_line
		(start 25.2603 -28.26512)
		(end 25.2603 -28.07462)
		(stroke
			(width 1.016)
			(type default)
		)
		(layer "In4.Cu")
	)
	(gr_line
		(start 25.2603 -28.07462)
		(end 25.92324 -27.41168)
		(stroke
			(width 1.016)
			(type default)
		)
		(layer "In4.Cu")
	)
	(gr_line
		(start 25.2603 -18.87982)
		(end 25.35428 -18.9738)
		(stroke
			(width 1.016)
			(type default)
		)
		(layer "In4.Cu")
	)
	(gr_line
		(start 25.35428 -28.17114)
		(end 25.2603 -28.26512)
		(stroke
			(width 1.016)
			(type default)
		)
		(layer "In4.Cu")
	)
	(gr_line
		(start 25.35428 -18.9738)
		(end 25.35428 -28.17114)
		(stroke
			(width 1.016)
			(type default)
		)
		(layer "In4.Cu")
	)
	(gr_line
		(start 25.481534 -27.399488)
		(end 26.404062 -26.47696)
		(stroke
			(width 0.508)
			(type default)
		)
		(layer "In4.Cu")
	)
	(gr_line
		(start 25.481534 -21.265642)
		(end 25.481534 -27.399488)
		(stroke
			(width 0.508)
			(type default)
		)
		(layer "In4.Cu")
	)
	(gr_line
		(start 25.5524 -90.22842)
		(end 15.48384 -100.29698)
		(stroke
			(width 0.508)
			(type default)
		)
		(layer "In4.Cu")
	)
	(gr_line
		(start 25.5524 -72.49414)
		(end 25.5524 -90.22842)
		(stroke
			(width 0.508)
			(type default)
		)
		(layer "In4.Cu")
	)
	(gr_line
		(start 25.799542 -27.287982)
		(end 25.92324 -27.41168)
		(stroke
			(width 0.508)
			(type default)
		)
		(layer "In4.Cu")
	)
	(gr_line
		(start 25.799542 -20.782026)
		(end 25.799542 -27.287982)
		(stroke
			(width 0.508)
			(type default)
		)
		(layer "In4.Cu")
	)
	(gr_line
		(start 25.90546 -19.05254)
		(end 26.800048 -19.947128)
		(stroke
			(width 1.016)
			(type default)
		)
		(layer "In4.Cu")
	)
	(gr_line
		(start 25.90546 -19.03222)
		(end 25.90546 -19.05254)
		(stroke
			(width 1.016)
			(type default)
		)
		(layer "In4.Cu")
	)
	(gr_line
		(start 25.92324 -27.41168)
		(end 25.92324 -20.905724)
		(stroke
			(width 0.508)
			(type default)
		)
		(layer "In4.Cu")
	)
	(gr_line
		(start 25.92324 -27.41168)
		(end 25.92324 -19.05)
		(stroke
			(width 1.016)
			(type default)
		)
		(layer "In4.Cu")
	)
	(gr_line
		(start 25.92324 -27.41168)
		(end 26.800048 -26.534872)
		(stroke
			(width 0.508)
			(type default)
		)
		(layer "In4.Cu")
	)
	(gr_line
		(start 25.92324 -20.905724)
		(end 25.799542 -20.782026)
		(stroke
			(width 0.508)
			(type default)
		)
		(layer "In4.Cu")
	)
	(gr_line
		(start 25.92324 -19.05)
		(end 25.90546 -19.03222)
		(stroke
			(width 1.016)
			(type default)
		)
		(layer "In4.Cu")
	)
	(gr_line
		(start 26.404062 -26.47696)
		(end 26.404062 -20.018502)
		(stroke
			(width 0.508)
			(type default)
		)
		(layer "In4.Cu")
	)
	(gr_line
		(start 26.404062 -20.018502)
		(end 23.494238 -20.018502)
		(stroke
			(width 0.508)
			(type default)
		)
		(layer "In4.Cu")
	)
	(gr_line
		(start 26.792682 -182.865268)
		(end 26.792682 -181.388004)
		(stroke
			(width 1.016)
			(type default)
		)
		(layer "In4.Cu")
	)
	(gr_line
		(start 26.792682 -182.865268)
		(end 26.792682 -180.982874)
		(stroke
			(width 0.1524)
			(type default)
		)
		(layer "In4.Cu")
	)
	(gr_line
		(start 26.792682 -182.865268)
		(end 27.17038 -182.48757)
		(stroke
			(width 0.1524)
			(type default)
		)
		(layer "In4.Cu")
	)
	(gr_line
		(start 26.792682 -182.865268)
		(end 27.264868 -182.393082)
		(stroke
			(width 0.1524)
			(type default)
		)
		(layer "In4.Cu")
	)
	(gr_line
		(start 26.792682 -182.865268)
		(end 27.276552 -182.381398)
		(stroke
			(width 0.1524)
			(type default)
		)
		(layer "In4.Cu")
	)
	(gr_line
		(start 26.792682 -182.865268)
		(end 27.294332 -182.363618)
		(stroke
			(width 0.1524)
			(type default)
		)
		(layer "In4.Cu")
	)
	(gr_line
		(start 26.792682 -181.25694)
		(end 26.792682 -182.865268)
		(stroke
			(width 0.1524)
			(type default)
		)
		(layer "In4.Cu")
	)
	(gr_line
		(start 26.792682 -181.239414)
		(end 26.792682 -182.865268)
		(stroke
			(width 0.1524)
			(type default)
		)
		(layer "In4.Cu")
	)
	(gr_line
		(start 26.792682 -181.151022)
		(end 26.792682 -182.865268)
		(stroke
			(width 0.1524)
			(type default)
		)
		(layer "In4.Cu")
	)
	(gr_line
		(start 26.792682 -180.982874)
		(end 26.792682 -182.865268)
		(stroke
			(width 0.1524)
			(type default)
		)
		(layer "In4.Cu")
	)
	(gr_line
		(start 26.792682 -180.982874)
		(end 27.17038 -180.605176)
		(stroke
			(width 0.1524)
			(type default)
		)
		(layer "In4.Cu")
	)
	(gr_line
		(start 26.800048 -181.322726)
		(end 26.800048 -182.79999)
		(stroke
			(width 0.2)
			(type default)
		)
		(layer "In4.Cu")
	)
	(gr_line
		(start 26.800048 -26.534872)
		(end 26.800048 -19.947128)
		(stroke
			(width 0.508)
			(type default)
		)
		(layer "In4.Cu")
	)
	(gr_line
		(start 26.800048 -25.322784)
		(end 26.800048 -26.800048)
		(stroke
			(width 1.016)
			(type default)
		)
		(layer "In4.Cu")
	)
	(gr_line
		(start 26.800048 -19.947128)
		(end 25.481534 -21.265642)
		(stroke
			(width 0.508)
			(type default)
		)
		(layer "In4.Cu")
	)
	(gr_line
		(start 26.800048 -19.947128)
		(end 26.800048 -25.322784)
		(stroke
			(width 1.016)
			(type default)
		)
		(layer "In4.Cu")
	)
	(gr_line
		(start 26.800302 -182.79999)
		(end 26.800302 -181.322726)
		(stroke
			(width 1.016)
			(type default)
		)
		(layer "In4.Cu")
	)
	(gr_line
		(start 26.800302 -182.79999)
		(end 26.800302 -181.322726)
		(stroke
			(width 2.032)
			(type default)
		)
		(layer "In4.Cu")
	)
	(gr_line
		(start 26.801064 -181.32044)
		(end 26.801064 -182.79872)
		(stroke
			(width 0.2)
			(type default)
		)
		(layer "In4.Cu")
	)
	(gr_line
		(start 27.17038 -182.48757)
		(end 26.792682 -182.865268)
		(stroke
			(width 0.1524)
			(type default)
		)
		(layer "In4.Cu")
	)
	(gr_line
		(start 27.17038 -182.48757)
		(end 27.17038 -180.605176)
		(stroke
			(width 0.1524)
			(type default)
		)
		(layer "In4.Cu")
	)
	(gr_line
		(start 27.17038 -182.455312)
		(end 27.17038 -180.605176)
		(stroke
			(width 0.1524)
			(type default)
		)
		(layer "In4.Cu")
	)
	(gr_arc
		(start 27.17038 -180.605176)
		(mid 24.992584 -174.365301)
		(end 22.814788 -180.605176)
		(stroke
			(width 1.016)
			(type default)
		)
		(layer "In4.Cu")
	)
	(gr_arc
		(start 27.17038 -180.605176)
		(mid 26.892013 -180.953405)
		(end 26.792682 -181.388004)
		(stroke
			(width 1.016)
			(type default)
		)
		(layer "In4.Cu")
	)
	(gr_arc
		(start 27.17038 -180.605176)
		(mid 26.892039 -180.953416)
		(end 26.792682 -181.388004)
		(stroke
			(width 1.016)
			(type default)
		)
		(layer "In4.Cu")
	)
	(gr_line
		(start 27.17038 -180.605176)
		(end 26.792682 -180.982874)
		(stroke
			(width 0.1524)
			(type default)
		)
		(layer "In4.Cu")
	)
	(gr_line
		(start 27.17038 -180.605176)
		(end 27.17038 -182.48757)
		(stroke
			(width 0.1524)
			(type default)
		)
		(layer "In4.Cu")
	)
	(gr_line
		(start 27.17038 -180.605176)
		(end 27.288236 -180.723032)
		(stroke
			(width 0.1524)
			(type default)
		)
		(layer "In4.Cu")
	)
	(gr_arc
		(start 27.176984 -180.53812)
		(mid 26.89979 -180.886397)
		(end 26.801064 -181.32044)
		(stroke
			(width 0.2)
			(type default)
		)
		(layer "In4.Cu")
	)
	(gr_arc
		(start 27.178 -180.539898)
		(mid 25.000077 -174.299864)
		(end 22.822154 -180.539898)
		(stroke
			(width 0.2)
			(type default)
		)
		(layer "In4.Cu")
	)
	(gr_arc
		(start 27.178 -180.539898)
		(mid 25.000204 -174.300023)
		(end 22.822408 -180.539898)
		(stroke
			(width 1.016)
			(type default)
		)
		(layer "In4.Cu")
	)
	(gr_arc
		(start 27.178 -180.539898)
		(mid 25.000204 -174.300023)
		(end 22.822408 -180.539898)
		(stroke
			(width 2.032)
			(type default)
		)
		(layer "In4.Cu")
	)
	(gr_arc
		(start 27.178 -180.539898)
		(mid 26.899555 -180.888117)
		(end 26.800048 -181.322726)
		(stroke
			(width 0.2)
			(type default)
		)
		(layer "In4.Cu")
	)
	(gr_arc
		(start 27.178 -180.539898)
		(mid 26.899661 -180.888138)
		(end 26.800302 -181.322726)
		(stroke
			(width 1.016)
			(type default)
		)
		(layer "In4.Cu")
	)
	(gr_arc
		(start 27.178 -180.539898)
		(mid 26.899661 -180.888138)
		(end 26.800302 -181.322726)
		(stroke
			(width 2.032)
			(type default)
		)
		(layer "In4.Cu")
	)
	(gr_arc
		(start 27.178 -24.539956)
		(mid 25.000077 -18.299922)
		(end 22.822154 -24.539956)
		(stroke
			(width 1.016)
			(type default)
		)
		(layer "In4.Cu")
	)
	(gr_arc
		(start 27.178 -24.539956)
		(mid 26.899576 -24.888179)
		(end 26.800048 -25.322784)
		(stroke
			(width 1.016)
			(type default)
		)
		(layer "In4.Cu")
	)
	(gr_line
		(start 27.178 -24.539956)
		(end 27.30754 -24.410416)
		(stroke
			(width 1.016)
			(type default)
		)
		(layer "In4.Cu")
	)
	(gr_arc
		(start 27.179524 -180.53812)
		(mid 25.000204 -174.298655)
		(end 22.820884 -180.53812)
		(stroke
			(width 0.2)
			(type default)
		)
		(layer "In4.Cu")
	)
	(gr_line
		(start 27.264868 -182.393082)
		(end 27.264868 -180.767228)
		(stroke
			(width 0.1524)
			(type default)
		)
		(layer "In4.Cu")
	)
	(gr_line
		(start 27.264868 -180.767228)
		(end 26.792682 -181.239414)
		(stroke
			(width 0.1524)
			(type default)
		)
		(layer "In4.Cu")
	)
	(gr_line
		(start 27.276552 -182.381398)
		(end 27.276552 -180.667152)
		(stroke
			(width 0.1524)
			(type default)
		)
		(layer "In4.Cu")
	)
	(gr_line
		(start 27.276552 -180.667152)
		(end 26.792682 -181.151022)
		(stroke
			(width 0.1524)
			(type default)
		)
		(layer "In4.Cu")
	)
	(gr_line
		(start 27.288236 -182.573168)
		(end 27.17038 -182.455312)
		(stroke
			(width 0.1524)
			(type default)
		)
		(layer "In4.Cu")
	)
	(gr_line
		(start 27.288236 -180.723032)
		(end 27.288236 -182.573168)
		(stroke
			(width 0.1524)
			(type default)
		)
		(layer "In4.Cu")
	)
	(gr_line
		(start 27.294332 -182.363618)
		(end 27.294332 -180.75529)
		(stroke
			(width 0.1524)
			(type default)
		)
		(layer "In4.Cu")
	)
	(gr_line
		(start 27.294332 -180.75529)
		(end 26.792682 -181.25694)
		(stroke
			(width 0.1524)
			(type default)
		)
		(layer "In4.Cu")
	)
	(gr_line
		(start 27.30754 -24.410416)
		(end 27.30754 -20.22602)
		(stroke
			(width 1.016)
			(type default)
		)
		(layer "In4.Cu")
	)
	(gr_line
		(start 27.30754 -20.22602)
		(end 27.8003 -20.71878)
		(stroke
			(width 1.016)
			(type default)
		)
		(layer "In4.Cu")
	)
	(gr_line
		(start 27.8003 -20.71878)
		(end 27.8003 -22.67204)
		(stroke
			(width 1.016)
			(type default)
		)
		(layer "In4.Cu")
	)
	(gr_line
		(start 28.46578 -69.58076)
		(end 25.5524 -72.49414)
		(stroke
			(width 0.508)
			(type default)
		)
		(layer "In4.Cu")
	)
	(gr_line
		(start 33.99028 -117.3861)
		(end 55.6641 -95.71228)
		(stroke
			(width 0.508)
			(type default)
		)
		(layer "In4.Cu")
	)
	(gr_line
		(start 48.85436 -69.15404)
		(end 48.85436 -17.29994)
		(stroke
			(width 0.508)
			(type default)
		)
		(layer "In4.Cu")
	)
	(gr_line
		(start 48.85436 -17.29994)
		(end 49.98974 -16.16456)
		(stroke
			(width 0.508)
			(type default)
		)
		(layer "In4.Cu")
	)
	(gr_line
		(start 49.28108 -69.58076)
		(end 28.46578 -69.58076)
		(stroke
			(width 0.508)
			(type default)
		)
		(layer "In4.Cu")
	)
	(gr_line
		(start 49.28108 -69.58076)
		(end 48.85436 -69.15404)
		(stroke
			(width 0.508)
			(type default)
		)
		(layer "In4.Cu")
	)
	(gr_line
		(start 49.98974 -16.16456)
		(end 83.2739 -16.16456)
		(stroke
			(width 0.508)
			(type default)
		)
		(layer "In4.Cu")
	)
	(gr_line
		(start 55.6641 -95.71228)
		(end 55.6641 -81.1911)
		(stroke
			(width 0.508)
			(type default)
		)
		(layer "In4.Cu")
	)
	(gr_line
		(start 55.6641 -81.1911)
		(end 56.05018 -80.80502)
		(stroke
			(width 0.508)
			(type default)
		)
		(layer "In4.Cu")
	)
	(gr_line
		(start 56.05018 -80.80502)
		(end 64.337438 -80.80502)
		(stroke
			(width 0.508)
			(type default)
		)
		(layer "In4.Cu")
	)
	(gr_line
		(start 58.50509 -179.092098)
		(end 58.50509 -163.121086)
		(stroke
			(width 0.508)
			(type default)
		)
		(layer "In4.Cu")
	)
	(gr_line
		(start 58.50509 -163.121086)
		(end 60.859416 -160.76676)
		(stroke
			(width 0.508)
			(type default)
		)
		(layer "In4.Cu")
	)
	(gr_line
		(start 60.859416 -160.76676)
		(end 66.776854 -160.76676)
		(stroke
			(width 0.508)
			(type default)
		)
		(layer "In4.Cu")
	)
	(gr_line
		(start 62.436502 -77.029818)
		(end 62.436502 -80.77581)
		(stroke
			(width 0.508)
			(type default)
		)
		(layer "In4.Cu")
	)
	(gr_line
		(start 64.337438 -80.80502)
		(end 65.17386 -81.641442)
		(stroke
			(width 0.508)
			(type default)
		)
		(layer "In4.Cu")
	)
	(gr_line
		(start 64.486282 -185.07329)
		(end 58.50509 -179.092098)
		(stroke
			(width 0.508)
			(type default)
		)
		(layer "In4.Cu")
	)
	(gr_line
		(start 64.588644 -74.877676)
		(end 62.436502 -77.029818)
		(stroke
			(width 0.508)
			(type default)
		)
		(layer "In4.Cu")
	)
	(gr_line
		(start 65.17386 -89.68994)
		(end 65.66916 -90.18524)
		(stroke
			(width 0.508)
			(type default)
		)
		(layer "In4.Cu")
	)
	(gr_line
		(start 65.17386 -81.641442)
		(end 65.17386 -89.68994)
		(stroke
			(width 0.508)
			(type default)
		)
		(layer "In4.Cu")
	)
	(gr_line
		(start 65.66916 -90.18524)
		(end 86.31428 -90.18524)
		(stroke
			(width 0.508)
			(type default)
		)
		(layer "In4.Cu")
	)
	(gr_line
		(start 65.695322 -74.877676)
		(end 64.588644 -74.877676)
		(stroke
			(width 0.508)
			(type default)
		)
		(layer "In4.Cu")
	)
	(gr_line
		(start 65.75298 -69.58076)
		(end 49.28108 -69.58076)
		(stroke
			(width 0.508)
			(type default)
		)
		(layer "In4.Cu")
	)
	(gr_line
		(start 66.37528 -70.20306)
		(end 65.75298 -69.58076)
		(stroke
			(width 0.508)
			(type default)
		)
		(layer "In4.Cu")
	)
	(gr_line
		(start 66.41592 -74.157078)
		(end 65.695322 -74.877676)
		(stroke
			(width 0.508)
			(type default)
		)
		(layer "In4.Cu")
	)
	(gr_line
		(start 66.41592 -70.20306)
		(end 66.37528 -70.20306)
		(stroke
			(width 0.508)
			(type default)
		)
		(layer "In4.Cu")
	)
	(gr_line
		(start 66.41592 -70.20306)
		(end 66.41592 -74.157078)
		(stroke
			(width 0.508)
			(type default)
		)
		(layer "In4.Cu")
	)
	(gr_line
		(start 66.65214 -69.96684)
		(end 66.41592 -70.20306)
		(stroke
			(width 0.508)
			(type default)
		)
		(layer "In4.Cu")
	)
	(gr_line
		(start 66.776854 -160.76676)
		(end 67.349624 -161.33953)
		(stroke
			(width 0.508)
			(type default)
		)
		(layer "In4.Cu")
	)
	(gr_line
		(start 67.11188 -110.42904)
		(end 67.84848 -111.16564)
		(stroke
			(width 0.508)
			(type default)
		)
		(layer "In4.Cu")
	)
	(gr_line
		(start 67.11188 -105.50652)
		(end 67.11188 -110.42904)
		(stroke
			(width 0.508)
			(type default)
		)
		(layer "In4.Cu")
	)
	(gr_line
		(start 67.349624 -170.883834)
		(end 67.923664 -171.457874)
		(stroke
			(width 0.508)
			(type default)
		)
		(layer "In4.Cu")
	)
	(gr_line
		(start 67.349624 -161.33953)
		(end 67.349624 -170.883834)
		(stroke
			(width 0.508)
			(type default)
		)
		(layer "In4.Cu")
	)
	(gr_line
		(start 67.78498 -104.83342)
		(end 67.11188 -105.50652)
		(stroke
			(width 0.508)
			(type default)
		)
		(layer "In4.Cu")
	)
	(gr_line
		(start 67.84848 -111.16564)
		(end 70.18274 -111.16564)
		(stroke
			(width 0.508)
			(type default)
		)
		(layer "In4.Cu")
	)
	(gr_line
		(start 67.923664 -171.457874)
		(end 74.947272 -171.457874)
		(stroke
			(width 0.508)
			(type default)
		)
		(layer "In4.Cu")
	)
	(gr_line
		(start 70.18274 -111.16564)
		(end 70.7263 -111.7092)
		(stroke
			(width 0.508)
			(type default)
		)
		(layer "In4.Cu")
	)
	(gr_line
		(start 70.7263 -123.60402)
		(end 74.24166 -127.11938)
		(stroke
			(width 0.508)
			(type default)
		)
		(layer "In4.Cu")
	)
	(gr_line
		(start 70.7263 -111.7092)
		(end 70.7263 -123.60402)
		(stroke
			(width 0.508)
			(type default)
		)
		(layer "In4.Cu")
	)
	(gr_line
		(start 74.24166 -127.11938)
		(end 78.65618 -127.11938)
		(stroke
			(width 0.508)
			(type default)
		)
		(layer "In4.Cu")
	)
	(gr_line
		(start 74.947272 -171.457874)
		(end 76.461366 -169.94378)
		(stroke
			(width 0.508)
			(type default)
		)
		(layer "In4.Cu")
	)
	(gr_line
		(start 76.461366 -169.94378)
		(end 79.549498 -169.94378)
		(stroke
			(width 0.508)
			(type default)
		)
		(layer "In4.Cu")
	)
	(gr_line
		(start 78.20406 -104.83342)
		(end 67.78498 -104.83342)
		(stroke
			(width 0.508)
			(type default)
		)
		(layer "In4.Cu")
	)
	(gr_line
		(start 78.65618 -127.11938)
		(end 88.43518 -136.89838)
		(stroke
			(width 0.508)
			(type default)
		)
		(layer "In4.Cu")
	)
	(gr_line
		(start 79.549498 -169.94378)
		(end 81.521808 -171.91609)
		(stroke
			(width 0.508)
			(type default)
		)
		(layer "In4.Cu")
	)
	(gr_line
		(start 80.1878 -120.14708)
		(end 80.1878 -106.81716)
		(stroke
			(width 0.508)
			(type default)
		)
		(layer "In4.Cu")
	)
	(gr_line
		(start 80.1878 -106.81716)
		(end 78.20406 -104.83342)
		(stroke
			(width 0.508)
			(type default)
		)
		(layer "In4.Cu")
	)
	(gr_line
		(start 80.83042 -69.75094)
		(end 80.91678 -69.8373)
		(stroke
			(width 0.508)
			(type default)
		)
		(layer "In4.Cu")
	)
	(gr_line
		(start 80.83042 -26.27376)
		(end 80.83042 -69.75094)
		(stroke
			(width 0.508)
			(type default)
		)
		(layer "In4.Cu")
	)
	(gr_line
		(start 81.521808 -171.91609)
		(end 89.132156 -171.91609)
		(stroke
			(width 0.508)
			(type default)
		)
		(layer "In4.Cu")
	)
	(gr_line
		(start 83.064604 -208.699608)
		(end 12.864084 -208.699608)
		(stroke
			(width 2.032)
			(type default)
		)
		(layer "In4.Cu")
	)
	(gr_line
		(start 83.064604 -208.699608)
		(end 83.54441 -208.222342)
		(stroke
			(width 2.032)
			(type default)
		)
		(layer "In4.Cu")
	)
	(gr_line
		(start 83.2739 -16.16456)
		(end 84.17306 -17.06372)
		(stroke
			(width 0.508)
			(type default)
		)
		(layer "In4.Cu")
	)
	(gr_line
		(start 83.54441 -208.222342)
		(end 83.559904 -208.206848)
		(stroke
			(width 2.032)
			(type default)
		)
		(layer "In4.Cu")
	)
	(gr_line
		(start 83.559904 -208.206848)
		(end 83.559904 -201.250042)
		(stroke
			(width 2.032)
			(type default)
		)
		(layer "In4.Cu")
	)
	(gr_line
		(start 84.17306 -22.93112)
		(end 80.83042 -26.27376)
		(stroke
			(width 0.508)
			(type default)
		)
		(layer "In4.Cu")
	)
	(gr_line
		(start 84.17306 -17.06372)
		(end 84.17306 -22.93112)
		(stroke
			(width 0.508)
			(type default)
		)
		(layer "In4.Cu")
	)
	(gr_line
		(start 85.460078 -208.196942)
		(end 85.464904 -208.201768)
		(stroke
			(width 2.032)
			(type default)
		)
		(layer "In4.Cu")
	)
	(gr_arc
		(start 85.460078 -201.250042)
		(mid 84.509991 -200.299828)
		(end 83.559904 -201.250042)
		(stroke
			(width 2.032)
			(type default)
		)
		(layer "In4.Cu")
	)
	(gr_line
		(start 85.460078 -201.250042)
		(end 85.460078 -208.196942)
		(stroke
			(width 2.032)
			(type default)
		)
		(layer "In4.Cu")
	)
	(gr_line
		(start 85.464904 -208.201768)
		(end 85.965284 -208.699608)
		(stroke
			(width 2.032)
			(type default)
		)
		(layer "In4.Cu")
	)
	(gr_line
		(start 86.31428 -90.18524)
		(end 91.5416 -95.41256)
		(stroke
			(width 0.508)
			(type default)
		)
		(layer "In4.Cu")
	)
	(gr_line
		(start 88.31072 -128.27)
		(end 80.1878 -120.14708)
		(stroke
			(width 0.508)
			(type default)
		)
		(layer "In4.Cu")
	)
	(gr_line
		(start 88.3412 -158.45028)
		(end 88.78824 -158.89732)
		(stroke
			(width 0.508)
			(type default)
		)
		(layer "In4.Cu")
	)
	(gr_line
		(start 88.3412 -146.0119)
		(end 88.3412 -158.45028)
		(stroke
			(width 0.508)
			(type default)
		)
		(layer "In4.Cu")
	)
	(gr_line
		(start 88.43518 -145.91792)
		(end 88.3412 -146.0119)
		(stroke
			(width 0.508)
			(type default)
		)
		(layer "In4.Cu")
	)
	(gr_line
		(start 88.43518 -136.89838)
		(end 88.43518 -145.91792)
		(stroke
			(width 0.508)
			(type default)
		)
		(layer "In4.Cu")
	)
	(gr_line
		(start 88.78824 -158.89732)
		(end 95.885 -158.89732)
		(stroke
			(width 0.508)
			(type default)
		)
		(layer "In4.Cu")
	)
	(gr_line
		(start 89.132156 -171.91609)
		(end 91.16441 -169.883836)
		(stroke
			(width 0.508)
			(type default)
		)
		(layer "In4.Cu")
	)
	(gr_line
		(start 91.16441 -169.883836)
		(end 92.300044 -169.883836)
		(stroke
			(width 0.508)
			(type default)
		)
		(layer "In4.Cu")
	)
	(gr_line
		(start 91.5416 -109.63402)
		(end 98.99396 -117.08638)
		(stroke
			(width 0.508)
			(type default)
		)
		(layer "In4.Cu")
	)
	(gr_line
		(start 91.5416 -95.41256)
		(end 91.5416 -109.63402)
		(stroke
			(width 0.508)
			(type default)
		)
		(layer "In4.Cu")
	)
	(gr_line
		(start 92.300044 -169.883836)
		(end 92.718382 -170.302174)
		(stroke
			(width 0.508)
			(type default)
		)
		(layer "In4.Cu")
	)
	(gr_line
		(start 92.718382 -173.473618)
		(end 93.110304 -173.86554)
		(stroke
			(width 0.508)
			(type default)
		)
		(layer "In4.Cu")
	)
	(gr_line
		(start 92.718382 -170.302174)
		(end 92.718382 -173.473618)
		(stroke
			(width 0.508)
			(type default)
		)
		(layer "In4.Cu")
	)
	(gr_line
		(start 93.110304 -173.86554)
		(end 120.99036 -173.86554)
		(stroke
			(width 0.508)
			(type default)
		)
		(layer "In4.Cu")
	)
	(gr_line
		(start 95.47098 -128.27)
		(end 88.31072 -128.27)
		(stroke
			(width 0.508)
			(type default)
		)
		(layer "In4.Cu")
	)
	(gr_line
		(start 96.10344 -162.9664)
		(end 96.10344 -148.14296)
		(stroke
			(width 0.508)
			(type default)
		)
		(layer "In4.Cu")
	)
	(gr_line
		(start 96.10344 -148.14296)
		(end 96.9391 -147.3073)
		(stroke
			(width 0.508)
			(type default)
		)
		(layer "In4.Cu")
	)
	(gr_line
		(start 96.165924 -208.699608)
		(end 85.965284 -208.699608)
		(stroke
			(width 2.032)
			(type default)
		)
		(layer "In4.Cu")
	)
	(gr_line
		(start 96.165924 -208.699608)
		(end 96.659954 -208.205578)
		(stroke
			(width 2.032)
			(type default)
		)
		(layer "In4.Cu")
	)
	(gr_line
		(start 96.61652 -163.47948)
		(end 96.10344 -162.9664)
		(stroke
			(width 0.508)
			(type default)
		)
		(layer "In4.Cu")
	)
	(gr_line
		(start 96.659954 -208.205578)
		(end 96.659954 -188.250068)
		(stroke
			(width 2.032)
			(type default)
		)
		(layer "In4.Cu")
	)
	(gr_line
		(start 96.9391 -147.3073)
		(end 96.9391 -129.73812)
		(stroke
			(width 0.508)
			(type default)
		)
		(layer "In4.Cu")
	)
	(gr_line
		(start 96.9391 -147.3073)
		(end 114.31524 -147.3073)
		(stroke
			(width 0.508)
			(type default)
		)
		(layer "In4.Cu")
	)
	(gr_line
		(start 96.9391 -129.73812)
		(end 95.47098 -128.27)
		(stroke
			(width 0.508)
			(type default)
		)
		(layer "In4.Cu")
	)
	(gr_line
		(start 97.350834 -185.07329)
		(end 64.486282 -185.07329)
		(stroke
			(width 0.508)
			(type default)
		)
		(layer "In4.Cu")
	)
	(gr_line
		(start 98.99396 -117.08638)
		(end 99.57308 -117.08638)
		(stroke
			(width 0.508)
			(type default)
		)
		(layer "In4.Cu")
	)
	(gr_line
		(start 99.030282 -158.83509)
		(end 100.138738 -159.943546)
		(stroke
			(width 0.508)
			(type default)
		)
		(layer "In4.Cu")
	)
	(gr_line
		(start 99.030282 -153.248614)
		(end 99.030282 -158.83509)
		(stroke
			(width 0.508)
			(type default)
		)
		(layer "In4.Cu")
	)
	(gr_line
		(start 99.268534 -153.010362)
		(end 99.030282 -153.248614)
		(stroke
			(width 0.508)
			(type default)
		)
		(layer "In4.Cu")
	)
	(gr_line
		(start 99.57308 -117.08638)
		(end 120.60682 -117.08638)
		(stroke
			(width 0.508)
			(type default)
		)
		(layer "In4.Cu")
	)
	(gr_line
		(start 100.138738 -159.943546)
		(end 104.553258 -159.943546)
		(stroke
			(width 0.508)
			(type default)
		)
		(layer "In4.Cu")
	)
	(gr_line
		(start 101.25583 -153.010362)
		(end 99.268534 -153.010362)
		(stroke
			(width 0.508)
			(type default)
		)
		(layer "In4.Cu")
	)
	(gr_line
		(start 101.320092 -152.9461)
		(end 101.25583 -153.010362)
		(stroke
			(width 0.508)
			(type default)
		)
		(layer "In4.Cu")
	)
	(gr_line
		(start 101.576378 -152.689814)
		(end 101.320092 -152.9461)
		(stroke
			(width 0.381)
			(type default)
		)
		(layer "In4.Cu")
	)
	(gr_line
		(start 103.359966 -208.19745)
		(end 103.364284 -208.201768)
		(stroke
			(width 2.032)
			(type default)
		)
		(layer "In4.Cu")
	)
	(gr_arc
		(start 103.359966 -188.250068)
		(mid 100.00996 -184.900062)
		(end 96.659954 -188.250068)
		(stroke
			(width 2.032)
			(type default)
		)
		(layer "In4.Cu")
	)
	(gr_line
		(start 103.359966 -188.250068)
		(end 103.359966 -208.19745)
		(stroke
			(width 2.032)
			(type default)
		)
		(layer "In4.Cu")
	)
	(gr_line
		(start 103.364284 -208.201768)
		(end 103.864664 -208.699608)
		(stroke
			(width 2.032)
			(type default)
		)
		(layer "In4.Cu")
	)
	(gr_line
		(start 103.719884 -152.689814)
		(end 101.576378 -152.689814)
		(stroke
			(width 0.381)
			(type default)
		)
		(layer "In4.Cu")
	)
	(gr_line
		(start 104.553258 -159.943546)
		(end 107.484164 -157.01264)
		(stroke
			(width 0.508)
			(type default)
		)
		(layer "In4.Cu")
	)
	(gr_line
		(start 105.000044 -95.79991)
		(end 105.000044 -95.800164)
		(stroke
			(width 10.541)
			(type default)
		)
		(layer "In4.Cu")
	)
	(gr_line
		(start 106.21264 -69.96684)
		(end 66.65214 -69.96684)
		(stroke
			(width 0.508)
			(type default)
		)
		(layer "In4.Cu")
	)
	(gr_line
		(start 107.33786 -152.689814)
		(end 103.719884 -152.689814)
		(stroke
			(width 0.508)
			(type default)
		)
		(layer "In4.Cu")
	)
	(gr_line
		(start 107.484164 -157.01264)
		(end 107.484164 -152.836118)
		(stroke
			(width 0.508)
			(type default)
		)
		(layer "In4.Cu")
	)
	(gr_line
		(start 107.484164 -152.836118)
		(end 107.33786 -152.689814)
		(stroke
			(width 0.508)
			(type default)
		)
		(layer "In4.Cu")
	)
	(gr_line
		(start 114.31524 -147.3073)
		(end 116.0653 -145.55724)
		(stroke
			(width 0.508)
			(type default)
		)
		(layer "In4.Cu")
	)
	(gr_line
		(start 116.0653 -145.55724)
		(end 116.0653 -127.58166)
		(stroke
			(width 0.508)
			(type default)
		)
		(layer "In4.Cu")
	)
	(gr_line
		(start 116.0653 -127.58166)
		(end 116.32184 -127.32512)
		(stroke
			(width 0.508)
			(type default)
		)
		(layer "In4.Cu")
	)
	(gr_line
		(start 116.32184 -127.32512)
		(end 116.83492 -126.81204)
		(stroke
			(width 0.508)
			(type default)
		)
		(layer "In4.Cu")
	)
	(gr_line
		(start 116.83492 -126.81204)
		(end 121.22658 -126.81204)
		(stroke
			(width 0.508)
			(type default)
		)
		(layer "In4.Cu")
	)
	(gr_line
		(start 120.60682 -117.08638)
		(end 122.40514 -115.28806)
		(stroke
			(width 0.508)
			(type default)
		)
		(layer "In4.Cu")
	)
	(gr_line
		(start 120.73382 -163.47948)
		(end 96.61652 -163.47948)
		(stroke
			(width 0.508)
			(type default)
		)
		(layer "In4.Cu")
	)
	(gr_line
		(start 120.99036 -173.86554)
		(end 121.24944 -174.12462)
		(stroke
			(width 0.508)
			(type default)
		)
		(layer "In4.Cu")
	)
	(gr_line
		(start 121.22658 -126.81204)
		(end 122.23242 -127.81788)
		(stroke
			(width 0.508)
			(type default)
		)
		(layer "In4.Cu")
	)
	(gr_line
		(start 121.24944 -174.12462)
		(end 124.90958 -174.12462)
		(stroke
			(width 0.508)
			(type default)
		)
		(layer "In4.Cu")
	)
	(gr_line
		(start 122.23242 -161.98088)
		(end 120.73382 -163.47948)
		(stroke
			(width 0.508)
			(type default)
		)
		(layer "In4.Cu")
	)
	(gr_line
		(start 122.23242 -127.81788)
		(end 122.23242 -161.98088)
		(stroke
			(width 0.508)
			(type default)
		)
		(layer "In4.Cu")
	)
	(gr_line
		(start 122.40514 -115.28806)
		(end 122.40514 -86.15934)
		(stroke
			(width 0.508)
			(type default)
		)
		(layer "In4.Cu")
	)
	(gr_line
		(start 122.40514 -86.15934)
		(end 106.21264 -69.96684)
		(stroke
			(width 0.508)
			(type default)
		)
		(layer "In4.Cu")
	)
	(gr_line
		(start 124.90958 -174.12462)
		(end 127.705104 -176.920144)
		(stroke
			(width 0.508)
			(type default)
		)
		(layer "In4.Cu")
	)
	(gr_line
		(start 127.705104 -183.066944)
		(end 128.5494 -183.91124)
		(stroke
			(width 0.508)
			(type default)
		)
		(layer "In4.Cu")
	)
	(gr_line
		(start 127.705104 -176.920144)
		(end 127.705104 -183.066944)
		(stroke
			(width 0.508)
			(type default)
		)
		(layer "In4.Cu")
	)
	(gr_line
		(start 128.5494 -183.91124)
		(end 139.58062 -183.91124)
		(stroke
			(width 0.508)
			(type default)
		)
		(layer "In4.Cu")
	)
	(gr_line
		(start 133.24078 -47.69104)
		(end 133.24078 -21.17598)
		(stroke
			(width 0.508)
			(type default)
		)
		(layer "In4.Cu")
	)
	(gr_line
		(start 133.24078 -21.17598)
		(end 135.42518 -18.99158)
		(stroke
			(width 0.508)
			(type default)
		)
		(layer "In4.Cu")
	)
	(gr_line
		(start 135.42518 -18.99158)
		(end 147.4216 -18.99158)
		(stroke
			(width 0.508)
			(type default)
		)
		(layer "In4.Cu")
	)
	(gr_line
		(start 139.58062 -183.91124)
		(end 140.33246 -183.1594)
		(stroke
			(width 0.508)
			(type default)
		)
		(layer "In4.Cu")
	)
	(gr_line
		(start 140.26642 -54.71668)
		(end 133.24078 -47.69104)
		(stroke
			(width 0.508)
			(type default)
		)
		(layer "In4.Cu")
	)
	(gr_line
		(start 140.33246 -183.1594)
		(end 140.33246 -170.80484)
		(stroke
			(width 0.508)
			(type default)
		)
		(layer "In4.Cu")
	)
	(gr_line
		(start 140.33246 -170.80484)
		(end 140.65504 -170.48226)
		(stroke
			(width 0.508)
			(type default)
		)
		(layer "In4.Cu")
	)
	(gr_line
		(start 140.65504 -170.48226)
		(end 147.6121 -170.48226)
		(stroke
			(width 0.508)
			(type default)
		)
		(layer "In4.Cu")
	)
	(gr_line
		(start 147.4216 -18.99158)
		(end 148.40458 -19.97456)
		(stroke
			(width 0.508)
			(type default)
		)
		(layer "In4.Cu")
	)
	(gr_line
		(start 147.6121 -170.48226)
		(end 169.86758 -148.22678)
		(stroke
			(width 0.508)
			(type default)
		)
		(layer "In4.Cu")
	)
	(gr_line
		(start 148.40458 -27.34564)
		(end 163.91382 -27.34564)
		(stroke
			(width 0.508)
			(type default)
		)
		(layer "In4.Cu")
	)
	(gr_line
		(start 148.40458 -19.97456)
		(end 148.40458 -27.34564)
		(stroke
			(width 0.508)
			(type default)
		)
		(layer "In4.Cu")
	)
	(gr_line
		(start 150.0759 -54.71668)
		(end 140.26642 -54.71668)
		(stroke
			(width 0.508)
			(type default)
		)
		(layer "In4.Cu")
	)
	(gr_line
		(start 162.19932 -177.61458)
		(end 162.19932 -208.49844)
		(stroke
			(width 0.508)
			(type default)
		)
		(layer "In4.Cu")
	)
	(gr_line
		(start 163.91382 -27.34564)
		(end 166.22776 -25.0317)
		(stroke
			(width 0.508)
			(type default)
		)
		(layer "In4.Cu")
	)
	(gr_line
		(start 166.22776 -25.0317)
		(end 179.0319 -25.0317)
		(stroke
			(width 0.508)
			(type default)
		)
		(layer "In4.Cu")
	)
	(gr_line
		(start 169.86758 -148.22678)
		(end 169.86758 -74.50836)
		(stroke
			(width 0.508)
			(type default)
		)
		(layer "In4.Cu")
	)
	(gr_line
		(start 169.86758 -74.50836)
		(end 150.0759 -54.71668)
		(stroke
			(width 0.508)
			(type default)
		)
		(layer "In4.Cu")
	)
	(gr_line
		(start 172.0977 -22.84476)
		(end 173.53788 -24.28494)
		(stroke
			(width 1.016)
			(type default)
		)
		(layer "In4.Cu")
	)
	(gr_line
		(start 172.0977 -21.21154)
		(end 172.0977 -22.84476)
		(stroke
			(width 1.016)
			(type default)
		)
		(layer "In4.Cu")
	)
	(gr_line
		(start 172.49394 -179.61356)
		(end 173.74616 -180.86578)
		(stroke
			(width 1.016)
			(type default)
		)
		(layer "In4.Cu")
	)
	(gr_line
		(start 172.49394 -176.03216)
		(end 172.49394 -179.61356)
		(stroke
			(width 1.016)
			(type default)
		)
		(layer "In4.Cu")
	)
	(gr_line
		(start 172.74286 -23.48992)
		(end 173.53788 -24.28494)
		(stroke
			(width 1.016)
			(type default)
		)
		(layer "In4.Cu")
	)
	(gr_line
		(start 172.74286 -19.99742)
		(end 172.74286 -23.48992)
		(stroke
			(width 1.016)
			(type default)
		)
		(layer "In4.Cu")
	)
	(gr_line
		(start 173.08068 -175.14062)
		(end 173.290484 -175.350424)
		(stroke
			(width 1.016)
			(type default)
		)
		(layer "In4.Cu")
	)
	(gr_line
		(start 173.100238 -182.749952)
		(end 173.100238 -181.1909)
		(stroke
			(width 1.016)
			(type default)
		)
		(layer "In4.Cu")
	)
	(gr_arc
		(start 173.100238 -182.749952)
		(mid 175.000158 -184.649872)
		(end 176.900078 -182.749952)
		(stroke
			(width 1.016)
			(type default)
		)
		(layer "In4.Cu")
	)
	(gr_arc
		(start 173.100238 -181.1909)
		(mid 173.006986 -180.769307)
		(end 172.744638 -180.42636)
		(stroke
			(width 1.016)
			(type default)
		)
		(layer "In4.Cu")
	)
	(gr_line
		(start 173.100238 -26.75001)
		(end 173.100238 -25.190958)
		(stroke
			(width 1.016)
			(type default)
		)
		(layer "In4.Cu")
	)
	(gr_arc
		(start 173.100238 -26.75001)
		(mid 175.000158 -28.64993)
		(end 176.900078 -26.75001)
		(stroke
			(width 1.016)
			(type default)
		)
		(layer "In4.Cu")
	)
	(gr_arc
		(start 173.100238 -25.190958)
		(mid 173.007041 -24.769225)
		(end 172.744638 -24.426164)
		(stroke
			(width 1.016)
			(type default)
		)
		(layer "In4.Cu")
	)
	(gr_line
		(start 173.1772 -182.91302)
		(end 173.55566 -182.91302)
		(stroke
			(width 1.016)
			(type default)
		)
		(layer "In4.Cu")
	)
	(gr_line
		(start 173.1772 -182.91302)
		(end 174.54372 -184.27954)
		(stroke
			(width 1.016)
			(type default)
		)
		(layer "In4.Cu")
	)
	(gr_line
		(start 173.1772 -176.02962)
		(end 173.1772 -182.91302)
		(stroke
			(width 1.016)
			(type default)
		)
		(layer "In4.Cu")
	)
	(gr_line
		(start 173.1772 -23.75408)
		(end 173.65218 -23.2791)
		(stroke
			(width 1.016)
			(type default)
		)
		(layer "In4.Cu")
	)
	(gr_line
		(start 173.1772 -20.26412)
		(end 173.1772 -23.75408)
		(stroke
			(width 1.016)
			(type default)
		)
		(layer "In4.Cu")
	)
	(gr_line
		(start 173.290484 -175.350424)
		(end 177.255424 -175.350424)
		(stroke
			(width 1.016)
			(type default)
		)
		(layer "In4.Cu")
	)
	(gr_line
		(start 173.53788 -26.312368)
		(end 173.100238 -26.75001)
		(stroke
			(width 1.016)
			(type default)
		)
		(layer "In4.Cu")
	)
	(gr_line
		(start 173.53788 -24.28494)
		(end 173.53788 -26.312368)
		(stroke
			(width 1.016)
			(type default)
		)
		(layer "In4.Cu")
	)
	(gr_line
		(start 173.53788 -24.28494)
		(end 173.53788 -20.6248)
		(stroke
			(width 1.016)
			(type default)
		)
		(layer "In4.Cu")
	)
	(gr_line
		(start 173.53788 -20.6248)
		(end 173.1772 -20.26412)
		(stroke
			(width 1.016)
			(type default)
		)
		(layer "In4.Cu")
	)
	(gr_line
		(start 173.55566 -182.91302)
		(end 173.95444 -183.3118)
		(stroke
			(width 1.016)
			(type default)
		)
		(layer "In4.Cu")
	)
	(gr_line
		(start 173.65218 -23.2791)
		(end 173.65218 -19.56308)
		(stroke
			(width 1.016)
			(type default)
		)
		(layer "In4.Cu")
	)
	(gr_line
		(start 173.74616 -180.86578)
		(end 173.76394 -180.848)
		(stroke
			(width 1.016)
			(type default)
		)
		(layer "In4.Cu")
	)
	(gr_line
		(start 173.76394 -180.848)
		(end 173.76394 -175.44288)
		(stroke
			(width 1.016)
			(type default)
		)
		(layer "In4.Cu")
	)
	(gr_line
		(start 173.76394 -175.44288)
		(end 173.1772 -176.02962)
		(stroke
			(width 1.016)
			(type default)
		)
		(layer "In4.Cu")
	)
	(gr_line
		(start 173.78426 -28.00096)
		(end 173.78426 -19.60118)
		(stroke
			(width 1.016)
			(type default)
		)
		(layer "In4.Cu")
	)
	(gr_line
		(start 173.78426 -19.60118)
		(end 174.54372 -18.84172)
		(stroke
			(width 1.016)
			(type default)
		)
		(layer "In4.Cu")
	)
	(gr_line
		(start 173.89856 -18.84172)
		(end 172.74286 -19.99742)
		(stroke
			(width 1.016)
			(type default)
		)
		(layer "In4.Cu")
	)
	(gr_line
		(start 173.95444 -183.3118)
		(end 173.95444 -175.63338)
		(stroke
			(width 1.016)
			(type default)
		)
		(layer "In4.Cu")
	)
	(gr_line
		(start 173.95444 -175.63338)
		(end 173.76394 -175.44288)
		(stroke
			(width 1.016)
			(type default)
		)
		(layer "In4.Cu")
	)
	(gr_line
		(start 174.065184 -208.699608)
		(end 103.864664 -208.699608)
		(stroke
			(width 2.032)
			(type default)
		)
		(layer "In4.Cu")
	)
	(gr_line
		(start 174.271178 -177.549556)
		(end 175.0187 -178.297078)
		(stroke
			(width 5.08)
			(type default)
		)
		(layer "In4.Cu")
	)
	(gr_line
		(start 174.342552 -208.423764)
		(end 174.065184 -208.699608)
		(stroke
			(width 2.032)
			(type default)
		)
		(layer "In4.Cu")
	)
	(gr_line
		(start 174.342552 -178.623976)
		(end 175.29683 -177.669698)
		(stroke
			(width 5.08)
			(type default)
		)
		(layer "In4.Cu")
	)
	(gr_line
		(start 174.342552 -177.716688)
		(end 174.342552 -178.623976)
		(stroke
			(width 5.08)
			(type default)
		)
		(layer "In4.Cu")
	)
	(gr_line
		(start 174.462186 -177.358548)
		(end 174.271178 -177.549556)
		(stroke
			(width 5.08)
			(type default)
		)
		(layer "In4.Cu")
	)
	(gr_line
		(start 174.50562 -18.80362)
		(end 172.0977 -21.21154)
		(stroke
			(width 1.016)
			(type default)
		)
		(layer "In4.Cu")
	)
	(gr_line
		(start 174.50562 -18.80362)
		(end 174.86376 -18.80362)
		(stroke
			(width 1.016)
			(type default)
		)
		(layer "In4.Cu")
	)
	(gr_line
		(start 174.54372 -184.27954)
		(end 173.1772 -182.91302)
		(stroke
			(width 1.016)
			(type default)
		)
		(layer "In4.Cu")
	)
	(gr_line
		(start 174.54372 -184.27954)
		(end 174.54372 -174.89424)
		(stroke
			(width 1.016)
			(type default)
		)
		(layer "In4.Cu")
	)
	(gr_line
		(start 174.54372 -174.89424)
		(end 175.28286 -175.63338)
		(stroke
			(width 1.016)
			(type default)
		)
		(layer "In4.Cu")
	)
	(gr_line
		(start 174.54372 -28.11526)
		(end 174.54372 -18.84172)
		(stroke
			(width 1.016)
			(type default)
		)
		(layer "In4.Cu")
	)
	(gr_line
		(start 174.54372 -18.84172)
		(end 173.89856 -18.84172)
		(stroke
			(width 1.016)
			(type default)
		)
		(layer "In4.Cu")
	)
	(gr_line
		(start 174.54372 -18.84172)
		(end 174.50562 -18.80362)
		(stroke
			(width 1.016)
			(type default)
		)
		(layer "In4.Cu")
	)
	(gr_line
		(start 174.559976 -208.20634)
		(end 174.342552 -208.423764)
		(stroke
			(width 2.032)
			(type default)
		)
		(layer "In4.Cu")
	)
	(gr_line
		(start 174.559976 -201.250042)
		(end 174.559976 -208.20634)
		(stroke
			(width 2.032)
			(type default)
		)
		(layer "In4.Cu")
	)
	(gr_line
		(start 174.700692 -177.724562)
		(end 174.700692 -177.358548)
		(stroke
			(width 5.08)
			(type default)
		)
		(layer "In4.Cu")
	)
	(gr_line
		(start 174.700692 -177.358548)
		(end 174.342552 -177.716688)
		(stroke
			(width 5.08)
			(type default)
		)
		(layer "In4.Cu")
	)
	(gr_line
		(start 174.700692 -177.358548)
		(end 174.462186 -177.358548)
		(stroke
			(width 5.08)
			(type default)
		)
		(layer "In4.Cu")
	)
	(gr_line
		(start 174.86376 -18.80362)
		(end 175.15078 -19.09064)
		(stroke
			(width 1.016)
			(type default)
		)
		(layer "In4.Cu")
	)
	(gr_line
		(start 175.0187 -178.297078)
		(end 175.273208 -178.297078)
		(stroke
			(width 5.08)
			(type default)
		)
		(layer "In4.Cu")
	)
	(gr_line
		(start 175.15078 -27.92476)
		(end 175.69942 -27.37612)
		(stroke
			(width 1.016)
			(type default)
		)
		(layer "In4.Cu")
	)
	(gr_line
		(start 175.15078 -19.09064)
		(end 175.15078 -27.92476)
		(stroke
			(width 1.016)
			(type default)
		)
		(layer "In4.Cu")
	)
	(gr_line
		(start 175.193706 -178.535838)
		(end 175.193706 -177.851562)
		(stroke
			(width 5.08)
			(type default)
		)
		(layer "In4.Cu")
	)
	(gr_line
		(start 175.193706 -177.851562)
		(end 174.700692 -177.358548)
		(stroke
			(width 5.08)
			(type default)
		)
		(layer "In4.Cu")
	)
	(gr_line
		(start 175.209708 -178.55184)
		(end 175.193706 -178.535838)
		(stroke
			(width 5.08)
			(type default)
		)
		(layer "In4.Cu")
	)
	(gr_line
		(start 175.273208 -178.297078)
		(end 174.700692 -177.724562)
		(stroke
			(width 5.08)
			(type default)
		)
		(layer "In4.Cu")
	)
	(gr_line
		(start 175.28286 -183.99506)
		(end 175.30064 -183.97728)
		(stroke
			(width 1.016)
			(type default)
		)
		(layer "In4.Cu")
	)
	(gr_line
		(start 175.28286 -175.63338)
		(end 175.28286 -183.99506)
		(stroke
			(width 1.016)
			(type default)
		)
		(layer "In4.Cu")
	)
	(gr_line
		(start 175.29683 -177.669698)
		(end 175.29683 -177.255932)
		(stroke
			(width 5.08)
			(type default)
		)
		(layer "In4.Cu")
	)
	(gr_line
		(start 175.30064 -183.97728)
		(end 175.30064 -174.62754)
		(stroke
			(width 1.016)
			(type default)
		)
		(layer "In4.Cu")
	)
	(gr_line
		(start 175.30064 -174.62754)
		(end 175.47082 -174.62754)
		(stroke
			(width 1.016)
			(type default)
		)
		(layer "In4.Cu")
	)
	(gr_line
		(start 175.47082 -174.62754)
		(end 175.7934 -174.95012)
		(stroke
			(width 1.016)
			(type default)
		)
		(layer "In4.Cu")
	)
	(gr_line
		(start 175.69942 -27.37612)
		(end 175.69942 -18.82394)
		(stroke
			(width 1.016)
			(type default)
		)
		(layer "In4.Cu")
	)
	(gr_line
		(start 175.69942 -18.82394)
		(end 176.23028 -19.3548)
		(stroke
			(width 1.016)
			(type default)
		)
		(layer "In4.Cu")
	)
	(gr_line
		(start 175.7934 -183.6928)
		(end 176.26838 -183.21782)
		(stroke
			(width 1.016)
			(type default)
		)
		(layer "In4.Cu")
	)
	(gr_line
		(start 175.7934 -174.95012)
		(end 175.7934 -183.6928)
		(stroke
			(width 1.016)
			(type default)
		)
		(layer "In4.Cu")
	)
	(gr_line
		(start 176.022 -18.80362)
		(end 174.50562 -18.80362)
		(stroke
			(width 1.016)
			(type default)
		)
		(layer "In4.Cu")
	)
	(gr_line
		(start 176.13376 -175.14062)
		(end 173.08068 -175.14062)
		(stroke
			(width 1.016)
			(type default)
		)
		(layer "In4.Cu")
	)
	(gr_line
		(start 176.23028 -27.2796)
		(end 176.66716 -26.84272)
		(stroke
			(width 1.016)
			(type default)
		)
		(layer "In4.Cu")
	)
	(gr_line
		(start 176.23028 -19.3548)
		(end 176.23028 -27.2796)
		(stroke
			(width 1.016)
			(type default)
		)
		(layer "In4.Cu")
	)
	(gr_line
		(start 176.26838 -183.21782)
		(end 176.26838 -174.85614)
		(stroke
			(width 1.016)
			(type default)
		)
		(layer "In4.Cu")
	)
	(gr_line
		(start 176.26838 -174.85614)
		(end 176.51476 -174.60976)
		(stroke
			(width 1.016)
			(type default)
		)
		(layer "In4.Cu")
	)
	(gr_line
		(start 176.459896 -208.19618)
		(end 176.459896 -201.250042)
		(stroke
			(width 2.032)
			(type default)
		)
		(layer "In4.Cu")
	)
	(gr_arc
		(start 176.459896 -201.250042)
		(mid 175.509936 -200.300082)
		(end 174.559976 -201.250042)
		(stroke
			(width 2.032)
			(type default)
		)
		(layer "In4.Cu")
	)
	(gr_line
		(start 176.465484 -208.201768)
		(end 176.459896 -208.19618)
		(stroke
			(width 2.032)
			(type default)
		)
		(layer "In4.Cu")
	)
	(gr_line
		(start 176.47412 -179.760372)
		(end 176.728628 -179.505864)
		(stroke
			(width 0.508)
			(type default)
		)
		(layer "In4.Cu")
	)
	(gr_line
		(start 176.47412 -176.131728)
		(end 176.47412 -179.760372)
		(stroke
			(width 0.508)
			(type default)
		)
		(layer "In4.Cu")
	)
	(gr_line
		(start 176.51476 -174.60976)
		(end 177.255424 -175.350424)
		(stroke
			(width 1.016)
			(type default)
		)
		(layer "In4.Cu")
	)
	(gr_line
		(start 176.573688 -176.03216)
		(end 172.49394 -176.03216)
		(stroke
			(width 1.016)
			(type default)
		)
		(layer "In4.Cu")
	)
	(gr_line
		(start 176.573688 -176.03216)
		(end 176.47412 -176.131728)
		(stroke
			(width 0.508)
			(type default)
		)
		(layer "In4.Cu")
	)
	(gr_line
		(start 176.66716 -26.84272)
		(end 176.66716 -19.44878)
		(stroke
			(width 1.016)
			(type default)
		)
		(layer "In4.Cu")
	)
	(gr_line
		(start 176.66716 -19.44878)
		(end 177.255424 -20.037044)
		(stroke
			(width 1.016)
			(type default)
		)
		(layer "In4.Cu")
	)
	(gr_line
		(start 176.728628 -179.505864)
		(end 176.728628 -176.29251)
		(stroke
			(width 0.508)
			(type default)
		)
		(layer "In4.Cu")
	)
	(gr_line
		(start 176.728628 -176.29251)
		(end 176.855882 -176.419764)
		(stroke
			(width 0.508)
			(type default)
		)
		(layer "In4.Cu")
	)
	(gr_line
		(start 176.855882 -176.419764)
		(end 176.855882 -179.728368)
		(stroke
			(width 0.508)
			(type default)
		)
		(layer "In4.Cu")
	)
	(gr_line
		(start 176.900078 -181.1909)
		(end 176.900078 -182.749952)
		(stroke
			(width 1.016)
			(type default)
		)
		(layer "In4.Cu")
	)
	(gr_line
		(start 176.900078 -25.190958)
		(end 176.900078 -26.75001)
		(stroke
			(width 1.016)
			(type default)
		)
		(layer "In4.Cu")
	)
	(gr_line
		(start 176.965864 -208.699608)
		(end 176.465484 -208.201768)
		(stroke
			(width 2.032)
			(type default)
		)
		(layer "In4.Cu")
	)
	(gr_arc
		(start 177.255424 -180.42636)
		(mid 175.000255 -174.250058)
		(end 172.744638 -180.42636)
		(stroke
			(width 1.016)
			(type default)
		)
		(layer "In4.Cu")
	)
	(gr_line
		(start 177.255424 -180.42636)
		(end 177.255424 -176.713896)
		(stroke
			(width 0.508)
			(type default)
		)
		(layer "In4.Cu")
	)
	(gr_line
		(start 177.255424 -178.177444)
		(end 177.84064 -178.76266)
		(stroke
			(width 1.016)
			(type default)
		)
		(layer "In4.Cu")
	)
	(gr_line
		(start 177.255424 -176.713896)
		(end 176.573688 -176.03216)
		(stroke
			(width 0.508)
			(type default)
		)
		(layer "In4.Cu")
	)
	(gr_line
		(start 177.255424 -175.350424)
		(end 176.573688 -176.03216)
		(stroke
			(width 1.016)
			(type default)
		)
		(layer "In4.Cu")
	)
	(gr_line
		(start 177.255424 -175.350424)
		(end 177.255424 -180.42636)
		(stroke
			(width 1.016)
			(type default)
		)
		(layer "In4.Cu")
	)
	(gr_line
		(start 177.255424 -175.350424)
		(end 177.255424 -178.177444)
		(stroke
			(width 1.016)
			(type default)
		)
		(layer "In4.Cu")
	)
	(gr_arc
		(start 177.255424 -24.426418)
		(mid 175.000031 -18.249953)
		(end 172.744638 -24.426418)
		(stroke
			(width 1.016)
			(type default)
		)
		(layer "In4.Cu")
	)
	(gr_arc
		(start 177.255424 -24.426418)
		(mid 175.000255 -18.250116)
		(end 172.744638 -24.426418)
		(stroke
			(width 1.016)
			(type default)
		)
		(layer "In4.Cu")
	)
	(gr_line
		(start 177.255424 -24.426418)
		(end 177.255424 -23.562056)
		(stroke
			(width 1.016)
			(type default)
		)
		(layer "In4.Cu")
	)
	(gr_line
		(start 177.255424 -23.562056)
		(end 177.84318 -22.9743)
		(stroke
			(width 1.016)
			(type default)
		)
		(layer "In4.Cu")
	)
	(gr_line
		(start 177.255424 -20.037044)
		(end 177.255424 -24.426418)
		(stroke
			(width 1.016)
			(type default)
		)
		(layer "In4.Cu")
	)
	(gr_arc
		(start 177.255678 -180.42636)
		(mid 176.993377 -180.769332)
		(end 176.900078 -181.1909)
		(stroke
			(width 1.016)
			(type default)
		)
		(layer "In4.Cu")
	)
	(gr_arc
		(start 177.255678 -24.426164)
		(mid 176.993325 -24.769252)
		(end 176.900078 -25.190958)
		(stroke
			(width 1.016)
			(type default)
		)
		(layer "In4.Cu")
	)
	(gr_line
		(start 177.84064 -178.76266)
		(end 177.87874 -178.72456)
		(stroke
			(width 1.016)
			(type default)
		)
		(layer "In4.Cu")
	)
	(gr_line
		(start 177.84318 -22.9743)
		(end 177.84318 -20.6248)
		(stroke
			(width 1.016)
			(type default)
		)
		(layer "In4.Cu")
	)
	(gr_line
		(start 177.84318 -20.6248)
		(end 176.022 -18.80362)
		(stroke
			(width 1.016)
			(type default)
		)
		(layer "In4.Cu")
	)
	(gr_line
		(start 177.87874 -178.72456)
		(end 177.87874 -176.8856)
		(stroke
			(width 1.016)
			(type default)
		)
		(layer "In4.Cu")
	)
	(gr_line
		(start 177.87874 -176.8856)
		(end 176.13376 -175.14062)
		(stroke
			(width 1.016)
			(type default)
		)
		(layer "In4.Cu")
	)
	(gr_line
		(start 178.00574 -69.66712)
		(end 181.68874 -73.35012)
		(stroke
			(width 0.508)
			(type default)
		)
		(layer "In4.Cu")
	)
	(gr_line
		(start 178.00574 -38.481)
		(end 178.00574 -69.66712)
		(stroke
			(width 0.508)
			(type default)
		)
		(layer "In4.Cu")
	)
	(gr_line
		(start 179.0319 -25.0317)
		(end 179.80406 -24.25954)
		(stroke
			(width 0.508)
			(type default)
		)
		(layer "In4.Cu")
	)
	(gr_line
		(start 179.80406 -24.25954)
		(end 191.32804 -24.25954)
		(stroke
			(width 0.508)
			(type default)
		)
		(layer "In4.Cu")
	)
	(gr_line
		(start 181.68874 -158.12516)
		(end 162.19932 -177.61458)
		(stroke
			(width 0.508)
			(type default)
		)
		(layer "In4.Cu")
	)
	(gr_line
		(start 181.68874 -73.35012)
		(end 181.68874 -158.12516)
		(stroke
			(width 0.508)
			(type default)
		)
		(layer "In4.Cu")
	)
	(gr_line
		(start 183.31688 -33.16986)
		(end 178.00574 -38.481)
		(stroke
			(width 0.508)
			(type default)
		)
		(layer "In4.Cu")
	)
	(gr_line
		(start 187.163964 -208.699608)
		(end 176.965864 -208.699608)
		(stroke
			(width 2.032)
			(type default)
		)
		(layer "In4.Cu")
	)
	(gr_line
		(start 187.62853 -208.237328)
		(end 187.163964 -208.699608)
		(stroke
			(width 2.032)
			(type default)
		)
		(layer "In4.Cu")
	)
	(gr_line
		(start 187.660026 -208.205832)
		(end 187.62853 -208.237328)
		(stroke
			(width 2.032)
			(type default)
		)
		(layer "In4.Cu")
	)
	(gr_line
		(start 187.660026 -172.699934)
		(end 187.660026 -208.205832)
		(stroke
			(width 2.032)
			(type default)
		)
		(layer "In4.Cu")
	)
	(gr_arc
		(start 189.660022 -170.699938)
		(mid 188.245811 -171.285723)
		(end 187.660026 -172.699934)
		(stroke
			(width 2.032)
			(type default)
		)
		(layer "In4.Cu")
	)
	(gr_line
		(start 190.12916 -33.16986)
		(end 183.31688 -33.16986)
		(stroke
			(width 0.508)
			(type default)
		)
		(layer "In4.Cu")
	)
	(gr_line
		(start 191.32804 -24.25954)
		(end 191.62776 -24.55926)
		(stroke
			(width 0.508)
			(type default)
		)
		(layer "In4.Cu")
	)
	(gr_line
		(start 191.62776 -31.67126)
		(end 190.12916 -33.16986)
		(stroke
			(width 0.508)
			(type default)
		)
		(layer "In4.Cu")
	)
	(gr_line
		(start 191.62776 -24.55926)
		(end 191.62776 -31.67126)
		(stroke
			(width 0.508)
			(type default)
		)
		(layer "In4.Cu")
	)
	(gr_arc
		(start 196.699886 -72.650096)
		(mid 197.139352 -73.71068)
		(end 198.20001 -74.149966)
		(stroke
			(width 2.032)
			(type default)
		)
		(layer "In4.Cu")
	)
	(gr_line
		(start 196.699886 -33.64992)
		(end 196.699886 -72.650096)
		(stroke
			(width 2.032)
			(type default)
		)
		(layer "In4.Cu")
	)
	(gr_line
		(start 198.000112 -170.699938)
		(end 189.660022 -170.699938)
		(stroke
			(width 2.032)
			(type default)
		)
		(layer "In4.Cu")
	)
	(gr_arc
		(start 198.000112 -170.699938)
		(mid 199.41433 -170.114151)
		(end 200.000108 -168.699942)
		(stroke
			(width 2.032)
			(type default)
		)
		(layer "In4.Cu")
	)
	(gr_line
		(start 198.20001 -74.149966)
		(end 198.499984 -74.149966)
		(stroke
			(width 2.032)
			(type default)
		)
		(layer "In4.Cu")
	)
	(gr_arc
		(start 198.20001 -32.15005)
		(mid 197.139352 -32.589336)
		(end 196.699886 -33.64992)
		(stroke
			(width 2.032)
			(type default)
		)
		(layer "In4.Cu")
	)
	(gr_line
		(start 198.499984 -32.15005)
		(end 198.20001 -32.15005)
		(stroke
			(width 2.032)
			(type default)
		)
		(layer "In4.Cu")
	)
	(gr_arc
		(start 198.499984 -32.15005)
		(mid 199.560751 -31.710681)
		(end 200.000108 -30.649926)
		(stroke
			(width 2.032)
			(type default)
		)
		(layer "In4.Cu")
	)
	(gr_arc
		(start 200.000108 -75.65009)
		(mid 199.560727 -74.589354)
		(end 198.499984 -74.149966)
		(stroke
			(width 2.032)
			(type default)
		)
		(layer "In4.Cu")
	)
	(gr_line
		(start 200.000108 -75.65009)
		(end 200.000108 -168.699942)
		(stroke
			(width 2.032)
			(type default)
		)
		(layer "In4.Cu")
	)
	(gr_arc
		(start 200.000108 -1.999996)
		(mid 199.414322 -0.585784)
		(end 198.000112 0)
		(stroke
			(width 2.032)
			(type default)
		)
		(layer "In4.Cu")
	)
	(gr_line
		(start 200.000108 -1.999996)
		(end 200.000108 -30.649926)
		(stroke
			(width 2.032)
			(type default)
		)
		(layer "In4.Cu")
	)
	(gr_line
		(start -18.237962 -206.70012)
		(end -18.237962 -1.999996)
		(stroke
			(width 1.016)
			(type default)
		)
		(layer "In5.Cu")
	)
	(gr_arc
		(start -18.237962 -206.70012)
		(mid -17.652177 -208.114331)
		(end -16.237966 -208.700116)
		(stroke
			(width 1.016)
			(type default)
		)
		(layer "In5.Cu")
	)
	(gr_arc
		(start -16.237966 0)
		(mid -17.652177 -0.585785)
		(end -18.237962 -1.999996)
		(stroke
			(width 1.016)
			(type default)
		)
		(layer "In5.Cu")
	)
	(gr_line
		(start -16.237966 0)
		(end -1.999996 0)
		(stroke
			(width 1.016)
			(type default)
		)
		(layer "In5.Cu")
	)
	(gr_line
		(start -1.999996 -160.375092)
		(end -1.999742 -160.375092)
		(stroke
			(width 1.016)
			(type default)
		)
		(layer "In5.Cu")
	)
	(gr_line
		(start -1.999996 0)
		(end -1.999996 -160.375092)
		(stroke
			(width 1.016)
			(type default)
		)
		(layer "In5.Cu")
	)
	(gr_line
		(start -1.999742 -208.700116)
		(end -16.237966 -208.700116)
		(stroke
			(width 1.016)
			(type default)
		)
		(layer "In5.Cu")
	)
	(gr_line
		(start -1.999742 -160.375092)
		(end -1.999742 -208.700116)
		(stroke
			(width 1.016)
			(type default)
		)
		(layer "In5.Cu")
	)
	(gr_arc
		(start 0 -168.699942)
		(mid 0.585785 -170.114153)
		(end 1.999996 -170.699938)
		(stroke
			(width 1.016)
			(type default)
		)
		(layer "In5.Cu")
	)
	(gr_line
		(start 0 -72.300084)
		(end 0 -168.699942)
		(stroke
			(width 1.016)
			(type default)
		)
		(layer "In5.Cu")
	)
	(gr_line
		(start 0 -29.299916)
		(end 0 -1.999996)
		(stroke
			(width 1.016)
			(type default)
		)
		(layer "In5.Cu")
	)
	(gr_arc
		(start 0 -29.299916)
		(mid 0.439376 -30.360664)
		(end 1.500124 -30.80004)
		(stroke
			(width 1.016)
			(type default)
		)
		(layer "In5.Cu")
	)
	(gr_poly
		(pts
			(xy -2.634742 -208.192116) (xy -2.618087 -208.191622) (xy -2.585913 -208.183001) (xy -2.557066 -208.166346)
			(xy -2.533512 -208.142792) (xy -2.516857 -208.113945) (xy -2.508236 -208.081771) (xy -2.507742 -208.065116)
			(xy -2.507742 -160.883092) (xy -2.507996 -160.883092) (xy -2.507996 -0.635) (xy -2.50849 -0.618345)
			(xy -2.517111 -0.586171) (xy -2.533766 -0.557324) (xy -2.55732 -0.53377) (xy -2.586167 -0.517115)
			(xy -2.618341 -0.508494) (xy -2.634996 -0.508) (xy -16.237966 -0.508) (xy -16.293773 -0.508522) (xy -16.405075 -0.516863)
			(xy -16.515442 -0.533498) (xy -16.624258 -0.558335) (xy -16.730913 -0.591234) (xy -16.834812 -0.632011)
			(xy -16.935372 -0.680438) (xy -17.032033 -0.736246) (xy -17.124253 -0.79912) (xy -17.211516 -0.86871)
			(xy -17.293335 -0.944627) (xy -17.369252 -1.026446) (xy -17.438842 -1.113709) (xy -17.501716 -1.205929)
			(xy -17.557524 -1.30259) (xy -17.605951 -1.40315) (xy -17.646728 -1.507049) (xy -17.679627 -1.613704)
			(xy -17.704464 -1.72252) (xy -17.721099 -1.832887) (xy -17.72944 -1.944189) (xy -17.729962 -1.999996)
			(xy -17.729962 -31.846463) (xy -12.286746 -31.846463) (xy -12.286746 -31.761741) (xy -12.278693 -31.677404)
			(xy -12.262659 -31.594214) (xy -12.238791 -31.512924) (xy -12.207303 -31.434272) (xy -12.168481 -31.358969)
			(xy -12.122678 -31.287697) (xy -12.070307 -31.221101) (xy -12.011842 -31.159786) (xy -11.947814 -31.104305)
			(xy -11.878802 -31.055162) (xy -11.805432 -31.012802) (xy -11.728367 -30.977607) (xy -11.648305 -30.949898)
			(xy -11.565972 -30.929924) (xy -11.482113 -30.917867) (xy -11.397488 -30.913836) (xy -11.312863 -30.917867)
			(xy -11.229004 -30.929924) (xy -11.146671 -30.949898) (xy -11.066609 -30.977607) (xy -10.989544 -31.012802)
			(xy -10.916174 -31.055162) (xy -10.847162 -31.104305) (xy -10.783134 -31.159786) (xy -10.724669 -31.221101)
			(xy -10.672298 -31.287697) (xy -10.626495 -31.358969) (xy -10.587673 -31.434272) (xy -10.556185 -31.512924)
			(xy -10.532317 -31.594214) (xy -10.516283 -31.677404) (xy -10.50823 -31.761741) (xy -10.507726 -31.804102)
			(xy -10.50823 -31.846463) (xy -7.714746 -31.846463) (xy -7.714746 -31.761741) (xy -7.706693 -31.677404)
			(xy -7.690659 -31.594214) (xy -7.666791 -31.512924) (xy -7.635303 -31.434272) (xy -7.596481 -31.358969)
			(xy -7.550678 -31.287697) (xy -7.498307 -31.221101) (xy -7.439842 -31.159786) (xy -7.375814 -31.104305)
			(xy -7.306802 -31.055162) (xy -7.233432 -31.012802) (xy -7.156367 -30.977607) (xy -7.076305 -30.949898)
			(xy -6.993972 -30.929924) (xy -6.910113 -30.917867) (xy -6.825488 -30.913836) (xy -6.740863 -30.917867)
			(xy -6.657004 -30.929924) (xy -6.574671 -30.949898) (xy -6.494609 -30.977607) (xy -6.417544 -31.012802)
			(xy -6.344174 -31.055162) (xy -6.275162 -31.104305) (xy -6.211134 -31.159786) (xy -6.152669 -31.221101)
			(xy -6.100298 -31.287697) (xy -6.054495 -31.358969) (xy -6.015673 -31.434272) (xy -5.984185 -31.512924)
			(xy -5.960317 -31.594214) (xy -5.944283 -31.677404) (xy -5.93623 -31.761741) (xy -5.935726 -31.804102)
			(xy -5.93623 -31.846463) (xy -5.944283 -31.9308) (xy -5.960317 -32.01399) (xy -5.984185 -32.09528)
			(xy -6.015673 -32.173932) (xy -6.054495 -32.249235) (xy -6.100298 -32.320507) (xy -6.152669 -32.387103)
			(xy -6.211134 -32.448418) (xy -6.275162 -32.503899) (xy -6.344174 -32.553042) (xy -6.417544 -32.595402)
			(xy -6.494609 -32.630597) (xy -6.574671 -32.658306) (xy -6.657004 -32.67828) (xy -6.740863 -32.690337)
			(xy -6.825488 -32.694369) (xy -6.910113 -32.690337) (xy -6.993972 -32.67828) (xy -7.076305 -32.658306)
			(xy -7.156367 -32.630597) (xy -7.233432 -32.595402) (xy -7.306802 -32.553042) (xy -7.375814 -32.503899)
			(xy -7.439842 -32.448418) (xy -7.498307 -32.387103) (xy -7.550678 -32.320507) (xy -7.596481 -32.249235)
			(xy -7.635303 -32.173932) (xy -7.666791 -32.09528) (xy -7.690659 -32.01399) (xy -7.706693 -31.9308)
			(xy -7.714746 -31.846463) (xy -10.50823 -31.846463) (xy -10.516283 -31.9308) (xy -10.532317 -32.01399)
			(xy -10.556185 -32.09528) (xy -10.587673 -32.173932) (xy -10.626495 -32.249235) (xy -10.672298 -32.320507)
			(xy -10.724669 -32.387103) (xy -10.783134 -32.448418) (xy -10.847162 -32.503899) (xy -10.916174 -32.553042)
			(xy -10.989544 -32.595402) (xy -11.066609 -32.630597) (xy -11.146671 -32.658306) (xy -11.229004 -32.67828)
			(xy -11.312863 -32.690337) (xy -11.397488 -32.694369) (xy -11.482113 -32.690337) (xy -11.565972 -32.67828)
			(xy -11.648305 -32.658306) (xy -11.728367 -32.630597) (xy -11.805432 -32.595402) (xy -11.878802 -32.553042)
			(xy -11.947814 -32.503899) (xy -12.011842 -32.448418) (xy -12.070307 -32.387103) (xy -12.122678 -32.320507)
			(xy -12.168481 -32.249235) (xy -12.207303 -32.173932) (xy -12.238791 -32.09528) (xy -12.262659 -32.01399)
			(xy -12.278693 -31.9308) (xy -12.286746 -31.846463) (xy -17.729962 -31.846463) (xy -17.729962 -35.910463)
			(xy -12.286746 -35.910463) (xy -12.286746 -35.825741) (xy -12.278693 -35.741404) (xy -12.262659 -35.658214)
			(xy -12.238791 -35.576924) (xy -12.207303 -35.498272) (xy -12.168481 -35.422969) (xy -12.122678 -35.351697)
			(xy -12.070307 -35.285101) (xy -12.011842 -35.223786) (xy -11.947814 -35.168305) (xy -11.878802 -35.119162)
			(xy -11.805432 -35.076802) (xy -11.728367 -35.041607) (xy -11.648305 -35.013898) (xy -11.565972 -34.993924)
			(xy -11.482113 -34.981867) (xy -11.397488 -34.977836) (xy -11.312863 -34.981867) (xy -11.229004 -34.993924)
			(xy -11.146671 -35.013898) (xy -11.066609 -35.041607) (xy -10.989544 -35.076802) (xy -10.916174 -35.119162)
			(xy -10.847162 -35.168305) (xy -10.783134 -35.223786) (xy -10.724669 -35.285101) (xy -10.672298 -35.351697)
			(xy -10.626495 -35.422969) (xy -10.587673 -35.498272) (xy -10.556185 -35.576924) (xy -10.532317 -35.658214)
			(xy -10.516283 -35.741404) (xy -10.50823 -35.825741) (xy -10.507726 -35.868102) (xy -10.50823 -35.910463)
			(xy -7.714746 -35.910463) (xy -7.714746 -35.825741) (xy -7.706693 -35.741404) (xy -7.690659 -35.658214)
			(xy -7.666791 -35.576924) (xy -7.635303 -35.498272) (xy -7.596481 -35.422969) (xy -7.550678 -35.351697)
			(xy -7.498307 -35.285101) (xy -7.439842 -35.223786) (xy -7.375814 -35.168305) (xy -7.306802 -35.119162)
			(xy -7.233432 -35.076802) (xy -7.156367 -35.041607) (xy -7.076305 -35.013898) (xy -6.993972 -34.993924)
			(xy -6.910113 -34.981867) (xy -6.825488 -34.977836) (xy -6.740863 -34.981867) (xy -6.657004 -34.993924)
			(xy -6.574671 -35.013898) (xy -6.494609 -35.041607) (xy -6.417544 -35.076802) (xy -6.344174 -35.119162)
			(xy -6.275162 -35.168305) (xy -6.211134 -35.223786) (xy -6.152669 -35.285101) (xy -6.100298 -35.351697)
			(xy -6.054495 -35.422969) (xy -6.015673 -35.498272) (xy -5.984185 -35.576924) (xy -5.960317 -35.658214)
			(xy -5.944283 -35.741404) (xy -5.93623 -35.825741) (xy -5.935726 -35.868102) (xy -5.93623 -35.910463)
			(xy -5.944283 -35.9948) (xy -5.960317 -36.07799) (xy -5.984185 -36.15928) (xy -6.015673 -36.237932)
			(xy -6.054495 -36.313235) (xy -6.100298 -36.384507) (xy -6.152669 -36.451103) (xy -6.211134 -36.512418)
			(xy -6.275162 -36.567899) (xy -6.344174 -36.617042) (xy -6.417544 -36.659402) (xy -6.494609 -36.694597)
			(xy -6.574671 -36.722306) (xy -6.657004 -36.74228) (xy -6.740863 -36.754337) (xy -6.825488 -36.758369)
			(xy -6.910113 -36.754337) (xy -6.993972 -36.74228) (xy -7.076305 -36.722306) (xy -7.156367 -36.694597)
			(xy -7.233432 -36.659402) (xy -7.306802 -36.617042) (xy -7.375814 -36.567899) (xy -7.439842 -36.512418)
			(xy -7.498307 -36.451103) (xy -7.550678 -36.384507) (xy -7.596481 -36.313235) (xy -7.635303 -36.237932)
			(xy -7.666791 -36.15928) (xy -7.690659 -36.07799) (xy -7.706693 -35.9948) (xy -7.714746 -35.910463)
			(xy -10.50823 -35.910463) (xy -10.516283 -35.9948) (xy -10.532317 -36.07799) (xy -10.556185 -36.15928)
			(xy -10.587673 -36.237932) (xy -10.626495 -36.313235) (xy -10.672298 -36.384507) (xy -10.724669 -36.451103)
			(xy -10.783134 -36.512418) (xy -10.847162 -36.567899) (xy -10.916174 -36.617042) (xy -10.989544 -36.659402)
			(xy -11.066609 -36.694597) (xy -11.146671 -36.722306) (xy -11.229004 -36.74228) (xy -11.312863 -36.754337)
			(xy -11.397488 -36.758369) (xy -11.482113 -36.754337) (xy -11.565972 -36.74228) (xy -11.648305 -36.722306)
			(xy -11.728367 -36.694597) (xy -11.805432 -36.659402) (xy -11.878802 -36.617042) (xy -11.947814 -36.567899)
			(xy -12.011842 -36.512418) (xy -12.070307 -36.451103) (xy -12.122678 -36.384507) (xy -12.168481 -36.313235)
			(xy -12.207303 -36.237932) (xy -12.238791 -36.15928) (xy -12.262659 -36.07799) (xy -12.278693 -35.9948)
			(xy -12.286746 -35.910463) (xy -17.729962 -35.910463) (xy -17.729962 -59.105743) (xy -12.286746 -59.105743)
			(xy -12.286746 -59.021021) (xy -12.278693 -58.936684) (xy -12.262659 -58.853494) (xy -12.238791 -58.772204)
			(xy -12.207303 -58.693552) (xy -12.168481 -58.618249) (xy -12.122678 -58.546977) (xy -12.070307 -58.480381)
			(xy -12.011842 -58.419066) (xy -11.947814 -58.363585) (xy -11.878802 -58.314442) (xy -11.805432 -58.272082)
			(xy -11.728367 -58.236887) (xy -11.648305 -58.209178) (xy -11.565972 -58.189204) (xy -11.482113 -58.177147)
			(xy -11.397488 -58.173116) (xy -11.312863 -58.177147) (xy -11.229004 -58.189204) (xy -11.146671 -58.209178)
			(xy -11.066609 -58.236887) (xy -10.989544 -58.272082) (xy -10.916174 -58.314442) (xy -10.847162 -58.363585)
			(xy -10.783134 -58.419066) (xy -10.724669 -58.480381) (xy -10.672298 -58.546977) (xy -10.626495 -58.618249)
			(xy -10.587673 -58.693552) (xy -10.556185 -58.772204) (xy -10.532317 -58.853494) (xy -10.516283 -58.936684)
			(xy -10.50823 -59.021021) (xy -10.507726 -59.063382) (xy -10.50823 -59.105743) (xy -7.714746 -59.105743)
			(xy -7.714746 -59.021021) (xy -7.706693 -58.936684) (xy -7.690659 -58.853494) (xy -7.666791 -58.772204)
			(xy -7.635303 -58.693552) (xy -7.596481 -58.618249) (xy -7.550678 -58.546977) (xy -7.498307 -58.480381)
			(xy -7.439842 -58.419066) (xy -7.375814 -58.363585) (xy -7.306802 -58.314442) (xy -7.233432 -58.272082)
			(xy -7.156367 -58.236887) (xy -7.076305 -58.209178) (xy -6.993972 -58.189204) (xy -6.910113 -58.177147)
			(xy -6.825488 -58.173116) (xy -6.740863 -58.177147) (xy -6.657004 -58.189204) (xy -6.574671 -58.209178)
			(xy -6.494609 -58.236887) (xy -6.417544 -58.272082) (xy -6.344174 -58.314442) (xy -6.275162 -58.363585)
			(xy -6.211134 -58.419066) (xy -6.152669 -58.480381) (xy -6.100298 -58.546977) (xy -6.054495 -58.618249)
			(xy -6.015673 -58.693552) (xy -5.984185 -58.772204) (xy -5.960317 -58.853494) (xy -5.944283 -58.936684)
			(xy -5.93623 -59.021021) (xy -5.935726 -59.063382) (xy -5.93623 -59.105743) (xy -5.944283 -59.19008)
			(xy -5.960317 -59.27327) (xy -5.984185 -59.35456) (xy -6.015673 -59.433212) (xy -6.054495 -59.508515)
			(xy -6.100298 -59.579787) (xy -6.152669 -59.646383) (xy -6.211134 -59.707698) (xy -6.275162 -59.763179)
			(xy -6.344174 -59.812322) (xy -6.417544 -59.854682) (xy -6.494609 -59.889877) (xy -6.574671 -59.917586)
			(xy -6.657004 -59.93756) (xy -6.740863 -59.949617) (xy -6.825488 -59.953649) (xy -6.910113 -59.949617)
			(xy -6.993972 -59.93756) (xy -7.076305 -59.917586) (xy -7.156367 -59.889877) (xy -7.233432 -59.854682)
			(xy -7.306802 -59.812322) (xy -7.375814 -59.763179) (xy -7.439842 -59.707698) (xy -7.498307 -59.646383)
			(xy -7.550678 -59.579787) (xy -7.596481 -59.508515) (xy -7.635303 -59.433212) (xy -7.666791 -59.35456)
			(xy -7.690659 -59.27327) (xy -7.706693 -59.19008) (xy -7.714746 -59.105743) (xy -10.50823 -59.105743)
			(xy -10.516283 -59.19008) (xy -10.532317 -59.27327) (xy -10.556185 -59.35456) (xy -10.587673 -59.433212)
			(xy -10.626495 -59.508515) (xy -10.672298 -59.579787) (xy -10.724669 -59.646383) (xy -10.783134 -59.707698)
			(xy -10.847162 -59.763179) (xy -10.916174 -59.812322) (xy -10.989544 -59.854682) (xy -11.066609 -59.889877)
			(xy -11.146671 -59.917586) (xy -11.229004 -59.93756) (xy -11.312863 -59.949617) (xy -11.397488 -59.953649)
			(xy -11.482113 -59.949617) (xy -11.565972 -59.93756) (xy -11.648305 -59.917586) (xy -11.728367 -59.889877)
			(xy -11.805432 -59.854682) (xy -11.878802 -59.812322) (xy -11.947814 -59.763179) (xy -12.011842 -59.707698)
			(xy -12.070307 -59.646383) (xy -12.122678 -59.579787) (xy -12.168481 -59.508515) (xy -12.207303 -59.433212)
			(xy -12.238791 -59.35456) (xy -12.262659 -59.27327) (xy -12.278693 -59.19008) (xy -12.286746 -59.105743)
			(xy -17.729962 -59.105743) (xy -17.729962 -63.169743) (xy -12.286746 -63.169743) (xy -12.286746 -63.085021)
			(xy -12.278693 -63.000684) (xy -12.262659 -62.917494) (xy -12.238791 -62.836204) (xy -12.207303 -62.757552)
			(xy -12.168481 -62.682249) (xy -12.122678 -62.610977) (xy -12.070307 -62.544381) (xy -12.011842 -62.483066)
			(xy -11.947814 -62.427585) (xy -11.878802 -62.378442) (xy -11.805432 -62.336082) (xy -11.728367 -62.300887)
			(xy -11.648305 -62.273178) (xy -11.565972 -62.253204) (xy -11.482113 -62.241147) (xy -11.397488 -62.237116)
			(xy -11.312863 -62.241147) (xy -11.229004 -62.253204) (xy -11.146671 -62.273178) (xy -11.066609 -62.300887)
			(xy -10.989544 -62.336082) (xy -10.916174 -62.378442) (xy -10.847162 -62.427585) (xy -10.783134 -62.483066)
			(xy -10.724669 -62.544381) (xy -10.672298 -62.610977) (xy -10.626495 -62.682249) (xy -10.587673 -62.757552)
			(xy -10.556185 -62.836204) (xy -10.532317 -62.917494) (xy -10.516283 -63.000684) (xy -10.50823 -63.085021)
			(xy -10.507726 -63.127382) (xy -10.50823 -63.169743) (xy -7.714746 -63.169743) (xy -7.714746 -63.085021)
			(xy -7.706693 -63.000684) (xy -7.690659 -62.917494) (xy -7.666791 -62.836204) (xy -7.635303 -62.757552)
			(xy -7.596481 -62.682249) (xy -7.550678 -62.610977) (xy -7.498307 -62.544381) (xy -7.439842 -62.483066)
			(xy -7.375814 -62.427585) (xy -7.306802 -62.378442) (xy -7.233432 -62.336082) (xy -7.156367 -62.300887)
			(xy -7.076305 -62.273178) (xy -6.993972 -62.253204) (xy -6.910113 -62.241147) (xy -6.825488 -62.237116)
			(xy -6.740863 -62.241147) (xy -6.657004 -62.253204) (xy -6.574671 -62.273178) (xy -6.494609 -62.300887)
			(xy -6.417544 -62.336082) (xy -6.344174 -62.378442) (xy -6.275162 -62.427585) (xy -6.211134 -62.483066)
			(xy -6.152669 -62.544381) (xy -6.100298 -62.610977) (xy -6.054495 -62.682249) (xy -6.015673 -62.757552)
			(xy -5.984185 -62.836204) (xy -5.960317 -62.917494) (xy -5.944283 -63.000684) (xy -5.93623 -63.085021)
			(xy -5.935726 -63.127382) (xy -5.93623 -63.169743) (xy -5.944283 -63.25408) (xy -5.960317 -63.33727)
			(xy -5.984185 -63.41856) (xy -6.015673 -63.497212) (xy -6.054495 -63.572515) (xy -6.100298 -63.643787)
			(xy -6.152669 -63.710383) (xy -6.211134 -63.771698) (xy -6.275162 -63.827179) (xy -6.344174 -63.876322)
			(xy -6.417544 -63.918682) (xy -6.494609 -63.953877) (xy -6.574671 -63.981586) (xy -6.657004 -64.00156)
			(xy -6.740863 -64.013617) (xy -6.825488 -64.017649) (xy -6.910113 -64.013617) (xy -6.993972 -64.00156)
			(xy -7.076305 -63.981586) (xy -7.156367 -63.953877) (xy -7.233432 -63.918682) (xy -7.306802 -63.876322)
			(xy -7.375814 -63.827179) (xy -7.439842 -63.771698) (xy -7.498307 -63.710383) (xy -7.550678 -63.643787)
			(xy -7.596481 -63.572515) (xy -7.635303 -63.497212) (xy -7.666791 -63.41856) (xy -7.690659 -63.33727)
			(xy -7.706693 -63.25408) (xy -7.714746 -63.169743) (xy -10.50823 -63.169743) (xy -10.516283 -63.25408)
			(xy -10.532317 -63.33727) (xy -10.556185 -63.41856) (xy -10.587673 -63.497212) (xy -10.626495 -63.572515)
			(xy -10.672298 -63.643787) (xy -10.724669 -63.710383) (xy -10.783134 -63.771698) (xy -10.847162 -63.827179)
			(xy -10.916174 -63.876322) (xy -10.989544 -63.918682) (xy -11.066609 -63.953877) (xy -11.146671 -63.981586)
			(xy -11.229004 -64.00156) (xy -11.312863 -64.013617) (xy -11.397488 -64.017649) (xy -11.482113 -64.013617)
			(xy -11.565972 -64.00156) (xy -11.648305 -63.981586) (xy -11.728367 -63.953877) (xy -11.805432 -63.918682)
			(xy -11.878802 -63.876322) (xy -11.947814 -63.827179) (xy -12.011842 -63.771698) (xy -12.070307 -63.710383)
			(xy -12.122678 -63.643787) (xy -12.168481 -63.572515) (xy -12.207303 -63.497212) (xy -12.238791 -63.41856)
			(xy -12.262659 -63.33727) (xy -12.278693 -63.25408) (xy -12.286746 -63.169743) (xy -17.729962 -63.169743)
			(xy -17.729962 -187.619583) (xy -12.286746 -187.619583) (xy -12.286746 -187.534861) (xy -12.278693 -187.450524)
			(xy -12.262659 -187.367334) (xy -12.238791 -187.286044) (xy -12.207303 -187.207392) (xy -12.168481 -187.132089)
			(xy -12.122678 -187.060817) (xy -12.070307 -186.994221) (xy -12.011842 -186.932906) (xy -11.947814 -186.877425)
			(xy -11.878802 -186.828282) (xy -11.805432 -186.785922) (xy -11.728367 -186.750727) (xy -11.648305 -186.723018)
			(xy -11.565972 -186.703044) (xy -11.482113 -186.690987) (xy -11.397488 -186.686956) (xy -11.312863 -186.690987)
			(xy -11.229004 -186.703044) (xy -11.146671 -186.723018) (xy -11.066609 -186.750727) (xy -10.989544 -186.785922)
			(xy -10.916174 -186.828282) (xy -10.847162 -186.877425) (xy -10.783134 -186.932906) (xy -10.724669 -186.994221)
			(xy -10.672298 -187.060817) (xy -10.626495 -187.132089) (xy -10.587673 -187.207392) (xy -10.556185 -187.286044)
			(xy -10.532317 -187.367334) (xy -10.516283 -187.450524) (xy -10.50823 -187.534861) (xy -10.507726 -187.577222)
			(xy -10.50823 -187.619583) (xy -7.714746 -187.619583) (xy -7.714746 -187.534861) (xy -7.706693 -187.450524)
			(xy -7.690659 -187.367334) (xy -7.666791 -187.286044) (xy -7.635303 -187.207392) (xy -7.596481 -187.132089)
			(xy -7.550678 -187.060817) (xy -7.498307 -186.994221) (xy -7.439842 -186.932906) (xy -7.375814 -186.877425)
			(xy -7.306802 -186.828282) (xy -7.233432 -186.785922) (xy -7.156367 -186.750727) (xy -7.076305 -186.723018)
			(xy -6.993972 -186.703044) (xy -6.910113 -186.690987) (xy -6.825488 -186.686956) (xy -6.740863 -186.690987)
			(xy -6.657004 -186.703044) (xy -6.574671 -186.723018) (xy -6.494609 -186.750727) (xy -6.417544 -186.785922)
			(xy -6.344174 -186.828282) (xy -6.275162 -186.877425) (xy -6.211134 -186.932906) (xy -6.152669 -186.994221)
			(xy -6.100298 -187.060817) (xy -6.054495 -187.132089) (xy -6.015673 -187.207392) (xy -5.984185 -187.286044)
			(xy -5.960317 -187.367334) (xy -5.944283 -187.450524) (xy -5.93623 -187.534861) (xy -5.935726 -187.577222)
			(xy -5.93623 -187.619583) (xy -5.944283 -187.70392) (xy -5.960317 -187.78711) (xy -5.984185 -187.8684)
			(xy -6.015673 -187.947052) (xy -6.054495 -188.022355) (xy -6.100298 -188.093627) (xy -6.152669 -188.160223)
			(xy -6.211134 -188.221538) (xy -6.275162 -188.277019) (xy -6.344174 -188.326162) (xy -6.417544 -188.368522)
			(xy -6.494609 -188.403717) (xy -6.574671 -188.431426) (xy -6.657004 -188.4514) (xy -6.740863 -188.463457)
			(xy -6.825488 -188.467489) (xy -6.910113 -188.463457) (xy -6.993972 -188.4514) (xy -7.076305 -188.431426)
			(xy -7.156367 -188.403717) (xy -7.233432 -188.368522) (xy -7.306802 -188.326162) (xy -7.375814 -188.277019)
			(xy -7.439842 -188.221538) (xy -7.498307 -188.160223) (xy -7.550678 -188.093627) (xy -7.596481 -188.022355)
			(xy -7.635303 -187.947052) (xy -7.666791 -187.8684) (xy -7.690659 -187.78711) (xy -7.706693 -187.70392)
			(xy -7.714746 -187.619583) (xy -10.50823 -187.619583) (xy -10.516283 -187.70392) (xy -10.532317 -187.78711)
			(xy -10.556185 -187.8684) (xy -10.587673 -187.947052) (xy -10.626495 -188.022355) (xy -10.672298 -188.093627)
			(xy -10.724669 -188.160223) (xy -10.783134 -188.221538) (xy -10.847162 -188.277019) (xy -10.916174 -188.326162)
			(xy -10.989544 -188.368522) (xy -11.066609 -188.403717) (xy -11.146671 -188.431426) (xy -11.229004 -188.4514)
			(xy -11.312863 -188.463457) (xy -11.397488 -188.467489) (xy -11.482113 -188.463457) (xy -11.565972 -188.4514)
			(xy -11.648305 -188.431426) (xy -11.728367 -188.403717) (xy -11.805432 -188.368522) (xy -11.878802 -188.326162)
			(xy -11.947814 -188.277019) (xy -12.011842 -188.221538) (xy -12.070307 -188.160223) (xy -12.122678 -188.093627)
			(xy -12.168481 -188.022355) (xy -12.207303 -187.947052) (xy -12.238791 -187.8684) (xy -12.262659 -187.78711)
			(xy -12.278693 -187.70392) (xy -12.286746 -187.619583) (xy -17.729962 -187.619583) (xy -17.729962 -191.683583)
			(xy -12.286746 -191.683583) (xy -12.286746 -191.598861) (xy -12.278693 -191.514524) (xy -12.262659 -191.431334)
			(xy -12.238791 -191.350044) (xy -12.207303 -191.271392) (xy -12.168481 -191.196089) (xy -12.122678 -191.124817)
			(xy -12.070307 -191.058221) (xy -12.011842 -190.996906) (xy -11.947814 -190.941425) (xy -11.878802 -190.892282)
			(xy -11.805432 -190.849922) (xy -11.728367 -190.814727) (xy -11.648305 -190.787018) (xy -11.565972 -190.767044)
			(xy -11.482113 -190.754987) (xy -11.397488 -190.750956) (xy -11.312863 -190.754987) (xy -11.229004 -190.767044)
			(xy -11.146671 -190.787018) (xy -11.066609 -190.814727) (xy -10.989544 -190.849922) (xy -10.916174 -190.892282)
			(xy -10.847162 -190.941425) (xy -10.783134 -190.996906) (xy -10.724669 -191.058221) (xy -10.672298 -191.124817)
			(xy -10.626495 -191.196089) (xy -10.587673 -191.271392) (xy -10.556185 -191.350044) (xy -10.532317 -191.431334)
			(xy -10.516283 -191.514524) (xy -10.50823 -191.598861) (xy -10.507726 -191.641222) (xy -10.50823 -191.683583)
			(xy -7.714746 -191.683583) (xy -7.714746 -191.598861) (xy -7.706693 -191.514524) (xy -7.690659 -191.431334)
			(xy -7.666791 -191.350044) (xy -7.635303 -191.271392) (xy -7.596481 -191.196089) (xy -7.550678 -191.124817)
			(xy -7.498307 -191.058221) (xy -7.439842 -190.996906) (xy -7.375814 -190.941425) (xy -7.306802 -190.892282)
			(xy -7.233432 -190.849922) (xy -7.156367 -190.814727) (xy -7.076305 -190.787018) (xy -6.993972 -190.767044)
			(xy -6.910113 -190.754987) (xy -6.825488 -190.750956) (xy -6.740863 -190.754987) (xy -6.657004 -190.767044)
			(xy -6.574671 -190.787018) (xy -6.494609 -190.814727) (xy -6.417544 -190.849922) (xy -6.344174 -190.892282)
			(xy -6.275162 -190.941425) (xy -6.211134 -190.996906) (xy -6.152669 -191.058221) (xy -6.100298 -191.124817)
			(xy -6.054495 -191.196089) (xy -6.015673 -191.271392) (xy -5.984185 -191.350044) (xy -5.960317 -191.431334)
			(xy -5.944283 -191.514524) (xy -5.93623 -191.598861) (xy -5.935726 -191.641222) (xy -5.93623 -191.683583)
			(xy -5.944283 -191.76792) (xy -5.960317 -191.85111) (xy -5.984185 -191.9324) (xy -6.015673 -192.011052)
			(xy -6.054495 -192.086355) (xy -6.100298 -192.157627) (xy -6.152669 -192.224223) (xy -6.211134 -192.285538)
			(xy -6.275162 -192.341019) (xy -6.344174 -192.390162) (xy -6.417544 -192.432522) (xy -6.494609 -192.467717)
			(xy -6.574671 -192.495426) (xy -6.657004 -192.5154) (xy -6.740863 -192.527457) (xy -6.825488 -192.531489)
			(xy -6.910113 -192.527457) (xy -6.993972 -192.5154) (xy -7.076305 -192.495426) (xy -7.156367 -192.467717)
			(xy -7.233432 -192.432522) (xy -7.306802 -192.390162) (xy -7.375814 -192.341019) (xy -7.439842 -192.285538)
			(xy -7.498307 -192.224223) (xy -7.550678 -192.157627) (xy -7.596481 -192.086355) (xy -7.635303 -192.011052)
			(xy -7.666791 -191.9324) (xy -7.690659 -191.85111) (xy -7.706693 -191.76792) (xy -7.714746 -191.683583)
			(xy -10.50823 -191.683583) (xy -10.516283 -191.76792) (xy -10.532317 -191.85111) (xy -10.556185 -191.9324)
			(xy -10.587673 -192.011052) (xy -10.626495 -192.086355) (xy -10.672298 -192.157627) (xy -10.724669 -192.224223)
			(xy -10.783134 -192.285538) (xy -10.847162 -192.341019) (xy -10.916174 -192.390162) (xy -10.989544 -192.432522)
			(xy -11.066609 -192.467717) (xy -11.146671 -192.495426) (xy -11.229004 -192.5154) (xy -11.312863 -192.527457)
			(xy -11.397488 -192.531489) (xy -11.482113 -192.527457) (xy -11.565972 -192.5154) (xy -11.648305 -192.495426)
			(xy -11.728367 -192.467717) (xy -11.805432 -192.432522) (xy -11.878802 -192.390162) (xy -11.947814 -192.341019)
			(xy -12.011842 -192.285538) (xy -12.070307 -192.224223) (xy -12.122678 -192.157627) (xy -12.168481 -192.086355)
			(xy -12.207303 -192.011052) (xy -12.238791 -191.9324) (xy -12.262659 -191.85111) (xy -12.278693 -191.76792)
			(xy -12.286746 -191.683583) (xy -17.729962 -191.683583) (xy -17.729962 -206.70012) (xy -17.72944 -206.755927)
			(xy -17.721099 -206.867229) (xy -17.704464 -206.977596) (xy -17.679627 -207.086412) (xy -17.646728 -207.193067)
			(xy -17.605951 -207.296966) (xy -17.557524 -207.397526) (xy -17.501716 -207.494187) (xy -17.438842 -207.586407)
			(xy -17.369252 -207.67367) (xy -17.293335 -207.755489) (xy -17.211516 -207.831406) (xy -17.124253 -207.900996)
			(xy -17.032033 -207.96387) (xy -16.935372 -208.019678) (xy -16.834812 -208.068105) (xy -16.730913 -208.108882)
			(xy -16.624258 -208.141781) (xy -16.515442 -208.166618) (xy -16.405075 -208.183253) (xy -16.293773 -208.191594)
			(xy -16.237966 -208.192116)
		)
		(stroke
			(width 0)
			(type solid)
		)
		(fill yes)
		(layer "In5.Cu")
		(net "GND")
	)
	(gr_poly
		(pts
			(xy 83.01355 -208.032604) (xy 83.025039 -208.020438) (xy 83.041779 -207.991476) (xy 83.050425 -207.959161)
			(xy 83.050888 -207.942434) (xy 83.050888 -201.250042) (xy 83.051381 -201.195462) (xy 83.05953 -201.086606)
			(xy 83.075791 -200.978664) (xy 83.100073 -200.872238) (xy 83.132241 -200.767925) (xy 83.172115 -200.666308)
			(xy 83.219472 -200.567955) (xy 83.274047 -200.473416) (xy 83.335534 -200.38322) (xy 83.40359 -200.297872)
			(xy 83.477835 -200.217848) (xy 83.557852 -200.143597) (xy 83.643194 -200.075534) (xy 83.733385 -200.014038)
			(xy 83.827919 -199.959456) (xy 83.926268 -199.91209) (xy 84.027881 -199.872207) (xy 84.132192 -199.84003)
			(xy 84.238615 -199.815738) (xy 84.346556 -199.799468) (xy 84.455411 -199.79131) (xy 84.564571 -199.79131)
			(xy 84.673426 -199.799468) (xy 84.781367 -199.815738) (xy 84.88779 -199.84003) (xy 84.992101 -199.872207)
			(xy 85.093714 -199.91209) (xy 85.192063 -199.959456) (xy 85.286597 -200.014038) (xy 85.376788 -200.075534)
			(xy 85.46213 -200.143597) (xy 85.542147 -200.217848) (xy 85.616392 -200.297872) (xy 85.684448 -200.38322)
			(xy 85.745935 -200.473416) (xy 85.80051 -200.567955) (xy 85.847867 -200.666308) (xy 85.887741 -200.767925)
			(xy 85.919909 -200.872238) (xy 85.944191 -200.978664) (xy 85.960452 -201.086606) (xy 85.968601 -201.195462)
			(xy 85.969094 -201.250042) (xy 85.969094 -207.932528) (xy 85.969564 -207.949255) (xy 85.978195 -207.981575)
			(xy 85.994937 -208.010538) (xy 86.006432 -208.022698) (xy 86.175342 -208.190592) (xy 95.955104 -208.190592)
			(xy 96.150938 -207.994758) (xy 96.150938 -188.250068) (xy 96.151438 -188.162213) (xy 96.159435 -187.986685)
			(xy 96.175414 -187.811703) (xy 96.199339 -187.637629) (xy 96.231163 -187.464825) (xy 96.27082 -187.293648)
			(xy 96.318226 -187.124454) (xy 96.373283 -186.957593) (xy 96.435879 -186.79341) (xy 96.505882 -186.632247)
			(xy 96.583147 -186.474437) (xy 96.667516 -186.320307) (xy 96.758812 -186.170177) (xy 96.856847 -186.024358)
			(xy 96.961417 -185.883151) (xy 97.072305 -185.746851) (xy 97.189283 -185.615739) (xy 97.312106 -185.490087)
			(xy 97.440521 -185.370156) (xy 97.574262 -185.256193) (xy 97.713051 -185.148436) (xy 97.856601 -185.047107)
			(xy 98.004614 -184.952418) (xy 98.156784 -184.864562) (xy 98.312794 -184.783724) (xy 98.472322 -184.710071)
			(xy 98.635037 -184.643754) (xy 98.800602 -184.584913) (xy 98.968673 -184.533668) (xy 99.138903 -184.490125)
			(xy 99.310938 -184.454376) (xy 99.484422 -184.426494) (xy 99.658995 -184.406537) (xy 99.834295 -184.394546)
			(xy 100.00996 -184.390546) (xy 100.185625 -184.394546) (xy 100.360925 -184.406537) (xy 100.535498 -184.426494)
			(xy 100.708982 -184.454376) (xy 100.881017 -184.490125) (xy 101.051247 -184.533668) (xy 101.219318 -184.584913)
			(xy 101.384883 -184.643754) (xy 101.547598 -184.710071) (xy 101.707126 -184.783724) (xy 101.863136 -184.864562)
			(xy 102.015306 -184.952418) (xy 102.163319 -185.047107) (xy 102.306869 -185.148436) (xy 102.445658 -185.256193)
			(xy 102.579399 -185.370156) (xy 102.707814 -185.490087) (xy 102.830637 -185.615739) (xy 102.947615 -185.746851)
			(xy 103.058503 -185.883151) (xy 103.163073 -186.024358) (xy 103.261108 -186.170177) (xy 103.352404 -186.320307)
			(xy 103.436773 -186.474437) (xy 103.514038 -186.632247) (xy 103.584041 -186.79341) (xy 103.646637 -186.957593)
			(xy 103.701694 -187.124454) (xy 103.7491 -187.293648) (xy 103.788757 -187.464825) (xy 103.820581 -187.637629)
			(xy 103.844506 -187.811703) (xy 103.860485 -187.986685) (xy 103.868482 -188.162213) (xy 103.868982 -188.250068)
			(xy 103.868982 -207.933036) (xy 103.869452 -207.949763) (xy 103.878085 -207.982082) (xy 103.894826 -208.011044)
			(xy 103.90632 -208.023206) (xy 104.074722 -208.190592) (xy 173.855126 -208.190592) (xy 173.983142 -208.063338)
			(xy 174.05096 -207.99552) (xy 174.05096 -201.250042) (xy 174.05147 -201.19547) (xy 174.059626 -201.086631)
			(xy 174.075893 -200.978707) (xy 174.10018 -200.872299) (xy 174.132351 -200.768004) (xy 174.172226 -200.666405)
			(xy 174.219582 -200.56807) (xy 174.274153 -200.473548) (xy 174.335636 -200.383369) (xy 174.403687 -200.298037)
			(xy 174.477923 -200.218029) (xy 174.557931 -200.143793) (xy 174.643263 -200.075742) (xy 174.733442 -200.014259)
			(xy 174.827964 -199.959688) (xy 174.926299 -199.912332) (xy 175.027898 -199.872457) (xy 175.132193 -199.840286)
			(xy 175.238601 -199.815999) (xy 175.346525 -199.799732) (xy 175.455364 -199.791576) (xy 175.564508 -199.791576)
			(xy 175.673347 -199.799732) (xy 175.781271 -199.815999) (xy 175.887679 -199.840286) (xy 175.991974 -199.872457)
			(xy 176.093573 -199.912332) (xy 176.191908 -199.959688) (xy 176.28643 -200.014259) (xy 176.376609 -200.075742)
			(xy 176.461941 -200.143793) (xy 176.541949 -200.218029) (xy 176.616185 -200.298037) (xy 176.684236 -200.383369)
			(xy 176.745719 -200.473548) (xy 176.80029 -200.56807) (xy 176.847646 -200.666405) (xy 176.887521 -200.768004)
			(xy 176.919692 -200.872299) (xy 176.943979 -200.978707) (xy 176.960246 -201.086631) (xy 176.968402 -201.19547)
			(xy 176.968912 -201.250042) (xy 176.968912 -207.931766) (xy 176.969386 -207.948491) (xy 176.978027 -207.980804)
			(xy 176.994775 -208.009758) (xy 177.00625 -208.021936) (xy 177.175922 -208.190592) (xy 186.953652 -208.190592)
			(xy 187.113672 -208.031588) (xy 187.125158 -208.01942) (xy 187.141892 -207.990458) (xy 187.150531 -207.958143)
			(xy 187.15101 -207.941418) (xy 187.15101 -172.699934) (xy 187.151494 -172.629551) (xy 187.159385 -172.489007)
			(xy 187.175144 -172.349126) (xy 187.198721 -172.210349) (xy 187.230043 -172.073112) (xy 187.269011 -171.937847)
			(xy 187.315502 -171.804981) (xy 187.369369 -171.67493) (xy 187.430445 -171.548104) (xy 187.498535 -171.424902)
			(xy 187.573426 -171.305711) (xy 187.654883 -171.190908) (xy 187.742648 -171.080853) (xy 187.836447 -170.975891)
			(xy 187.935983 -170.876355) (xy 188.040943 -170.782556) (xy 188.150998 -170.69479) (xy 188.265801 -170.613333)
			(xy 188.384991 -170.538441) (xy 188.508193 -170.47035) (xy 188.635019 -170.409274) (xy 188.765069 -170.355406)
			(xy 188.897936 -170.308915) (xy 189.0332 -170.269946) (xy 189.170437 -170.238624) (xy 189.309214 -170.215046)
			(xy 189.449095 -170.199286) (xy 189.589639 -170.191394) (xy 189.660022 -170.190922) (xy 198.000112 -170.190922)
			(xy 198.055881 -170.1904) (xy 198.167108 -170.182064) (xy 198.277401 -170.16544) (xy 198.386143 -170.14062)
			(xy 198.492726 -170.107743) (xy 198.596554 -170.066993) (xy 198.697047 -170.018599) (xy 198.793643 -169.96283)
			(xy 198.885801 -169.899998) (xy 198.973006 -169.830456) (xy 199.05477 -169.754591) (xy 199.130636 -169.672828)
			(xy 199.200181 -169.585625) (xy 199.263014 -169.493468) (xy 199.318785 -169.396874) (xy 199.367181 -169.296382)
			(xy 199.407933 -169.192554) (xy 199.440812 -169.085972) (xy 199.465634 -168.97723) (xy 199.482261 -168.866938)
			(xy 199.490599 -168.755711) (xy 199.491092 -168.699942) (xy 199.491092 -75.65009) (xy 199.490579 -75.604293)
			(xy 199.482127 -75.513089) (xy 199.465295 -75.423053) (xy 199.440228 -75.334955) (xy 199.407139 -75.249546)
			(xy 199.366311 -75.167554) (xy 199.318091 -75.089679) (xy 199.262892 -75.016586) (xy 199.201184 -74.948897)
			(xy 199.133494 -74.887191) (xy 199.060399 -74.831994) (xy 198.982523 -74.783776) (xy 198.90053 -74.74295)
			(xy 198.81512 -74.709864) (xy 198.727021 -74.684799) (xy 198.636986 -74.66797) (xy 198.545781 -74.65952)
			(xy 198.499984 -74.658982) (xy 198.20001 -74.658982) (xy 198.13689 -74.658487) (xy 198.0109 -74.650562)
			(xy 197.885655 -74.634742) (xy 197.761651 -74.611089) (xy 197.639377 -74.579698) (xy 197.519314 -74.540692)
			(xy 197.401938 -74.494225) (xy 197.287711 -74.44048) (xy 197.177083 -74.379669) (xy 197.070492 -74.312032)
			(xy 196.968357 -74.237837) (xy 196.871082 -74.157375) (xy 196.779051 -74.070965) (xy 196.692627 -73.978947)
			(xy 196.612151 -73.881685) (xy 196.53794 -73.779562) (xy 196.470287 -73.67298) (xy 196.409459 -73.562362)
			(xy 196.355697 -73.448143) (xy 196.309212 -73.330774) (xy 196.270187 -73.210717) (xy 196.238777 -73.088448)
			(xy 196.215106 -72.964447) (xy 196.199267 -72.839205) (xy 196.191323 -72.713216) (xy 196.19087 -72.650096)
			(xy 196.19087 -33.64992) (xy 196.191374 -33.586802) (xy 196.199318 -33.460815) (xy 196.215155 -33.335575)
			(xy 196.238825 -33.211577) (xy 196.270233 -33.08931) (xy 196.309256 -32.969256) (xy 196.35574 -32.851889)
			(xy 196.4095 -32.737672) (xy 196.470326 -32.627055) (xy 196.537977 -32.520476) (xy 196.612186 -32.418354)
			(xy 196.69266 -32.321094) (xy 196.779082 -32.229077) (xy 196.871111 -32.142669) (xy 196.968384 -32.062208)
			(xy 197.070516 -31.988014) (xy 197.177105 -31.920379) (xy 197.28773 -31.859569) (xy 197.401955 -31.805825)
			(xy 197.519329 -31.759358) (xy 197.639389 -31.720352) (xy 197.76166 -31.688962) (xy 197.885662 -31.66531)
			(xy 198.010904 -31.64949) (xy 198.136892 -31.641565) (xy 198.20001 -31.641034) (xy 198.499984 -31.641034)
			(xy 198.545782 -31.640506) (xy 198.636988 -31.632056) (xy 198.727025 -31.615227) (xy 198.815125 -31.590162)
			(xy 198.900537 -31.557075) (xy 198.982531 -31.516249) (xy 199.060409 -31.468031) (xy 199.133505 -31.412833)
			(xy 199.201197 -31.351127) (xy 199.262907 -31.283438) (xy 199.318107 -31.210343) (xy 199.366328 -31.132468)
			(xy 199.407158 -31.050475) (xy 199.440249 -30.965065) (xy 199.465317 -30.876966) (xy 199.48215 -30.78693)
			(xy 199.490604 -30.695724) (xy 199.491092 -30.649926) (xy 199.491092 -1.999996) (xy 199.49057 -1.944227)
			(xy 199.482235 -1.833001) (xy 199.465611 -1.722708) (xy 199.440791 -1.613967) (xy 199.407915 -1.507384)
			(xy 199.367165 -1.403556) (xy 199.31877 -1.303063) (xy 199.263001 -1.206468) (xy 199.20017 -1.114311)
			(xy 199.130627 -1.027107) (xy 199.054762 -0.945344) (xy 198.972999 -0.869478) (xy 198.885795 -0.799935)
			(xy 198.793638 -0.737103) (xy 198.697044 -0.681333) (xy 198.596552 -0.632938) (xy 198.492724 -0.592188)
			(xy 198.386141 -0.559311) (xy 198.2774 -0.534491) (xy 198.167107 -0.517866) (xy 198.055881 -0.50953)
			(xy 198.000112 -0.509016) (xy 1.999996 -0.509016) (xy 1.944227 -0.509538) (xy 1.833001 -0.517873)
			(xy 1.722709 -0.534497) (xy 1.613967 -0.559317) (xy 1.507385 -0.592194) (xy 1.403557 -0.632943) (xy 1.303065 -0.681338)
			(xy 1.20647 -0.737107) (xy 1.114313 -0.799938) (xy 1.027109 -0.869481) (xy 0.945346 -0.945346) (xy 0.869481 -1.027109)
			(xy 0.799938 -1.114313) (xy 0.737107 -1.20647) (xy 0.681338 -1.303065) (xy 0.632943 -1.403557) (xy 0.592194 -1.507385)
			(xy 0.559317 -1.613967) (xy 0.534497 -1.722709) (xy 0.517873 -1.833001) (xy 0.509538 -1.944227) (xy 0.509016 -1.999996)
			(xy 0.509016 -9.750405) (xy 89.064349 -9.750405) (xy 89.072055 -9.665303) (xy 89.08745 -9.58125)
			(xy 89.110408 -9.498942) (xy 89.140739 -9.419055) (xy 89.178194 -9.342251) (xy 89.222464 -9.269162)
			(xy 89.273182 -9.20039) (xy 89.329931 -9.136505) (xy 89.360756 -9.106916) (xy 89.44864 -9.106916)
			(xy 89.465307 -9.106475) (xy 89.497514 -9.097891) (xy 89.526391 -9.081243) (xy 89.549958 -9.057672)
			(xy 89.5666 -9.028792) (xy 89.575178 -8.996583) (xy 89.57564 -8.979916) (xy 89.57564 -8.955532) (xy 89.615755 -8.935545)
			(xy 89.69906 -8.902468) (xy 89.785135 -8.877468) (xy 89.873199 -8.860773) (xy 89.962451 -8.852535)
			(xy 90.052082 -8.852827) (xy 90.141279 -8.861648) (xy 90.229232 -8.878917) (xy 90.315142 -8.904478)
			(xy 90.398229 -8.938099) (xy 90.438224 -8.958326) (xy 90.438224 -8.979408) (xy 90.438881 -8.996035)
			(xy 90.447554 -9.028141) (xy 90.464208 -9.056928) (xy 90.487718 -9.08045) (xy 90.516496 -9.09712)
			(xy 90.548598 -9.10581) (xy 90.565224 -9.106408) (xy 90.647266 -9.106408) (xy 90.678125 -9.135996)
			(xy 90.734975 -9.199856) (xy 90.785794 -9.268611) (xy 90.830163 -9.341696) (xy 90.867716 -9.418505)
			(xy 90.898142 -9.498406) (xy 90.921191 -9.580739) (xy 90.936672 -9.664824) (xy 90.944458 -9.749967)
			(xy 90.944463 -9.750405) (xy 99.064304 -9.750405) (xy 99.07201 -9.665301) (xy 99.087407 -9.581247)
			(xy 99.110367 -9.498937) (xy 99.140701 -9.41905) (xy 99.178159 -9.342246) (xy 99.222432 -9.269157)
			(xy 99.273155 -9.200387) (xy 99.329909 -9.136503) (xy 99.360736 -9.106916) (xy 99.44862 -9.106916)
			(xy 99.465286 -9.106457) (xy 99.497493 -9.097878) (xy 99.526369 -9.081234) (xy 99.549936 -9.057666)
			(xy 99.566579 -9.028789) (xy 99.575157 -8.996582) (xy 99.57562 -8.979916) (xy 99.57562 -8.955532)
			(xy 99.615743 -8.935561) (xy 99.699047 -8.902482) (xy 99.78512 -8.877481) (xy 99.873182 -8.860785)
			(xy 99.962434 -8.852545) (xy 100.052064 -8.852835) (xy 100.14126 -8.861655) (xy 100.229212 -8.878922)
			(xy 100.315122 -8.904481) (xy 100.398209 -8.9381) (xy 100.438204 -8.958326) (xy 100.438204 -8.979408)
			(xy 100.438782 -8.996041) (xy 100.447462 -9.028159) (xy 100.464129 -9.056954) (xy 100.487655 -9.080479)
			(xy 100.516452 -9.097143) (xy 100.548571 -9.10582) (xy 100.565204 -9.106408) (xy 100.647246 -9.106408)
			(xy 100.678101 -9.136) (xy 100.734952 -9.199859) (xy 100.785772 -9.268614) (xy 100.830141 -9.341697)
			(xy 100.867694 -9.418507) (xy 100.898121 -9.498407) (xy 100.92117 -9.58074) (xy 100.936652 -9.664824)
			(xy 100.944438 -9.749967) (xy 100.944934 -9.792716) (xy 100.94442 -9.835465) (xy 100.936641 -9.920609)
			(xy 100.921165 -10.004695) (xy 100.898121 -10.08703) (xy 100.867699 -10.166933) (xy 100.83015 -10.243745)
			(xy 100.785784 -10.316831) (xy 100.734968 -10.38559) (xy 100.67812 -10.449452) (xy 100.647246 -10.479024)
			(xy 100.565204 -10.479024) (xy 100.548566 -10.479581) (xy 100.516434 -10.488245) (xy 100.487627 -10.504909)
			(xy 100.464097 -10.528443) (xy 100.447438 -10.557252) (xy 100.438779 -10.589386) (xy 100.438204 -10.606024)
			(xy 100.438204 -10.627106) (xy 100.39822 -10.647284) (xy 100.315185 -10.680859) (xy 100.229335 -10.706392)
			(xy 100.141446 -10.72365) (xy 100.052316 -10.732478) (xy 99.96275 -10.732795) (xy 99.873559 -10.724599)
			(xy 99.78555 -10.707965) (xy 99.699521 -10.683041) (xy 99.61625 -10.650055) (xy 99.576128 -10.630154)
			(xy 99.576128 -10.606024) (xy 99.575536 -10.589379) (xy 99.566926 -10.557222) (xy 99.550287 -10.528389)
			(xy 99.526753 -10.504845) (xy 99.497926 -10.488194) (xy 99.465773 -10.479571) (xy 99.449128 -10.479024)
			(xy 99.361498 -10.479024) (xy 99.33065 -10.449458) (xy 99.273824 -10.385638) (xy 99.223024 -10.316926)
			(xy 99.178669 -10.243887) (xy 99.141124 -10.167125) (xy 99.110699 -10.087272) (xy 99.087646 -10.004988)
			(xy 99.072154 -9.920952) (xy 99.064352 -9.835857) (xy 99.064304 -9.750405) (xy 90.944463 -9.750405)
			(xy 90.944954 -9.792716) (xy 90.944434 -9.835465) (xy 90.936654 -9.920608) (xy 90.921179 -10.004694)
			(xy 90.898135 -10.087029) (xy 90.867714 -10.166931) (xy 90.830166 -10.243743) (xy 90.785801 -10.31683)
			(xy 90.734986 -10.385589) (xy 90.67814 -10.449451) (xy 90.647266 -10.479024) (xy 90.565224 -10.479024)
			(xy 90.548586 -10.479599) (xy 90.516455 -10.488258) (xy 90.487648 -10.504918) (xy 90.464118 -10.528448)
			(xy 90.447458 -10.557255) (xy 90.438799 -10.589386) (xy 90.438224 -10.606024) (xy 90.438224 -10.627106)
			(xy 90.398233 -10.647268) (xy 90.315199 -10.680845) (xy 90.22935 -10.706379) (xy 90.141463 -10.723638)
			(xy 90.052333 -10.732468) (xy 89.962768 -10.732787) (xy 89.873578 -10.724593) (xy 89.78557 -10.70796)
			(xy 89.699541 -10.683038) (xy 89.61627 -10.650054) (xy 89.576148 -10.630154) (xy 89.576148 -10.606024)
			(xy 89.575536 -10.589381) (xy 89.566928 -10.557227) (xy 89.550292 -10.528395) (xy 89.526762 -10.504852)
			(xy 89.49794 -10.488199) (xy 89.465791 -10.479573) (xy 89.449148 -10.479024) (xy 89.361518 -10.479024)
			(xy 89.330672 -10.449456) (xy 89.273851 -10.385635) (xy 89.223055 -10.316921) (xy 89.178703 -10.243882)
			(xy 89.141162 -10.16712) (xy 89.11074 -10.087268) (xy 89.087689 -10.004985) (xy 89.072199 -9.92095)
			(xy 89.064398 -9.835856) (xy 89.064349 -9.750405) (xy 0.509016 -9.750405) (xy 0.509016 -17.571212)
			(xy 147.308316 -17.571212) (xy 147.308773 -17.52685) (xy 147.316505 -17.438465) (xy 147.331911 -17.351089)
			(xy 147.354874 -17.265389) (xy 147.385219 -17.182016) (xy 147.422715 -17.101605) (xy 147.467076 -17.024769)
			(xy 147.517966 -16.952091) (xy 147.574997 -16.884125) (xy 147.637734 -16.821389) (xy 147.7057 -16.764359)
			(xy 147.778379 -16.71347) (xy 147.855216 -16.669109) (xy 147.935627 -16.631614) (xy 148.019 -16.60127)
			(xy 148.104701 -16.578309) (xy 148.192076 -16.562904) (xy 148.280462 -16.555173) (xy 148.324824 -16.554704)
			(xy 148.370622 -16.555198) (xy 148.461827 -16.563651) (xy 148.551863 -16.580484) (xy 148.639962 -16.605552)
			(xy 148.725372 -16.638643) (xy 148.807365 -16.679472) (xy 148.88524 -16.727693) (xy 148.958334 -16.782893)
			(xy 149.026023 -16.844602) (xy 149.08773 -16.912294) (xy 149.142928 -16.98539) (xy 149.191145 -17.063267)
			(xy 149.231972 -17.145261) (xy 149.265059 -17.230672) (xy 149.290124 -17.318772) (xy 149.306954 -17.408809)
			(xy 149.315404 -17.500014) (xy 149.315932 -17.545812) (xy 149.315932 -17.571212) (xy 153.571448 -17.571212)
			(xy 153.571987 -17.526853) (xy 153.579718 -17.438472) (xy 153.595123 -17.351101) (xy 153.618083 -17.265406)
			(xy 153.648425 -17.182037) (xy 153.685918 -17.10163) (xy 153.730275 -17.024797) (xy 153.78116 -16.952122)
			(xy 153.838185 -16.884158) (xy 153.900917 -16.821423) (xy 153.968877 -16.764394) (xy 154.04155 -16.713505)
			(xy 154.118381 -16.669144) (xy 154.198785 -16.631647) (xy 154.282152 -16.6013) (xy 154.367847 -16.578335)
			(xy 154.455216 -16.562926) (xy 154.543597 -16.55519) (xy 154.587956 -16.554704) (xy 154.633754 -16.555247)
			(xy 154.724958 -16.563695) (xy 154.814995 -16.580522) (xy 154.903094 -16.605585) (xy 154.988505 -16.63867)
			(xy 155.070499 -16.679496) (xy 155.148376 -16.727712) (xy 155.221471 -16.782909) (xy 155.289162 -16.844615)
			(xy 155.35087 -16.912304) (xy 155.40607 -16.985398) (xy 155.454289 -17.063273) (xy 155.495117 -17.145266)
			(xy 155.528205 -17.230676) (xy 155.553271 -17.318774) (xy 155.570101 -17.40881) (xy 155.578551 -17.500014)
			(xy 155.579064 -17.545812) (xy 155.579064 -17.571212) (xy 155.578559 -17.61627) (xy 155.570481 -17.706024)
			(xy 155.55439 -17.794693) (xy 155.530415 -17.881562) (xy 155.498751 -17.965933) (xy 155.45965 -18.047125)
			(xy 155.41343 -18.124486) (xy 155.36046 -18.197392) (xy 155.301169 -18.265256) (xy 155.236033 -18.327532)
			(xy 155.165577 -18.383719) (xy 155.090368 -18.433364) (xy 155.011012 -18.476068) (xy 154.928147 -18.511486)
			(xy 154.842441 -18.539333) (xy 154.754583 -18.559386) (xy 154.665282 -18.571483) (xy 154.575256 -18.575526)
			(xy 154.48523 -18.571483) (xy 154.395929 -18.559386) (xy 154.308071 -18.539333) (xy 154.222365 -18.511486)
			(xy 154.1395 -18.476068) (xy 154.060144 -18.433364) (xy 153.984935 -18.383719) (xy 153.914479 -18.327532)
			(xy 153.849343 -18.265256) (xy 153.790052 -18.197392) (xy 153.737082 -18.124486) (xy 153.690862 -18.047125)
			(xy 153.651761 -17.965933) (xy 153.620097 -17.881562) (xy 153.596122 -17.794693) (xy 153.580031 -17.706024)
			(xy 153.571953 -17.61627) (xy 153.571448 -17.571212) (xy 149.315932 -17.571212) (xy 149.315427 -17.61627)
			(xy 149.307349 -17.706024) (xy 149.291258 -17.794693) (xy 149.267283 -17.881562) (xy 149.235619 -17.965933)
			(xy 149.196518 -18.047125) (xy 149.150298 -18.124486) (xy 149.097328 -18.197392) (xy 149.038037 -18.265256)
			(xy 148.972901 -18.327532) (xy 148.902445 -18.383719) (xy 148.827236 -18.433364) (xy 148.74788 -18.476068)
			(xy 148.665015 -18.511486) (xy 148.579309 -18.539333) (xy 148.491451 -18.559386) (xy 148.40215 -18.571483)
			(xy 148.312124 -18.575526) (xy 148.222098 -18.571483) (xy 148.132797 -18.559386) (xy 148.044939 -18.539333)
			(xy 147.959233 -18.511486) (xy 147.876368 -18.476068) (xy 147.797012 -18.433364) (xy 147.721803 -18.383719)
			(xy 147.651347 -18.327532) (xy 147.586211 -18.265256) (xy 147.52692 -18.197392) (xy 147.47395 -18.124486)
			(xy 147.42773 -18.047125) (xy 147.388629 -17.965933) (xy 147.356965 -17.881562) (xy 147.33299 -17.794693)
			(xy 147.316899 -17.706024) (xy 147.308821 -17.61627) (xy 147.308316 -17.571212) (xy 0.509016 -17.571212)
			(xy 0.509016 -25.099663) (xy 37.367456 -25.099663) (xy 37.367456 -25.000313) (xy 37.37545 -24.901285)
			(xy 37.391387 -24.803222) (xy 37.415163 -24.706759) (xy 37.446624 -24.612522) (xy 37.485566 -24.521123)
			(xy 37.531736 -24.433153) (xy 37.584835 -24.349183) (xy 37.644519 -24.269759) (xy 37.7104 -24.195394)
			(xy 37.782051 -24.126572) (xy 37.859008 -24.063739) (xy 37.940771 -24.007302) (xy 38.026811 -23.957627)
			(xy 38.116568 -23.915036) (xy 38.209462 -23.879807) (xy 38.304889 -23.852166) (xy 38.402231 -23.832293)
			(xy 38.500857 -23.820318) (xy 38.600126 -23.816318) (xy 38.699395 -23.820318) (xy 38.798021 -23.832293)
			(xy 38.895363 -23.852166) (xy 38.99079 -23.879807) (xy 39.083684 -23.915036) (xy 39.173441 -23.957627)
			(xy 39.259481 -24.007302) (xy 39.341244 -24.063739) (xy 39.418201 -24.126572) (xy 39.489852 -24.195394)
			(xy 39.555733 -24.269759) (xy 39.615417 -24.349183) (xy 39.668516 -24.433153) (xy 39.714686 -24.521123)
			(xy 39.753628 -24.612522) (xy 39.785089 -24.706759) (xy 39.808865 -24.803222) (xy 39.824802 -24.901285)
			(xy 39.832796 -25.000313) (xy 39.833296 -25.049988) (xy 39.832848 -25.094499) (xy 104.408977 -25.094499)
			(xy 104.408977 -25.005477) (xy 104.416957 -24.916813) (xy 104.432853 -24.829222) (xy 104.456536 -24.743407)
			(xy 104.487816 -24.660062) (xy 104.526442 -24.579856) (xy 104.572101 -24.503435) (xy 104.624427 -24.431414)
			(xy 104.682998 -24.364374) (xy 104.747343 -24.302854) (xy 104.816943 -24.24735) (xy 104.891239 -24.198308)
			(xy 104.969631 -24.156123) (xy 105.05149 -24.121135) (xy 105.136155 -24.093626) (xy 105.222945 -24.073816)
			(xy 105.311161 -24.061866) (xy 105.400094 -24.057873) (xy 105.489027 -24.061866) (xy 105.577243 -24.073816)
			(xy 105.664033 -24.093626) (xy 105.748698 -24.121135) (xy 105.830557 -24.156123) (xy 105.908949 -24.198308)
			(xy 105.983245 -24.24735) (xy 106.052845 -24.302854) (xy 106.11719 -24.364374) (xy 106.175761 -24.431414)
			(xy 106.228087 -24.503435) (xy 106.273746 -24.579856) (xy 106.312372 -24.660062) (xy 106.343652 -24.743407)
			(xy 106.367335 -24.829222) (xy 106.383231 -24.916813) (xy 106.391211 -25.005477) (xy 106.39171 -25.049988)
			(xy 106.391211 -25.094499) (xy 106.383231 -25.183163) (xy 106.367335 -25.270754) (xy 106.343652 -25.356569)
			(xy 106.312372 -25.439914) (xy 106.273746 -25.52012) (xy 106.228087 -25.596541) (xy 106.175761 -25.668562)
			(xy 106.11719 -25.735602) (xy 106.052845 -25.797122) (xy 105.983245 -25.852626) (xy 105.908949 -25.901668)
			(xy 105.830557 -25.943853) (xy 105.748698 -25.978841) (xy 105.664033 -26.00635) (xy 105.577243 -26.02616)
			(xy 105.489027 -26.03811) (xy 105.400094 -26.042104) (xy 105.311161 -26.03811) (xy 105.222945 -26.02616)
			(xy 105.136155 -26.00635) (xy 105.05149 -25.978841) (xy 104.969631 -25.943853) (xy 104.891239 -25.901668)
			(xy 104.816943 -25.852626) (xy 104.747343 -25.797122) (xy 104.682998 -25.735602) (xy 104.624427 -25.668562)
			(xy 104.572101 -25.596541) (xy 104.526442 -25.52012) (xy 104.487816 -25.439914) (xy 104.456536 -25.356569)
			(xy 104.432853 -25.270754) (xy 104.416957 -25.183163) (xy 104.408977 -25.094499) (xy 39.832848 -25.094499)
			(xy 39.832796 -25.099663) (xy 39.824802 -25.198691) (xy 39.808865 -25.296754) (xy 39.785089 -25.393217)
			(xy 39.753628 -25.487454) (xy 39.714686 -25.578853) (xy 39.668516 -25.666823) (xy 39.615417 -25.750793)
			(xy 39.555733 -25.830217) (xy 39.489852 -25.904582) (xy 39.418201 -25.973404) (xy 39.341244 -26.036237)
			(xy 39.259481 -26.092674) (xy 39.173441 -26.142349) (xy 39.083684 -26.18494) (xy 38.99079 -26.220169)
			(xy 38.895363 -26.24781) (xy 38.798021 -26.267683) (xy 38.699395 -26.279658) (xy 38.600126 -26.283659)
			(xy 38.500857 -26.279658) (xy 38.402231 -26.267683) (xy 38.304889 -26.24781) (xy 38.209462 -26.220169)
			(xy 38.116568 -26.18494) (xy 38.026811 -26.142349) (xy 37.940771 -26.092674) (xy 37.859008 -26.036237)
			(xy 37.782051 -25.973404) (xy 37.7104 -25.904582) (xy 37.644519 -25.830217) (xy 37.584835 -25.750793)
			(xy 37.531736 -25.666823) (xy 37.485566 -25.578853) (xy 37.446624 -25.487454) (xy 37.415163 -25.393217)
			(xy 37.391387 -25.296754) (xy 37.37545 -25.198691) (xy 37.367456 -25.099663) (xy 0.509016 -25.099663)
			(xy 0.509016 -29.299916) (xy 0.509545 -29.345713) (xy 0.517996 -29.436917) (xy 0.534827 -29.526952)
			(xy 0.559893 -29.61505) (xy 0.59298 -29.700459) (xy 0.633808 -29.782451) (xy 0.682026 -29.860326)
			(xy 0.737224 -29.93342) (xy 0.798931 -30.001109) (xy 0.86662 -30.062816) (xy 0.939714 -30.118014)
			(xy 1.017589 -30.166232) (xy 1.099581 -30.20706) (xy 1.18499 -30.240147) (xy 1.273088 -30.265213)
			(xy 1.363123 -30.282044) (xy 1.454327 -30.290495) (xy 1.500124 -30.291024) (xy 6.500114 -30.291024)
			(xy 6.56323 -30.29152) (xy 6.689213 -30.299446) (xy 6.81445 -30.315267) (xy 6.938446 -30.338921)
			(xy 7.060713 -30.370314) (xy 7.180767 -30.409322) (xy 7.298135 -30.455792) (xy 7.412353 -30.509539)
			(xy 7.522971 -30.570352) (xy 7.629552 -30.637991) (xy 7.731676 -30.712188) (xy 7.82894 -30.792652)
			(xy 7.920959 -30.879064) (xy 8.007371 -30.971083) (xy 8.087834 -31.068347) (xy 8.162032 -31.170471)
			(xy 8.22967 -31.277053) (xy 8.290483 -31.387671) (xy 8.34423 -31.501889) (xy 8.390699 -31.619257)
			(xy 8.429707 -31.739311) (xy 8.4611 -31.861577) (xy 8.484753 -31.985574) (xy 8.500574 -32.110811)
			(xy 8.5085 -32.236794) (xy 8.509 -32.29991) (xy 8.509 -42.857987) (xy 9.994378 -42.857987) (xy 9.994378 -42.762365)
			(xy 10.002274 -42.667069) (xy 10.018013 -42.572751) (xy 10.041487 -42.480054) (xy 10.072536 -42.389613)
			(xy 10.110947 -42.302045) (xy 10.156458 -42.217947) (xy 10.208758 -42.137895) (xy 10.267491 -42.062436)
			(xy 10.332254 -41.992084) (xy 10.402606 -41.927321) (xy 10.478065 -41.868588) (xy 10.558117 -41.816288)
			(xy 10.642215 -41.770777) (xy 10.729783 -41.732366) (xy 10.820224 -41.701317) (xy 10.912921 -41.677843)
			(xy 11.007239 -41.662104) (xy 11.102535 -41.654208) (xy 11.198157 -41.654208) (xy 11.293453 -41.662104)
			(xy 11.387771 -41.677843) (xy 11.480468 -41.701317) (xy 11.570909 -41.732366) (xy 11.658477 -41.770777)
			(xy 11.742575 -41.816288) (xy 11.822627 -41.868588) (xy 11.898086 -41.927321) (xy 11.968438 -41.992084)
			(xy 12.033201 -42.062436) (xy 12.091934 -42.137895) (xy 12.144234 -42.217947) (xy 12.189745 -42.302045)
			(xy 12.228156 -42.389613) (xy 12.259205 -42.480054) (xy 12.282679 -42.572751) (xy 12.298418 -42.667069)
			(xy 12.306314 -42.762365) (xy 12.306808 -42.810176) (xy 12.306314 -42.857987) (xy 12.298418 -42.953283)
			(xy 12.282679 -43.047601) (xy 12.259205 -43.140298) (xy 12.228156 -43.230739) (xy 12.189745 -43.318307)
			(xy 12.144234 -43.402405) (xy 12.091934 -43.482457) (xy 12.033201 -43.557916) (xy 11.968438 -43.628268)
			(xy 11.898086 -43.693031) (xy 11.822627 -43.751764) (xy 11.742575 -43.804064) (xy 11.658477 -43.849575)
			(xy 11.570909 -43.887986) (xy 11.480468 -43.919035) (xy 11.387771 -43.942509) (xy 11.293453 -43.958248)
			(xy 11.198157 -43.966144) (xy 11.102535 -43.966144) (xy 11.007239 -43.958248) (xy 10.912921 -43.942509)
			(xy 10.820224 -43.919035) (xy 10.729783 -43.887986) (xy 10.642215 -43.849575) (xy 10.558117 -43.804064)
			(xy 10.478065 -43.751764) (xy 10.402606 -43.693031) (xy 10.332254 -43.628268) (xy 10.267491 -43.557916)
			(xy 10.208758 -43.482457) (xy 10.156458 -43.402405) (xy 10.110947 -43.318307) (xy 10.072536 -43.230739)
			(xy 10.041487 -43.140298) (xy 10.018013 -43.047601) (xy 10.002274 -42.953283) (xy 9.994378 -42.857987)
			(xy 8.509 -42.857987) (xy 8.509 -47.517812) (xy 154.521408 -47.517812) (xy 154.521408 -45.112686)
			(xy 155.019756 -44.614338) (xy 155.72486 -44.614338) (xy 156.223208 -45.112686) (xy 156.223208 -47.146464)
			(xy 158.2928 -47.146464) (xy 158.2928 -45.53966) (xy 158.530798 -45.301662) (xy 158.867602 -45.301662)
			(xy 159.1056 -45.53966) (xy 159.1056 -47.146464) (xy 158.867602 -47.384462) (xy 158.530798 -47.384462)
			(xy 158.2928 -47.146464) (xy 156.223208 -47.146464) (xy 156.223208 -47.517812) (xy 155.72486 -48.01616)
			(xy 155.019756 -48.01616) (xy 154.521408 -47.517812) (xy 8.509 -47.517812) (xy 8.509 -51.327812)
			(xy 154.521408 -51.327812) (xy 154.521408 -48.922686) (xy 155.019756 -48.424338) (xy 155.72486 -48.424338)
			(xy 156.223208 -48.922686) (xy 156.223208 -50.999136) (xy 160.873948 -50.999136) (xy 160.873948 -49.392332)
			(xy 161.111946 -49.154334) (xy 161.44875 -49.154334) (xy 161.686748 -49.392332) (xy 161.686748 -50.999136)
			(xy 161.44875 -51.237134) (xy 161.111946 -51.237134) (xy 160.873948 -50.999136) (xy 156.223208 -50.999136)
			(xy 156.223208 -51.327812) (xy 155.72486 -51.82616) (xy 155.019756 -51.82616) (xy 154.521408 -51.327812)
			(xy 8.509 -51.327812) (xy 8.509 -58.837889) (xy 9.994378 -58.837889) (xy 9.994378 -58.742267) (xy 10.002274 -58.646971)
			(xy 10.018013 -58.552653) (xy 10.041487 -58.459956) (xy 10.072536 -58.369515) (xy 10.110947 -58.281947)
			(xy 10.156458 -58.197849) (xy 10.208758 -58.117797) (xy 10.267491 -58.042338) (xy 10.332254 -57.971986)
			(xy 10.402606 -57.907223) (xy 10.478065 -57.84849) (xy 10.558117 -57.79619) (xy 10.642215 -57.750679)
			(xy 10.729783 -57.712268) (xy 10.820224 -57.681219) (xy 10.912921 -57.657745) (xy 11.007239 -57.642006)
			(xy 11.102535 -57.63411) (xy 11.198157 -57.63411) (xy 11.293453 -57.642006) (xy 11.387771 -57.657745)
			(xy 11.480468 -57.681219) (xy 11.570909 -57.712268) (xy 11.658477 -57.750679) (xy 11.742575 -57.79619)
			(xy 11.822627 -57.84849) (xy 11.898086 -57.907223) (xy 11.968438 -57.971986) (xy 12.033201 -58.042338)
			(xy 12.091934 -58.117797) (xy 12.144234 -58.197849) (xy 12.189745 -58.281947) (xy 12.228156 -58.369515)
			(xy 12.259205 -58.459956) (xy 12.282679 -58.552653) (xy 12.298418 -58.646971) (xy 12.306314 -58.742267)
			(xy 12.306808 -58.790078) (xy 12.306314 -58.837889) (xy 12.298418 -58.933185) (xy 12.282679 -59.027503)
			(xy 12.259205 -59.1202) (xy 12.253908 -59.13563) (xy 109.258606 -59.13563) (xy 109.258606 -59.04549)
			(xy 109.266686 -58.955714) (xy 109.282781 -58.867023) (xy 109.306761 -58.780131) (xy 109.338434 -58.69574)
			(xy 109.377544 -58.614527) (xy 109.423776 -58.537147) (xy 109.476759 -58.464222) (xy 109.536065 -58.396341)
			(xy 109.601218 -58.334049) (xy 109.671692 -58.277847) (xy 109.74692 -58.22819) (xy 109.826296 -58.185476)
			(xy 109.909182 -58.150048) (xy 109.99491 -58.122194) (xy 110.082789 -58.102136) (xy 110.172113 -58.090036)
			(xy 110.262162 -58.085992) (xy 110.352211 -58.090036) (xy 110.441535 -58.102136) (xy 110.529414 -58.122194)
			(xy 110.615142 -58.150048) (xy 110.698028 -58.185476) (xy 110.777404 -58.22819) (xy 110.852632 -58.277847)
			(xy 110.923106 -58.334049) (xy 110.988259 -58.396341) (xy 111.047565 -58.464222) (xy 111.100548 -58.537147)
			(xy 111.14678 -58.614527) (xy 111.18589 -58.69574) (xy 111.217563 -58.780131) (xy 111.241543 -58.867023)
			(xy 111.257638 -58.955714) (xy 111.265718 -59.04549) (xy 111.266224 -59.09056) (xy 111.265718 -59.13563)
			(xy 111.257638 -59.225406) (xy 111.241543 -59.314097) (xy 111.217563 -59.400989) (xy 111.18589 -59.48538)
			(xy 111.14678 -59.566593) (xy 111.100548 -59.643973) (xy 111.047565 -59.716898) (xy 110.988259 -59.784779)
			(xy 110.923106 -59.847071) (xy 110.852632 -59.903273) (xy 110.777404 -59.95293) (xy 110.698028 -59.995644)
			(xy 110.615142 -60.031072) (xy 110.529414 -60.058926) (xy 110.441535 -60.078984) (xy 110.352211 -60.091084)
			(xy 110.262162 -60.095128) (xy 110.172113 -60.091084) (xy 110.082789 -60.078984) (xy 109.99491 -60.058926)
			(xy 109.909182 -60.031072) (xy 109.826296 -59.995644) (xy 109.74692 -59.95293) (xy 109.671692 -59.903273)
			(xy 109.601218 -59.847071) (xy 109.536065 -59.784779) (xy 109.476759 -59.716898) (xy 109.423776 -59.643973)
			(xy 109.377544 -59.566593) (xy 109.338434 -59.48538) (xy 109.306761 -59.400989) (xy 109.282781 -59.314097)
			(xy 109.266686 -59.225406) (xy 109.258606 -59.13563) (xy 12.253908 -59.13563) (xy 12.228156 -59.210641)
			(xy 12.189745 -59.298209) (xy 12.144234 -59.382307) (xy 12.091934 -59.462359) (xy 12.033201 -59.537818)
			(xy 11.968438 -59.60817) (xy 11.898086 -59.672933) (xy 11.822627 -59.731666) (xy 11.742575 -59.783966)
			(xy 11.658477 -59.829477) (xy 11.570909 -59.867888) (xy 11.480468 -59.898937) (xy 11.387771 -59.922411)
			(xy 11.293453 -59.93815) (xy 11.198157 -59.946046) (xy 11.102535 -59.946046) (xy 11.007239 -59.93815)
			(xy 10.912921 -59.922411) (xy 10.820224 -59.898937) (xy 10.729783 -59.867888) (xy 10.642215 -59.829477)
			(xy 10.558117 -59.783966) (xy 10.478065 -59.731666) (xy 10.402606 -59.672933) (xy 10.332254 -59.60817)
			(xy 10.267491 -59.537818) (xy 10.208758 -59.462359) (xy 10.156458 -59.382307) (xy 10.110947 -59.298209)
			(xy 10.072536 -59.210641) (xy 10.041487 -59.1202) (xy 10.018013 -59.027503) (xy 10.002274 -58.933185)
			(xy 9.994378 -58.837889) (xy 8.509 -58.837889) (xy 8.509 -62.863044) (xy 23.993081 -62.863044) (xy 23.993081 -62.736908)
			(xy 24.001001 -62.61102) (xy 24.016811 -62.485878) (xy 24.040446 -62.361975) (xy 24.071815 -62.239802)
			(xy 24.110793 -62.119839) (xy 24.157227 -62.00256) (xy 24.210934 -61.888428) (xy 24.271701 -61.777893)
			(xy 24.339288 -61.671393) (xy 24.413429 -61.569346) (xy 24.493832 -61.472156) (xy 24.580178 -61.380206)
			(xy 24.672128 -61.29386) (xy 24.769318 -61.213457) (xy 24.871365 -61.139316) (xy 24.977865 -61.071729)
			(xy 25.0884 -61.010962) (xy 25.202532 -60.957255) (xy 25.319811 -60.910821) (xy 25.439774 -60.871843)
			(xy 25.561947 -60.840474) (xy 25.68585 -60.816839) (xy 25.810992 -60.801029) (xy 25.93688 -60.793109)
			(xy 26.063016 -60.793109) (xy 26.188904 -60.801029) (xy 26.314046 -60.816839) (xy 26.437949 -60.840474)
			(xy 26.560122 -60.871843) (xy 26.680085 -60.910821) (xy 26.797364 -60.957255) (xy 26.911496 -61.010962)
			(xy 27.022031 -61.071729) (xy 27.128531 -61.139316) (xy 27.230578 -61.213457) (xy 27.327768 -61.29386)
			(xy 27.419718 -61.380206) (xy 27.506064 -61.472156) (xy 27.586467 -61.569346) (xy 27.660608 -61.671393)
			(xy 27.728195 -61.777893) (xy 27.788962 -61.888428) (xy 27.842669 -62.00256) (xy 27.889103 -62.119839)
			(xy 27.928081 -62.239802) (xy 27.95945 -62.361975) (xy 27.983085 -62.485878) (xy 27.998895 -62.61102)
			(xy 28.006815 -62.736908) (xy 28.00731 -62.799976) (xy 28.006815 -62.863044) (xy 87.993207 -62.863044)
			(xy 87.993207 -62.736908) (xy 88.001127 -62.61102) (xy 88.016937 -62.485878) (xy 88.040572 -62.361975)
			(xy 88.071941 -62.239802) (xy 88.110919 -62.119839) (xy 88.157353 -62.00256) (xy 88.21106 -61.888428)
			(xy 88.271827 -61.777893) (xy 88.339414 -61.671393) (xy 88.413555 -61.569346) (xy 88.493958 -61.472156)
			(xy 88.580304 -61.380206) (xy 88.672254 -61.29386) (xy 88.769444 -61.213457) (xy 88.871491 -61.139316)
			(xy 88.977991 -61.071729) (xy 89.088526 -61.010962) (xy 89.202658 -60.957255) (xy 89.319937 -60.910821)
			(xy 89.4399 -60.871843) (xy 89.562073 -60.840474) (xy 89.685976 -60.816839) (xy 89.811118 -60.801029)
			(xy 89.937006 -60.793109) (xy 90.063142 -60.793109) (xy 90.18903 -60.801029) (xy 90.314172 -60.816839)
			(xy 90.438075 -60.840474) (xy 90.560248 -60.871843) (xy 90.680211 -60.910821) (xy 90.79749 -60.957255)
			(xy 90.911622 -61.010962) (xy 91.022157 -61.071729) (xy 91.128657 -61.139316) (xy 91.230704 -61.213457)
			(xy 91.327894 -61.29386) (xy 91.419844 -61.380206) (xy 91.50619 -61.472156) (xy 91.586593 -61.569346)
			(xy 91.660734 -61.671393) (xy 91.728321 -61.777893) (xy 91.789088 -61.888428) (xy 91.842795 -62.00256)
			(xy 91.889229 -62.119839) (xy 91.928207 -62.239802) (xy 91.959576 -62.361975) (xy 91.983211 -62.485878)
			(xy 91.999021 -62.61102) (xy 92.006941 -62.736908) (xy 92.007436 -62.799976) (xy 92.006941 -62.863044)
			(xy 91.999021 -62.988932) (xy 91.983211 -63.114074) (xy 91.959576 -63.237977) (xy 91.928207 -63.36015)
			(xy 91.889229 -63.480113) (xy 91.842795 -63.597392) (xy 91.789088 -63.711524) (xy 91.728321 -63.822059)
			(xy 91.660734 -63.928559) (xy 91.586593 -64.030606) (xy 91.50619 -64.127796) (xy 91.419844 -64.219746)
			(xy 91.327894 -64.306092) (xy 91.230704 -64.386495) (xy 91.128657 -64.460636) (xy 91.022157 -64.528223)
			(xy 90.911622 -64.58899) (xy 90.79749 -64.642697) (xy 90.680211 -64.689131) (xy 90.560248 -64.728109)
			(xy 90.438075 -64.759478) (xy 90.314172 -64.783113) (xy 90.18903 -64.798923) (xy 90.063142 -64.806843)
			(xy 89.937006 -64.806843) (xy 89.811118 -64.798923) (xy 89.685976 -64.783113) (xy 89.562073 -64.759478)
			(xy 89.4399 -64.728109) (xy 89.319937 -64.689131) (xy 89.202658 -64.642697) (xy 89.088526 -64.58899)
			(xy 88.977991 -64.528223) (xy 88.871491 -64.460636) (xy 88.769444 -64.386495) (xy 88.672254 -64.306092)
			(xy 88.580304 -64.219746) (xy 88.493958 -64.127796) (xy 88.413555 -64.030606) (xy 88.339414 -63.928559)
			(xy 88.271827 -63.822059) (xy 88.21106 -63.711524) (xy 88.157353 -63.597392) (xy 88.110919 -63.480113)
			(xy 88.071941 -63.36015) (xy 88.040572 -63.237977) (xy 88.016937 -63.114074) (xy 88.001127 -62.988932)
			(xy 87.993207 -62.863044) (xy 28.006815 -62.863044) (xy 27.998895 -62.988932) (xy 27.983085 -63.114074)
			(xy 27.95945 -63.237977) (xy 27.928081 -63.36015) (xy 27.889103 -63.480113) (xy 27.842669 -63.597392)
			(xy 27.788962 -63.711524) (xy 27.728195 -63.822059) (xy 27.660608 -63.928559) (xy 27.586467 -64.030606)
			(xy 27.506064 -64.127796) (xy 27.419718 -64.219746) (xy 27.327768 -64.306092) (xy 27.230578 -64.386495)
			(xy 27.128531 -64.460636) (xy 27.022031 -64.528223) (xy 26.911496 -64.58899) (xy 26.797364 -64.642697)
			(xy 26.680085 -64.689131) (xy 26.560122 -64.728109) (xy 26.437949 -64.759478) (xy 26.314046 -64.783113)
			(xy 26.188904 -64.798923) (xy 26.063016 -64.806843) (xy 25.93688 -64.806843) (xy 25.810992 -64.798923)
			(xy 25.68585 -64.783113) (xy 25.561947 -64.759478) (xy 25.439774 -64.728109) (xy 25.319811 -64.689131)
			(xy 25.202532 -64.642697) (xy 25.0884 -64.58899) (xy 24.977865 -64.528223) (xy 24.871365 -64.460636)
			(xy 24.769318 -64.386495) (xy 24.672128 -64.306092) (xy 24.580178 -64.219746) (xy 24.493832 -64.127796)
			(xy 24.413429 -64.030606) (xy 24.339288 -63.928559) (xy 24.271701 -63.822059) (xy 24.210934 -63.711524)
			(xy 24.157227 -63.597392) (xy 24.110793 -63.480113) (xy 24.071815 -63.36015) (xy 24.040446 -63.237977)
			(xy 24.016811 -63.114074) (xy 24.001001 -62.988932) (xy 23.993081 -62.863044) (xy 8.509 -62.863044)
			(xy 8.509 -69.30009) (xy 8.508504 -69.363206) (xy 8.500578 -69.48919) (xy 8.484757 -69.614427) (xy 8.461104 -69.738423)
			(xy 8.429711 -69.86069) (xy 8.390703 -69.980744) (xy 8.344234 -70.098112) (xy 8.290487 -70.212331)
			(xy 8.229674 -70.32295) (xy 8.162035 -70.429531) (xy 8.087837 -70.531656) (xy 8.007374 -70.628919)
			(xy 7.920962 -70.720939) (xy 7.828942 -70.807351) (xy 7.731679 -70.887815) (xy 7.629555 -70.962013)
			(xy 7.522973 -71.029652) (xy 7.412355 -71.090465) (xy 7.298136 -71.144212) (xy 7.180768 -71.190682)
			(xy 7.060714 -71.22969) (xy 6.938447 -71.261083) (xy 6.814451 -71.284737) (xy 6.689214 -71.300558)
			(xy 6.56323 -71.308484) (xy 6.500114 -71.308976) (xy 1.500124 -71.308976) (xy 1.454327 -71.309505)
			(xy 1.363123 -71.317956) (xy 1.273088 -71.334787) (xy 1.18499 -71.359853) (xy 1.099581 -71.39294)
			(xy 1.017589 -71.433768) (xy 0.939714 -71.481986) (xy 0.86662 -71.537184) (xy 0.798931 -71.598891)
			(xy 0.737224 -71.66658) (xy 0.682026 -71.739674) (xy 0.633808 -71.817549) (xy 0.59298 -71.899541)
			(xy 0.559893 -71.98495) (xy 0.534827 -72.073048) (xy 0.517996 -72.163083) (xy 0.509545 -72.254287)
			(xy 0.509016 -72.300084) (xy 0.509016 -77.082841) (xy 4.534904 -77.082841) (xy 4.534904 -76.959015)
			(xy 4.542837 -76.835444) (xy 4.558672 -76.712636) (xy 4.582342 -76.591094) (xy 4.613751 -76.471318)
			(xy 4.652769 -76.353801) (xy 4.699237 -76.239025) (xy 4.752963 -76.127462) (xy 4.813726 -76.019571)
			(xy 4.881277 -75.915794) (xy 4.955339 -75.816559) (xy 5.035606 -75.722272) (xy 5.121749 -75.633322)
			(xy 5.213414 -75.550074) (xy 5.310225 -75.472871) (xy 5.411783 -75.402028) (xy 5.517671 -75.337838)
			(xy 5.627455 -75.280564) (xy 5.740682 -75.230441) (xy 5.856889 -75.187676) (xy 5.975596 -75.152445)
			(xy 6.096317 -75.124891) (xy 6.218555 -75.105128) (xy 6.341808 -75.093238) (xy 6.46557 -75.08927)
			(xy 6.589332 -75.093238) (xy 6.712585 -75.105128) (xy 6.834823 -75.124891) (xy 6.955544 -75.152445)
			(xy 7.074251 -75.187676) (xy 7.190458 -75.230441) (xy 7.303685 -75.280564) (xy 7.413469 -75.337838)
			(xy 7.519357 -75.402028) (xy 7.620915 -75.472871) (xy 7.717726 -75.550074) (xy 7.809391 -75.633322)
			(xy 7.895534 -75.722272) (xy 7.975801 -75.816559) (xy 8.049863 -75.915794) (xy 8.117414 -76.019571)
			(xy 8.178177 -76.127462) (xy 8.231903 -76.239025) (xy 8.278371 -76.353801) (xy 8.317389 -76.471318)
			(xy 8.348798 -76.591094) (xy 8.372468 -76.712636) (xy 8.388303 -76.835444) (xy 8.396236 -76.959015)
			(xy 8.396732 -77.020928) (xy 8.396236 -77.082841) (xy 8.388303 -77.206412) (xy 8.372468 -77.32922)
			(xy 8.348798 -77.450762) (xy 8.317389 -77.570538) (xy 8.278371 -77.688055) (xy 8.231903 -77.802831)
			(xy 8.178177 -77.914394) (xy 8.117414 -78.022285) (xy 8.049863 -78.126062) (xy 7.975801 -78.225297)
			(xy 7.895534 -78.319584) (xy 7.809391 -78.408534) (xy 7.717726 -78.491782) (xy 7.620915 -78.568985)
			(xy 7.519357 -78.639828) (xy 7.413469 -78.704018) (xy 7.303685 -78.761292) (xy 7.190458 -78.811415)
			(xy 7.074251 -78.85418) (xy 6.955544 -78.889411) (xy 6.834823 -78.916965) (xy 6.712585 -78.936728)
			(xy 6.589332 -78.948618) (xy 6.46557 -78.952587) (xy 6.341808 -78.948618) (xy 6.218555 -78.936728)
			(xy 6.096317 -78.916965) (xy 5.975596 -78.889411) (xy 5.856889 -78.85418) (xy 5.740682 -78.811415)
			(xy 5.627455 -78.761292) (xy 5.517671 -78.704018) (xy 5.411783 -78.639828) (xy 5.310225 -78.568985)
			(xy 5.213414 -78.491782) (xy 5.121749 -78.408534) (xy 5.035606 -78.319584) (xy 4.955339 -78.225297)
			(xy 4.881277 -78.126062) (xy 4.813726 -78.022285) (xy 4.752963 -77.914394) (xy 4.699237 -77.802831)
			(xy 4.652769 -77.688055) (xy 4.613751 -77.570538) (xy 4.582342 -77.450762) (xy 4.558672 -77.32922)
			(xy 4.542837 -77.206412) (xy 4.534904 -77.082841) (xy 0.509016 -77.082841) (xy 0.509016 -79.26132)
			(xy 109.258606 -79.26132) (xy 109.258606 -79.17118) (xy 109.266686 -79.081404) (xy 109.282781 -78.992713)
			(xy 109.306761 -78.905821) (xy 109.338434 -78.82143) (xy 109.377544 -78.740217) (xy 109.423776 -78.662837)
			(xy 109.476759 -78.589912) (xy 109.536065 -78.522031) (xy 109.601218 -78.459739) (xy 109.671692 -78.403537)
			(xy 109.74692 -78.35388) (xy 109.826296 -78.311166) (xy 109.909182 -78.275738) (xy 109.99491 -78.247884)
			(xy 110.082789 -78.227826) (xy 110.172113 -78.215726) (xy 110.262162 -78.211682) (xy 110.352211 -78.215726)
			(xy 110.441535 -78.227826) (xy 110.529414 -78.247884) (xy 110.615142 -78.275738) (xy 110.698028 -78.311166)
			(xy 110.777404 -78.35388) (xy 110.852632 -78.403537) (xy 110.923106 -78.459739) (xy 110.988259 -78.522031)
			(xy 111.047565 -78.589912) (xy 111.100548 -78.662837) (xy 111.14678 -78.740217) (xy 111.18589 -78.82143)
			(xy 111.217563 -78.905821) (xy 111.241543 -78.992713) (xy 111.257638 -79.081404) (xy 111.265718 -79.17118)
			(xy 111.266224 -79.21625) (xy 111.265718 -79.26132) (xy 111.257638 -79.351096) (xy 111.241543 -79.439787)
			(xy 111.217563 -79.526679) (xy 111.18589 -79.61107) (xy 111.14678 -79.692283) (xy 111.100548 -79.769663)
			(xy 111.047565 -79.842588) (xy 110.988259 -79.910469) (xy 110.923106 -79.972761) (xy 110.852632 -80.028963)
			(xy 110.777404 -80.07862) (xy 110.698028 -80.121334) (xy 110.615142 -80.156762) (xy 110.529414 -80.184616)
			(xy 110.441535 -80.204674) (xy 110.352211 -80.216774) (xy 110.262162 -80.220818) (xy 110.172113 -80.216774)
			(xy 110.082789 -80.204674) (xy 109.99491 -80.184616) (xy 109.909182 -80.156762) (xy 109.826296 -80.121334)
			(xy 109.74692 -80.07862) (xy 109.671692 -80.028963) (xy 109.601218 -79.972761) (xy 109.536065 -79.910469)
			(xy 109.476759 -79.842588) (xy 109.423776 -79.769663) (xy 109.377544 -79.692283) (xy 109.338434 -79.61107)
			(xy 109.306761 -79.526679) (xy 109.282781 -79.439787) (xy 109.266686 -79.351096) (xy 109.258606 -79.26132)
			(xy 0.509016 -79.26132) (xy 0.509016 -90.697241) (xy 4.534904 -90.697241) (xy 4.534904 -90.573415)
			(xy 4.542837 -90.449844) (xy 4.558672 -90.327036) (xy 4.582342 -90.205494) (xy 4.613751 -90.085718)
			(xy 4.652769 -89.968201) (xy 4.699237 -89.853425) (xy 4.752963 -89.741862) (xy 4.813726 -89.633971)
			(xy 4.881277 -89.530194) (xy 4.955339 -89.430959) (xy 5.035606 -89.336672) (xy 5.121749 -89.247722)
			(xy 5.213414 -89.164474) (xy 5.310225 -89.087271) (xy 5.411783 -89.016428) (xy 5.517671 -88.952238)
			(xy 5.627455 -88.894964) (xy 5.740682 -88.844841) (xy 5.856889 -88.802076) (xy 5.975596 -88.766845)
			(xy 6.096317 -88.739291) (xy 6.218555 -88.719528) (xy 6.341808 -88.707638) (xy 6.46557 -88.70367)
			(xy 6.589332 -88.707638) (xy 6.712585 -88.719528) (xy 6.834823 -88.739291) (xy 6.955544 -88.766845)
			(xy 7.074251 -88.802076) (xy 7.190458 -88.844841) (xy 7.231461 -88.862992) (xy 23.993081 -88.862992)
			(xy 23.993081 -88.736856) (xy 24.001001 -88.610968) (xy 24.016811 -88.485826) (xy 24.040446 -88.361923)
			(xy 24.071815 -88.23975) (xy 24.110793 -88.119787) (xy 24.157227 -88.002508) (xy 24.210934 -87.888376)
			(xy 24.271701 -87.777841) (xy 24.339288 -87.671341) (xy 24.413429 -87.569294) (xy 24.493832 -87.472104)
			(xy 24.580178 -87.380154) (xy 24.672128 -87.293808) (xy 24.769318 -87.213405) (xy 24.871365 -87.139264)
			(xy 24.977865 -87.071677) (xy 25.0884 -87.01091) (xy 25.202532 -86.957203) (xy 25.319811 -86.910769)
			(xy 25.439774 -86.871791) (xy 25.561947 -86.840422) (xy 25.68585 -86.816787) (xy 25.810992 -86.800977)
			(xy 25.93688 -86.793057) (xy 26.063016 -86.793057) (xy 26.188904 -86.800977) (xy 26.314046 -86.816787)
			(xy 26.437949 -86.840422) (xy 26.560122 -86.871791) (xy 26.680085 -86.910769) (xy 26.797364 -86.957203)
			(xy 26.911496 -87.01091) (xy 27.022031 -87.071677) (xy 27.128531 -87.139264) (xy 27.230578 -87.213405)
			(xy 27.327768 -87.293808) (xy 27.419718 -87.380154) (xy 27.506064 -87.472104) (xy 27.586467 -87.569294)
			(xy 27.660608 -87.671341) (xy 27.728195 -87.777841) (xy 27.788962 -87.888376) (xy 27.842669 -88.002508)
			(xy 27.889103 -88.119787) (xy 27.928081 -88.23975) (xy 27.95945 -88.361923) (xy 27.983085 -88.485826)
			(xy 27.998895 -88.610968) (xy 28.006815 -88.736856) (xy 28.00731 -88.799924) (xy 28.006815 -88.862992)
			(xy 87.993207 -88.862992) (xy 87.993207 -88.736856) (xy 88.001127 -88.610968) (xy 88.016937 -88.485826)
			(xy 88.040572 -88.361923) (xy 88.071941 -88.23975) (xy 88.110919 -88.119787) (xy 88.157353 -88.002508)
			(xy 88.21106 -87.888376) (xy 88.271827 -87.777841) (xy 88.339414 -87.671341) (xy 88.413555 -87.569294)
			(xy 88.493958 -87.472104) (xy 88.580304 -87.380154) (xy 88.672254 -87.293808) (xy 88.769444 -87.213405)
			(xy 88.871491 -87.139264) (xy 88.977991 -87.071677) (xy 89.088526 -87.01091) (xy 89.202658 -86.957203)
			(xy 89.319937 -86.910769) (xy 89.4399 -86.871791) (xy 89.562073 -86.840422) (xy 89.685976 -86.816787)
			(xy 89.811118 -86.800977) (xy 89.937006 -86.793057) (xy 90.063142 -86.793057) (xy 90.18903 -86.800977)
			(xy 90.314172 -86.816787) (xy 90.438075 -86.840422) (xy 90.560248 -86.871791) (xy 90.680211 -86.910769)
			(xy 90.79749 -86.957203) (xy 90.911622 -87.01091) (xy 91.022157 -87.071677) (xy 91.128657 -87.139264)
			(xy 91.230704 -87.213405) (xy 91.327894 -87.293808) (xy 91.419844 -87.380154) (xy 91.50619 -87.472104)
			(xy 91.586593 -87.569294) (xy 91.660734 -87.671341) (xy 91.728321 -87.777841) (xy 91.789088 -87.888376)
			(xy 91.842795 -88.002508) (xy 91.889229 -88.119787) (xy 91.928207 -88.23975) (xy 91.959576 -88.361923)
			(xy 91.983211 -88.485826) (xy 91.999021 -88.610968) (xy 92.006941 -88.736856) (xy 92.007436 -88.799924)
			(xy 92.006941 -88.862992) (xy 91.999021 -88.98888) (xy 91.983211 -89.114022) (xy 91.959576 -89.237925)
			(xy 91.928207 -89.360098) (xy 91.889229 -89.480061) (xy 91.842795 -89.59734) (xy 91.789088 -89.711472)
			(xy 91.728321 -89.822007) (xy 91.660734 -89.928507) (xy 91.586593 -90.030554) (xy 91.50619 -90.127744)
			(xy 91.419844 -90.219694) (xy 91.327894 -90.30604) (xy 91.230704 -90.386443) (xy 91.128657 -90.460584)
			(xy 91.022157 -90.528171) (xy 90.911622 -90.588938) (xy 90.79749 -90.642645) (xy 90.680211 -90.689079)
			(xy 90.560248 -90.728057) (xy 90.438075 -90.759426) (xy 90.314172 -90.783061) (xy 90.18903 -90.798871)
			(xy 90.063142 -90.806791) (xy 89.937006 -90.806791) (xy 89.811118 -90.798871) (xy 89.685976 -90.783061)
			(xy 89.562073 -90.759426) (xy 89.4399 -90.728057) (xy 89.319937 -90.689079) (xy 89.202658 -90.642645)
			(xy 89.088526 -90.588938) (xy 88.977991 -90.528171) (xy 88.871491 -90.460584) (xy 88.769444 -90.386443)
			(xy 88.672254 -90.30604) (xy 88.580304 -90.219694) (xy 88.493958 -90.127744) (xy 88.413555 -90.030554)
			(xy 88.339414 -89.928507) (xy 88.271827 -89.822007) (xy 88.21106 -89.711472) (xy 88.157353 -89.59734)
			(xy 88.110919 -89.480061) (xy 88.071941 -89.360098) (xy 88.040572 -89.237925) (xy 88.016937 -89.114022)
			(xy 88.001127 -88.98888) (xy 87.993207 -88.862992) (xy 28.006815 -88.862992) (xy 27.998895 -88.98888)
			(xy 27.983085 -89.114022) (xy 27.95945 -89.237925) (xy 27.928081 -89.360098) (xy 27.889103 -89.480061)
			(xy 27.842669 -89.59734) (xy 27.788962 -89.711472) (xy 27.728195 -89.822007) (xy 27.660608 -89.928507)
			(xy 27.586467 -90.030554) (xy 27.506064 -90.127744) (xy 27.419718 -90.219694) (xy 27.327768 -90.30604)
			(xy 27.230578 -90.386443) (xy 27.128531 -90.460584) (xy 27.022031 -90.528171) (xy 26.911496 -90.588938)
			(xy 26.797364 -90.642645) (xy 26.680085 -90.689079) (xy 26.560122 -90.728057) (xy 26.437949 -90.759426)
			(xy 26.314046 -90.783061) (xy 26.188904 -90.798871) (xy 26.063016 -90.806791) (xy 25.93688 -90.806791)
			(xy 25.810992 -90.798871) (xy 25.68585 -90.783061) (xy 25.561947 -90.759426) (xy 25.439774 -90.728057)
			(xy 25.319811 -90.689079) (xy 25.202532 -90.642645) (xy 25.0884 -90.588938) (xy 24.977865 -90.528171)
			(xy 24.871365 -90.460584) (xy 24.769318 -90.386443) (xy 24.672128 -90.30604) (xy 24.580178 -90.219694)
			(xy 24.493832 -90.127744) (xy 24.413429 -90.030554) (xy 24.339288 -89.928507) (xy 24.271701 -89.822007)
			(xy 24.210934 -89.711472) (xy 24.157227 -89.59734) (xy 24.110793 -89.480061) (xy 24.071815 -89.360098)
			(xy 24.040446 -89.237925) (xy 24.016811 -89.114022) (xy 24.001001 -88.98888) (xy 23.993081 -88.862992)
			(xy 7.231461 -88.862992) (xy 7.303685 -88.894964) (xy 7.413469 -88.952238) (xy 7.519357 -89.016428)
			(xy 7.620915 -89.087271) (xy 7.717726 -89.164474) (xy 7.809391 -89.247722) (xy 7.895534 -89.336672)
			(xy 7.975801 -89.430959) (xy 8.049863 -89.530194) (xy 8.117414 -89.633971) (xy 8.178177 -89.741862)
			(xy 8.231903 -89.853425) (xy 8.278371 -89.968201) (xy 8.317389 -90.085718) (xy 8.348798 -90.205494)
			(xy 8.372468 -90.327036) (xy 8.388303 -90.449844) (xy 8.396236 -90.573415) (xy 8.396732 -90.635328)
			(xy 8.396236 -90.697241) (xy 8.388303 -90.820812) (xy 8.372468 -90.94362) (xy 8.348798 -91.065162)
			(xy 8.317389 -91.184938) (xy 8.278371 -91.302455) (xy 8.231903 -91.417231) (xy 8.178177 -91.528794)
			(xy 8.117414 -91.636685) (xy 8.049863 -91.740462) (xy 7.975801 -91.839697) (xy 7.895534 -91.933984)
			(xy 7.809391 -92.022934) (xy 7.717726 -92.106182) (xy 7.620915 -92.183385) (xy 7.519357 -92.254228)
			(xy 7.413469 -92.318418) (xy 7.303685 -92.375692) (xy 7.190458 -92.425815) (xy 7.074251 -92.46858)
			(xy 6.955544 -92.503811) (xy 6.834823 -92.531365) (xy 6.712585 -92.551128) (xy 6.589332 -92.563018)
			(xy 6.46557 -92.566987) (xy 6.341808 -92.563018) (xy 6.218555 -92.551128) (xy 6.096317 -92.531365)
			(xy 5.975596 -92.503811) (xy 5.856889 -92.46858) (xy 5.740682 -92.425815) (xy 5.627455 -92.375692)
			(xy 5.517671 -92.318418) (xy 5.411783 -92.254228) (xy 5.310225 -92.183385) (xy 5.213414 -92.106182)
			(xy 5.121749 -92.022934) (xy 5.035606 -91.933984) (xy 4.955339 -91.839697) (xy 4.881277 -91.740462)
			(xy 4.813726 -91.636685) (xy 4.752963 -91.528794) (xy 4.699237 -91.417231) (xy 4.652769 -91.302455)
			(xy 4.613751 -91.184938) (xy 4.582342 -91.065162) (xy 4.558672 -90.94362) (xy 4.542837 -90.820812)
			(xy 4.534904 -90.697241) (xy 0.509016 -90.697241) (xy 0.509016 -95.79991) (xy 102.486719 -95.79991)
			(xy 102.490744 -95.657718) (xy 102.502807 -95.515982) (xy 102.52287 -95.375156) (xy 102.550868 -95.23569)
			(xy 102.586712 -95.098031) (xy 102.630286 -94.962621) (xy 102.681451 -94.829893) (xy 102.740044 -94.700272)
			(xy 102.805875 -94.574174) (xy 102.878736 -94.452002) (xy 102.958391 -94.334148) (xy 103.044587 -94.220989)
			(xy 103.137046 -94.112887) (xy 103.235474 -94.01019) (xy 103.339553 -93.913226) (xy 103.448952 -93.822306)
			(xy 103.56332 -93.73772) (xy 103.682289 -93.65974) (xy 103.80548 -93.588616) (xy 103.932497 -93.524575)
			(xy 104.062934 -93.467823) (xy 104.196373 -93.418541) (xy 104.332386 -93.376887) (xy 104.470538 -93.342995)
			(xy 104.610387 -93.316974) (xy 104.751483 -93.298906) (xy 104.893375 -93.288849) (xy 105.03561 -93.286836)
			(xy 105.17773 -93.292873) (xy 105.319281 -93.306941) (xy 105.45981 -93.328995) (xy 105.598865 -93.358964)
			(xy 105.736003 -93.396752) (xy 105.870783 -93.442238) (xy 106.002774 -93.495276) (xy 106.131553 -93.555697)
			(xy 106.256707 -93.623306) (xy 106.377835 -93.697888) (xy 106.494551 -93.779204) (xy 106.606479 -93.866992)
			(xy 106.713261 -93.960972) (xy 106.814555 -94.060842) (xy 106.910036 -94.166284) (xy 106.9994 -94.276958)
			(xy 107.082358 -94.392511) (xy 107.158647 -94.512572) (xy 107.228021 -94.636757) (xy 107.290258 -94.764668)
			(xy 107.345159 -94.895895) (xy 107.392547 -95.030018) (xy 107.432272 -95.166607) (xy 107.464205 -95.305225)
			(xy 107.488246 -95.445427) (xy 107.504315 -95.586765) (xy 107.512363 -95.728786) (xy 107.512866 -95.79991)
			(xy 107.512363 -95.871034) (xy 107.504315 -96.013055) (xy 107.488246 -96.154393) (xy 107.464205 -96.294595)
			(xy 107.432272 -96.433213) (xy 107.392547 -96.569802) (xy 107.345159 -96.703925) (xy 107.290258 -96.835152)
			(xy 107.228021 -96.963063) (xy 107.158647 -97.087248) (xy 107.082358 -97.207309) (xy 106.9994 -97.322862)
			(xy 106.910036 -97.433536) (xy 106.814555 -97.538978) (xy 106.713261 -97.638848) (xy 106.606479 -97.732828)
			(xy 106.494551 -97.820616) (xy 106.377835 -97.901932) (xy 106.256707 -97.976514) (xy 106.131553 -98.044123)
			(xy 106.002774 -98.104544) (xy 105.870783 -98.157582) (xy 105.736003 -98.203068) (xy 105.598865 -98.240856)
			(xy 105.45981 -98.270825) (xy 105.319281 -98.292879) (xy 105.17773 -98.306947) (xy 105.03561 -98.312984)
			(xy 104.893375 -98.310971) (xy 104.751483 -98.300914) (xy 104.610387 -98.282846) (xy 104.470538 -98.256825)
			(xy 104.332386 -98.222933) (xy 104.196373 -98.181279) (xy 104.062934 -98.131997) (xy 103.932497 -98.075245)
			(xy 103.80548 -98.011204) (xy 103.682289 -97.94008) (xy 103.56332 -97.8621) (xy 103.448952 -97.777514)
			(xy 103.339553 -97.686594) (xy 103.235474 -97.58963) (xy 103.137046 -97.486933) (xy 103.044587 -97.378831)
			(xy 102.958391 -97.265672) (xy 102.878736 -97.147818) (xy 102.805875 -97.025646) (xy 102.740044 -96.899548)
			(xy 102.681451 -96.769927) (xy 102.630286 -96.637199) (xy 102.586712 -96.501789) (xy 102.550868 -96.36413)
			(xy 102.52287 -96.224664) (xy 102.502807 -96.083838) (xy 102.490744 -95.942102) (xy 102.486719 -95.79991)
			(xy 0.509016 -95.79991) (xy 0.509016 -165.180264) (xy 0.508 -165.179248) (xy 0.508 -167.433752) (xy 0.509016 -167.433752)
			(xy 0.509016 -168.699942) (xy 0.509537 -168.755711) (xy 0.517873 -168.866937) (xy 0.534497 -168.977229)
			(xy 0.559316 -169.085971) (xy 0.592193 -169.192554) (xy 0.632942 -169.296382) (xy 0.681337 -169.396874)
			(xy 0.737106 -169.493469) (xy 0.799937 -169.585626) (xy 0.86948 -169.67283) (xy 0.945345 -169.754593)
			(xy 1.027108 -169.830458) (xy 1.114312 -169.900001) (xy 1.206469 -169.962832) (xy 1.303064 -170.018601)
			(xy 1.403556 -170.066996) (xy 1.507384 -170.107745) (xy 1.613967 -170.140622) (xy 1.722709 -170.165441)
			(xy 1.833001 -170.182065) (xy 1.944227 -170.190401) (xy 1.999996 -170.190922) (xy 10.359898 -170.190922)
			(xy 10.43028 -170.191416) (xy 10.570824 -170.199308) (xy 10.710703 -170.215069) (xy 10.849479 -170.238648)
			(xy 10.986714 -170.269971) (xy 11.121978 -170.308939) (xy 11.254843 -170.35543) (xy 11.384893 -170.409299)
			(xy 11.511717 -170.470374) (xy 11.634918 -170.538464) (xy 11.754107 -170.613356) (xy 11.868909 -170.694812)
			(xy 11.978964 -170.782577) (xy 12.083924 -170.876375) (xy 12.18346 -170.97591) (xy 12.277258 -171.08087)
			(xy 12.365023 -171.190924) (xy 12.44648 -171.305726) (xy 12.521372 -171.424915) (xy 12.589462 -171.548115)
			(xy 12.650538 -171.67494) (xy 12.704407 -171.804989) (xy 12.750899 -171.937855) (xy 12.789867 -172.073118)
			(xy 12.821191 -172.210353) (xy 12.84477 -172.349129) (xy 12.860531 -172.489008) (xy 12.868424 -172.629552)
			(xy 12.86891 -172.699934) (xy 12.86891 -207.93329) (xy 12.869375 -207.950019) (xy 12.878 -207.982344)
			(xy 12.894737 -208.011313) (xy 12.906248 -208.02346) (xy 13.074396 -208.190592) (xy 82.854546 -208.190592)
		)
		(stroke
			(width 0)
			(type solid)
		)
		(fill yes)
		(layer "In5.Cu")
		(net "GND")
	)
	(gr_arc
		(start 1.500124 -70.79996)
		(mid 0.439376 -71.239336)
		(end 0 -72.300084)
		(stroke
			(width 1.016)
			(type default)
		)
		(layer "In5.Cu")
	)
	(gr_line
		(start 1.500124 -70.79996)
		(end 6.500114 -70.79996)
		(stroke
			(width 1.016)
			(type default)
		)
		(layer "In5.Cu")
	)
	(gr_line
		(start 1.999996 -170.699938)
		(end 10.359898 -170.699938)
		(stroke
			(width 1.016)
			(type default)
		)
		(layer "In5.Cu")
	)
	(gr_arc
		(start 1.999996 0)
		(mid 0.585785 -0.585785)
		(end 0 -1.999996)
		(stroke
			(width 1.016)
			(type default)
		)
		(layer "In5.Cu")
	)
	(gr_line
		(start 1.999996 0)
		(end 198.000112 0)
		(stroke
			(width 1.016)
			(type default)
		)
		(layer "In5.Cu")
	)
	(gr_arc
		(start 6.500114 -70.79996)
		(mid 7.560682 -70.360658)
		(end 7.999984 -69.30009)
		(stroke
			(width 1.016)
			(type default)
		)
		(layer "In5.Cu")
	)
	(gr_line
		(start 6.500114 -30.80004)
		(end 1.500124 -30.80004)
		(stroke
			(width 1.016)
			(type default)
		)
		(layer "In5.Cu")
	)
	(gr_line
		(start 7.999984 -69.30009)
		(end 7.999984 -32.29991)
		(stroke
			(width 1.016)
			(type default)
		)
		(layer "In5.Cu")
	)
	(gr_arc
		(start 7.999984 -32.29991)
		(mid 7.560682 -31.239342)
		(end 6.500114 -30.80004)
		(stroke
			(width 1.016)
			(type default)
		)
		(layer "In5.Cu")
	)
	(gr_line
		(start 12.359894 -208.197196)
		(end 12.497054 -208.334356)
		(stroke
			(width 1.016)
			(type default)
		)
		(layer "In5.Cu")
	)
	(gr_arc
		(start 12.359894 -172.699934)
		(mid 11.774121 -171.285702)
		(end 10.359898 -170.699938)
		(stroke
			(width 1.016)
			(type default)
		)
		(layer "In5.Cu")
	)
	(gr_line
		(start 12.359894 -172.699934)
		(end 12.359894 -208.197196)
		(stroke
			(width 1.016)
			(type default)
		)
		(layer "In5.Cu")
	)
	(gr_line
		(start 12.497054 -208.334356)
		(end 12.864084 -208.699608)
		(stroke
			(width 1.016)
			(type default)
		)
		(layer "In5.Cu")
	)
	(gr_line
		(start 83.064604 -208.699608)
		(end 12.864084 -208.699608)
		(stroke
			(width 1.016)
			(type default)
		)
		(layer "In5.Cu")
	)
	(gr_line
		(start 83.064604 -208.699608)
		(end 83.54441 -208.222342)
		(stroke
			(width 1.016)
			(type default)
		)
		(layer "In5.Cu")
	)
	(gr_line
		(start 83.54441 -208.222342)
		(end 83.559904 -208.206848)
		(stroke
			(width 1.016)
			(type default)
		)
		(layer "In5.Cu")
	)
	(gr_line
		(start 83.559904 -208.206848)
		(end 83.559904 -201.250042)
		(stroke
			(width 1.016)
			(type default)
		)
		(layer "In5.Cu")
	)
	(gr_line
		(start 85.460078 -208.196942)
		(end 85.464904 -208.201768)
		(stroke
			(width 1.016)
			(type default)
		)
		(layer "In5.Cu")
	)
	(gr_arc
		(start 85.460078 -201.250042)
		(mid 84.509991 -200.299828)
		(end 83.559904 -201.250042)
		(stroke
			(width 1.016)
			(type default)
		)
		(layer "In5.Cu")
	)
	(gr_line
		(start 85.460078 -201.250042)
		(end 85.460078 -208.196942)
		(stroke
			(width 1.016)
			(type default)
		)
		(layer "In5.Cu")
	)
	(gr_line
		(start 85.464904 -208.201768)
		(end 85.965284 -208.699608)
		(stroke
			(width 1.016)
			(type default)
		)
		(layer "In5.Cu")
	)
	(gr_line
		(start 96.165924 -208.699608)
		(end 85.965284 -208.699608)
		(stroke
			(width 1.016)
			(type default)
		)
		(layer "In5.Cu")
	)
	(gr_line
		(start 96.165924 -208.699608)
		(end 96.659954 -208.205578)
		(stroke
			(width 1.016)
			(type default)
		)
		(layer "In5.Cu")
	)
	(gr_line
		(start 96.659954 -208.205578)
		(end 96.659954 -188.250068)
		(stroke
			(width 1.016)
			(type default)
		)
		(layer "In5.Cu")
	)
	(gr_line
		(start 103.359966 -208.19745)
		(end 103.364284 -208.201768)
		(stroke
			(width 1.016)
			(type default)
		)
		(layer "In5.Cu")
	)
	(gr_arc
		(start 103.359966 -188.250068)
		(mid 100.00996 -184.900062)
		(end 96.659954 -188.250068)
		(stroke
			(width 1.016)
			(type default)
		)
		(layer "In5.Cu")
	)
	(gr_line
		(start 103.359966 -188.250068)
		(end 103.359966 -208.19745)
		(stroke
			(width 1.016)
			(type default)
		)
		(layer "In5.Cu")
	)
	(gr_line
		(start 103.364284 -208.201768)
		(end 103.864664 -208.699608)
		(stroke
			(width 1.016)
			(type default)
		)
		(layer "In5.Cu")
	)
	(gr_line
		(start 155.372308 -49.275238)
		(end 155.372308 -50.97526)
		(stroke
			(width 1.7018)
			(type default)
		)
		(layer "In5.Cu")
	)
	(gr_line
		(start 155.372308 -45.465238)
		(end 155.372308 -47.16526)
		(stroke
			(width 1.7018)
			(type default)
		)
		(layer "In5.Cu")
	)
	(gr_line
		(start 158.6992 -45.708062)
		(end 158.6992 -46.978062)
		(stroke
			(width 0.8128)
			(type default)
		)
		(layer "In5.Cu")
	)
	(gr_line
		(start 161.280348 -49.560734)
		(end 161.280348 -50.830734)
		(stroke
			(width 0.8128)
			(type default)
		)
		(layer "In5.Cu")
	)
	(gr_line
		(start 174.065184 -208.699608)
		(end 103.864664 -208.699608)
		(stroke
			(width 1.016)
			(type default)
		)
		(layer "In5.Cu")
	)
	(gr_line
		(start 174.342552 -208.423764)
		(end 174.065184 -208.699608)
		(stroke
			(width 1.016)
			(type default)
		)
		(layer "In5.Cu")
	)
	(gr_line
		(start 174.559976 -208.20634)
		(end 174.342552 -208.423764)
		(stroke
			(width 1.016)
			(type default)
		)
		(layer "In5.Cu")
	)
	(gr_line
		(start 174.559976 -201.250042)
		(end 174.559976 -208.20634)
		(stroke
			(width 1.016)
			(type default)
		)
		(layer "In5.Cu")
	)
	(gr_line
		(start 176.459896 -208.19618)
		(end 176.459896 -201.250042)
		(stroke
			(width 1.016)
			(type default)
		)
		(layer "In5.Cu")
	)
	(gr_arc
		(start 176.459896 -201.250042)
		(mid 175.509936 -200.300082)
		(end 174.559976 -201.250042)
		(stroke
			(width 1.016)
			(type default)
		)
		(layer "In5.Cu")
	)
	(gr_line
		(start 176.465484 -208.201768)
		(end 176.459896 -208.19618)
		(stroke
			(width 1.016)
			(type default)
		)
		(layer "In5.Cu")
	)
	(gr_line
		(start 176.965864 -208.699608)
		(end 176.465484 -208.201768)
		(stroke
			(width 1.016)
			(type default)
		)
		(layer "In5.Cu")
	)
	(gr_line
		(start 187.163964 -208.699608)
		(end 176.965864 -208.699608)
		(stroke
			(width 1.016)
			(type default)
		)
		(layer "In5.Cu")
	)
	(gr_line
		(start 187.62853 -208.237328)
		(end 187.163964 -208.699608)
		(stroke
			(width 1.016)
			(type default)
		)
		(layer "In5.Cu")
	)
	(gr_line
		(start 187.660026 -208.205832)
		(end 187.62853 -208.237328)
		(stroke
			(width 1.016)
			(type default)
		)
		(layer "In5.Cu")
	)
	(gr_line
		(start 187.660026 -172.699934)
		(end 187.660026 -208.205832)
		(stroke
			(width 1.016)
			(type default)
		)
		(layer "In5.Cu")
	)
	(gr_arc
		(start 189.660022 -170.699938)
		(mid 188.245811 -171.285723)
		(end 187.660026 -172.699934)
		(stroke
			(width 1.016)
			(type default)
		)
		(layer "In5.Cu")
	)
	(gr_arc
		(start 196.699886 -72.650096)
		(mid 197.139352 -73.71068)
		(end 198.20001 -74.149966)
		(stroke
			(width 1.016)
			(type default)
		)
		(layer "In5.Cu")
	)
	(gr_line
		(start 196.699886 -33.64992)
		(end 196.699886 -72.650096)
		(stroke
			(width 1.016)
			(type default)
		)
		(layer "In5.Cu")
	)
	(gr_line
		(start 198.000112 -170.699938)
		(end 189.660022 -170.699938)
		(stroke
			(width 1.016)
			(type default)
		)
		(layer "In5.Cu")
	)
	(gr_arc
		(start 198.000112 -170.699938)
		(mid 199.41433 -170.114151)
		(end 200.000108 -168.699942)
		(stroke
			(width 1.016)
			(type default)
		)
		(layer "In5.Cu")
	)
	(gr_line
		(start 198.20001 -74.149966)
		(end 198.499984 -74.149966)
		(stroke
			(width 1.016)
			(type default)
		)
		(layer "In5.Cu")
	)
	(gr_arc
		(start 198.20001 -32.15005)
		(mid 197.139352 -32.589336)
		(end 196.699886 -33.64992)
		(stroke
			(width 1.016)
			(type default)
		)
		(layer "In5.Cu")
	)
	(gr_line
		(start 198.499984 -32.15005)
		(end 198.20001 -32.15005)
		(stroke
			(width 1.016)
			(type default)
		)
		(layer "In5.Cu")
	)
	(gr_arc
		(start 198.499984 -32.15005)
		(mid 199.560751 -31.710681)
		(end 200.000108 -30.649926)
		(stroke
			(width 1.016)
			(type default)
		)
		(layer "In5.Cu")
	)
	(gr_arc
		(start 200.000108 -75.65009)
		(mid 199.560727 -74.589354)
		(end 198.499984 -74.149966)
		(stroke
			(width 1.016)
			(type default)
		)
		(layer "In5.Cu")
	)
	(gr_line
		(start 200.000108 -75.65009)
		(end 200.000108 -168.699942)
		(stroke
			(width 1.016)
			(type default)
		)
		(layer "In5.Cu")
	)
	(gr_arc
		(start 200.000108 -1.999996)
		(mid 199.414322 -0.585784)
		(end 198.000112 0)
		(stroke
			(width 1.016)
			(type default)
		)
		(layer "In5.Cu")
	)
	(gr_line
		(start 200.000108 -1.999996)
		(end 200.000108 -30.649926)
		(stroke
			(width 1.016)
			(type default)
		)
		(layer "In5.Cu")
	)
	(gr_poly
		(pts
			(xy 46.92142 -164.267896) (xy 40.18534 -164.267896) (xy 40.18534 -167.674544) (xy 46.92142 -167.674544)
		)
		(stroke
			(width 0)
			(type solid)
		)
		(fill yes)
		(layer "In6.Cu")
		(net "GND")
	)
	(gr_poly
		(pts
			(xy 165.3159 -140.901674) (xy 158.83636 -140.901674) (xy 158.83636 -143.152114) (xy 165.3159 -143.152114)
		)
		(stroke
			(width 0)
			(type solid)
		)
		(fill yes)
		(layer "In6.Cu")
		(net "GND")
	)
	(gr_poly
		(pts
			(xy 85.51926 -86.813644) (xy 85.51926 -82.564224) (xy 85.45068 -82.495644) (xy 83.48472 -82.495644)
			(xy 83.37804 -82.602324) (xy 83.37804 -86.760304) (xy 83.5279 -86.910164) (xy 85.42274 -86.910164)
		)
		(stroke
			(width 0)
			(type solid)
		)
		(fill yes)
		(layer "In6.Cu")
		(net "GND")
	)
	(gr_poly
		(pts
			(xy 163.689538 -155.73248) (xy 163.689538 -150.539196) (xy 163.605464 -150.455122) (xy 158.317946 -150.455122)
			(xy 158.265368 -150.5077) (xy 158.265368 -155.77439) (xy 158.317946 -155.826968) (xy 163.59505 -155.826968)
		)
		(stroke
			(width 0)
			(type solid)
		)
		(fill yes)
		(layer "In6.Cu")
		(net "GND")
	)
	(gr_poly
		(pts
			(xy 192.51422 -80.314038) (xy 192.51422 -78.634082) (xy 192.37325 -78.493112) (xy 189.38494 -78.493112)
			(xy 189.23254 -78.645512) (xy 189.23254 -80.076802) (xy 189.55512 -80.399382) (xy 192.428876 -80.399382)
		)
		(stroke
			(width 0)
			(type solid)
		)
		(fill yes)
		(layer "In6.Cu")
		(net "P5V_STB_NODE1")
	)
	(gr_poly
		(pts
			(xy 69.728588 -159.29102) (xy 69.728588 -152.533604) (xy 69.629274 -152.43429) (xy 69.144642 -152.43429)
			(xy 65.170558 -152.43429) (xy 65.02273 -152.582118) (xy 65.02273 -159.220916) (xy 65.308226 -159.506412)
			(xy 68.895214 -159.506412) (xy 69.244718 -159.506412) (xy 69.513196 -159.506412)
		)
		(stroke
			(width 0)
			(type solid)
		)
		(fill yes)
		(layer "In6.Cu")
		(net "P5V_STB_NODE1")
	)
	(gr_poly
		(pts
			(xy 142.253716 -160.98266) (xy 142.253716 -158.190438) (xy 142.226538 -158.16326) (xy 138.788394 -158.16326)
			(xy 138.66114 -158.290514)
			(arc
				(start 138.66114 -160.919414)
				(mid 138.698337 -161.009217)
				(end 138.78814 -161.046414)
			)
			(xy 142.189962 -161.046414)
		)
		(stroke
			(width 0)
			(type solid)
		)
		(fill yes)
		(layer "In6.Cu")
		(net "GND")
	)
	(gr_poly
		(pts
			(xy 136.9568 -121.198386) (xy 136.9568 -113.977166) (xy 136.4996 -113.519966) (xy 135.959088 -113.519966)
			(arc
				(start 135.940292 -113.526062)
				(mid 135.823452 -113.544392)
				(end 135.706612 -113.526062)
			)
			(xy 135.687816 -113.519966) (xy 129.286762 -113.519966) (xy 128.90246 -113.904268) (xy 128.90246 -120.913652)
			(xy 129.511044 -121.522236) (xy 136.63295 -121.522236)
		)
		(stroke
			(width 0)
			(type solid)
		)
		(fill yes)
		(layer "In6.Cu")
		(net "GND")
	)
	(gr_poly
		(pts
			(xy 84.73694 -113.94313) (xy 84.73694 -112.518444) (xy 83.82508 -111.606584) (xy 80.44561 -111.606584)
			(arc
				(start 80.41894 -111.619792)
				(mid 80.24876 -111.659859)
				(end 80.07858 -111.619792)
			)
			(xy 80.05191 -111.606584) (xy 74.249788 -111.606584) (xy 73.88225 -111.974122) (xy 68.655692 -111.974122)
			(xy 68.44792 -112.181894) (xy 68.44792 -113.716562) (xy 68.495926 -113.764568) (xy 82.33156 -113.764568)
			(xy 82.501232 -113.93424) (xy 82.653886 -113.93424) (xy 83.12531 -114.40541) (xy 84.27466 -114.40541)
		)
		(stroke
			(width 0)
			(type solid)
		)
		(fill yes)
		(layer "In6.Cu")
		(net "P1V8_NODE1")
	)
	(gr_poly
		(pts
			(arc
				(start 42.237914 -25.098502)
				(mid 41.936162 -25.098502)
				(end 42.237914 -25.098502)
			)
		)
		(stroke
			(width 0)
			(type solid)
		)
		(fill yes)
		(layer "In6.Cu")
		(net "GND")
	)
	(gr_poly
		(pts
			(arc
				(start 43.827954 -26.691082)
				(mid 43.526202 -26.691082)
				(end 43.827954 -26.691082)
			)
		)
		(stroke
			(width 0)
			(type solid)
		)
		(fill yes)
		(layer "In6.Cu")
		(net "GND")
	)
	(gr_poly
		(pts
			(arc
				(start 52.538376 -24.98598)
				(mid 52.236624 -24.98598)
				(end 52.538376 -24.98598)
			)
		)
		(stroke
			(width 0)
			(type solid)
		)
		(fill yes)
		(layer "In6.Cu")
		(net "GND")
	)
	(gr_poly
		(pts
			(arc
				(start 54.654196 -23.812246)
				(mid 54.352444 -23.812246)
				(end 54.654196 -23.812246)
			)
		)
		(stroke
			(width 0)
			(type solid)
		)
		(fill yes)
		(layer "In6.Cu")
		(net "GND")
	)
	(gr_poly
		(pts
			(arc
				(start 55.280814 -26.187146)
				(mid 54.979062 -26.187146)
				(end 55.280814 -26.187146)
			)
		)
		(stroke
			(width 0)
			(type solid)
		)
		(fill yes)
		(layer "In6.Cu")
		(net "GND")
	)
	(gr_poly
		(pts
			(arc
				(start 59.057794 -26.850086)
				(mid 58.756042 -26.850086)
				(end 59.057794 -26.850086)
			)
		)
		(stroke
			(width 0)
			(type solid)
		)
		(fill yes)
		(layer "In6.Cu")
		(net "GND")
	)
	(gr_poly
		(pts
			(arc
				(start 59.890914 -24.608282)
				(mid 59.589162 -24.608282)
				(end 59.890914 -24.608282)
			)
		)
		(stroke
			(width 0)
			(type solid)
		)
		(fill yes)
		(layer "In6.Cu")
		(net "GND")
	)
	(gr_poly
		(pts
			(arc
				(start 60.188094 -23.852886)
				(mid 59.886342 -23.852886)
				(end 60.188094 -23.852886)
			)
		)
		(stroke
			(width 0)
			(type solid)
		)
		(fill yes)
		(layer "In6.Cu")
		(net "GND")
	)
	(gr_poly
		(pts
			(arc
				(start 63.111634 -26.872946)
				(mid 62.809882 -26.872946)
				(end 63.111634 -26.872946)
			)
		)
		(stroke
			(width 0)
			(type solid)
		)
		(fill yes)
		(layer "In6.Cu")
		(net "GND")
	)
	(gr_poly
		(pts
			(arc
				(start 85.583014 -25.207722)
				(mid 85.281262 -25.207722)
				(end 85.583014 -25.207722)
			)
		)
		(stroke
			(width 0)
			(type solid)
		)
		(fill yes)
		(layer "In6.Cu")
		(net "GND")
	)
	(gr_poly
		(pts
			(arc
				(start 95.156274 -24.124412)
				(mid 94.854522 -24.124412)
				(end 95.156274 -24.124412)
			)
		)
		(stroke
			(width 0)
			(type solid)
		)
		(fill yes)
		(layer "In6.Cu")
		(net "GND")
	)
	(gr_poly
		(pts
			(arc
				(start 98.923094 -24.888952)
				(mid 98.621342 -24.888952)
				(end 98.923094 -24.888952)
			)
		)
		(stroke
			(width 0)
			(type solid)
		)
		(fill yes)
		(layer "In6.Cu")
		(net "GND")
	)
	(gr_poly
		(pts
			(arc
				(start 99.514914 -26.454354)
				(mid 99.213162 -26.454354)
				(end 99.514914 -26.454354)
			)
		)
		(stroke
			(width 0)
			(type solid)
		)
		(fill yes)
		(layer "In6.Cu")
		(net "GND")
	)
	(gr_poly
		(pts
			(arc
				(start 37.5412 -61.523626)
				(mid 37.21608 -61.523626)
				(end 37.5412 -61.523626)
			)
		)
		(stroke
			(width 0)
			(type solid)
		)
		(fill yes)
		(layer "In6.Cu")
		(net "GND")
	)
	(gr_poly
		(pts
			(arc
				(start 117.36578 -46.18228)
				(mid 117.431566 -46.176563)
				(end 117.497352 -46.18228)
			)
			(xy 117.508274 -46.184058)
			(arc
				(start 117.990874 -46.184058)
				(mid 118.080677 -46.146861)
				(end 118.117874 -46.057058)
			)
			(arc
				(start 118.117874 -38.945058)
				(mid 118.080677 -38.855255)
				(end 117.990874 -38.818058)
			)
			(arc
				(start 112.910874 -38.818058)
				(mid 112.821071 -38.855255)
				(end 112.783874 -38.945058)
			)
			(arc
				(start 112.783874 -46.057058)
				(mid 112.821071 -46.146861)
				(end 112.910874 -46.184058)
			)
			(xy 113.137442 -46.184058) (xy 114.094768 -46.184058) (xy 117.354858 -46.184058)
		)
		(stroke
			(width 0)
			(type solid)
		)
		(fill yes)
		(layer "In6.Cu")
		(net "GND")
	)
	(gr_poly
		(pts
			(arc
				(start 56.08574 -119.913146)
				(mid 56.175543 -119.875949)
				(end 56.21274 -119.786146)
			)
			(arc
				(start 56.21274 -116.878862)
				(mid 56.175543 -116.789059)
				(end 56.08574 -116.751862)
			)
			(xy 54.675024 -116.751862) (xy 54.66334 -116.763546)
			(arc
				(start 52.45354 -116.763546)
				(mid 52.363737 -116.800743)
				(end 52.32654 -116.890546)
			)
			(xy 52.32654 -117.348254)
			(arc
				(start 52.331366 -117.365272)
				(mid 52.345854 -117.469412)
				(end 52.331366 -117.573552)
			)
			(xy 52.32654 -117.59057)
			(arc
				(start 52.32654 -119.786146)
				(mid 52.363737 -119.875949)
				(end 52.45354 -119.913146)
			)
		)
		(stroke
			(width 0)
			(type solid)
		)
		(fill yes)
		(layer "In6.Cu")
		(net "GND")
	)
	(gr_poly
		(pts
			(arc
				(start 129.249678 -109.84611)
				(mid 129.409444 -109.811047)
				(end 129.56921 -109.84611)
			)
			(xy 129.59461 -109.857794)
			(arc
				(start 131.572 -109.857794)
				(mid 131.661803 -109.820597)
				(end 131.699 -109.730794)
			)
			(arc
				(start 131.699 -106.71048)
				(mid 131.661803 -106.620677)
				(end 131.572 -106.58348)
			)
			(arc
				(start 126.814072 -106.58348)
				(mid 126.724269 -106.620677)
				(end 126.687072 -106.71048)
			)
			(arc
				(start 126.687072 -109.730794)
				(mid 126.724269 -109.820597)
				(end 126.814072 -109.857794)
			)
			(xy 129.224278 -109.857794)
		)
		(stroke
			(width 0)
			(type solid)
		)
		(fill yes)
		(layer "In6.Cu")
		(net "GND")
	)
	(gr_poly
		(pts
			(xy 104.37368 -152.787858)
			(arc
				(start 104.37368 -151.370284)
				(mid 104.338702 -151.282757)
				(end 104.25303 -151.243538)
			)
			(arc
				(start 104.25303 -151.243538)
				(mid 103.90394 -150.960734)
				(end 104.066086 -150.541736)
			)
			(arc
				(start 104.066086 -150.541736)
				(mid 104.180907 -150.355289)
				(end 104.107996 -150.148798)
			)
			(xy 103.86187 -149.902672) (xy 103.085392 -149.902672) (xy 102.73284 -150.25497) (xy 102.73284 -152.684226)
			(xy 102.96906 -152.920446) (xy 104.241092 -152.920446)
		)
		(stroke
			(width 0)
			(type solid)
		)
		(fill yes)
		(layer "In6.Cu")
		(net "P5V_STB_NODE1")
	)
	(gr_poly
		(pts
			(arc
				(start 81.63052 -88.205056)
				(mid 81.720323 -88.167859)
				(end 81.75752 -88.078056)
			)
			(arc
				(start 81.75752 -87.606378)
				(mid 81.691891 -87.43599)
				(end 81.52892 -87.353648)
			)
			(arc
				(start 81.52892 -87.353648)
				(mid 81.21896 -87.130082)
				(end 81.25841 -86.74989)
			)
			(xy 81.286096 -86.71179) (xy 81.278984 -86.618572) (xy 80.933036 -86.272624)
			(arc
				(start 80.918304 -86.264242)
				(mid 80.838286 -86.203036)
				(end 80.77708 -86.123018)
			)
			(xy 80.768698 -86.108286) (xy 80.453992 -85.793834) (xy 80.453992 -85.660484) (xy 79.884524 -85.091016)
			(xy 79.648812 -85.091016) (xy 79.09306 -85.646768) (xy 79.09306 -86.455504) (xy 80.842358 -88.205056)
		)
		(stroke
			(width 0)
			(type solid)
		)
		(fill yes)
		(layer "In6.Cu")
		(net "P3V3_NODE1")
	)
	(gr_poly
		(pts
			(arc
				(start 169.470578 -92.547186)
				(mid 169.533189 -92.53068)
				(end 169.579544 -92.485464)
			)
			(arc
				(start 169.579544 -92.485464)
				(mid 169.90695 -92.299794)
				(end 170.234356 -92.485464)
			)
			(xy 170.251628 -92.514166) (xy 170.30954 -92.547186)
			(arc
				(start 172.11802 -92.547186)
				(mid 172.207823 -92.509989)
				(end 172.24502 -92.420186)
			)
			(arc
				(start 172.24502 -90.177366)
				(mid 172.207823 -90.087563)
				(end 172.11802 -90.050366)
			)
			(arc
				(start 166.6113 -90.050366)
				(mid 166.521497 -90.087563)
				(end 166.4843 -90.177366)
			)
			(arc
				(start 166.4843 -92.420186)
				(mid 166.521497 -92.509989)
				(end 166.6113 -92.547186)
			)
		)
		(stroke
			(width 0)
			(type solid)
		)
		(fill yes)
		(layer "In6.Cu")
		(net "GND")
	)
	(gr_poly
		(pts
			(xy 10.962132 -90.960194) (xy 10.991088 -90.890344) (xy 13.83792 -88.043258) (xy 13.83792 -79.836772)
			(xy 13.159486 -79.158338) (xy 2.878074 -79.158338) (xy 1.840484 -80.195928) (xy 1.840484 -81.774992)
			(xy 10.396718 -81.774992) (xy 10.396718 -81.68112) (xy 10.404679 -81.587586) (xy 10.420543 -81.495064)
			(xy 10.444197 -81.404221) (xy 10.475469 -81.315712) (xy 10.514135 -81.230173) (xy 10.559916 -81.148221)
			(xy 10.612482 -81.070447) (xy 10.671455 -80.997412) (xy 10.736408 -80.92964) (xy 10.806875 -80.867621)
			(xy 10.882348 -80.811802) (xy 10.962283 -80.762584) (xy 11.046104 -80.720322) (xy 11.133207 -80.685322)
			(xy 11.222964 -80.657834) (xy 11.314729 -80.638057) (xy 11.407841 -80.626134) (xy 11.501628 -80.62215)
			(xy 11.595415 -80.626134) (xy 11.688527 -80.638057) (xy 11.780292 -80.657834) (xy 11.870049 -80.685322)
			(xy 11.957152 -80.720322) (xy 12.040973 -80.762584) (xy 12.120908 -80.811802) (xy 12.196381 -80.867621)
			(xy 12.266848 -80.92964) (xy 12.331801 -80.997412) (xy 12.390774 -81.070447) (xy 12.44334 -81.148221)
			(xy 12.489121 -81.230173) (xy 12.527787 -81.315712) (xy 12.559059 -81.404221) (xy 12.582713 -81.495064)
			(xy 12.598577 -81.587586) (xy 12.606538 -81.68112) (xy 12.607036 -81.728056) (xy 12.606538 -81.774992)
			(xy 12.598577 -81.868526) (xy 12.582713 -81.961048) (xy 12.559059 -82.051891) (xy 12.527787 -82.1404)
			(xy 12.489121 -82.225939) (xy 12.44334 -82.307891) (xy 12.390774 -82.385665) (xy 12.331801 -82.4587)
			(xy 12.266848 -82.526472) (xy 12.196381 -82.588491) (xy 12.120908 -82.64431) (xy 12.040973 -82.693528)
			(xy 11.957152 -82.73579) (xy 11.870049 -82.77079) (xy 11.780292 -82.798278) (xy 11.688527 -82.818055)
			(xy 11.595415 -82.829978) (xy 11.501628 -82.833963) (xy 11.407841 -82.829978) (xy 11.314729 -82.818055)
			(xy 11.222964 -82.798278) (xy 11.133207 -82.77079) (xy 11.046104 -82.73579) (xy 10.962283 -82.693528)
			(xy 10.882348 -82.64431) (xy 10.806875 -82.588491) (xy 10.736408 -82.526472) (xy 10.671455 -82.4587)
			(xy 10.612482 -82.385665) (xy 10.559916 -82.307891) (xy 10.514135 -82.225939) (xy 10.475469 -82.1404)
			(xy 10.444197 -82.051891) (xy 10.420543 -81.961048) (xy 10.404679 -81.868526) (xy 10.396718 -81.774992)
			(xy 1.840484 -81.774992) (xy 1.840484 -85.975136) (xy 10.396718 -85.975136) (xy 10.396718 -85.881264)
			(xy 10.404679 -85.78773) (xy 10.420543 -85.695208) (xy 10.444197 -85.604365) (xy 10.475469 -85.515856)
			(xy 10.514135 -85.430317) (xy 10.559916 -85.348365) (xy 10.612482 -85.270591) (xy 10.671455 -85.197556)
			(xy 10.736408 -85.129784) (xy 10.806875 -85.067765) (xy 10.882348 -85.011946) (xy 10.962283 -84.962728)
			(xy 11.046104 -84.920466) (xy 11.133207 -84.885466) (xy 11.222964 -84.857978) (xy 11.314729 -84.838201)
			(xy 11.407841 -84.826278) (xy 11.501628 -84.822294) (xy 11.595415 -84.826278) (xy 11.688527 -84.838201)
			(xy 11.780292 -84.857978) (xy 11.870049 -84.885466) (xy 11.957152 -84.920466) (xy 12.040973 -84.962728)
			(xy 12.120908 -85.011946) (xy 12.196381 -85.067765) (xy 12.266848 -85.129784) (xy 12.331801 -85.197556)
			(xy 12.390774 -85.270591) (xy 12.44334 -85.348365) (xy 12.489121 -85.430317) (xy 12.527787 -85.515856)
			(xy 12.559059 -85.604365) (xy 12.582713 -85.695208) (xy 12.598577 -85.78773) (xy 12.606538 -85.881264)
			(xy 12.607036 -85.9282) (xy 12.606538 -85.975136) (xy 12.598577 -86.06867) (xy 12.582713 -86.161192)
			(xy 12.559059 -86.252035) (xy 12.527787 -86.340544) (xy 12.489121 -86.426083) (xy 12.44334 -86.508035)
			(xy 12.390774 -86.585809) (xy 12.331801 -86.658844) (xy 12.266848 -86.726616) (xy 12.196381 -86.788635)
			(xy 12.120908 -86.844454) (xy 12.040973 -86.893672) (xy 11.957152 -86.935934) (xy 11.870049 -86.970934)
			(xy 11.780292 -86.998422) (xy 11.688527 -87.018199) (xy 11.595415 -87.030122) (xy 11.501628 -87.034107)
			(xy 11.407841 -87.030122) (xy 11.314729 -87.018199) (xy 11.222964 -86.998422) (xy 11.133207 -86.970934)
			(xy 11.046104 -86.935934) (xy 10.962283 -86.893672) (xy 10.882348 -86.844454) (xy 10.806875 -86.788635)
			(xy 10.736408 -86.726616) (xy 10.671455 -86.658844) (xy 10.612482 -86.585809) (xy 10.559916 -86.508035)
			(xy 10.514135 -86.426083) (xy 10.475469 -86.340544) (xy 10.444197 -86.252035) (xy 10.420543 -86.161192)
			(xy 10.404679 -86.06867) (xy 10.396718 -85.975136) (xy 1.840484 -85.975136) (xy 1.840484 -90.697241)
			(xy 4.534904 -90.697241) (xy 4.534904 -90.573415) (xy 4.542837 -90.449844) (xy 4.558672 -90.327036)
			(xy 4.582342 -90.205494) (xy 4.613751 -90.085718) (xy 4.652769 -89.968201) (xy 4.699237 -89.853425)
			(xy 4.752963 -89.741862) (xy 4.813726 -89.633971) (xy 4.881277 -89.530194) (xy 4.955339 -89.430959)
			(xy 5.035606 -89.336672) (xy 5.121749 -89.247722) (xy 5.213414 -89.164474) (xy 5.310225 -89.087271)
			(xy 5.411783 -89.016428) (xy 5.517671 -88.952238) (xy 5.627455 -88.894964) (xy 5.740682 -88.844841)
			(xy 5.856889 -88.802076) (xy 5.975596 -88.766845) (xy 6.096317 -88.739291) (xy 6.218555 -88.719528)
			(xy 6.341808 -88.707638) (xy 6.46557 -88.70367) (xy 6.589332 -88.707638) (xy 6.712585 -88.719528)
			(xy 6.834823 -88.739291) (xy 6.955544 -88.766845) (xy 7.074251 -88.802076) (xy 7.190458 -88.844841)
			(xy 7.303685 -88.894964) (xy 7.413469 -88.952238) (xy 7.519357 -89.016428) (xy 7.620915 -89.087271)
			(xy 7.717726 -89.164474) (xy 7.809391 -89.247722) (xy 7.895534 -89.336672) (xy 7.975801 -89.430959)
			(xy 8.049863 -89.530194) (xy 8.117414 -89.633971) (xy 8.178177 -89.741862) (xy 8.231903 -89.853425)
			(xy 8.278371 -89.968201) (xy 8.317389 -90.085718) (xy 8.348798 -90.205494) (xy 8.372468 -90.327036)
			(xy 8.388303 -90.449844) (xy 8.396236 -90.573415) (xy 8.396732 -90.635328) (xy 8.396236 -90.697241)
			(xy 8.388303 -90.820812) (xy 8.372468 -90.94362) (xy 8.348798 -91.065162) (xy 8.317389 -91.184938)
			(xy 8.278371 -91.302455) (xy 8.231903 -91.417231) (xy 8.178177 -91.528794) (xy 8.117414 -91.636685)
			(xy 8.049863 -91.740462) (xy 7.975801 -91.839697) (xy 7.895534 -91.933984) (xy 7.809391 -92.022934)
			(xy 7.717726 -92.106182) (xy 7.620915 -92.183385) (xy 7.519357 -92.254228) (xy 7.413469 -92.318418)
			(xy 7.303685 -92.375692) (xy 7.190458 -92.425815) (xy 7.074251 -92.46858) (xy 6.955544 -92.503811)
			(xy 6.834823 -92.531365) (xy 6.712585 -92.551128) (xy 6.589332 -92.563018) (xy 6.46557 -92.566987)
			(xy 6.341808 -92.563018) (xy 6.218555 -92.551128) (xy 6.096317 -92.531365) (xy 5.975596 -92.503811)
			(xy 5.856889 -92.46858) (xy 5.740682 -92.425815) (xy 5.627455 -92.375692) (xy 5.517671 -92.318418)
			(xy 5.411783 -92.254228) (xy 5.310225 -92.183385) (xy 5.213414 -92.106182) (xy 5.121749 -92.022934)
			(xy 5.035606 -91.933984) (xy 4.955339 -91.839697) (xy 4.881277 -91.740462) (xy 4.813726 -91.636685)
			(xy 4.752963 -91.528794) (xy 4.699237 -91.417231) (xy 4.652769 -91.302455) (xy 4.613751 -91.184938)
			(xy 4.582342 -91.065162) (xy 4.558672 -90.94362) (xy 4.542837 -90.820812) (xy 4.534904 -90.697241)
			(xy 1.840484 -90.697241) (xy 1.840484 -95.52813) (xy 2.60858 -96.296226) (xy 5.623814 -96.296226)
		)
		(stroke
			(width 0)
			(type solid)
		)
		(fill yes)
		(layer "In6.Cu")
		(net "P12V_DBG")
	)
	(gr_poly
		(pts
			(xy 84.606892 -159.481012) (xy 84.606892 -154.786584) (xy 83.64728 -153.826972) (xy 78.038706 -153.826972)
			(xy 77.89164 -153.974038) (xy 77.89164 -155.60548) (xy 77.641958 -155.855162) (xy 81.02803 -155.855162)
			(xy 81.032101 -155.79954) (xy 81.044227 -155.745103) (xy 81.06415 -155.693012) (xy 81.091446 -155.644377)
			(xy 81.125532 -155.600234) (xy 81.165681 -155.561525) (xy 81.211039 -155.529074) (xy 81.260639 -155.503573)
			(xy 81.313423 -155.485566) (xy 81.368266 -155.475436) (xy 81.424 -155.473399) (xy 81.479437 -155.479499)
			(xy 81.533394 -155.493605) (xy 81.584723 -155.515417) (xy 81.632329 -155.544471) (xy 81.675197 -155.580146)
			(xy 81.712414 -155.621683) (xy 81.743187 -155.668196) (xy 81.766859 -155.718693) (xy 81.782927 -155.7721)
			(xy 81.791047 -155.827276) (xy 81.791556 -155.855162) (xy 81.791047 -155.883048) (xy 81.782927 -155.938224)
			(xy 81.766859 -155.991631) (xy 81.743187 -156.042128) (xy 81.712414 -156.088641) (xy 81.675197 -156.130178)
			(xy 81.632329 -156.165853) (xy 81.584723 -156.194907) (xy 81.533394 -156.216719) (xy 81.479437 -156.230825)
			(xy 81.424 -156.236925) (xy 81.368266 -156.234888) (xy 81.313423 -156.224758) (xy 81.260639 -156.206751)
			(xy 81.211039 -156.18125) (xy 81.165681 -156.148799) (xy 81.125532 -156.11009) (xy 81.091446 -156.065947)
			(xy 81.06415 -156.017312) (xy 81.044227 -155.965221) (xy 81.032101 -155.910784) (xy 81.02803 -155.855162)
			(xy 77.641958 -155.855162) (xy 77.2541 -156.24302) (xy 77.2541 -157.022038) (xy 78.690976 -157.022038)
			(xy 78.695047 -156.966416) (xy 78.707173 -156.911979) (xy 78.727096 -156.859888) (xy 78.754392 -156.811253)
			(xy 78.788478 -156.76711) (xy 78.828627 -156.728401) (xy 78.873985 -156.69595) (xy 78.923585 -156.670449)
			(xy 78.976369 -156.652442) (xy 79.031212 -156.642312) (xy 79.086946 -156.640275) (xy 79.142383 -156.646375)
			(xy 79.19634 -156.660481) (xy 79.247669 -156.682293) (xy 79.295275 -156.711347) (xy 79.338143 -156.747022)
			(xy 79.37536 -156.788559) (xy 79.406133 -156.835072) (xy 79.429805 -156.885569) (xy 79.445873 -156.938976)
			(xy 79.453993 -156.994152) (xy 79.454483 -157.021022) (xy 80.26095 -157.021022) (xy 80.265021 -156.9654)
			(xy 80.277147 -156.910963) (xy 80.29707 -156.858872) (xy 80.324366 -156.810237) (xy 80.358452 -156.766094)
			(xy 80.398601 -156.727385) (xy 80.443959 -156.694934) (xy 80.493559 -156.669433) (xy 80.546343 -156.651426)
			(xy 80.601186 -156.641296) (xy 80.65692 -156.639259) (xy 80.712357 -156.645359) (xy 80.766314 -156.659465)
			(xy 80.817643 -156.681277) (xy 80.865249 -156.710331) (xy 80.908117 -156.746006) (xy 80.945334 -156.787543)
			(xy 80.976107 -156.834056) (xy 80.999779 -156.884553) (xy 81.015847 -156.93796) (xy 81.023967 -156.993136)
			(xy 81.024476 -157.021022) (xy 81.023967 -157.048908) (xy 81.015847 -157.104084) (xy 80.999779 -157.157491)
			(xy 80.976107 -157.207988) (xy 80.945334 -157.254501) (xy 80.908117 -157.296038) (xy 80.865249 -157.331713)
			(xy 80.817643 -157.360767) (xy 80.766314 -157.382579) (xy 80.712357 -157.396685) (xy 80.65692 -157.402785)
			(xy 80.601186 -157.400748) (xy 80.546343 -157.390618) (xy 80.493559 -157.372611) (xy 80.443959 -157.34711)
			(xy 80.398601 -157.314659) (xy 80.358452 -157.27595) (xy 80.324366 -157.231807) (xy 80.29707 -157.183172)
			(xy 80.277147 -157.131081) (xy 80.265021 -157.076644) (xy 80.26095 -157.021022) (xy 79.454483 -157.021022)
			(xy 79.454502 -157.022038) (xy 79.453993 -157.049924) (xy 79.445873 -157.1051) (xy 79.429805 -157.158507)
			(xy 79.406133 -157.209004) (xy 79.37536 -157.255517) (xy 79.338143 -157.297054) (xy 79.295275 -157.332729)
			(xy 79.247669 -157.361783) (xy 79.19634 -157.383595) (xy 79.142383 -157.397701) (xy 79.086946 -157.403801)
			(xy 79.031212 -157.401764) (xy 78.976369 -157.391634) (xy 78.923585 -157.373627) (xy 78.873985 -157.348126)
			(xy 78.828627 -157.315675) (xy 78.788478 -157.276966) (xy 78.754392 -157.232823) (xy 78.727096 -157.184188)
			(xy 78.707173 -157.132097) (xy 78.695047 -157.07766) (xy 78.690976 -157.022038) (xy 77.2541 -157.022038)
			(xy 77.2541 -157.475936) (xy 76.759816 -157.97022) (xy 81.747866 -157.97022) (xy 81.751937 -157.914598)
			(xy 81.764063 -157.860161) (xy 81.783986 -157.80807) (xy 81.811282 -157.759435) (xy 81.845368 -157.715292)
			(xy 81.885517 -157.676583) (xy 81.930875 -157.644132) (xy 81.980475 -157.618631) (xy 82.033259 -157.600624)
			(xy 82.088102 -157.590494) (xy 82.143836 -157.588457) (xy 82.199273 -157.594557) (xy 82.25323 -157.608663)
			(xy 82.304559 -157.630475) (xy 82.352165 -157.659529) (xy 82.395033 -157.695204) (xy 82.43225 -157.736741)
			(xy 82.463023 -157.783254) (xy 82.486695 -157.833751) (xy 82.502763 -157.887158) (xy 82.510883 -157.942334)
			(xy 82.511392 -157.97022) (xy 82.510883 -157.998106) (xy 82.502763 -158.053282) (xy 82.486695 -158.106689)
			(xy 82.463023 -158.157186) (xy 82.43225 -158.203699) (xy 82.395033 -158.245236) (xy 82.352165 -158.280911)
			(xy 82.304559 -158.309965) (xy 82.25323 -158.331777) (xy 82.199273 -158.345883) (xy 82.143836 -158.351983)
			(xy 82.088102 -158.349946) (xy 82.033259 -158.339816) (xy 81.980475 -158.321809) (xy 81.930875 -158.296308)
			(xy 81.885517 -158.263857) (xy 81.845368 -158.225148) (xy 81.811282 -158.181005) (xy 81.783986 -158.13237)
			(xy 81.764063 -158.080279) (xy 81.751937 -158.025842) (xy 81.747866 -157.97022) (xy 76.759816 -157.97022)
			(xy 76.675488 -158.054548) (xy 75.88758 -158.054548) (xy 75.60564 -158.336488) (xy 75.60564 -158.463234)
			(xy 78.038196 -158.463234) (xy 78.042267 -158.407612) (xy 78.054393 -158.353175) (xy 78.074316 -158.301084)
			(xy 78.101612 -158.252449) (xy 78.135698 -158.208306) (xy 78.175847 -158.169597) (xy 78.221205 -158.137146)
			(xy 78.270805 -158.111645) (xy 78.323589 -158.093638) (xy 78.378432 -158.083508) (xy 78.434166 -158.081471)
			(xy 78.489603 -158.087571) (xy 78.54356 -158.101677) (xy 78.594889 -158.123489) (xy 78.642495 -158.152543)
			(xy 78.685363 -158.188218) (xy 78.72258 -158.229755) (xy 78.753353 -158.276268) (xy 78.777025 -158.326765)
			(xy 78.790802 -158.372556) (xy 83.211922 -158.372556) (xy 83.215993 -158.316934) (xy 83.228119 -158.262497)
			(xy 83.248042 -158.210406) (xy 83.275338 -158.161771) (xy 83.309424 -158.117628) (xy 83.349573 -158.078919)
			(xy 83.394931 -158.046468) (xy 83.444531 -158.020967) (xy 83.497315 -158.00296) (xy 83.552158 -157.99283)
			(xy 83.607892 -157.990793) (xy 83.663329 -157.996893) (xy 83.717286 -158.010999) (xy 83.768615 -158.032811)
			(xy 83.816221 -158.061865) (xy 83.859089 -158.09754) (xy 83.896306 -158.139077) (xy 83.927079 -158.18559)
			(xy 83.950751 -158.236087) (xy 83.966819 -158.289494) (xy 83.974939 -158.34467) (xy 83.975448 -158.372556)
			(xy 83.974939 -158.400442) (xy 83.966819 -158.455618) (xy 83.950751 -158.509025) (xy 83.927079 -158.559522)
			(xy 83.896306 -158.606035) (xy 83.859089 -158.647572) (xy 83.816221 -158.683247) (xy 83.768615 -158.712301)
			(xy 83.717286 -158.734113) (xy 83.663329 -158.748219) (xy 83.607892 -158.754319) (xy 83.552158 -158.752282)
			(xy 83.497315 -158.742152) (xy 83.444531 -158.724145) (xy 83.394931 -158.698644) (xy 83.349573 -158.666193)
			(xy 83.309424 -158.627484) (xy 83.275338 -158.583341) (xy 83.248042 -158.534706) (xy 83.228119 -158.482615)
			(xy 83.215993 -158.428178) (xy 83.211922 -158.372556) (xy 78.790802 -158.372556) (xy 78.793093 -158.380172)
			(xy 78.801213 -158.435348) (xy 78.801722 -158.463234) (xy 78.801213 -158.49112) (xy 78.793093 -158.546296)
			(xy 78.777025 -158.599703) (xy 78.753353 -158.6502) (xy 78.72258 -158.696713) (xy 78.685363 -158.73825)
			(xy 78.642495 -158.773925) (xy 78.594889 -158.802979) (xy 78.54356 -158.824791) (xy 78.489603 -158.838897)
			(xy 78.434166 -158.844997) (xy 78.378432 -158.84296) (xy 78.323589 -158.83283) (xy 78.270805 -158.814823)
			(xy 78.221205 -158.789322) (xy 78.175847 -158.756871) (xy 78.135698 -158.718162) (xy 78.101612 -158.674019)
			(xy 78.074316 -158.625384) (xy 78.054393 -158.573293) (xy 78.042267 -158.518856) (xy 78.038196 -158.463234)
			(xy 75.60564 -158.463234) (xy 75.60564 -159.389318) (xy 75.828144 -159.611822) (xy 84.476336 -159.611822)
		)
		(stroke
			(width 0)
			(type solid)
		)
		(fill yes)
		(layer "In6.Cu")
		(net "GND")
	)
	(gr_poly
		(pts
			(xy 16.861028 -120.031002) (xy 27.808936 -120.031002) (xy 28.216352 -119.62384) (xy 29.049726 -119.62384)
			(xy 29.537914 -119.135652) (xy 31.53029 -119.135652) (xy 31.549273 -119.150339) (xy 31.591553 -119.173041)
			(xy 31.637344 -119.187397) (xy 31.685018 -119.192897) (xy 31.732875 -119.189344) (xy 31.779214 -119.176865)
			(xy 31.822384 -119.155905) (xy 31.841948 -119.142002) (xy 31.856054 -119.131742) (xy 31.885817 -119.113548)
			(xy 31.901384 -119.10568) (xy 31.914897 -119.098539) (xy 31.938327 -119.078929) (xy 31.956417 -119.054307)
			(xy 31.968127 -119.026087) (xy 31.972784 -118.99589) (xy 31.970121 -118.965453) (xy 31.960291 -118.936524)
			(xy 31.943859 -118.910766) (xy 31.921768 -118.889659) (xy 31.90875 -118.881652) (xy 31.885364 -118.867575)
			(xy 31.842503 -118.833776) (xy 31.804897 -118.794213) (xy 31.773312 -118.749696) (xy 31.748392 -118.701132)
			(xy 31.730647 -118.649512) (xy 31.720439 -118.595891) (xy 31.717976 -118.541363) (xy 31.723308 -118.48704)
			(xy 31.736327 -118.434031) (xy 31.756767 -118.383418) (xy 31.78421 -118.336234) (xy 31.818096 -118.293442)
			(xy 31.857734 -118.255916) (xy 31.902316 -118.224421) (xy 31.95093 -118.1996) (xy 32.002585 -118.18196)
			(xy 32.056227 -118.17186) (xy 32.11076 -118.169507) (xy 32.165073 -118.17495) (xy 32.218055 -118.188075)
			(xy 32.268626 -118.208617) (xy 32.315755 -118.236156) (xy 32.358478 -118.270129) (xy 32.395924 -118.309843)
			(xy 32.427328 -118.354488) (xy 32.452051 -118.403153) (xy 32.469587 -118.454843) (xy 32.479578 -118.508505)
			(xy 32.48182 -118.563043) (xy 32.476268 -118.617344) (xy 32.463035 -118.6703) (xy 32.44239 -118.72083)
			(xy 32.414757 -118.767902) (xy 32.380697 -118.810557) (xy 32.361124 -118.829582) (xy 32.345334 -118.845069)
			(xy 32.318831 -118.880472) (xy 32.298862 -118.919931) (xy 32.28603 -118.962253) (xy 32.280725 -119.006158)
			(xy 32.283106 -119.050319) (xy 32.293101 -119.093399) (xy 32.310407 -119.134096) (xy 32.334503 -119.17118)
			(xy 32.349186 -119.187722) (xy 32.368151 -119.208838) (xy 32.400262 -119.255636) (xy 32.425083 -119.306676)
			(xy 32.442065 -119.360831) (xy 32.450833 -119.416904) (xy 32.451548 -119.445278) (xy 32.452177 -119.467354)
			(xy 32.460117 -119.510795) (xy 32.475449 -119.552209) (xy 32.497709 -119.590348) (xy 32.526229 -119.624064)
			(xy 32.56015 -119.652341) (xy 32.598448 -119.674327) (xy 32.639971 -119.68936) (xy 32.683468 -119.696988)
			(xy 32.705548 -119.6975) (xy 33.66008 -119.6975) (xy 34.051494 -119.306086) (xy 34.062162 -119.219472)
			(xy 34.039556 -119.181626) (xy 34.025335 -119.157009) (xy 34.003548 -119.104502) (xy 33.989797 -119.049342)
			(xy 33.984387 -118.992752) (xy 33.987436 -118.935985) (xy 33.998879 -118.8803) (xy 34.018461 -118.826931)
			(xy 34.045749 -118.77706) (xy 34.080137 -118.731793) (xy 34.120864 -118.692131) (xy 34.167028 -118.658955)
			(xy 34.217604 -118.632999) (xy 34.271474 -118.614838) (xy 34.327442 -118.604876) (xy 34.384269 -118.603331)
			(xy 34.440696 -118.61024) (xy 34.495472 -118.625449) (xy 34.521648 -118.636542) (xy 34.54654 -118.647464)
			(xy 43.068748 -118.647464) (xy 43.104562 -118.683278) (xy 43.209464 -118.683278) (xy 43.25747 -118.635526)
			(xy 43.265344 -118.622572) (xy 43.281119 -118.597956) (xy 43.318953 -118.553387) (xy 43.363138 -118.515104)
			(xy 43.41264 -118.484001) (xy 43.466304 -118.460805) (xy 43.494452 -118.4529) (xy 43.527726 -118.444264)
			(xy 44.43984 -117.532404) (xy 45.777658 -117.532404) (xy 47.66564 -115.644168) (xy 47.66564 -112.107472)
			(xy 47.665094 -112.090824) (xy 47.656472 -112.058664) (xy 47.639823 -112.02983) (xy 47.61628 -112.006285)
			(xy 47.587447 -111.989633) (xy 47.555288 -111.981008) (xy 47.53864 -111.980472) (xy 46.081188 -111.980472)
			(xy 46.064539 -111.981017) (xy 46.032377 -111.989636) (xy 46.00354 -112.006284) (xy 45.979994 -112.029828)
			(xy 45.963342 -112.058662) (xy 45.954719 -112.090823) (xy 45.954188 -112.107472) (xy 45.954188 -114.125248)
			(xy 45.57268 -114.506756) (xy 44.589192 -114.506756) (xy 43.692572 -115.403376) (xy 43.43654 -115.403376)
			(xy 43.41876 -115.421156) (xy 30.606746 -115.421156) (xy 30.58393 -115.421672) (xy 30.539032 -115.429829)
			(xy 30.496311 -115.445871) (xy 30.457142 -115.469283) (xy 30.422781 -115.499312) (xy 30.394335 -115.534993)
			(xy 30.372716 -115.57518) (xy 30.358619 -115.618581) (xy 30.355032 -115.64112) (xy 30.350893 -115.668216)
			(xy 30.335854 -115.720926) (xy 30.313425 -115.77094) (xy 30.284067 -115.817228) (xy 30.248384 -115.858836)
			(xy 30.207113 -115.894907) (xy 30.161103 -115.924699) (xy 30.111301 -115.947597) (xy 30.058735 -115.963129)
			(xy 30.004487 -115.970976) (xy 29.949673 -115.970976) (xy 29.895425 -115.963129) (xy 29.842859 -115.947597)
			(xy 29.793057 -115.924699) (xy 29.747047 -115.894907) (xy 29.705776 -115.858836) (xy 29.670093 -115.817228)
			(xy 29.640735 -115.77094) (xy 29.618306 -115.720926) (xy 29.603267 -115.668216) (xy 29.599128 -115.64112)
			(xy 29.59559 -115.618571) (xy 29.58149 -115.575165) (xy 29.559866 -115.534973) (xy 29.531412 -115.499289)
			(xy 29.497045 -115.469259) (xy 29.457867 -115.445848) (xy 29.415139 -115.429809) (xy 29.370234 -115.421658)
			(xy 29.347414 -115.421156) (xy 12.015216 -115.421156) (xy 11.36142 -116.074952) (xy 11.36142 -116.867499)
			(xy 30.372467 -116.867499) (xy 30.374793 -116.811363) (xy 30.385326 -116.756176) (xy 30.40384 -116.70313)
			(xy 30.429934 -116.653374) (xy 30.463043 -116.607982) (xy 30.502451 -116.567938) (xy 30.547307 -116.534106)
			(xy 30.596639 -116.507219) (xy 30.649382 -116.487859) (xy 30.704393 -116.476443) (xy 30.760484 -116.473219)
			(xy 30.816442 -116.478257) (xy 30.871055 -116.491448) (xy 30.923143 -116.512506) (xy 30.947614 -116.52631)
			(xy 30.967809 -116.537602) (xy 31.011272 -116.553456) (xy 31.056887 -116.56118) (xy 31.103147 -116.56052)
			(xy 31.148523 -116.551497) (xy 31.191516 -116.53441) (xy 31.230706 -116.509822) (xy 31.248096 -116.49456)
			(xy 31.26942 -116.475705) (xy 31.316603 -116.443869) (xy 31.367993 -116.419396) (xy 31.422448 -116.402831)
			(xy 31.47876 -116.394539) (xy 31.535679 -116.394706) (xy 31.591941 -116.403328) (xy 31.646298 -116.420214)
			(xy 31.697543 -116.444988) (xy 31.744538 -116.4771) (xy 31.765748 -116.496084) (xy 31.783436 -116.511807)
			(xy 31.823472 -116.537033) (xy 31.867486 -116.55441) (xy 31.913957 -116.563335) (xy 31.961277 -116.5635)
			(xy 32.00781 -116.554899) (xy 32.051944 -116.537829) (xy 32.072326 -116.525802) (xy 32.095868 -116.511861)
			(xy 32.146016 -116.489993) (xy 32.198775 -116.475516) (xy 32.253061 -116.468725) (xy 32.30776 -116.469761)
			(xy 32.36175 -116.478601) (xy 32.413923 -116.495066) (xy 32.463208 -116.518816) (xy 32.508594 -116.549364)
			(xy 32.549149 -116.586084) (xy 32.584042 -116.628222) (xy 32.612555 -116.674913) (xy 32.613964 -116.678202)
			(xy 37.85692 -116.678202) (xy 37.860991 -116.62258) (xy 37.873117 -116.568143) (xy 37.89304 -116.516052)
			(xy 37.920336 -116.467417) (xy 37.954422 -116.423274) (xy 37.994571 -116.384565) (xy 38.039929 -116.352114)
			(xy 38.089529 -116.326613) (xy 38.142313 -116.308606) (xy 38.197156 -116.298476) (xy 38.25289 -116.296439)
			(xy 38.308327 -116.302539) (xy 38.362284 -116.316645) (xy 38.413613 -116.338457) (xy 38.461219 -116.367511)
			(xy 38.504087 -116.403186) (xy 38.541304 -116.444723) (xy 38.572077 -116.491236) (xy 38.595749 -116.541733)
			(xy 38.611817 -116.59514) (xy 38.619937 -116.650316) (xy 38.620446 -116.678202) (xy 38.619937 -116.706088)
			(xy 38.611817 -116.761264) (xy 38.595749 -116.814671) (xy 38.572077 -116.865168) (xy 38.541304 -116.911681)
			(xy 38.504087 -116.953218) (xy 38.461219 -116.988893) (xy 38.413613 -117.017947) (xy 38.362284 -117.039759)
			(xy 38.308327 -117.053865) (xy 38.25289 -117.059965) (xy 38.197156 -117.057928) (xy 38.142313 -117.047798)
			(xy 38.089529 -117.029791) (xy 38.039929 -117.00429) (xy 37.994571 -116.971839) (xy 37.954422 -116.93313)
			(xy 37.920336 -116.888987) (xy 37.89304 -116.840352) (xy 37.873117 -116.788261) (xy 37.860991 -116.733824)
			(xy 37.85692 -116.678202) (xy 32.613964 -116.678202) (xy 32.634105 -116.725199) (xy 32.648248 -116.778049)
			(xy 32.654695 -116.832377) (xy 32.653313 -116.887068) (xy 32.64413 -116.941001) (xy 32.627336 -116.993069)
			(xy 32.603274 -117.042202) (xy 32.572439 -117.087394) (xy 32.535463 -117.127716) (xy 32.493105 -117.162341)
			(xy 32.446234 -117.190558) (xy 32.395813 -117.211788) (xy 32.342875 -117.225597) (xy 32.288507 -117.231699)
			(xy 32.233825 -117.229971) (xy 32.179952 -117.220447) (xy 32.127991 -117.203323) (xy 32.079011 -117.178951)
			(xy 32.034016 -117.14783) (xy 32.013652 -117.12956) (xy 31.995966 -117.113835) (xy 31.955929 -117.088613)
			(xy 31.911914 -117.071241) (xy 31.865443 -117.062317) (xy 31.818124 -117.062152) (xy 31.771592 -117.070751)
			(xy 31.727457 -117.087817) (xy 31.707074 -117.099842) (xy 31.681617 -117.11497) (xy 31.627058 -117.137991)
			(xy 31.569598 -117.152308) (xy 31.510616 -117.157577) (xy 31.451528 -117.153672) (xy 31.393753 -117.140687)
			(xy 31.338676 -117.118933) (xy 31.312866 -117.104414) (xy 31.292683 -117.093099) (xy 31.249216 -117.077246)
			(xy 31.203598 -117.069523) (xy 31.157336 -117.070186) (xy 31.111958 -117.079213) (xy 31.068963 -117.096306)
			(xy 31.029774 -117.120899) (xy 31.012384 -117.136164) (xy 30.99135 -117.154791) (xy 30.944846 -117.186319)
			(xy 30.894221 -117.210685) (xy 30.84057 -117.227363) (xy 30.785053 -117.235991) (xy 30.728871 -117.236383)
			(xy 30.673238 -117.228532) (xy 30.619359 -117.212605) (xy 30.568399 -117.188949) (xy 30.521459 -117.158074)
			(xy 30.479555 -117.120648) (xy 30.443594 -117.077482) (xy 30.414352 -117.029507) (xy 30.392463 -116.977763)
			(xy 30.3784 -116.923368) (xy 30.372467 -116.867499) (xy 11.36142 -116.867499) (xy 11.36142 -118.167888)
			(xy 15.159009 -118.167888) (xy 15.166229 -118.112696) (xy 15.181391 -118.059139) (xy 15.204174 -118.008353)
			(xy 15.234094 -117.961416) (xy 15.270516 -117.919325) (xy 15.312667 -117.882971) (xy 15.359652 -117.853128)
			(xy 15.410475 -117.830428) (xy 15.464057 -117.815354) (xy 15.51926 -117.808224) (xy 15.574914 -117.809191)
			(xy 15.629837 -117.818233) (xy 15.682863 -117.835159) (xy 15.732867 -117.85961) (xy 15.778788 -117.891067)
			(xy 15.799562 -117.909594) (xy 15.816336 -117.924366) (xy 15.853973 -117.948466) (xy 15.895242 -117.965617)
			(xy 15.938874 -117.975293) (xy 15.983525 -117.977195) (xy 16.027821 -117.971265) (xy 16.070399 -117.957686)
			(xy 16.090392 -117.947694) (xy 16.115908 -117.934752) (xy 16.169914 -117.915865) (xy 16.226134 -117.905254)
			(xy 16.283308 -117.903155) (xy 16.340155 -117.909616) (xy 16.3954 -117.924492) (xy 16.447805 -117.947449)
			(xy 16.496195 -117.977974) (xy 16.539485 -118.015381) (xy 16.576705 -118.058832) (xy 16.592296 -118.082822)
			(xy 16.601398 -118.096288) (xy 16.625047 -118.118563) (xy 16.653554 -118.134145) (xy 16.685072 -118.142022)
			(xy 16.717558 -118.141684) (xy 16.748905 -118.133154) (xy 16.763238 -118.125494) (xy 16.78763 -118.111951)
			(xy 16.839513 -118.091437) (xy 16.893831 -118.078696) (xy 16.949425 -118.074001) (xy 17.00511 -118.077451)
			(xy 17.059699 -118.088973) (xy 17.112028 -118.108321) (xy 17.160982 -118.135083) (xy 17.205518 -118.168688)
			(xy 17.244686 -118.20842) (xy 17.27765 -118.253432) (xy 17.303709 -118.302764) (xy 17.322306 -118.355365)
			(xy 17.333046 -118.410113) (xy 17.335699 -118.465842) (xy 17.330209 -118.521363) (xy 17.316692 -118.575493)
			(xy 17.295438 -118.627077) (xy 17.266898 -118.675017) (xy 17.231683 -118.71829) (xy 17.190541 -118.755974)
			(xy 17.14435 -118.787265) (xy 17.094095 -118.811497) (xy 17.040848 -118.828153) (xy 16.985742 -118.836877)
			(xy 16.929954 -118.837484) (xy 16.874672 -118.829962) (xy 16.821074 -118.814469) (xy 16.770304 -118.791337)
			(xy 16.723443 -118.761058) (xy 16.68149 -118.724279) (xy 16.645341 -118.681783) (xy 16.630142 -118.658386)
			(xy 16.621102 -118.644875) (xy 16.59744 -118.622597) (xy 16.568918 -118.607018) (xy 16.537387 -118.599149)
			(xy 16.504889 -118.599498) (xy 16.473534 -118.608045) (xy 16.4592 -118.615714) (xy 16.435665 -118.628779)
			(xy 16.385699 -118.648811) (xy 16.333415 -118.661625) (xy 16.27985 -118.666966) (xy 16.226065 -118.66473)
			(xy 16.173128 -118.654959) (xy 16.122089 -118.637848) (xy 16.073959 -118.613737) (xy 16.029694 -118.583104)
			(xy 16.00962 -118.565168) (xy 15.992854 -118.550385) (xy 15.955217 -118.526282) (xy 15.913946 -118.509128)
			(xy 15.870312 -118.499453) (xy 15.825659 -118.497553) (xy 15.781361 -118.503487) (xy 15.738783 -118.517073)
			(xy 15.71879 -118.527068) (xy 15.693948 -118.539625) (xy 15.64148 -118.558211) (xy 15.58687 -118.568977)
			(xy 15.531274 -118.571695) (xy 15.475873 -118.566305) (xy 15.421844 -118.552924) (xy 15.370332 -118.531834)
			(xy 15.32243 -118.503484) (xy 15.279157 -118.468475) (xy 15.241428 -118.42755) (xy 15.210047 -118.381578)
			(xy 15.185677 -118.331534) (xy 15.168838 -118.27848) (xy 15.159885 -118.223543) (xy 15.159009 -118.167888)
			(xy 11.36142 -118.167888) (xy 11.36142 -120.638316) (xy 11.64971 -120.926606) (xy 15.965424 -120.926606)
		)
		(stroke
			(width 0)
			(type solid)
		)
		(fill yes)
		(layer "In6.Cu")
		(net "P12V_AUX")
	)
	(gr_poly
		(pts
			(xy 89.59723 -131.200144) (xy 89.621916 -131.197314) (xy 89.671604 -131.197314) (xy 89.69629 -131.200144)
			(xy 89.704672 -131.20116) (xy 90.207338 -131.20116) (xy 90.217244 -131.191) (xy 94.87789 -131.191)
			(xy 95.998538 -130.070352) (xy 96.014678 -130.053454) (xy 96.041111 -130.014927) (xy 96.060057 -129.972217)
			(xy 96.070876 -129.926763) (xy 96.073205 -129.880098) (xy 96.066964 -129.833794) (xy 96.052364 -129.78941)
			(xy 96.029897 -129.748443) (xy 96.015556 -129.729992) (xy 95.998194 -129.707948) (xy 95.96945 -129.659758)
			(xy 95.948076 -129.607878) (xy 95.934532 -129.553425) (xy 95.929112 -129.497577) (xy 95.931931 -129.441536)
			(xy 95.94293 -129.386513) (xy 95.961871 -129.333696) (xy 95.988345 -129.284222) (xy 96.021781 -129.239161)
			(xy 96.061457 -129.199484) (xy 96.106518 -129.166048) (xy 96.155991 -129.139573) (xy 96.208809 -129.120632)
			(xy 96.263831 -129.109632) (xy 96.319872 -129.106812) (xy 96.375721 -129.112231) (xy 96.430173 -129.125774)
			(xy 96.482054 -129.147148) (xy 96.530244 -129.175891) (xy 96.552258 -129.19329) (xy 96.57068 -129.207668)
			(xy 96.611651 -129.230132) (xy 96.656039 -129.244727) (xy 96.702346 -129.250961) (xy 96.749013 -129.248623)
			(xy 96.794466 -129.237792) (xy 96.837172 -129.218834) (xy 96.875693 -129.192387) (xy 96.892618 -129.176272)
			(xy 100.530152 -125.538484) (xy 100.530152 -121.95302) (xy 98.93554 -120.358154) (xy 96.273874 -120.358154)
			(xy 96.257011 -120.358671) (xy 96.224465 -120.367512) (xy 96.195385 -120.384593) (xy 96.171814 -120.408713)
			(xy 96.16313 -120.423178) (xy 96.149547 -120.446514) (xy 96.116816 -120.489455) (xy 96.078357 -120.527353)
			(xy 96.034939 -120.55945) (xy 95.98743 -120.585105) (xy 95.936777 -120.603805) (xy 95.883995 -120.615177)
			(xy 95.830136 -120.618993) (xy 95.776277 -120.615177) (xy 95.723495 -120.603805) (xy 95.672842 -120.585105)
			(xy 95.625333 -120.55945) (xy 95.581915 -120.527353) (xy 95.543456 -120.489455) (xy 95.510725 -120.446514)
			(xy 95.497142 -120.423178) (xy 95.480124 -120.392952) (xy 95.420942 -120.358154) (xy 94.046802 -120.358154)
			(xy 94.0292 -120.358671) (xy 93.995317 -120.368211) (xy 93.965346 -120.386673) (xy 93.953076 -120.399302)
			(xy 93.933258 -120.420144) (xy 93.888469 -120.456219) (xy 93.838772 -120.485162) (xy 93.785293 -120.506317)
			(xy 93.729246 -120.519205) (xy 93.671898 -120.523534) (xy 93.61455 -120.519205) (xy 93.558503 -120.506317)
			(xy 93.505024 -120.485162) (xy 93.455327 -120.456219) (xy 93.410538 -120.420144) (xy 93.39072 -120.399302)
			(xy 93.378396 -120.386743) (xy 93.348429 -120.368326) (xy 93.314581 -120.358758) (xy 93.296994 -120.358154)
			(xy 88.736424 -120.358154) (xy 88.00084 -121.093738) (xy 88.00084 -121.688352) (xy 88.073484 -121.76125)
			(xy 88.073484 -122.320266) (xy 93.872309 -122.320266) (xy 93.876805 -122.264976) (xy 93.889261 -122.210919)
			(xy 93.909416 -122.159237) (xy 93.936843 -122.111018) (xy 93.970964 -122.067281) (xy 94.01106 -122.028946)
			(xy 94.056286 -121.996823) (xy 94.105687 -121.971588) (xy 94.158222 -121.953775) (xy 94.212783 -121.943758)
			(xy 94.26822 -121.941749) (xy 94.323363 -121.94779) (xy 94.350332 -121.95429) (xy 94.372108 -121.959463)
			(xy 94.416724 -121.962972) (xy 94.461266 -121.958614) (xy 94.504356 -121.946523) (xy 94.544663 -121.927074)
			(xy 94.580941 -121.900867) (xy 94.61207 -121.868712) (xy 94.637087 -121.831603) (xy 94.655219 -121.790686)
			(xy 94.665905 -121.747227) (xy 94.667832 -121.724928) (xy 94.670149 -121.69687) (xy 94.682008 -121.641835)
			(xy 94.701827 -121.58914) (xy 94.729175 -121.539931) (xy 94.763459 -121.495275) (xy 94.803933 -121.456143)
			(xy 94.84972 -121.423385) (xy 94.899824 -121.397712) (xy 94.953157 -121.379682) (xy 95.00856 -121.369686)
			(xy 95.064832 -121.367942) (xy 95.120748 -121.374487) (xy 95.175095 -121.389179) (xy 95.226693 -121.411699)
			(xy 95.274421 -121.441559) (xy 95.317241 -121.478108) (xy 95.354225 -121.520555) (xy 95.384569 -121.567976)
			(xy 95.407613 -121.619342) (xy 95.422858 -121.673537) (xy 95.429972 -121.729384) (xy 95.428801 -121.78567)
			(xy 95.419369 -121.841172) (xy 95.401883 -121.894686) (xy 95.376722 -121.945049) (xy 95.344431 -121.991166)
			(xy 95.325438 -122.011948) (xy 95.314698 -122.023896) (xy 95.299126 -122.051988) (xy 95.291063 -122.083079)
			(xy 95.291022 -122.115198) (xy 95.299005 -122.14631) (xy 95.314506 -122.174441) (xy 95.325184 -122.186446)
			(xy 95.343707 -122.206733) (xy 95.375264 -122.251699) (xy 95.400046 -122.300726) (xy 95.41754 -122.352801)
			(xy 95.427384 -122.406846) (xy 95.429374 -122.461745) (xy 95.423469 -122.516361) (xy 95.409793 -122.569566)
			(xy 95.388626 -122.620259) (xy 95.360407 -122.667392) (xy 95.32572 -122.70999) (xy 95.285282 -122.747173)
			(xy 95.239929 -122.778171) (xy 95.190599 -122.802344) (xy 95.138311 -122.819192) (xy 95.084148 -122.828365)
			(xy 95.029229 -122.829676) (xy 94.97469 -122.823095) (xy 94.921659 -122.808761) (xy 94.871231 -122.786968)
			(xy 94.824452 -122.758168) (xy 94.782286 -122.722956) (xy 94.76359 -122.702828) (xy 94.748784 -122.686924)
			(xy 94.714692 -122.659983) (xy 94.676513 -122.639238) (xy 94.635361 -122.625293) (xy 94.592435 -122.618556)
			(xy 94.548989 -122.619222) (xy 94.50629 -122.627274) (xy 94.465584 -122.642474) (xy 94.446598 -122.653044)
			(xy 94.422365 -122.666548) (xy 94.370908 -122.687272) (xy 94.316993 -122.700325) (xy 94.261755 -122.705432)
			(xy 94.20636 -122.702485) (xy 94.151977 -122.691545) (xy 94.099751 -122.672845) (xy 94.050784 -122.646778)
			(xy 94.006108 -122.613894) (xy 93.966667 -122.574886) (xy 93.933291 -122.530577) (xy 93.906684 -122.481901)
			(xy 93.887408 -122.429885) (xy 93.875868 -122.375625) (xy 93.872309 -122.320266) (xy 88.073484 -122.320266)
			(xy 88.073484 -122.942858) (xy 88.073962 -122.965252) (xy 88.08182 -123.009344) (xy 88.097281 -123.051378)
			(xy 88.119868 -123.090053) (xy 88.148881 -123.124172) (xy 88.183424 -123.15268) (xy 88.222428 -123.174694)
			(xy 88.264685 -123.189534) (xy 88.308889 -123.196741) (xy 88.353671 -123.196091) (xy 88.375744 -123.192286)
			(xy 88.403339 -123.187473) (xy 88.459302 -123.185035) (xy 88.515019 -123.190807) (xy 88.569293 -123.204665)
			(xy 88.620957 -123.22631) (xy 88.668901 -123.255277) (xy 88.712094 -123.290943) (xy 88.749607 -123.332542)
			(xy 88.780634 -123.37918) (xy 88.804507 -123.429853) (xy 88.820714 -123.483473) (xy 88.828906 -123.538886)
			(xy 88.828907 -123.594901) (xy 88.822754 -123.636532) (xy 89.826082 -123.636532) (xy 89.830153 -123.58091)
			(xy 89.842279 -123.526473) (xy 89.862202 -123.474382) (xy 89.889498 -123.425747) (xy 89.923584 -123.381604)
			(xy 89.963733 -123.342895) (xy 90.009091 -123.310444) (xy 90.058691 -123.284943) (xy 90.111475 -123.266936)
			(xy 90.166318 -123.256806) (xy 90.222052 -123.254769) (xy 90.277489 -123.260869) (xy 90.331446 -123.274975)
			(xy 90.382775 -123.296787) (xy 90.430381 -123.325841) (xy 90.473249 -123.361516) (xy 90.510466 -123.403053)
			(xy 90.541239 -123.449566) (xy 90.564911 -123.500063) (xy 90.580979 -123.55347) (xy 90.589099 -123.608646)
			(xy 90.589608 -123.636532) (xy 90.589099 -123.664418) (xy 90.580979 -123.719594) (xy 90.564911 -123.773001)
			(xy 90.541239 -123.823498) (xy 90.510466 -123.870011) (xy 90.473249 -123.911548) (xy 90.430381 -123.947223)
			(xy 90.382775 -123.976277) (xy 90.331446 -123.998089) (xy 90.277489 -124.012195) (xy 90.222052 -124.018295)
			(xy 90.166318 -124.016258) (xy 90.111475 -124.006128) (xy 90.058691 -123.988121) (xy 90.009091 -123.96262)
			(xy 89.963733 -123.930169) (xy 89.923584 -123.89146) (xy 89.889498 -123.847317) (xy 89.862202 -123.798682)
			(xy 89.842279 -123.746591) (xy 89.830153 -123.692154) (xy 89.826082 -123.636532) (xy 88.822754 -123.636532)
			(xy 88.820717 -123.650314) (xy 88.804512 -123.703934) (xy 88.78064 -123.754608) (xy 88.749615 -123.801247)
			(xy 88.712104 -123.842847) (xy 88.668912 -123.878515) (xy 88.620969 -123.907484) (xy 88.569306 -123.929131)
			(xy 88.515032 -123.94299) (xy 88.459315 -123.948764) (xy 88.403353 -123.946329) (xy 88.375744 -123.941586)
			(xy 88.353669 -123.937797) (xy 88.308887 -123.93713) (xy 88.264682 -123.944324) (xy 88.222424 -123.959157)
			(xy 88.18342 -123.98117) (xy 88.148881 -124.009679) (xy 88.119874 -124.043804) (xy 88.0973 -124.082485)
			(xy 88.081858 -124.124524) (xy 88.074025 -124.168621) (xy 88.073484 -124.191014) (xy 88.073484 -124.721366)
			(xy 94.665544 -124.721366) (xy 94.669615 -124.665744) (xy 94.681741 -124.611307) (xy 94.701664 -124.559216)
			(xy 94.72896 -124.510581) (xy 94.763046 -124.466438) (xy 94.803195 -124.427729) (xy 94.848553 -124.395278)
			(xy 94.898153 -124.369777) (xy 94.950937 -124.35177) (xy 95.00578 -124.34164) (xy 95.061514 -124.339603)
			(xy 95.116951 -124.345703) (xy 95.170908 -124.359809) (xy 95.222237 -124.381621) (xy 95.269843 -124.410675)
			(xy 95.312711 -124.44635) (xy 95.349928 -124.487887) (xy 95.380701 -124.5344) (xy 95.404373 -124.584897)
			(xy 95.420441 -124.638304) (xy 95.428561 -124.69348) (xy 95.42907 -124.721366) (xy 95.428561 -124.749252)
			(xy 95.420441 -124.804428) (xy 95.404373 -124.857835) (xy 95.380701 -124.908332) (xy 95.349928 -124.954845)
			(xy 95.316066 -124.992638) (xy 98.45116 -124.992638) (xy 98.455231 -124.937016) (xy 98.467357 -124.882579)
			(xy 98.48728 -124.830488) (xy 98.514576 -124.781853) (xy 98.548662 -124.73771) (xy 98.588811 -124.699001)
			(xy 98.634169 -124.66655) (xy 98.683769 -124.641049) (xy 98.736553 -124.623042) (xy 98.791396 -124.612912)
			(xy 98.84713 -124.610875) (xy 98.902567 -124.616975) (xy 98.956524 -124.631081) (xy 99.007853 -124.652893)
			(xy 99.055459 -124.681947) (xy 99.098327 -124.717622) (xy 99.135544 -124.759159) (xy 99.166317 -124.805672)
			(xy 99.189989 -124.856169) (xy 99.206057 -124.909576) (xy 99.214177 -124.964752) (xy 99.214686 -124.992638)
			(xy 99.214177 -125.020524) (xy 99.206057 -125.0757) (xy 99.189989 -125.129107) (xy 99.166317 -125.179604)
			(xy 99.135544 -125.226117) (xy 99.098327 -125.267654) (xy 99.055459 -125.303329) (xy 99.007853 -125.332383)
			(xy 98.956524 -125.354195) (xy 98.902567 -125.368301) (xy 98.84713 -125.374401) (xy 98.791396 -125.372364)
			(xy 98.736553 -125.362234) (xy 98.683769 -125.344227) (xy 98.634169 -125.318726) (xy 98.588811 -125.286275)
			(xy 98.548662 -125.247566) (xy 98.514576 -125.203423) (xy 98.48728 -125.154788) (xy 98.467357 -125.102697)
			(xy 98.455231 -125.04826) (xy 98.45116 -124.992638) (xy 95.316066 -124.992638) (xy 95.312711 -124.996382)
			(xy 95.269843 -125.032057) (xy 95.222237 -125.061111) (xy 95.170908 -125.082923) (xy 95.116951 -125.097029)
			(xy 95.061514 -125.103129) (xy 95.00578 -125.101092) (xy 94.950937 -125.090962) (xy 94.898153 -125.072955)
			(xy 94.848553 -125.047454) (xy 94.803195 -125.015003) (xy 94.763046 -124.976294) (xy 94.72896 -124.932151)
			(xy 94.701664 -124.883516) (xy 94.681741 -124.831425) (xy 94.669615 -124.776988) (xy 94.665544 -124.721366)
			(xy 88.073484 -124.721366) (xy 88.073484 -126.131505) (xy 94.575951 -126.131505) (xy 94.580214 -126.075683)
			(xy 94.592591 -126.021084) (xy 94.612817 -125.968881) (xy 94.640456 -125.920195) (xy 94.674915 -125.876073)
			(xy 94.715454 -125.837462) (xy 94.761202 -125.805192) (xy 94.811176 -125.779955) (xy 94.864302 -125.762295)
			(xy 94.919438 -125.752591) (xy 94.975401 -125.75105) (xy 95.030988 -125.757707) (xy 95.085005 -125.772419)
			(xy 95.136291 -125.794868) (xy 95.183745 -125.824573) (xy 95.226346 -125.860896) (xy 95.26318 -125.903056)
			(xy 95.293456 -125.950148) (xy 95.309223 -125.985016) (xy 96.585022 -125.985016) (xy 96.589093 -125.929394)
			(xy 96.601219 -125.874957) (xy 96.621142 -125.822866) (xy 96.648438 -125.774231) (xy 96.682524 -125.730088)
			(xy 96.722673 -125.691379) (xy 96.768031 -125.658928) (xy 96.817631 -125.633427) (xy 96.870415 -125.61542)
			(xy 96.925258 -125.60529) (xy 96.980992 -125.603253) (xy 97.036429 -125.609353) (xy 97.090386 -125.623459)
			(xy 97.141715 -125.645271) (xy 97.189321 -125.674325) (xy 97.232189 -125.71) (xy 97.269406 -125.751537)
			(xy 97.300179 -125.79805) (xy 97.323851 -125.848547) (xy 97.339919 -125.901954) (xy 97.348039 -125.95713)
			(xy 97.348548 -125.985016) (xy 97.348039 -126.012902) (xy 97.339919 -126.068078) (xy 97.323851 -126.121485)
			(xy 97.300179 -126.171982) (xy 97.269406 -126.218495) (xy 97.265812 -126.222506) (xy 98.41941 -126.222506)
			(xy 98.423481 -126.166884) (xy 98.435607 -126.112447) (xy 98.45553 -126.060356) (xy 98.482826 -126.011721)
			(xy 98.516912 -125.967578) (xy 98.557061 -125.928869) (xy 98.602419 -125.896418) (xy 98.652019 -125.870917)
			(xy 98.704803 -125.85291) (xy 98.759646 -125.84278) (xy 98.81538 -125.840743) (xy 98.870817 -125.846843)
			(xy 98.924774 -125.860949) (xy 98.976103 -125.882761) (xy 99.023709 -125.911815) (xy 99.066577 -125.94749)
			(xy 99.103794 -125.989027) (xy 99.134567 -126.03554) (xy 99.158239 -126.086037) (xy 99.174307 -126.139444)
			(xy 99.182427 -126.19462) (xy 99.182936 -126.222506) (xy 99.182427 -126.250392) (xy 99.174307 -126.305568)
			(xy 99.158239 -126.358975) (xy 99.134567 -126.409472) (xy 99.103794 -126.455985) (xy 99.066577 -126.497522)
			(xy 99.023709 -126.533197) (xy 98.976103 -126.562251) (xy 98.924774 -126.584063) (xy 98.870817 -126.598169)
			(xy 98.81538 -126.604269) (xy 98.759646 -126.602232) (xy 98.704803 -126.592102) (xy 98.652019 -126.574095)
			(xy 98.602419 -126.548594) (xy 98.557061 -126.516143) (xy 98.516912 -126.477434) (xy 98.482826 -126.433291)
			(xy 98.45553 -126.384656) (xy 98.435607 -126.332565) (xy 98.423481 -126.278128) (xy 98.41941 -126.222506)
			(xy 97.265812 -126.222506) (xy 97.232189 -126.260032) (xy 97.189321 -126.295707) (xy 97.141715 -126.324761)
			(xy 97.090386 -126.346573) (xy 97.036429 -126.360679) (xy 96.980992 -126.366779) (xy 96.925258 -126.364742)
			(xy 96.870415 -126.354612) (xy 96.817631 -126.336605) (xy 96.768031 -126.311104) (xy 96.722673 -126.278653)
			(xy 96.682524 -126.239944) (xy 96.648438 -126.195801) (xy 96.621142 -126.147166) (xy 96.601219 -126.095075)
			(xy 96.589093 -126.040638) (xy 96.585022 -125.985016) (xy 95.309223 -125.985016) (xy 95.316522 -126.001159)
			(xy 95.324676 -126.027942) (xy 95.331265 -126.049326) (xy 95.350844 -126.089555) (xy 95.377166 -126.125733)
			(xy 95.409416 -126.156743) (xy 95.446599 -126.181626) (xy 95.487564 -126.199613) (xy 95.531047 -126.210148)
			(xy 95.575702 -126.212906) (xy 95.59798 -126.210822) (xy 95.625849 -126.208125) (xy 95.68181 -126.209981)
			(xy 95.736898 -126.219998) (xy 95.78993 -126.237961) (xy 95.839766 -126.263482) (xy 95.885336 -126.296016)
			(xy 95.92566 -126.334861) (xy 95.959873 -126.379184) (xy 95.987238 -126.428032) (xy 96.007169 -126.480356)
			(xy 96.019237 -126.535031) (xy 96.023182 -126.590883) (xy 96.01892 -126.646712) (xy 96.006543 -126.701318)
			(xy 95.986316 -126.753528) (xy 95.958673 -126.80222) (xy 95.92421 -126.846348) (xy 95.883666 -126.884964)
			(xy 95.837912 -126.917238) (xy 95.787932 -126.942477) (xy 95.734799 -126.960139) (xy 95.679656 -126.969843)
			(xy 95.623686 -126.971382) (xy 95.568092 -126.964722) (xy 95.514069 -126.950007) (xy 95.462777 -126.927553)
			(xy 95.415319 -126.897841) (xy 95.372715 -126.861512) (xy 95.335879 -126.819344) (xy 95.305603 -126.772244)
			(xy 95.282537 -126.721225) (xy 95.274384 -126.694438) (xy 95.267847 -126.673037) (xy 95.248261 -126.632806)
			(xy 95.221931 -126.596626) (xy 95.189673 -126.565617) (xy 95.152483 -126.540736) (xy 95.11151 -126.522752)
			(xy 95.068021 -126.512222) (xy 95.02336 -126.509471) (xy 95.00108 -126.511558) (xy 94.973213 -126.514244)
			(xy 94.91726 -126.512382) (xy 94.862179 -126.502362) (xy 94.809156 -126.484397) (xy 94.759328 -126.458875)
			(xy 94.713766 -126.426343) (xy 94.673449 -126.3875) (xy 94.639243 -126.34318) (xy 94.611883 -126.294337)
			(xy 94.591958 -126.242019) (xy 94.579894 -126.18735) (xy 94.575951 -126.131505) (xy 88.073484 -126.131505)
			(xy 88.073484 -126.83109) (xy 88.073979 -126.854644) (xy 88.08262 -126.900953) (xy 88.099644 -126.944877)
			(xy 88.12447 -126.984913) (xy 88.156247 -127.019689) (xy 88.193887 -127.048015) (xy 88.236102 -127.068922)
			(xy 88.281446 -127.081693) (xy 88.328366 -127.085892) (xy 88.375257 -127.081374) (xy 88.420513 -127.068295)
			(xy 88.441784 -127.058166) (xy 88.466806 -127.046155) (xy 88.51949 -127.028692) (xy 88.574148 -127.019049)
			(xy 88.629627 -127.01743) (xy 88.684755 -127.023869) (xy 88.738367 -127.03823) (xy 88.789332 -127.060209)
			(xy 88.836573 -127.089344) (xy 88.879093 -127.125017) (xy 88.915993 -127.166477) (xy 88.946495 -127.212846)
			(xy 88.969954 -127.263147) (xy 88.985875 -127.316317) (xy 88.993921 -127.371234) (xy 88.993924 -127.426736)
			(xy 88.985881 -127.481653) (xy 88.969965 -127.534824) (xy 88.94651 -127.585127) (xy 88.916012 -127.631499)
			(xy 88.879115 -127.672962) (xy 88.836598 -127.708638) (xy 88.789359 -127.737776) (xy 88.738396 -127.75976)
			(xy 88.684785 -127.774125) (xy 88.629658 -127.780569) (xy 88.574179 -127.778954) (xy 88.51952 -127.769315)
			(xy 88.466835 -127.751857) (xy 88.441784 -127.739902) (xy 88.420518 -127.729762) (xy 88.375264 -127.716679)
			(xy 88.328374 -127.712159) (xy 88.281454 -127.716357) (xy 88.236111 -127.729129) (xy 88.193898 -127.750038)
			(xy 88.156261 -127.778368) (xy 88.124489 -127.813148) (xy 88.09967 -127.853187) (xy 88.082654 -127.897113)
			(xy 88.074024 -127.943424) (xy 88.073484 -127.966978) (xy 88.073484 -128.614424) (xy 93.329504 -128.614424)
			(xy 93.333575 -128.558802) (xy 93.345701 -128.504365) (xy 93.365624 -128.452274) (xy 93.39292 -128.403639)
			(xy 93.427006 -128.359496) (xy 93.467155 -128.320787) (xy 93.512513 -128.288336) (xy 93.562113 -128.262835)
			(xy 93.614897 -128.244828) (xy 93.66974 -128.234698) (xy 93.725474 -128.232661) (xy 93.780911 -128.238761)
			(xy 93.834868 -128.252867) (xy 93.886197 -128.274679) (xy 93.933803 -128.303733) (xy 93.976671 -128.339408)
			(xy 94.013888 -128.380945) (xy 94.044661 -128.427458) (xy 94.068333 -128.477955) (xy 94.084401 -128.531362)
			(xy 94.092521 -128.586538) (xy 94.09303 -128.614424) (xy 94.092521 -128.64231) (xy 94.084401 -128.697486)
			(xy 94.068333 -128.750893) (xy 94.044661 -128.80139) (xy 94.013888 -128.847903) (xy 93.976671 -128.88944)
			(xy 93.933803 -128.925115) (xy 93.886197 -128.954169) (xy 93.834868 -128.975981) (xy 93.780911 -128.990087)
			(xy 93.725474 -128.996187) (xy 93.66974 -128.99415) (xy 93.614897 -128.98402) (xy 93.562113 -128.966013)
			(xy 93.512513 -128.940512) (xy 93.467155 -128.908061) (xy 93.427006 -128.869352) (xy 93.39292 -128.825209)
			(xy 93.365624 -128.776574) (xy 93.345701 -128.724483) (xy 93.333575 -128.670046) (xy 93.329504 -128.614424)
			(xy 88.073484 -128.614424) (xy 88.073484 -129.94767) (xy 88.332564 -130.20675) (xy 88.34873 -130.222246)
			(xy 88.385452 -130.24787) (xy 88.426096 -130.266663) (xy 88.469403 -130.278044) (xy 88.514035 -130.28166)
			(xy 88.55861 -130.277401) (xy 88.601749 -130.265397) (xy 88.642117 -130.24602) (xy 88.678466 -130.219869)
			(xy 88.70967 -130.187755) (xy 88.734765 -130.150669) (xy 88.752973 -130.10976) (xy 88.758776 -130.088132)
			(xy 88.766044 -130.060927) (xy 88.787487 -130.008861) (xy 88.816349 -129.960512) (xy 88.852003 -129.91693)
			(xy 88.893676 -129.879062) (xy 88.940462 -129.847729) (xy 88.991345 -129.823613) (xy 89.045219 -129.807237)
			(xy 89.100916 -129.798957) (xy 89.157224 -129.798953) (xy 89.212922 -129.807224) (xy 89.266799 -129.823591)
			(xy 89.317686 -129.8477) (xy 89.364477 -129.879025) (xy 89.406155 -129.916887) (xy 89.441817 -129.960463)
			(xy 89.470687 -130.008808) (xy 89.492138 -130.06087) (xy 89.505704 -130.11552) (xy 89.511091 -130.17157)
			(xy 89.508182 -130.227804) (xy 89.497039 -130.282999) (xy 89.477906 -130.335957) (xy 89.451197 -130.385528)
			(xy 89.417493 -130.430635) (xy 89.377525 -130.470299) (xy 89.355168 -130.48742) (xy 89.337399 -130.501076)
			(xy 89.306514 -130.533544) (xy 89.281804 -130.570927) (xy 89.264034 -130.612065) (xy 89.253758 -130.655682)
			(xy 89.251292 -130.700425) (xy 89.256714 -130.744907) (xy 89.269855 -130.787748) (xy 89.290308 -130.82762)
			(xy 89.317438 -130.863285) (xy 89.333578 -130.878834) (xy 89.351805 -130.896133) (xy 89.384017 -130.934704)
			(xy 89.410885 -130.97717) (xy 89.431946 -131.022796) (xy 89.446834 -131.070792) (xy 89.451434 -131.095496)
			(xy 89.459054 -131.141216) (xy 89.530174 -131.20116) (xy 89.588848 -131.20116)
		)
		(stroke
			(width 0)
			(type solid)
		)
		(fill yes)
		(layer "In6.Cu")
		(net "P1V8_NODE1")
	)
	(gr_poly
		(pts
			(xy 86.615778 -179.433728) (xy 87.237062 -179.433728) (xy 87.360252 -179.556918) (xy 88.86063 -179.556918)
			(xy 88.878164 -179.556359) (xy 88.911908 -179.546817) (xy 88.941788 -179.528462) (xy 88.965552 -179.502675)
			(xy 88.98141 -179.471398) (xy 88.985344 -179.454302) (xy 88.991151 -179.427133) (xy 89.009579 -179.374721)
			(xy 89.035413 -179.325536) (xy 89.068108 -179.280619) (xy 89.106973 -179.240919) (xy 89.151185 -179.207276)
			(xy 89.199809 -179.180402) (xy 89.251818 -179.160864) (xy 89.306109 -179.149077) (xy 89.361537 -179.145289)
			(xy 89.416928 -179.149581) (xy 89.47111 -179.161861) (xy 89.522938 -179.181871) (xy 89.571316 -179.209186)
			(xy 89.615221 -179.24323) (xy 89.653723 -179.283282) (xy 89.686008 -179.328495) (xy 89.711394 -179.377912)
			(xy 89.720928 -179.40401) (xy 89.726473 -179.418811) (xy 89.743696 -179.445302) (xy 89.766898 -179.466752)
			(xy 89.794657 -179.481846) (xy 89.825272 -179.489662) (xy 89.84107 -179.490116) (xy 92.195904 -179.490116)
			(xy 93.077792 -178.608228) (xy 93.083126 -178.5112) (xy 93.052646 -178.473354) (xy 93.035911 -178.451791)
			(xy 93.008127 -178.40481) (xy 92.987325 -178.354347) (xy 92.973928 -178.301434) (xy 92.968212 -178.247152)
			(xy 92.970293 -178.19261) (xy 92.980127 -178.138921) (xy 92.997515 -178.087182) (xy 93.022101 -178.038451)
			(xy 93.053383 -177.993722) (xy 93.071696 -177.973482) (xy 93.082473 -177.961254) (xy 93.097999 -177.932608)
			(xy 93.105753 -177.900961) (xy 93.10523 -177.868382) (xy 93.096464 -177.837) (xy 93.080027 -177.808866)
			(xy 93.068902 -177.796952) (xy 92.974414 -177.702464) (xy 92.890848 -177.690526) (xy 92.853764 -177.710846)
			(xy 92.827537 -177.724581) (xy 92.77185 -177.744673) (xy 92.71373 -177.755929) (xy 92.654568 -177.758079)
			(xy 92.595784 -177.751073) (xy 92.538785 -177.735077) (xy 92.511626 -177.723292) (xy 92.491699 -177.71466)
			(xy 92.449716 -177.703571) (xy 92.406459 -177.699786) (xy 92.363188 -177.703415) (xy 92.321165 -177.714353)
			(xy 92.281616 -177.73228) (xy 92.245692 -177.756674) (xy 92.214443 -177.786824) (xy 92.201238 -177.804064)
			(xy 92.184301 -177.826326) (xy 92.144985 -177.866114) (xy 92.100281 -177.899736) (xy 92.051147 -177.92647)
			(xy 91.998637 -177.945743) (xy 91.943874 -177.957143) (xy 91.888035 -177.960425) (xy 91.832314 -177.955518)
			(xy 91.777907 -177.942528) (xy 91.72598 -177.921733) (xy 91.677646 -177.893579) (xy 91.63394 -177.858669)
			(xy 91.595801 -177.817752) (xy 91.564044 -177.771705) (xy 91.539351 -177.721514) (xy 91.522251 -177.668256)
			(xy 91.513111 -177.613071) (xy 91.512136 -177.585116) (xy 91.511374 -177.533046) (xy 91.43746 -177.460402)
			(xy 86.715346 -177.460402) (xy 86.693718 -177.460842) (xy 86.651087 -177.468178) (xy 86.610315 -177.482627)
			(xy 86.572578 -177.503773) (xy 86.538969 -177.531005) (xy 86.510457 -177.563536) (xy 86.487867 -177.600426)
			(xy 86.47185 -177.640608) (xy 86.462871 -177.682923) (xy 86.461188 -177.726148) (xy 86.46685 -177.769033)
			(xy 86.472776 -177.78984) (xy 86.480479 -177.816225) (xy 86.489101 -177.870508) (xy 86.489842 -177.925467)
			(xy 86.482687 -177.979963) (xy 86.467785 -178.032868) (xy 86.445443 -178.083086) (xy 86.416126 -178.129578)
			(xy 86.380438 -178.171381) (xy 86.339121 -178.207628) (xy 86.293029 -178.23757) (xy 86.243116 -178.260587)
			(xy 86.190417 -178.276201) (xy 86.136022 -178.28409) (xy 86.081058 -178.28409) (xy 86.026663 -178.276201)
			(xy 85.973964 -178.260587) (xy 85.924051 -178.23757) (xy 85.877959 -178.207628) (xy 85.836642 -178.171381)
			(xy 85.800954 -178.129578) (xy 85.771637 -178.083086) (xy 85.749295 -178.032868) (xy 85.734393 -177.979963)
			(xy 85.727238 -177.925467) (xy 85.727979 -177.870508) (xy 85.736601 -177.816225) (xy 85.744304 -177.78984)
			(xy 85.750313 -177.769054) (xy 85.75598 -177.726161) (xy 85.754298 -177.682927) (xy 85.745316 -177.640604)
			(xy 85.729293 -177.600414) (xy 85.706693 -177.56352) (xy 85.678169 -177.530988) (xy 85.644546 -177.503759)
			(xy 85.606796 -177.48262) (xy 85.56601 -177.468182) (xy 85.523367 -177.460863) (xy 85.501734 -177.460402)
			(xy 84.952332 -177.460402) (xy 84.935607 -177.460903) (xy 84.903307 -177.469595) (xy 84.874378 -177.486389)
			(xy 84.850814 -177.510129) (xy 84.842096 -177.52441) (xy 84.826486 -177.550539) (xy 84.788286 -177.59792)
			(xy 84.743048 -177.638634) (xy 84.691919 -177.671648) (xy 84.664296 -177.68443) (xy 84.64318 -177.694267)
			(xy 84.604651 -177.720441) (xy 84.571534 -177.753195) (xy 84.544938 -177.791433) (xy 84.525752 -177.833877)
			(xy 84.514618 -177.879105) (xy 84.51191 -177.925604) (xy 84.517717 -177.971819) (xy 84.531845 -178.016203)
			(xy 84.542376 -178.036982) (xy 84.555137 -178.061864) (xy 84.574043 -178.11449) (xy 84.585064 -178.169312)
			(xy 84.587965 -178.225156) (xy 84.582683 -178.280825) (xy 84.569332 -178.335127) (xy 84.548197 -178.386898)
			(xy 84.519731 -178.435029) (xy 84.484544 -178.47849) (xy 84.44339 -178.516349) (xy 84.397151 -178.547795)
			(xy 84.346817 -178.572154) (xy 84.293466 -178.588905) (xy 84.238241 -178.597689) (xy 84.182325 -178.598318)
			(xy 84.126917 -178.590778) (xy 84.073203 -178.57523) (xy 84.022334 -178.552008) (xy 83.975399 -178.52161)
			(xy 83.933405 -178.484686) (xy 83.89725 -178.442027) (xy 83.867709 -178.394548) (xy 83.845416 -178.343265)
			(xy 83.830847 -178.289277) (xy 83.824315 -178.233741) (xy 83.82596 -178.177846) (xy 83.835746 -178.12279)
			(xy 83.853464 -178.069752) (xy 83.878734 -178.019869) (xy 83.911015 -177.974209) (xy 83.949615 -177.93375)
			(xy 83.993708 -177.899359) (xy 84.042349 -177.871772) (xy 84.094496 -177.851582) (xy 84.149031 -177.839219)
			(xy 84.17687 -177.836576) (xy 84.193192 -177.834804) (xy 84.22419 -177.824016) (xy 84.25141 -177.805679)
			(xy 84.273053 -177.781005) (xy 84.287685 -177.751626) (xy 84.29434 -177.719487) (xy 84.292576 -177.686714)
			(xy 84.282511 -177.655474) (xy 84.26481 -177.627835) (xy 84.25307 -177.616358) (xy 84.231664 -177.595982)
			(xy 84.194791 -177.549799) (xy 84.179664 -177.52441) (xy 84.162646 -177.494692) (xy 84.103718 -177.460402)
			(xy 82.524092 -177.460402) (xy 82.501735 -177.460865) (xy 82.457709 -177.468677) (xy 82.415731 -177.484076)
			(xy 82.377098 -177.506587) (xy 82.343002 -177.535514) (xy 82.314497 -177.569963) (xy 82.292463 -177.60887)
			(xy 82.277581 -177.651034) (xy 82.270311 -177.695153) (xy 82.270876 -177.739863) (xy 82.274664 -177.7619)
			(xy 82.279265 -177.788751) (xy 82.281702 -177.843171) (xy 82.27637 -177.897385) (xy 82.270346 -177.923952)
			(xy 82.265154 -177.947341) (xy 82.262614 -177.995179) (xy 82.26908 -178.042646) (xy 82.284323 -178.088061)
			(xy 82.307803 -178.129817) (xy 82.33869 -178.166435) (xy 82.375889 -178.19662) (xy 82.418084 -178.219301)
			(xy 82.44078 -178.226974) (xy 82.467085 -178.23576) (xy 82.517028 -178.259868) (xy 82.562956 -178.290952)
			(xy 82.6039 -178.328357) (xy 82.638997 -178.371295) (xy 82.66751 -178.418861) (xy 82.688836 -178.470054)
			(xy 82.702526 -178.523795) (xy 82.708293 -178.578952) (xy 82.706015 -178.634363) (xy 82.695739 -178.68886)
			(xy 82.677682 -178.741296) (xy 82.652224 -178.790565) (xy 82.619903 -178.83563) (xy 82.581398 -178.875541)
			(xy 82.537521 -178.909458) (xy 82.489196 -178.936666) (xy 82.437442 -178.956592) (xy 82.383349 -178.968815)
			(xy 82.328055 -178.97308) (xy 82.272727 -178.969295) (xy 82.21853 -178.95754) (xy 82.166605 -178.938063)
			(xy 82.118046 -178.911275) (xy 82.073877 -178.87774) (xy 82.035028 -178.838164) (xy 82.002317 -178.79338)
			(xy 81.976434 -178.744334) (xy 81.957923 -178.692057) (xy 81.947175 -178.63765) (xy 81.944417 -178.582262)
			(xy 81.949705 -178.527057) (xy 81.955894 -178.500024) (xy 81.961084 -178.476635) (xy 81.963619 -178.428799)
			(xy 81.95715 -178.381334) (xy 81.941906 -178.335921) (xy 81.918426 -178.294167) (xy 81.887542 -178.257549)
			(xy 81.850346 -178.227363) (xy 81.808154 -178.204678) (xy 81.78546 -178.197002) (xy 81.778856 -178.19497)
			(xy 81.763916 -178.190484) (xy 81.732821 -178.188129) (xy 81.702083 -178.193385) (xy 81.673537 -178.205939)
			(xy 81.648889 -178.225042) (xy 81.62961 -178.249553) (xy 81.616851 -178.278008) (xy 81.611375 -178.308708)
			(xy 81.613508 -178.339819) (xy 81.623123 -178.369484) (xy 81.631028 -178.38293) (xy 81.645314 -178.406636)
			(xy 81.667637 -178.457282) (xy 81.682406 -178.510622) (xy 81.68931 -178.565537) (xy 81.688205 -178.620873)
			(xy 81.679114 -178.675469) (xy 81.662228 -178.728177) (xy 81.637901 -178.777891) (xy 81.606644 -178.823567)
			(xy 81.569113 -178.864246) (xy 81.526098 -178.899074) (xy 81.4785 -178.927319) (xy 81.42732 -178.948388)
			(xy 81.373632 -178.961839) (xy 81.318564 -178.967388) (xy 81.263272 -178.964921) (xy 81.208917 -178.954488)
			(xy 81.156641 -178.936309) (xy 81.107541 -178.910765) (xy 81.062648 -178.878393) (xy 81.022906 -178.839872)
			(xy 80.989148 -178.796012) (xy 80.962084 -178.747733) (xy 80.942281 -178.69605) (xy 80.930157 -178.642047)
			(xy 80.925965 -178.586859) (xy 80.929793 -178.531644) (xy 80.941561 -178.477563) (xy 80.961022 -178.42575)
			(xy 80.987768 -178.377294) (xy 81.021236 -178.333212) (xy 81.060723 -178.29443) (xy 81.105402 -178.261763)
			(xy 81.154332 -178.235896) (xy 81.206488 -178.217372) (xy 81.260773 -178.206581) (xy 81.288382 -178.204622)
			(xy 81.310004 -178.203059) (xy 81.352285 -178.193497) (xy 81.392331 -178.176899) (xy 81.428979 -178.153748)
			(xy 81.461168 -178.124714) (xy 81.487964 -178.090639) (xy 81.508589 -178.052511) (xy 81.522446 -178.011437)
			(xy 81.529133 -177.968607) (xy 81.528455 -177.925264) (xy 81.524856 -177.903886) (xy 81.519906 -177.874685)
			(xy 81.518028 -177.81549) (xy 81.525314 -177.756715) (xy 81.541588 -177.69977) (xy 81.566461 -177.646021)
			(xy 81.599336 -177.596758) (xy 81.639423 -177.553163) (xy 81.66227 -177.534316) (xy 81.680528 -177.519092)
			(xy 81.711557 -177.483084) (xy 81.735353 -177.441936) (xy 81.751086 -177.397082) (xy 81.758208 -177.350086)
			(xy 81.756471 -177.302585) (xy 81.745935 -177.256234) (xy 81.726968 -177.21265) (xy 81.70023 -177.17335)
			(xy 81.68386 -177.15611) (xy 80.928464 -176.400714) (xy 80.912594 -176.385505) (xy 80.876628 -176.36024)
			(xy 80.836851 -176.341542) (xy 80.79445 -176.329968) (xy 80.750689 -176.325864) (xy 80.706875 -176.329352)
			(xy 80.664315 -176.340328) (xy 80.624279 -176.358465) (xy 80.587962 -176.383222) (xy 80.571848 -176.398174)
			(xy 80.551634 -176.417134) (xy 80.506725 -176.449608) (xy 80.45759 -176.475244) (xy 80.405264 -176.493501)
			(xy 80.350846 -176.503995) (xy 80.295483 -176.506506) (xy 80.240339 -176.500981) (xy 80.186575 -176.487536)
			(xy 80.135321 -176.466453) (xy 80.087657 -176.438178) (xy 80.044586 -176.403303) (xy 80.007013 -176.362565)
			(xy 79.975729 -176.316818) (xy 79.951393 -176.267027) (xy 79.934517 -176.214239) (xy 79.925455 -176.159565)
			(xy 79.924399 -176.104155) (xy 79.92745 -176.07661) (xy 79.92992 -176.052841) (xy 79.926977 -176.005151)
			(xy 79.91517 -175.958852) (xy 79.894916 -175.915576) (xy 79.866928 -175.87685) (xy 79.832194 -175.844039)
			(xy 79.791939 -175.818299) (xy 79.76997 -175.808894) (xy 79.745306 -175.798512) (xy 79.698913 -175.771841)
			(xy 79.656701 -175.73895) (xy 79.619498 -175.700486) (xy 79.588032 -175.657201) (xy 79.562922 -175.609946)
			(xy 79.544659 -175.559646) (xy 79.533601 -175.507288) (xy 79.529966 -175.453899) (xy 79.533825 -175.400525)
			(xy 79.545102 -175.348214) (xy 79.563576 -175.297991) (xy 79.588884 -175.250842) (xy 79.604362 -175.229012)
			(xy 79.612924 -175.216657) (xy 79.624564 -175.18895) (xy 79.62939 -175.159289) (xy 79.627135 -175.129321)
			(xy 79.617923 -175.100716) (xy 79.602267 -175.075064) (xy 79.591916 -175.064166) (xy 79.09052 -174.56277)
			(xy 79.09052 -171.988734) (xy 78.464918 -171.363132) (xy 77.534008 -171.363132) (xy 73.9648 -174.932086)
			(xy 73.9648 -175.13808) (xy 74.789282 -175.13808) (xy 74.793353 -175.082458) (xy 74.805479 -175.028021)
			(xy 74.825402 -174.97593) (xy 74.852698 -174.927295) (xy 74.886784 -174.883152) (xy 74.926933 -174.844443)
			(xy 74.972291 -174.811992) (xy 75.021891 -174.786491) (xy 75.074675 -174.768484) (xy 75.129518 -174.758354)
			(xy 75.185252 -174.756317) (xy 75.240689 -174.762417) (xy 75.294646 -174.776523) (xy 75.345975 -174.798335)
			(xy 75.393581 -174.827389) (xy 75.436449 -174.863064) (xy 75.473666 -174.904601) (xy 75.504439 -174.951114)
			(xy 75.528111 -175.001611) (xy 75.544179 -175.055018) (xy 75.552299 -175.110194) (xy 75.552808 -175.13808)
			(xy 75.552299 -175.165966) (xy 75.544179 -175.221142) (xy 75.528111 -175.274549) (xy 75.504439 -175.325046)
			(xy 75.473666 -175.371559) (xy 75.436449 -175.413096) (xy 75.393581 -175.448771) (xy 75.345975 -175.477825)
			(xy 75.294646 -175.499637) (xy 75.240689 -175.513743) (xy 75.185252 -175.519843) (xy 75.129518 -175.517806)
			(xy 75.074675 -175.507676) (xy 75.021891 -175.489669) (xy 74.972291 -175.464168) (xy 74.926933 -175.431717)
			(xy 74.886784 -175.393008) (xy 74.852698 -175.348865) (xy 74.825402 -175.30023) (xy 74.805479 -175.248139)
			(xy 74.793353 -175.193702) (xy 74.789282 -175.13808) (xy 73.9648 -175.13808) (xy 73.9648 -177.094134)
			(xy 75.132182 -177.094134) (xy 75.136253 -177.038512) (xy 75.148379 -176.984075) (xy 75.168302 -176.931984)
			(xy 75.195598 -176.883349) (xy 75.229684 -176.839206) (xy 75.269833 -176.800497) (xy 75.315191 -176.768046)
			(xy 75.364791 -176.742545) (xy 75.417575 -176.724538) (xy 75.472418 -176.714408) (xy 75.528152 -176.712371)
			(xy 75.583589 -176.718471) (xy 75.637546 -176.732577) (xy 75.688875 -176.754389) (xy 75.736481 -176.783443)
			(xy 75.779349 -176.819118) (xy 75.816566 -176.860655) (xy 75.847339 -176.907168) (xy 75.871011 -176.957665)
			(xy 75.887079 -177.011072) (xy 75.895199 -177.066248) (xy 75.89556 -177.086006) (xy 77.339442 -177.086006)
			(xy 77.343513 -177.030384) (xy 77.355639 -176.975947) (xy 77.375562 -176.923856) (xy 77.402858 -176.875221)
			(xy 77.436944 -176.831078) (xy 77.477093 -176.792369) (xy 77.522451 -176.759918) (xy 77.572051 -176.734417)
			(xy 77.624835 -176.71641) (xy 77.679678 -176.70628) (xy 77.735412 -176.704243) (xy 77.790849 -176.710343)
			(xy 77.844806 -176.724449) (xy 77.896135 -176.746261) (xy 77.943741 -176.775315) (xy 77.986609 -176.81099)
			(xy 78.023826 -176.852527) (xy 78.054599 -176.89904) (xy 78.078271 -176.949537) (xy 78.094339 -177.002944)
			(xy 78.102459 -177.05812) (xy 78.102968 -177.086006) (xy 78.102459 -177.113892) (xy 78.094339 -177.169068)
			(xy 78.078271 -177.222475) (xy 78.054599 -177.272972) (xy 78.023826 -177.319485) (xy 77.986609 -177.361022)
			(xy 77.943741 -177.396697) (xy 77.896135 -177.425751) (xy 77.844806 -177.447563) (xy 77.790849 -177.461669)
			(xy 77.735412 -177.467769) (xy 77.679678 -177.465732) (xy 77.624835 -177.455602) (xy 77.572051 -177.437595)
			(xy 77.522451 -177.412094) (xy 77.477093 -177.379643) (xy 77.436944 -177.340934) (xy 77.402858 -177.296791)
			(xy 77.375562 -177.248156) (xy 77.355639 -177.196065) (xy 77.343513 -177.141628) (xy 77.339442 -177.086006)
			(xy 75.89556 -177.086006) (xy 75.895708 -177.094134) (xy 75.895199 -177.12202) (xy 75.887079 -177.177196)
			(xy 75.871011 -177.230603) (xy 75.847339 -177.2811) (xy 75.816566 -177.327613) (xy 75.779349 -177.36915)
			(xy 75.736481 -177.404825) (xy 75.688875 -177.433879) (xy 75.637546 -177.455691) (xy 75.583589 -177.469797)
			(xy 75.528152 -177.475897) (xy 75.472418 -177.47386) (xy 75.417575 -177.46373) (xy 75.364791 -177.445723)
			(xy 75.315191 -177.420222) (xy 75.269833 -177.387771) (xy 75.229684 -177.349062) (xy 75.195598 -177.304919)
			(xy 75.168302 -177.256284) (xy 75.148379 -177.204193) (xy 75.136253 -177.149756) (xy 75.132182 -177.094134)
			(xy 73.9648 -177.094134) (xy 73.9648 -178.1175) (xy 73.965328 -178.140835) (xy 73.973849 -178.186722)
			(xy 73.990605 -178.230281) (xy 74.015031 -178.270048) (xy 74.046309 -178.304688) (xy 74.083384 -178.333035)
			(xy 74.125012 -178.354136) (xy 74.169793 -178.367282) (xy 74.216222 -178.372031) (xy 74.262737 -178.368223)
			(xy 74.307775 -178.355987) (xy 74.329036 -178.346354) (xy 74.35427 -178.334751) (xy 74.40727 -178.318151)
			(xy 74.462116 -178.309408) (xy 74.517651 -178.308706) (xy 74.5727 -178.31606) (xy 74.626103 -178.331316)
			(xy 74.67673 -178.35415) (xy 74.700384 -178.368706) (xy 74.720465 -178.380882) (xy 74.764012 -178.398448)
			(xy 74.810044 -178.40772) (xy 74.856996 -178.408383) (xy 74.903271 -178.400414) (xy 74.947296 -178.384085)
			(xy 74.987575 -178.35995) (xy 75.022738 -178.32883) (xy 75.05159 -178.291783) (xy 75.062842 -178.27117)
			(xy 75.07603 -178.246702) (xy 75.108413 -178.201527) (xy 75.147008 -178.161529) (xy 75.190998 -178.127555)
			(xy 75.239453 -178.100323) (xy 75.291346 -178.080411) (xy 75.34558 -178.068239) (xy 75.401006 -178.064066)
			(xy 75.45645 -178.06798) (xy 75.51074 -178.079897) (xy 75.562726 -178.099566) (xy 75.611308 -178.126571)
			(xy 75.655457 -178.160339) (xy 75.694239 -178.200155) (xy 75.726832 -178.245178) (xy 75.735349 -178.261497)
			(xy 76.248884 -178.261497) (xy 76.254133 -178.206459) (xy 76.267273 -178.152755) (xy 76.288027 -178.101511)
			(xy 76.315961 -178.053799) (xy 76.332842 -178.031902) (xy 76.343139 -178.018183) (xy 76.356611 -177.986647)
			(xy 76.361205 -177.952664) (xy 76.356591 -177.918683) (xy 76.343102 -177.887155) (xy 76.332842 -177.873406)
			(xy 76.315961 -177.851509) (xy 76.288027 -177.803797) (xy 76.267273 -177.752553) (xy 76.254133 -177.698849)
			(xy 76.248884 -177.643811) (xy 76.251634 -177.588591) (xy 76.262327 -177.534347) (xy 76.280738 -177.482215)
			(xy 76.306481 -177.433286) (xy 76.339019 -177.388586) (xy 76.377668 -177.349051) (xy 76.421619 -177.315509)
			(xy 76.469951 -177.288663) (xy 76.521653 -177.269076) (xy 76.575641 -177.257157) (xy 76.630784 -177.253156)
			(xy 76.685927 -177.257157) (xy 76.739915 -177.269076) (xy 76.791617 -177.288663) (xy 76.839949 -177.315509)
			(xy 76.8839 -177.349051) (xy 76.922549 -177.388586) (xy 76.955087 -177.433286) (xy 76.98083 -177.482215)
			(xy 76.999241 -177.534347) (xy 77.009934 -177.588591) (xy 77.012684 -177.643811) (xy 77.007435 -177.698849)
			(xy 76.994295 -177.752553) (xy 76.973541 -177.803797) (xy 76.945607 -177.851509) (xy 76.928726 -177.873406)
			(xy 76.918511 -177.887183) (xy 76.90502 -177.918696) (xy 76.900406 -177.952664) (xy 76.905001 -177.986634)
			(xy 76.918474 -178.018155) (xy 76.928726 -178.031902) (xy 76.945607 -178.053799) (xy 76.973541 -178.101511)
			(xy 76.994295 -178.152755) (xy 77.007435 -178.206459) (xy 77.012684 -178.261497) (xy 77.009934 -178.316717)
			(xy 76.999241 -178.370961) (xy 76.98083 -178.423093) (xy 76.979243 -178.42611) (xy 79.178402 -178.42611)
			(xy 79.182473 -178.370488) (xy 79.194599 -178.316051) (xy 79.214522 -178.26396) (xy 79.241818 -178.215325)
			(xy 79.275904 -178.171182) (xy 79.316053 -178.132473) (xy 79.361411 -178.100022) (xy 79.411011 -178.074521)
			(xy 79.463795 -178.056514) (xy 79.518638 -178.046384) (xy 79.574372 -178.044347) (xy 79.629809 -178.050447)
			(xy 79.683766 -178.064553) (xy 79.735095 -178.086365) (xy 79.782701 -178.115419) (xy 79.825569 -178.151094)
			(xy 79.862786 -178.192631) (xy 79.893559 -178.239144) (xy 79.917231 -178.289641) (xy 79.933299 -178.343048)
			(xy 79.941419 -178.398224) (xy 79.941928 -178.42611) (xy 79.941419 -178.453996) (xy 79.933299 -178.509172)
			(xy 79.917231 -178.562579) (xy 79.893559 -178.613076) (xy 79.862786 -178.659589) (xy 79.825569 -178.701126)
			(xy 79.782701 -178.736801) (xy 79.735095 -178.765855) (xy 79.683766 -178.787667) (xy 79.629809 -178.801773)
			(xy 79.574372 -178.807873) (xy 79.518638 -178.805836) (xy 79.463795 -178.795706) (xy 79.411011 -178.777699)
			(xy 79.361411 -178.752198) (xy 79.316053 -178.719747) (xy 79.275904 -178.681038) (xy 79.241818 -178.636895)
			(xy 79.214522 -178.58826) (xy 79.194599 -178.536169) (xy 79.182473 -178.481732) (xy 79.178402 -178.42611)
			(xy 76.979243 -178.42611) (xy 76.955087 -178.472022) (xy 76.922549 -178.516722) (xy 76.8839 -178.556257)
			(xy 76.839949 -178.589799) (xy 76.791617 -178.616645) (xy 76.739915 -178.636232) (xy 76.685927 -178.648151)
			(xy 76.630784 -178.652152) (xy 76.575641 -178.648151) (xy 76.521653 -178.636232) (xy 76.469951 -178.616645)
			(xy 76.421619 -178.589799) (xy 76.377668 -178.556257) (xy 76.339019 -178.516722) (xy 76.306481 -178.472022)
			(xy 76.280738 -178.423093) (xy 76.262327 -178.370961) (xy 76.251634 -178.316717) (xy 76.248884 -178.261497)
			(xy 75.735349 -178.261497) (xy 75.752548 -178.294454) (xy 75.770842 -178.34694) (xy 75.781325 -178.401525)
			(xy 75.783778 -178.457053) (xy 75.778147 -178.51235) (xy 75.764551 -178.566244) (xy 75.74328 -178.617595)
			(xy 75.714782 -178.665316) (xy 75.679661 -178.708397) (xy 75.63866 -178.745925) (xy 75.592648 -178.777107)
			(xy 75.542599 -178.801282) (xy 75.489571 -178.817939) (xy 75.434687 -178.826725) (xy 75.379109 -178.827454)
			(xy 75.324014 -178.820111) (xy 75.270567 -178.804851) (xy 75.219901 -178.781997) (xy 75.196192 -178.767486)
			(xy 75.176111 -178.755313) (xy 75.132566 -178.737752) (xy 75.086537 -178.728484) (xy 75.039588 -178.727824)
			(xy 74.993317 -178.735795) (xy 74.949296 -178.752126) (xy 74.909021 -178.776261) (xy 74.873861 -178.80738)
			(xy 74.845013 -178.844425) (xy 74.833734 -178.865022) (xy 74.820754 -178.889144) (xy 74.788931 -178.933729)
			(xy 74.75106 -178.973307) (xy 74.70792 -179.007063) (xy 74.660397 -179.034305) (xy 74.609467 -179.054472)
			(xy 74.556177 -179.067151) (xy 74.501622 -179.07208) (xy 74.446923 -179.069159) (xy 74.393203 -179.058447)
			(xy 74.341567 -179.040165) (xy 74.293075 -179.014688) (xy 74.248723 -178.982539) (xy 74.209424 -178.94438)
			(xy 74.192384 -178.922934) (xy 74.182365 -178.910709) (xy 74.15752 -178.891188) (xy 74.128636 -178.878377)
			(xy 74.097489 -178.873065) (xy 74.065992 -178.875579) (xy 74.036081 -178.885762) (xy 74.009594 -178.902991)
			(xy 73.988158 -178.926205) (xy 73.973092 -178.953979) (xy 73.965321 -178.984605) (xy 73.9648 -179.000404)
			(xy 73.9648 -179.076858) (xy 74.44486 -179.556918) (xy 86.492588 -179.556918)
		)
		(stroke
			(width 0)
			(type solid)
		)
		(fill yes)
		(layer "In6.Cu")
		(net "P5V_NODE1")
	)
	(gr_poly
		(pts
			(xy 193.20256 -153.039064) (xy 193.20256 -142.195804) (xy 192.83426 -141.827504) (xy 188.735208 -141.827504)
			(xy 187.326016 -143.236696) (xy 180.96992 -143.236696) (xy 180.95511 -143.237084) (xy 180.926291 -143.243919)
			(xy 180.89984 -143.257245) (xy 180.877195 -143.276336) (xy 180.868066 -143.288004) (xy 180.851367 -143.309691)
			(xy 180.812784 -143.348512) (xy 180.76905 -143.381422) (xy 180.721063 -143.407747) (xy 180.669808 -143.426945)
			(xy 180.616335 -143.438625) (xy 180.561742 -143.442544) (xy 180.507149 -143.438625) (xy 180.453676 -143.426945)
			(xy 180.402421 -143.407747) (xy 180.354434 -143.381422) (xy 180.3107 -143.348512) (xy 180.272117 -143.309691)
			(xy 180.255418 -143.288004) (xy 180.246236 -143.276395) (xy 180.223572 -143.257371) (xy 180.19714 -143.24407)
			(xy 180.168358 -143.237204) (xy 180.153564 -143.236696) (xy 176.131474 -143.236696) (xy 176.115586 -143.237151)
			(xy 176.084781 -143.244941) (xy 176.056858 -143.260106) (xy 176.033552 -143.281703) (xy 176.01631 -143.308393)
			(xy 176.010824 -143.32331) (xy 176.001215 -143.350482) (xy 175.97497 -143.401792) (xy 175.941292 -143.44856)
			(xy 175.90095 -143.489718) (xy 175.878236 -143.50746) (xy 175.859739 -143.522016) (xy 175.82798 -143.55675)
			(xy 175.80316 -143.596738) (xy 175.786126 -143.640612) (xy 175.777462 -143.686871) (xy 175.777462 -143.733936)
			(xy 175.786128 -143.780195) (xy 175.803163 -143.824069) (xy 175.827985 -143.864055) (xy 175.859744 -143.898789)
			(xy 175.878236 -143.913352) (xy 175.899698 -143.930076) (xy 175.938117 -143.968602) (xy 175.970674 -144.012196)
			(xy 175.996707 -144.059973) (xy 176.015688 -144.110963) (xy 176.027233 -144.164133) (xy 176.031108 -144.218404)
			(xy 176.027232 -144.272674) (xy 176.015686 -144.325844) (xy 175.996704 -144.376834) (xy 175.97067 -144.42461)
			(xy 175.938113 -144.468203) (xy 175.899692 -144.506728) (xy 175.878236 -144.52346) (xy 175.859739 -144.538016)
			(xy 175.82798 -144.57275) (xy 175.80316 -144.612738) (xy 175.786126 -144.656612) (xy 175.777462 -144.702871)
			(xy 175.777462 -144.749936) (xy 175.786128 -144.796195) (xy 175.803163 -144.840069) (xy 175.827985 -144.880055)
			(xy 175.859744 -144.914789) (xy 175.878236 -144.929352) (xy 175.899698 -144.946076) (xy 175.938117 -144.984602)
			(xy 175.970674 -145.028196) (xy 175.996707 -145.075973) (xy 176.015688 -145.126963) (xy 176.027233 -145.180133)
			(xy 176.031108 -145.234404) (xy 176.027232 -145.288674) (xy 176.015686 -145.341844) (xy 175.996704 -145.392834)
			(xy 175.97067 -145.44061) (xy 175.938113 -145.484203) (xy 175.899692 -145.522728) (xy 175.878236 -145.53946)
			(xy 175.859739 -145.554016) (xy 175.82798 -145.58875) (xy 175.80316 -145.628738) (xy 175.786126 -145.672612)
			(xy 175.777462 -145.718871) (xy 175.777462 -145.765936) (xy 175.786128 -145.812195) (xy 175.803163 -145.856069)
			(xy 175.827985 -145.896055) (xy 175.859744 -145.930789) (xy 175.878236 -145.945352) (xy 175.899698 -145.962076)
			(xy 175.938117 -146.000602) (xy 175.970674 -146.044196) (xy 175.996707 -146.091973) (xy 176.015688 -146.142963)
			(xy 176.027233 -146.196133) (xy 176.031108 -146.250404) (xy 176.027232 -146.304674) (xy 176.015686 -146.357844)
			(xy 175.996704 -146.408834) (xy 175.97067 -146.45661) (xy 175.938113 -146.500203) (xy 175.899692 -146.538728)
			(xy 175.878236 -146.55546) (xy 175.859739 -146.570016) (xy 175.82798 -146.60475) (xy 175.80316 -146.644738)
			(xy 175.786126 -146.688612) (xy 175.777462 -146.734871) (xy 175.777462 -146.781936) (xy 175.786128 -146.828195)
			(xy 175.803163 -146.872069) (xy 175.827985 -146.912055) (xy 175.859744 -146.946789) (xy 175.878236 -146.961352)
			(xy 175.899698 -146.978076) (xy 175.938117 -147.016602) (xy 175.970674 -147.060196) (xy 175.973145 -147.06473)
			(xy 180.796182 -147.06473) (xy 180.800253 -147.009108) (xy 180.812379 -146.954671) (xy 180.832302 -146.90258)
			(xy 180.859598 -146.853945) (xy 180.893684 -146.809802) (xy 180.933833 -146.771093) (xy 180.979191 -146.738642)
			(xy 181.028791 -146.713141) (xy 181.081575 -146.695134) (xy 181.136418 -146.685004) (xy 181.192152 -146.682967)
			(xy 181.247589 -146.689067) (xy 181.301546 -146.703173) (xy 181.352875 -146.724985) (xy 181.400481 -146.754039)
			(xy 181.443349 -146.789714) (xy 181.480566 -146.831251) (xy 181.511339 -146.877764) (xy 181.535011 -146.928261)
			(xy 181.551079 -146.981668) (xy 181.559199 -147.036844) (xy 181.559708 -147.06473) (xy 181.559199 -147.092616)
			(xy 181.551079 -147.147792) (xy 181.535011 -147.201199) (xy 181.511339 -147.251696) (xy 181.480566 -147.298209)
			(xy 181.443349 -147.339746) (xy 181.400481 -147.375421) (xy 181.352875 -147.404475) (xy 181.301546 -147.426287)
			(xy 181.247589 -147.440393) (xy 181.192152 -147.446493) (xy 181.136418 -147.444456) (xy 181.081575 -147.434326)
			(xy 181.028791 -147.416319) (xy 180.979191 -147.390818) (xy 180.933833 -147.358367) (xy 180.893684 -147.319658)
			(xy 180.859598 -147.275515) (xy 180.832302 -147.22688) (xy 180.812379 -147.174789) (xy 180.800253 -147.120352)
			(xy 180.796182 -147.06473) (xy 175.973145 -147.06473) (xy 175.996707 -147.107973) (xy 176.015688 -147.158963)
			(xy 176.027233 -147.212133) (xy 176.031108 -147.266404) (xy 176.027232 -147.320674) (xy 176.015686 -147.373844)
			(xy 175.996704 -147.424834) (xy 175.97067 -147.47261) (xy 175.938113 -147.516203) (xy 175.899692 -147.554728)
			(xy 175.878236 -147.57146) (xy 175.859739 -147.586016) (xy 175.82798 -147.62075) (xy 175.80316 -147.660738)
			(xy 175.786126 -147.704612) (xy 175.777462 -147.750871) (xy 175.777462 -147.797936) (xy 175.786128 -147.844195)
			(xy 175.803163 -147.888069) (xy 175.827985 -147.928055) (xy 175.859744 -147.962789) (xy 175.878236 -147.977352)
			(xy 175.899698 -147.994076) (xy 175.938117 -148.032602) (xy 175.970674 -148.076196) (xy 175.978265 -148.090128)
			(xy 180.768242 -148.090128) (xy 180.772313 -148.034506) (xy 180.784439 -147.980069) (xy 180.804362 -147.927978)
			(xy 180.831658 -147.879343) (xy 180.865744 -147.8352) (xy 180.905893 -147.796491) (xy 180.951251 -147.76404)
			(xy 181.000851 -147.738539) (xy 181.053635 -147.720532) (xy 181.108478 -147.710402) (xy 181.164212 -147.708365)
			(xy 181.219649 -147.714465) (xy 181.273606 -147.728571) (xy 181.324935 -147.750383) (xy 181.372541 -147.779437)
			(xy 181.415409 -147.815112) (xy 181.452626 -147.856649) (xy 181.483399 -147.903162) (xy 181.507071 -147.953659)
			(xy 181.523139 -148.007066) (xy 181.531259 -148.062242) (xy 181.531768 -148.090128) (xy 181.531259 -148.118014)
			(xy 181.523139 -148.17319) (xy 181.507071 -148.226597) (xy 181.483399 -148.277094) (xy 181.452626 -148.323607)
			(xy 181.415409 -148.365144) (xy 181.372541 -148.400819) (xy 181.324935 -148.429873) (xy 181.273606 -148.451685)
			(xy 181.219649 -148.465791) (xy 181.164212 -148.471891) (xy 181.108478 -148.469854) (xy 181.053635 -148.459724)
			(xy 181.000851 -148.441717) (xy 180.951251 -148.416216) (xy 180.905893 -148.383765) (xy 180.865744 -148.345056)
			(xy 180.831658 -148.300913) (xy 180.804362 -148.252278) (xy 180.784439 -148.200187) (xy 180.772313 -148.14575)
			(xy 180.768242 -148.090128) (xy 175.978265 -148.090128) (xy 175.996707 -148.123973) (xy 176.015688 -148.174963)
			(xy 176.027233 -148.228133) (xy 176.031108 -148.282404) (xy 176.027232 -148.336674) (xy 176.015686 -148.389844)
			(xy 175.996704 -148.440834) (xy 175.97067 -148.48861) (xy 175.938113 -148.532203) (xy 175.899692 -148.570728)
			(xy 175.878236 -148.58746) (xy 175.859739 -148.602016) (xy 175.82798 -148.63675) (xy 175.80316 -148.676738)
			(xy 175.786126 -148.720612) (xy 175.777462 -148.766871) (xy 175.777462 -148.813936) (xy 175.786128 -148.860195)
			(xy 175.803163 -148.904069) (xy 175.827985 -148.944055) (xy 175.859744 -148.978789) (xy 175.878236 -148.993352)
			(xy 175.900357 -149.010585) (xy 175.939782 -149.05046) (xy 175.972946 -149.095677) (xy 175.999133 -149.145261)
			(xy 176.01778 -149.198144) (xy 176.028486 -149.253187) (xy 176.031018 -149.309204) (xy 176.025324 -149.364989)
			(xy 176.011526 -149.419339) (xy 175.98992 -149.471084) (xy 175.960973 -149.519109) (xy 175.925307 -149.56238)
			(xy 175.883692 -149.599963) (xy 175.837023 -149.63105) (xy 175.786307 -149.654971) (xy 175.732636 -149.671211)
			(xy 175.677165 -149.679419) (xy 175.621091 -149.679419) (xy 175.56562 -149.671211) (xy 175.511949 -149.654971)
			(xy 175.461233 -149.63105) (xy 175.414564 -149.599963) (xy 175.372949 -149.56238) (xy 175.337283 -149.519109)
			(xy 175.308336 -149.471084) (xy 175.28673 -149.419339) (xy 175.272932 -149.364989) (xy 175.267238 -149.309204)
			(xy 175.26977 -149.253187) (xy 175.280476 -149.198144) (xy 175.299123 -149.145261) (xy 175.32531 -149.095677)
			(xy 175.358474 -149.05046) (xy 175.397899 -149.010585) (xy 175.42002 -148.993352) (xy 175.438521 -148.978798)
			(xy 175.470287 -148.944065) (xy 175.495114 -148.904077) (xy 175.512153 -148.860201) (xy 175.520821 -148.813938)
			(xy 175.520821 -148.766869) (xy 175.512155 -148.720606) (xy 175.495117 -148.67673) (xy 175.470291 -148.636741)
			(xy 175.438526 -148.602007) (xy 175.42002 -148.58746) (xy 175.398555 -148.570737) (xy 175.360129 -148.532213)
			(xy 175.327566 -148.48862) (xy 175.301527 -148.440843) (xy 175.282541 -148.38985) (xy 175.270993 -148.336678)
			(xy 175.267117 -148.282404) (xy 175.270992 -148.22813) (xy 175.282539 -148.174957) (xy 175.301524 -148.123964)
			(xy 175.327562 -148.076186) (xy 175.360124 -148.032592) (xy 175.39855 -147.994068) (xy 175.42002 -147.977352)
			(xy 175.438521 -147.962798) (xy 175.470287 -147.928065) (xy 175.495114 -147.888077) (xy 175.512153 -147.844201)
			(xy 175.520821 -147.797938) (xy 175.520821 -147.750869) (xy 175.512155 -147.704606) (xy 175.495117 -147.66073)
			(xy 175.470291 -147.620741) (xy 175.438526 -147.586007) (xy 175.42002 -147.57146) (xy 175.398555 -147.554737)
			(xy 175.360129 -147.516213) (xy 175.327566 -147.47262) (xy 175.301527 -147.424843) (xy 175.282541 -147.37385)
			(xy 175.270993 -147.320678) (xy 175.267117 -147.266404) (xy 175.270992 -147.21213) (xy 175.282539 -147.158957)
			(xy 175.301524 -147.107964) (xy 175.327562 -147.060186) (xy 175.360124 -147.016592) (xy 175.39855 -146.978068)
			(xy 175.42002 -146.961352) (xy 175.438521 -146.946798) (xy 175.470287 -146.912065) (xy 175.495114 -146.872077)
			(xy 175.512153 -146.828201) (xy 175.520821 -146.781938) (xy 175.520821 -146.734869) (xy 175.512155 -146.688606)
			(xy 175.495117 -146.64473) (xy 175.470291 -146.604741) (xy 175.438526 -146.570007) (xy 175.42002 -146.55546)
			(xy 175.398555 -146.538737) (xy 175.360129 -146.500213) (xy 175.327566 -146.45662) (xy 175.301527 -146.408843)
			(xy 175.282541 -146.35785) (xy 175.270993 -146.304678) (xy 175.267117 -146.250404) (xy 175.270992 -146.19613)
			(xy 175.282539 -146.142957) (xy 175.301524 -146.091964) (xy 175.327562 -146.044186) (xy 175.360124 -146.000592)
			(xy 175.39855 -145.962068) (xy 175.42002 -145.945352) (xy 175.438521 -145.930798) (xy 175.470287 -145.896065)
			(xy 175.495114 -145.856077) (xy 175.512153 -145.812201) (xy 175.520821 -145.765938) (xy 175.520821 -145.718869)
			(xy 175.512155 -145.672606) (xy 175.495117 -145.62873) (xy 175.470291 -145.588741) (xy 175.438526 -145.554007)
			(xy 175.42002 -145.53946) (xy 175.398555 -145.522737) (xy 175.360129 -145.484213) (xy 175.327566 -145.44062)
			(xy 175.301527 -145.392843) (xy 175.282541 -145.34185) (xy 175.270993 -145.288678) (xy 175.267117 -145.234404)
			(xy 175.270992 -145.18013) (xy 175.282539 -145.126957) (xy 175.301524 -145.075964) (xy 175.327562 -145.028186)
			(xy 175.360124 -144.984592) (xy 175.39855 -144.946068) (xy 175.42002 -144.929352) (xy 175.438521 -144.914798)
			(xy 175.470287 -144.880065) (xy 175.495114 -144.840077) (xy 175.512153 -144.796201) (xy 175.520821 -144.749938)
			(xy 175.520821 -144.702869) (xy 175.512155 -144.656606) (xy 175.495117 -144.61273) (xy 175.470291 -144.572741)
			(xy 175.438526 -144.538007) (xy 175.42002 -144.52346) (xy 175.398555 -144.506737) (xy 175.360129 -144.468213)
			(xy 175.327566 -144.42462) (xy 175.301527 -144.376843) (xy 175.282541 -144.32585) (xy 175.270993 -144.272678)
			(xy 175.267117 -144.218404) (xy 175.270992 -144.16413) (xy 175.282539 -144.110957) (xy 175.301524 -144.059964)
			(xy 175.327562 -144.012186) (xy 175.360124 -143.968592) (xy 175.39855 -143.930068) (xy 175.42002 -143.913352)
			(xy 175.438521 -143.898798) (xy 175.470287 -143.864065) (xy 175.495114 -143.824077) (xy 175.512153 -143.780201)
			(xy 175.520821 -143.733938) (xy 175.520821 -143.686869) (xy 175.512155 -143.640606) (xy 175.495117 -143.59673)
			(xy 175.470291 -143.556741) (xy 175.438526 -143.522007) (xy 175.42002 -143.50746) (xy 175.397315 -143.489712)
			(xy 175.356999 -143.448532) (xy 175.323323 -143.401768) (xy 175.297049 -143.350477) (xy 175.287432 -143.32331)
			(xy 175.281918 -143.308404) (xy 175.264682 -143.281713) (xy 175.241384 -143.26011) (xy 175.213468 -143.244938)
			(xy 175.182669 -143.237137) (xy 175.166782 -143.236696) (xy 174.097696 -143.236696) (xy 171.420028 -145.914364)
			(xy 164.908992 -145.914364) (xy 164.88719 -145.914807) (xy 164.844225 -145.92224) (xy 164.803161 -145.936902)
			(xy 164.765206 -145.958364) (xy 164.731474 -145.985994) (xy 164.702957 -146.018979) (xy 164.680495 -146.056351)
			(xy 164.664746 -146.097011) (xy 164.656174 -146.139763) (xy 164.655031 -146.183351) (xy 164.66135 -146.226494)
			(xy 164.667692 -146.247358) (xy 164.675813 -146.273837) (xy 164.685202 -146.32842) (xy 164.6866 -146.383787)
			(xy 164.679978 -146.438774) (xy 164.665475 -146.492226) (xy 164.643396 -146.543019) (xy 164.614206 -146.590086)
			(xy 164.578516 -146.632439) (xy 164.537079 -146.669185) (xy 164.490763 -146.699555) (xy 164.440543 -146.722909)
			(xy 164.387475 -146.738756) (xy 164.332672 -146.746764) (xy 164.277288 -146.746764) (xy 164.222485 -146.738756)
			(xy 164.169417 -146.722909) (xy 164.119197 -146.699555) (xy 164.072881 -146.669185) (xy 164.031444 -146.632439)
			(xy 163.995754 -146.590086) (xy 163.966564 -146.543019) (xy 163.944485 -146.492226) (xy 163.929982 -146.438774)
			(xy 163.92336 -146.383787) (xy 163.924758 -146.32842) (xy 163.934147 -146.273837) (xy 163.942268 -146.247358)
			(xy 163.948614 -146.226502) (xy 163.954894 -146.183365) (xy 163.953721 -146.139789) (xy 163.94513 -146.097053)
			(xy 163.929373 -146.056409) (xy 163.906912 -146.019049) (xy 163.878406 -145.986071) (xy 163.84469 -145.958439)
			(xy 163.806754 -145.936966) (xy 163.765711 -145.922281) (xy 163.722763 -145.914815) (xy 163.700968 -145.914364)
			(xy 162.999928 -145.914364) (xy 162.976889 -145.914862) (xy 162.931564 -145.923163) (xy 162.888479 -145.939498)
			(xy 162.849043 -145.963331) (xy 162.81455 -145.993883) (xy 162.786128 -146.030152) (xy 162.76471 -146.07095)
			(xy 162.750996 -146.11494) (xy 162.745437 -146.160682) (xy 162.748214 -146.206676) (xy 162.759236 -146.251417)
			(xy 162.778142 -146.293438) (xy 162.790886 -146.312636) (xy 162.806217 -146.335692) (xy 162.830776 -146.385314)
			(xy 162.847907 -146.437965) (xy 162.857249 -146.492538) (xy 162.858606 -146.547888) (xy 162.851949 -146.602854)
			(xy 162.837418 -146.65628) (xy 162.815319 -146.707046) (xy 162.786116 -146.754084) (xy 162.750421 -146.796409)
			(xy 162.708984 -146.833131) (xy 162.662674 -146.863478) (xy 162.612466 -146.886815) (xy 162.559411 -146.90265)
			(xy 162.504626 -146.910652) (xy 162.449258 -146.910652) (xy 162.394473 -146.90265) (xy 162.341418 -146.886815)
			(xy 162.29121 -146.863478) (xy 162.2449 -146.833131) (xy 162.203463 -146.796409) (xy 162.167768 -146.754084)
			(xy 162.138565 -146.707046) (xy 162.116466 -146.65628) (xy 162.101935 -146.602854) (xy 162.095278 -146.547888)
			(xy 162.096635 -146.492538) (xy 162.105977 -146.437965) (xy 162.123108 -146.385314) (xy 162.147667 -146.335692)
			(xy 162.162998 -146.312636) (xy 162.175664 -146.293393) (xy 162.194559 -146.251382) (xy 162.205573 -146.206654)
			(xy 162.208346 -146.160673) (xy 162.202788 -146.114945) (xy 162.18908 -146.070968) (xy 162.167671 -146.030181)
			(xy 162.139262 -145.993919) (xy 162.104784 -145.963372) (xy 162.065365 -145.939537) (xy 162.022296 -145.923197)
			(xy 161.976988 -145.914885) (xy 161.953956 -145.914364) (xy 161.506916 -145.914364) (xy 160.059878 -147.361402)
			(xy 160.887916 -147.361402) (xy 160.891987 -147.30578) (xy 160.904113 -147.251343) (xy 160.924036 -147.199252)
			(xy 160.951332 -147.150617) (xy 160.985418 -147.106474) (xy 161.025567 -147.067765) (xy 161.070925 -147.035314)
			(xy 161.120525 -147.009813) (xy 161.173309 -146.991806) (xy 161.228152 -146.981676) (xy 161.283886 -146.979639)
			(xy 161.339323 -146.985739) (xy 161.39328 -146.999845) (xy 161.444609 -147.021657) (xy 161.492215 -147.050711)
			(xy 161.49319 -147.051522) (xy 165.08298 -147.051522) (xy 165.087051 -146.9959) (xy 165.099177 -146.941463)
			(xy 165.1191 -146.889372) (xy 165.146396 -146.840737) (xy 165.180482 -146.796594) (xy 165.220631 -146.757885)
			(xy 165.265989 -146.725434) (xy 165.315589 -146.699933) (xy 165.368373 -146.681926) (xy 165.423216 -146.671796)
			(xy 165.47895 -146.669759) (xy 165.534387 -146.675859) (xy 165.588344 -146.689965) (xy 165.639673 -146.711777)
			(xy 165.687279 -146.740831) (xy 165.730147 -146.776506) (xy 165.767364 -146.818043) (xy 165.798137 -146.864556)
			(xy 165.821809 -146.915053) (xy 165.837877 -146.96846) (xy 165.845997 -147.023636) (xy 165.846506 -147.051522)
			(xy 165.845997 -147.079408) (xy 165.837877 -147.134584) (xy 165.821809 -147.187991) (xy 165.798137 -147.238488)
			(xy 165.767364 -147.285001) (xy 165.730147 -147.326538) (xy 165.687279 -147.362213) (xy 165.639673 -147.391267)
			(xy 165.588344 -147.413079) (xy 165.534387 -147.427185) (xy 165.47895 -147.433285) (xy 165.423216 -147.431248)
			(xy 165.368373 -147.421118) (xy 165.315589 -147.403111) (xy 165.265989 -147.37761) (xy 165.220631 -147.345159)
			(xy 165.180482 -147.30645) (xy 165.146396 -147.262307) (xy 165.1191 -147.213672) (xy 165.099177 -147.161581)
			(xy 165.087051 -147.107144) (xy 165.08298 -147.051522) (xy 161.49319 -147.051522) (xy 161.535083 -147.086386)
			(xy 161.5723 -147.127923) (xy 161.603073 -147.174436) (xy 161.626745 -147.224933) (xy 161.642813 -147.27834)
			(xy 161.650933 -147.333516) (xy 161.651442 -147.361402) (xy 161.650933 -147.389288) (xy 161.642813 -147.444464)
			(xy 161.626745 -147.497871) (xy 161.603073 -147.548368) (xy 161.5723 -147.594881) (xy 161.535083 -147.636418)
			(xy 161.492215 -147.672093) (xy 161.444609 -147.701147) (xy 161.39328 -147.722959) (xy 161.339323 -147.737065)
			(xy 161.283886 -147.743165) (xy 161.228152 -147.741128) (xy 161.173309 -147.730998) (xy 161.120525 -147.712991)
			(xy 161.070925 -147.68749) (xy 161.025567 -147.655039) (xy 160.985418 -147.61633) (xy 160.951332 -147.572187)
			(xy 160.924036 -147.523552) (xy 160.904113 -147.471461) (xy 160.891987 -147.417024) (xy 160.887916 -147.361402)
			(xy 160.059878 -147.361402) (xy 157.84068 -149.5806) (xy 167.612566 -149.5806) (xy 167.616637 -149.524978)
			(xy 167.628763 -149.470541) (xy 167.648686 -149.41845) (xy 167.675982 -149.369815) (xy 167.710068 -149.325672)
			(xy 167.750217 -149.286963) (xy 167.795575 -149.254512) (xy 167.845175 -149.229011) (xy 167.897959 -149.211004)
			(xy 167.952802 -149.200874) (xy 168.008536 -149.198837) (xy 168.063973 -149.204937) (xy 168.11793 -149.219043)
			(xy 168.169259 -149.240855) (xy 168.216865 -149.269909) (xy 168.259733 -149.305584) (xy 168.29695 -149.347121)
			(xy 168.327723 -149.393634) (xy 168.351395 -149.444131) (xy 168.367463 -149.497538) (xy 168.375583 -149.552714)
			(xy 168.376092 -149.5806) (xy 168.375583 -149.608486) (xy 168.367463 -149.663662) (xy 168.351395 -149.717069)
			(xy 168.327723 -149.767566) (xy 168.29695 -149.814079) (xy 168.259733 -149.855616) (xy 168.216865 -149.891291)
			(xy 168.169259 -149.920345) (xy 168.11793 -149.942157) (xy 168.063973 -149.956263) (xy 168.008536 -149.962363)
			(xy 167.952802 -149.960326) (xy 167.897959 -149.950196) (xy 167.845175 -149.932189) (xy 167.795575 -149.906688)
			(xy 167.750217 -149.874237) (xy 167.710068 -149.835528) (xy 167.675982 -149.791385) (xy 167.648686 -149.74275)
			(xy 167.628763 -149.690659) (xy 167.616637 -149.636222) (xy 167.612566 -149.5806) (xy 157.84068 -149.5806)
			(xy 157.361128 -150.060152) (xy 176.300382 -150.060152) (xy 176.304453 -150.00453) (xy 176.316579 -149.950093)
			(xy 176.336502 -149.898002) (xy 176.363798 -149.849367) (xy 176.397884 -149.805224) (xy 176.438033 -149.766515)
			(xy 176.483391 -149.734064) (xy 176.532991 -149.708563) (xy 176.585775 -149.690556) (xy 176.640618 -149.680426)
			(xy 176.696352 -149.678389) (xy 176.751789 -149.684489) (xy 176.805746 -149.698595) (xy 176.857075 -149.720407)
			(xy 176.904681 -149.749461) (xy 176.947549 -149.785136) (xy 176.984766 -149.826673) (xy 177.015539 -149.873186)
			(xy 177.039211 -149.923683) (xy 177.055279 -149.97709) (xy 177.063399 -150.032266) (xy 177.063908 -150.060152)
			(xy 177.063399 -150.088038) (xy 177.055279 -150.143214) (xy 177.039211 -150.196621) (xy 177.015539 -150.247118)
			(xy 176.984766 -150.293631) (xy 176.947549 -150.335168) (xy 176.904681 -150.370843) (xy 176.857075 -150.399897)
			(xy 176.805746 -150.421709) (xy 176.751789 -150.435815) (xy 176.696352 -150.441915) (xy 176.640618 -150.439878)
			(xy 176.585775 -150.429748) (xy 176.532991 -150.411741) (xy 176.483391 -150.38624) (xy 176.438033 -150.353789)
			(xy 176.397884 -150.31508) (xy 176.363798 -150.270937) (xy 176.336502 -150.222302) (xy 176.316579 -150.170211)
			(xy 176.304453 -150.115774) (xy 176.300382 -150.060152) (xy 157.361128 -150.060152) (xy 153.339546 -154.081734)
			(xy 153.32456 -154.157426) (xy 153.339546 -154.19324) (xy 153.344449 -154.205111) (xy 153.352841 -154.229388)
			(xy 153.35631 -154.241754) (xy 153.36249 -154.262955) (xy 153.381133 -154.302983) (xy 153.406412 -154.339186)
			(xy 153.437567 -154.370477) (xy 153.473661 -154.395914) (xy 153.513607 -154.41473) (xy 153.556204 -154.42636)
			(xy 153.60017 -154.430454) (xy 153.644182 -154.426888) (xy 153.665682 -154.42184) (xy 153.69297 -154.415236)
			(xy 153.748786 -154.409178) (xy 153.804887 -154.411364) (xy 153.860062 -154.421746) (xy 153.913121 -154.4401)
			(xy 153.962918 -154.46603) (xy 154.008378 -154.498976) (xy 154.04852 -154.538227) (xy 154.082479 -154.582936)
			(xy 154.10952 -154.632139) (xy 154.12906 -154.684772) (xy 154.140678 -154.7397) (xy 154.144122 -154.795738)
			(xy 154.139319 -154.851676) (xy 154.126371 -154.906306) (xy 154.105559 -154.958449) (xy 154.077332 -155.006981)
			(xy 154.042299 -155.050853) (xy 154.001215 -155.089118) (xy 153.954969 -155.120951) (xy 153.904557 -155.145665)
			(xy 153.851069 -155.162725) (xy 153.795658 -155.171765) (xy 153.73952 -155.172588) (xy 153.683868 -155.165178)
			(xy 153.629902 -155.149693) (xy 153.578788 -155.126468) (xy 153.531627 -155.096005) (xy 153.48944 -155.058961)
			(xy 153.453135 -155.016135) (xy 153.423496 -154.968453) (xy 153.401164 -154.916942) (xy 153.393394 -154.889962)
			(xy 153.387215 -154.86876) (xy 153.368574 -154.82873) (xy 153.343296 -154.792523) (xy 153.31214 -154.761229)
			(xy 153.276046 -154.735791) (xy 153.236098 -154.716973) (xy 153.1935 -154.705341) (xy 153.149532 -154.701247)
			(xy 153.105518 -154.704812) (xy 153.084022 -154.709876) (xy 153.063194 -154.714702) (xy 153.046203 -154.718698)
			(xy 153.015155 -154.734622) (xy 152.989578 -154.758356) (xy 152.971382 -154.788129) (xy 152.961926 -154.821716)
			(xy 152.96134 -154.839162) (xy 152.96134 -155.8798) (xy 158.01086 -155.8798) (xy 158.01086 -150.40229)
			(xy 158.212536 -150.200868) (xy 163.710874 -150.200868) (xy 163.943792 -150.433786) (xy 163.943792 -150.647654)
			(xy 180.653942 -150.647654) (xy 180.658013 -150.592032) (xy 180.670139 -150.537595) (xy 180.690062 -150.485504)
			(xy 180.717358 -150.436869) (xy 180.751444 -150.392726) (xy 180.791593 -150.354017) (xy 180.836951 -150.321566)
			(xy 180.886551 -150.296065) (xy 180.939335 -150.278058) (xy 180.994178 -150.267928) (xy 181.049912 -150.265891)
			(xy 181.105349 -150.271991) (xy 181.159306 -150.286097) (xy 181.210635 -150.307909) (xy 181.258241 -150.336963)
			(xy 181.301109 -150.372638) (xy 181.338326 -150.414175) (xy 181.369099 -150.460688) (xy 181.392771 -150.511185)
			(xy 181.408839 -150.564592) (xy 181.416959 -150.619768) (xy 181.417468 -150.647654) (xy 181.416959 -150.67554)
			(xy 181.408839 -150.730716) (xy 181.392771 -150.784123) (xy 181.369099 -150.83462) (xy 181.338326 -150.881133)
			(xy 181.301109 -150.92267) (xy 181.258241 -150.958345) (xy 181.210635 -150.987399) (xy 181.159306 -151.009211)
			(xy 181.105349 -151.023317) (xy 181.049912 -151.029417) (xy 180.994178 -151.02738) (xy 180.939335 -151.01725)
			(xy 180.886551 -150.999243) (xy 180.836951 -150.973742) (xy 180.791593 -150.941291) (xy 180.751444 -150.902582)
			(xy 180.717358 -150.858439) (xy 180.690062 -150.809804) (xy 180.670139 -150.757713) (xy 180.658013 -150.703276)
			(xy 180.653942 -150.647654) (xy 163.943792 -150.647654) (xy 163.943792 -151.369522) (xy 168.571162 -151.369522)
			(xy 168.575233 -151.3139) (xy 168.587359 -151.259463) (xy 168.607282 -151.207372) (xy 168.634578 -151.158737)
			(xy 168.668664 -151.114594) (xy 168.708813 -151.075885) (xy 168.754171 -151.043434) (xy 168.803771 -151.017933)
			(xy 168.856555 -150.999926) (xy 168.911398 -150.989796) (xy 168.967132 -150.987759) (xy 169.022569 -150.993859)
			(xy 169.076526 -151.007965) (xy 169.127855 -151.029777) (xy 169.175461 -151.058831) (xy 169.218329 -151.094506)
			(xy 169.255546 -151.136043) (xy 169.286319 -151.182556) (xy 169.309991 -151.233053) (xy 169.326059 -151.28646)
			(xy 169.334179 -151.341636) (xy 169.334688 -151.369522) (xy 169.334179 -151.397408) (xy 169.326059 -151.452584)
			(xy 169.309991 -151.505991) (xy 169.286319 -151.556488) (xy 169.255546 -151.603001) (xy 169.218329 -151.644538)
			(xy 169.175461 -151.680213) (xy 169.127855 -151.709267) (xy 169.076526 -151.731079) (xy 169.022569 -151.745185)
			(xy 168.967132 -151.751285) (xy 168.911398 -151.749248) (xy 168.856555 -151.739118) (xy 168.803771 -151.721111)
			(xy 168.754171 -151.69561) (xy 168.708813 -151.663159) (xy 168.668664 -151.62445) (xy 168.634578 -151.580307)
			(xy 168.607282 -151.531672) (xy 168.587359 -151.479581) (xy 168.575233 -151.425144) (xy 168.571162 -151.369522)
			(xy 163.943792 -151.369522) (xy 163.943792 -152.901904) (xy 168.427144 -152.901904) (xy 168.431215 -152.846282)
			(xy 168.443341 -152.791845) (xy 168.463264 -152.739754) (xy 168.49056 -152.691119) (xy 168.524646 -152.646976)
			(xy 168.564795 -152.608267) (xy 168.610153 -152.575816) (xy 168.659753 -152.550315) (xy 168.712537 -152.532308)
			(xy 168.76738 -152.522178) (xy 168.823114 -152.520141) (xy 168.878551 -152.526241) (xy 168.932508 -152.540347)
			(xy 168.983837 -152.562159) (xy 169.031443 -152.591213) (xy 169.074311 -152.626888) (xy 169.111528 -152.668425)
			(xy 169.142301 -152.714938) (xy 169.165973 -152.765435) (xy 169.182041 -152.818842) (xy 169.190161 -152.874018)
			(xy 169.19067 -152.901904) (xy 169.190161 -152.92979) (xy 169.182041 -152.984966) (xy 169.165973 -153.038373)
			(xy 169.142301 -153.08887) (xy 169.111528 -153.135383) (xy 169.074311 -153.17692) (xy 169.031443 -153.212595)
			(xy 168.983837 -153.241649) (xy 168.932508 -153.263461) (xy 168.878551 -153.277567) (xy 168.823114 -153.283667)
			(xy 168.76738 -153.28163) (xy 168.712537 -153.2715) (xy 168.659753 -153.253493) (xy 168.610153 -153.227992)
			(xy 168.564795 -153.195541) (xy 168.524646 -153.156832) (xy 168.49056 -153.112689) (xy 168.463264 -153.064054)
			(xy 168.443341 -153.011963) (xy 168.431215 -152.957526) (xy 168.427144 -152.901904) (xy 163.943792 -152.901904)
			(xy 163.943792 -154.850435) (xy 166.236406 -154.850435) (xy 166.239874 -154.795852) (xy 166.2511 -154.742323)
			(xy 166.269857 -154.690945) (xy 166.295758 -154.642773) (xy 166.328272 -154.598794) (xy 166.366735 -154.559909)
			(xy 166.410356 -154.526915) (xy 166.458241 -154.500488) (xy 166.50941 -154.481171) (xy 166.562813 -154.469359)
			(xy 166.617356 -154.465295) (xy 166.67192 -154.469061) (xy 166.725387 -154.480581) (xy 166.77666 -154.499618)
			(xy 166.82469 -154.525782) (xy 166.868491 -154.558537) (xy 166.88816 -154.577542) (xy 166.905259 -154.593845)
			(xy 166.944251 -154.620509) (xy 166.987498 -154.639509) (xy 167.033512 -154.650189) (xy 167.080707 -154.652182)
			(xy 167.127458 -154.645418) (xy 167.172153 -154.630132) (xy 167.19296 -154.618944) (xy 167.216979 -154.605866)
			(xy 167.267931 -154.585994) (xy 167.321199 -154.573602) (xy 167.37569 -154.568943) (xy 167.430288 -154.572113)
			(xy 167.483873 -154.583048) (xy 167.535348 -154.601523) (xy 167.583658 -154.62716) (xy 167.627811 -154.659432)
			(xy 167.666903 -154.697679) (xy 167.700132 -154.741116) (xy 167.726818 -154.788853) (xy 167.746414 -154.839912)
			(xy 167.758517 -154.893246) (xy 167.76288 -154.947762) (xy 167.759413 -155.002342) (xy 167.748188 -155.055867)
			(xy 167.729434 -155.107241) (xy 167.703536 -155.155411) (xy 167.671024 -155.199388) (xy 167.632566 -155.238272)
			(xy 167.588949 -155.271265) (xy 167.541068 -155.297692) (xy 167.489903 -155.31701) (xy 167.436504 -155.328824)
			(xy 167.381966 -155.332891) (xy 167.327405 -155.329128) (xy 167.273942 -155.317613) (xy 167.22267 -155.29858)
			(xy 167.174642 -155.272421) (xy 167.130842 -155.239672) (xy 167.111172 -155.22067) (xy 167.094124 -155.204311)
			(xy 167.055121 -155.177648) (xy 167.011863 -155.158654) (xy 166.965839 -155.147981) (xy 166.918636 -155.145998)
			(xy 166.871879 -155.152773) (xy 166.82718 -155.168073) (xy 166.806372 -155.179268) (xy 166.782346 -155.192338)
			(xy 166.731392 -155.212214) (xy 166.678121 -155.22461) (xy 166.623626 -155.229271) (xy 166.569025 -155.226102)
			(xy 166.515435 -155.215169) (xy 166.463956 -155.196694) (xy 166.415643 -155.171057) (xy 166.371486 -155.138784)
			(xy 166.332391 -155.100535) (xy 166.299158 -155.057095) (xy 166.27247 -155.009355) (xy 166.252873 -154.958292)
			(xy 166.240769 -154.904955) (xy 166.236406 -154.850435) (xy 163.943792 -154.850435) (xy 163.943792 -155.83789)
			(xy 163.70046 -156.081476) (xy 158.212536 -156.081476) (xy 158.01086 -155.8798) (xy 152.96134 -155.8798)
			(xy 152.96134 -156.625544) (xy 153.293318 -156.957522) (xy 154.876498 -156.957522) (xy 154.880569 -156.9019)
			(xy 154.892695 -156.847463) (xy 154.912618 -156.795372) (xy 154.939914 -156.746737) (xy 154.974 -156.702594)
			(xy 155.014149 -156.663885) (xy 155.059507 -156.631434) (xy 155.109107 -156.605933) (xy 155.161891 -156.587926)
			(xy 155.216734 -156.577796) (xy 155.272468 -156.575759) (xy 155.327905 -156.581859) (xy 155.381862 -156.595965)
			(xy 155.433191 -156.617777) (xy 155.480797 -156.646831) (xy 155.523665 -156.682506) (xy 155.560882 -156.724043)
			(xy 155.591655 -156.770556) (xy 155.615327 -156.821053) (xy 155.631395 -156.87446) (xy 155.639515 -156.929636)
			(xy 155.640024 -156.957522) (xy 155.639515 -156.985408) (xy 155.631395 -157.040584) (xy 155.615327 -157.093991)
			(xy 155.591655 -157.144488) (xy 155.560882 -157.191001) (xy 155.523665 -157.232538) (xy 155.480797 -157.268213)
			(xy 155.433191 -157.297267) (xy 155.381862 -157.319079) (xy 155.327905 -157.333185) (xy 155.272468 -157.339285)
			(xy 155.216734 -157.337248) (xy 155.161891 -157.327118) (xy 155.109107 -157.309111) (xy 155.059507 -157.28361)
			(xy 155.014149 -157.251159) (xy 154.974 -157.21245) (xy 154.939914 -157.168307) (xy 154.912618 -157.119672)
			(xy 154.892695 -157.067581) (xy 154.880569 -157.013144) (xy 154.876498 -156.957522) (xy 153.293318 -156.957522)
			(xy 153.92908 -157.593284) (xy 165.79342 -157.593284) (xy 168.06418 -155.322524) (xy 168.368726 -155.322524)
			(xy 168.934638 -154.756612) (xy 170.78579 -154.756612) (xy 171.247308 -155.217876) (xy 171.247308 -156.062172)
			(xy 171.53382 -156.348684) (xy 171.53382 -157.819629) (xy 173.712833 -157.819629) (xy 173.713685 -157.763753)
			(xy 173.72268 -157.708599) (xy 173.739626 -157.655347) (xy 173.764159 -157.605138) (xy 173.795755 -157.559045)
			(xy 173.833738 -157.518054) (xy 173.877294 -157.483044) (xy 173.925492 -157.454764) (xy 173.977301 -157.433817)
			(xy 174.031611 -157.420654) (xy 174.087261 -157.415555) (xy 174.143059 -157.418629) (xy 174.197811 -157.429811)
			(xy 174.250347 -157.448862) (xy 174.29954 -157.475373) (xy 174.322232 -157.491684) (xy 174.340725 -157.50489)
			(xy 174.381407 -157.525129) (xy 174.425042 -157.537806) (xy 174.470236 -157.542516) (xy 174.515547 -157.53911)
			(xy 174.559528 -157.527695) (xy 174.600777 -157.508637) (xy 174.619666 -157.496002) (xy 174.642809 -157.480332)
			(xy 174.692793 -157.455323) (xy 174.745891 -157.437874) (xy 174.800967 -157.428359) (xy 174.856841 -157.426981)
			(xy 174.912319 -157.433769) (xy 174.966213 -157.448579) (xy 175.017369 -157.471093) (xy 175.064694 -157.500829)
			(xy 175.107174 -157.537152) (xy 175.143899 -157.579284) (xy 175.149281 -157.58767) (xy 180.367373 -157.58767)
			(xy 180.369875 -157.53231) (xy 180.380357 -157.477895) (xy 180.398598 -157.425567) (xy 180.424216 -157.376427)
			(xy 180.45667 -157.331509) (xy 180.49528 -157.291757) (xy 180.539233 -157.258007) (xy 180.587605 -157.230968)
			(xy 180.639379 -157.211209) (xy 180.693466 -157.199145) (xy 180.748729 -157.19503) (xy 180.804006 -157.198951)
			(xy 180.858135 -157.210824) (xy 180.909978 -157.230401) (xy 180.958444 -157.25727) (xy 181.002515 -157.290866)
			(xy 181.022244 -157.310328) (xy 181.038839 -157.326632) (xy 181.076862 -157.353431) (xy 181.119131 -157.372854)
			(xy 181.164232 -157.384249) (xy 181.210654 -157.387236) (xy 181.256843 -157.381715) (xy 181.301253 -157.36787)
			(xy 181.342397 -157.346165) (xy 181.378897 -157.317327) (xy 181.394608 -157.300168) (xy 181.413248 -157.279658)
			(xy 181.455415 -157.243694) (xy 181.502339 -157.214206) (xy 181.553035 -157.191814) (xy 181.606436 -157.176989)
			(xy 181.661419 -157.170044) (xy 181.716829 -157.171123) (xy 181.771501 -157.180205) (xy 181.824284 -157.197098)
			(xy 181.874069 -157.221447) (xy 181.919809 -157.25274) (xy 181.960543 -157.29032) (xy 181.995413 -157.333395)
			(xy 182.023687 -157.381061) (xy 182.04477 -157.432315) (xy 182.058219 -157.486079) (xy 182.063751 -157.541223)
			(xy 182.06125 -157.596587) (xy 182.060223 -157.60192) (xy 182.51119 -157.60192) (xy 182.515261 -157.546298)
			(xy 182.527387 -157.491861) (xy 182.54731 -157.43977) (xy 182.574606 -157.391135) (xy 182.608692 -157.346992)
			(xy 182.648841 -157.308283) (xy 182.694199 -157.275832) (xy 182.743799 -157.250331) (xy 182.796583 -157.232324)
			(xy 182.851426 -157.222194) (xy 182.90716 -157.220157) (xy 182.962597 -157.226257) (xy 183.016554 -157.240363)
			(xy 183.067883 -157.262175) (xy 183.115489 -157.291229) (xy 183.158357 -157.326904) (xy 183.195574 -157.368441)
			(xy 183.226347 -157.414954) (xy 183.250019 -157.465451) (xy 183.266087 -157.518858) (xy 183.274207 -157.574034)
			(xy 183.274716 -157.60192) (xy 183.274207 -157.629806) (xy 183.266087 -157.684982) (xy 183.250019 -157.738389)
			(xy 183.226347 -157.788886) (xy 183.195574 -157.835399) (xy 183.158357 -157.876936) (xy 183.115489 -157.912611)
			(xy 183.067883 -157.941665) (xy 183.016554 -157.963477) (xy 182.962597 -157.977583) (xy 182.90716 -157.983683)
			(xy 182.851426 -157.981646) (xy 182.796583 -157.971516) (xy 182.743799 -157.953509) (xy 182.694199 -157.928008)
			(xy 182.648841 -157.895557) (xy 182.608692 -157.856848) (xy 182.574606 -157.812705) (xy 182.54731 -157.76407)
			(xy 182.527387 -157.711979) (xy 182.515261 -157.657542) (xy 182.51119 -157.60192) (xy 182.060223 -157.60192)
			(xy 182.050768 -157.651007) (xy 182.032525 -157.703339) (xy 182.006906 -157.752483) (xy 181.974449 -157.797405)
			(xy 181.935837 -157.83716) (xy 181.89188 -157.870913) (xy 181.843504 -157.897955) (xy 181.791726 -157.917715)
			(xy 181.737635 -157.92978) (xy 181.682367 -157.933894) (xy 181.627086 -157.929973) (xy 181.572952 -157.918097)
			(xy 181.521106 -157.898517) (xy 181.472636 -157.871645) (xy 181.428562 -157.838046) (xy 181.408832 -157.818582)
			(xy 181.392159 -157.802364) (xy 181.354148 -157.775572) (xy 181.311893 -157.756153) (xy 181.266807 -157.744755)
			(xy 181.220399 -157.74176) (xy 181.174223 -157.747269) (xy 181.129822 -157.761096) (xy 181.088683 -157.78278)
			(xy 181.052182 -157.811595) (xy 181.036468 -157.828742) (xy 181.017818 -157.849241) (xy 180.975653 -157.8852)
			(xy 180.928731 -157.914683) (xy 180.878039 -157.93707) (xy 180.824641 -157.951891) (xy 180.769662 -157.958833)
			(xy 180.714256 -157.957751) (xy 180.659589 -157.948668) (xy 180.606811 -157.931774) (xy 180.557031 -157.907425)
			(xy 180.511296 -157.876133) (xy 180.470567 -157.838555) (xy 180.4357 -157.795482) (xy 180.40743 -157.747819)
			(xy 180.38635 -157.696569) (xy 180.372903 -157.642809) (xy 180.367373 -157.58767) (xy 175.149281 -157.58767)
			(xy 175.174086 -157.626323) (xy 175.197086 -157.677262) (xy 175.212409 -157.731012) (xy 175.219725 -157.786423)
			(xy 175.21888 -157.842308) (xy 175.20989 -157.897472) (xy 175.192948 -157.950734) (xy 175.168416 -158.000954)
			(xy 175.136821 -158.047058) (xy 175.098837 -158.088059) (xy 175.055277 -158.12308) (xy 175.007075 -158.151371)
			(xy 174.955261 -158.172327) (xy 174.900943 -158.185499) (xy 174.845286 -158.190606) (xy 174.789478 -158.187537)
			(xy 174.734716 -158.17636) (xy 174.68217 -158.157313) (xy 174.632965 -158.130803) (xy 174.610268 -158.114492)
			(xy 174.591775 -158.101287) (xy 174.551092 -158.08105) (xy 174.507458 -158.068374) (xy 174.462264 -158.063664)
			(xy 174.416954 -158.06707) (xy 174.372972 -158.078484) (xy 174.331723 -158.09754) (xy 174.312834 -158.110174)
			(xy 174.289623 -158.125738) (xy 174.239643 -158.150737) (xy 174.186552 -158.168177) (xy 174.131484 -158.177685)
			(xy 174.075618 -158.179056) (xy 174.02015 -158.172263) (xy 173.966266 -158.157449) (xy 173.91512 -158.134933)
			(xy 173.867807 -158.105196) (xy 173.825338 -158.068874) (xy 173.788623 -158.026744) (xy 173.758447 -157.979709)
			(xy 173.735456 -157.928775) (xy 173.720142 -157.875032) (xy 173.712833 -157.819629) (xy 171.53382 -157.819629)
			(xy 171.53382 -159.985964) (xy 174.0408 -162.492944) (xy 183.74868 -162.492944)
		)
		(stroke
			(width 0)
			(type solid)
		)
		(fill yes)
		(layer "In6.Cu")
		(net "P1V9_LAN2")
	)
	(gr_poly
		(pts
			(xy 86.152736 -163.715446) (xy 86.164928 -163.67506) (xy 86.173248 -163.64932) (xy 86.19614 -163.600308)
			(xy 86.225725 -163.555021) (xy 86.261411 -163.514367) (xy 86.302482 -163.479162) (xy 86.348113 -163.450112)
			(xy 86.397391 -163.427798) (xy 86.449327 -163.412669) (xy 86.502879 -163.405028) (xy 86.556973 -163.405028)
			(xy 86.610525 -163.412669) (xy 86.662461 -163.427798) (xy 86.711739 -163.450112) (xy 86.75737 -163.479162)
			(xy 86.798441 -163.514367) (xy 86.834127 -163.555021) (xy 86.863712 -163.600308) (xy 86.886604 -163.64932)
			(xy 86.894924 -163.67506) (xy 86.900096 -163.690475) (xy 86.917065 -163.718197) (xy 86.9405 -163.74072)
			(xy 86.968874 -163.756577) (xy 87.000337 -163.764734) (xy 87.01659 -163.76523) (xy 87.792052 -163.76523)
			(xy 87.815291 -163.764706) (xy 87.860992 -163.756247) (xy 87.904393 -163.73962) (xy 87.944048 -163.71538)
			(xy 87.978635 -163.684333) (xy 88.007002 -163.647517) (xy 88.028202 -163.606156) (xy 88.041529 -163.56163)
			(xy 88.046539 -163.515424) (xy 88.043065 -163.469077) (xy 88.031222 -163.424134) (xy 88.011406 -163.382092)
			(xy 87.9983 -163.362894) (xy 87.982034 -163.339363) (xy 87.955985 -163.288436) (xy 87.93783 -163.234191)
			(xy 87.927979 -163.177843) (xy 87.92665 -163.120656) (xy 87.933874 -163.063911) (xy 87.94949 -163.008881)
			(xy 87.973146 -162.956799) (xy 88.004313 -162.908833) (xy 88.042292 -162.866058) (xy 88.086232 -162.829433)
			(xy 88.135148 -162.799778) (xy 88.187943 -162.777759) (xy 88.243433 -162.763869) (xy 88.271858 -162.76066)
			(xy 88.28779 -162.758661) (xy 88.317964 -162.747711) (xy 88.34445 -162.729577) (xy 88.365573 -162.705407)
			(xy 88.379994 -162.676729) (xy 88.386802 -162.64536) (xy 88.385565 -162.613284) (xy 88.376362 -162.582533)
			(xy 88.359774 -162.555051) (xy 88.336853 -162.532579) (xy 88.323166 -162.524186) (xy 88.302135 -162.511616)
			(xy 88.263155 -162.481932) (xy 88.245442 -162.465004) (xy 88.228927 -162.449337) (xy 88.191417 -162.423557)
			(xy 88.149911 -162.404875) (xy 88.10574 -162.393892) (xy 88.060319 -162.390957) (xy 88.015102 -162.396167)
			(xy 87.971538 -162.409352) (xy 87.951056 -162.419284) (xy 87.925942 -162.431573) (xy 87.872978 -162.449485)
			(xy 87.817967 -162.459474) (xy 87.762088 -162.461327) (xy 87.706536 -162.455004) (xy 87.652502 -162.440641)
			(xy 87.601143 -162.418545) (xy 87.553559 -162.389189) (xy 87.510769 -162.353202) (xy 87.47369 -162.311356)
			(xy 87.443117 -162.264545) (xy 87.419702 -162.213773) (xy 87.403949 -162.160128) (xy 87.396195 -162.104758)
			(xy 87.396605 -162.048849) (xy 87.405172 -161.993598) (xy 87.421711 -161.94019) (xy 87.445868 -161.889768)
			(xy 87.477125 -161.843411) (xy 87.514815 -161.802113) (xy 87.558128 -161.766758) (xy 87.606138 -161.738104)
			(xy 87.657815 -161.716764) (xy 87.712054 -161.703196) (xy 87.767693 -161.697689) (xy 87.82354 -161.700362)
			(xy 87.878398 -161.711158) (xy 87.931093 -161.729845) (xy 87.980497 -161.756023) (xy 88.02555 -161.789132)
			(xy 88.045798 -161.808414) (xy 88.062311 -161.824082) (xy 88.099819 -161.849864) (xy 88.141324 -161.868545)
			(xy 88.185494 -161.879526) (xy 88.230915 -161.882455) (xy 88.27613 -161.877238) (xy 88.31969 -161.864043)
			(xy 88.340184 -161.854134) (xy 88.364523 -161.842217) (xy 88.415774 -161.824613) (xy 88.469001 -161.81444)
			(xy 88.523133 -161.811903) (xy 88.577078 -161.817054) (xy 88.629752 -161.829787) (xy 88.680092 -161.849848)
			(xy 88.727087 -161.876832) (xy 88.760454 -161.902902) (xy 96.793302 -161.902902) (xy 96.797373 -161.84728)
			(xy 96.809499 -161.792843) (xy 96.829422 -161.740752) (xy 96.856718 -161.692117) (xy 96.890804 -161.647974)
			(xy 96.930953 -161.609265) (xy 96.976311 -161.576814) (xy 97.025911 -161.551313) (xy 97.078695 -161.533306)
			(xy 97.133538 -161.523176) (xy 97.189272 -161.521139) (xy 97.244709 -161.527239) (xy 97.298666 -161.541345)
			(xy 97.349995 -161.563157) (xy 97.397601 -161.592211) (xy 97.440469 -161.627886) (xy 97.477686 -161.669423)
			(xy 97.508459 -161.715936) (xy 97.532131 -161.766433) (xy 97.548199 -161.81984) (xy 97.556319 -161.875016)
			(xy 97.556828 -161.902902) (xy 97.556319 -161.930788) (xy 97.548199 -161.985964) (xy 97.532131 -162.039371)
			(xy 97.508459 -162.089868) (xy 97.477686 -162.136381) (xy 97.440469 -162.177918) (xy 97.397601 -162.213593)
			(xy 97.349995 -162.242647) (xy 97.298666 -162.264459) (xy 97.244709 -162.278565) (xy 97.189272 -162.284665)
			(xy 97.133538 -162.282628) (xy 97.078695 -162.272498) (xy 97.025911 -162.254491) (xy 96.976311 -162.22899)
			(xy 96.930953 -162.196539) (xy 96.890804 -162.15783) (xy 96.856718 -162.113687) (xy 96.829422 -162.065052)
			(xy 96.809499 -162.012961) (xy 96.797373 -161.958524) (xy 96.793302 -161.902902) (xy 88.760454 -161.902902)
			(xy 88.769789 -161.910196) (xy 88.80734 -161.949268) (xy 88.838982 -161.993261) (xy 88.864079 -162.04129)
			(xy 88.882125 -162.092387) (xy 88.892758 -162.145525) (xy 88.895762 -162.199632) (xy 88.891079 -162.25362)
			(xy 88.878801 -162.306401) (xy 88.859176 -162.356914) (xy 88.832599 -162.40414) (xy 88.799606 -162.447129)
			(xy 88.76086 -162.485016) (xy 88.724374 -162.51174) (xy 104.756202 -162.51174) (xy 104.760273 -162.456118)
			(xy 104.772399 -162.401681) (xy 104.792322 -162.34959) (xy 104.819618 -162.300955) (xy 104.853704 -162.256812)
			(xy 104.893853 -162.218103) (xy 104.939211 -162.185652) (xy 104.988811 -162.160151) (xy 105.041595 -162.142144)
			(xy 105.096438 -162.132014) (xy 105.152172 -162.129977) (xy 105.207609 -162.136077) (xy 105.261566 -162.150183)
			(xy 105.312895 -162.171995) (xy 105.360501 -162.201049) (xy 105.403369 -162.236724) (xy 105.440586 -162.278261)
			(xy 105.471359 -162.324774) (xy 105.495031 -162.375271) (xy 105.511099 -162.428678) (xy 105.519219 -162.483854)
			(xy 105.519728 -162.51174) (xy 105.519219 -162.539626) (xy 105.511099 -162.594802) (xy 105.495031 -162.648209)
			(xy 105.471359 -162.698706) (xy 105.440586 -162.745219) (xy 105.403369 -162.786756) (xy 105.360501 -162.822431)
			(xy 105.312895 -162.851485) (xy 105.261566 -162.873297) (xy 105.207609 -162.887403) (xy 105.152172 -162.893503)
			(xy 105.096438 -162.891466) (xy 105.041595 -162.881336) (xy 104.988811 -162.863329) (xy 104.939211 -162.837828)
			(xy 104.893853 -162.805377) (xy 104.853704 -162.766668) (xy 104.819618 -162.722525) (xy 104.792322 -162.67389)
			(xy 104.772399 -162.621799) (xy 104.760273 -162.567362) (xy 104.756202 -162.51174) (xy 88.724374 -162.51174)
			(xy 88.717142 -162.517037) (xy 88.693498 -162.530282) (xy 88.674277 -162.541064) (xy 88.639553 -162.568195)
			(xy 88.61003 -162.60091) (xy 88.586593 -162.638228) (xy 88.569946 -162.679029) (xy 88.560587 -162.72209)
			(xy 88.558798 -162.766121) (xy 88.564631 -162.8098) (xy 88.577913 -162.851817) (xy 88.598244 -162.890914)
			(xy 88.611202 -162.908742) (xy 88.627243 -162.930511) (xy 88.653677 -162.977683) (xy 88.673187 -163.028115)
			(xy 88.685381 -163.080796) (xy 88.690016 -163.13467) (xy 88.686999 -163.18866) (xy 88.67639 -163.241682)
			(xy 88.658401 -163.292676) (xy 88.633394 -163.34062) (xy 88.61806 -163.362894) (xy 88.604912 -163.382067)
			(xy 88.585089 -163.424113) (xy 88.573241 -163.469062) (xy 88.569764 -163.515417) (xy 88.574774 -163.56163)
			(xy 88.588104 -163.606163) (xy 88.60931 -163.647529) (xy 88.637684 -163.684349) (xy 88.67228 -163.715396)
			(xy 88.711945 -163.739635) (xy 88.755356 -163.756257) (xy 88.801066 -163.764708) (xy 88.824308 -163.76523)
			(xy 91.386406 -163.76523) (xy 91.403712 -163.764647) (xy 91.43705 -163.755346) (xy 91.466664 -163.737429)
			(xy 91.490374 -163.712214) (xy 91.498928 -163.697158) (xy 91.512225 -163.672884) (xy 91.544755 -163.628109)
			(xy 91.583413 -163.588503) (xy 91.627389 -163.554899) (xy 91.675759 -163.528002) (xy 91.727507 -163.508376)
			(xy 91.781548 -163.496433) (xy 91.836748 -163.492424) (xy 91.891948 -163.496433) (xy 91.945989 -163.508376)
			(xy 91.997737 -163.528002) (xy 92.046107 -163.554899) (xy 92.090083 -163.588503) (xy 92.128741 -163.628109)
			(xy 92.161271 -163.672884) (xy 92.174568 -163.697158) (xy 92.183112 -163.71222) (xy 92.206821 -163.737438)
			(xy 92.236439 -163.755349) (xy 92.269783 -163.764635) (xy 92.28709 -163.76523) (xy 92.524834 -163.76523)
			(xy 92.541286 -163.764756) (xy 92.573111 -163.756407) (xy 92.601729 -163.740174) (xy 92.625225 -163.717143)
			(xy 92.634054 -163.703254) (xy 92.648924 -163.679371) (xy 92.68458 -163.635855) (xy 92.726241 -163.598047)
			(xy 92.773002 -163.566767) (xy 92.82385 -163.542693) (xy 92.877682 -163.526348) (xy 92.933331 -163.518086)
			(xy 92.989589 -163.518086) (xy 93.045238 -163.526348) (xy 93.09907 -163.542693) (xy 93.149918 -163.566767)
			(xy 93.196679 -163.598047) (xy 93.23834 -163.635855) (xy 93.273996 -163.679371) (xy 93.288866 -163.703254)
			(xy 93.297745 -163.717097) (xy 93.321262 -163.740072) (xy 93.34986 -163.75629) (xy 93.381648 -163.764678)
			(xy 93.398086 -163.76523) (xy 94.103698 -163.76523) (xy 94.197424 -163.671504) (xy 94.213494 -163.654696)
			(xy 94.239837 -163.616383) (xy 94.258767 -163.573915) (xy 94.269653 -163.528711) (xy 94.272129 -163.48228)
			(xy 94.266115 -163.436175) (xy 94.25181 -163.391934) (xy 94.229692 -163.351035) (xy 94.200501 -163.314845)
			(xy 94.16521 -163.284571) (xy 94.145354 -163.27247) (xy 94.121847 -163.258214) (xy 94.078814 -163.224)
			(xy 94.041136 -163.183965) (xy 94.009594 -163.138937) (xy 93.98484 -163.089849) (xy 93.967388 -163.037716)
			(xy 93.957597 -162.983618) (xy 93.955672 -162.928675) (xy 93.961651 -162.874025) (xy 93.975412 -162.820798)
			(xy 93.996669 -162.770097) (xy 94.024981 -162.722972) (xy 94.059764 -162.680398) (xy 94.100297 -162.643256)
			(xy 94.14574 -162.612315) (xy 94.195153 -162.588216) (xy 94.247514 -162.571458) (xy 94.301737 -162.562388)
			(xy 94.3567 -162.561193) (xy 94.411267 -162.567899) (xy 94.464305 -162.582366) (xy 94.514719 -162.604295)
			(xy 94.561464 -162.633232) (xy 94.603572 -162.668578) (xy 94.640172 -162.709601) (xy 94.670506 -162.755451)
			(xy 94.693945 -162.805181) (xy 94.710005 -162.857759) (xy 94.718354 -162.912098) (xy 94.718818 -162.967073)
			(xy 94.711387 -163.021545) (xy 94.696216 -163.074387) (xy 94.673619 -163.124504) (xy 94.644063 -163.17086)
			(xy 94.62643 -163.191952) (xy 94.595442 -163.227512) (xy 94.595442 -163.274756) (xy 94.595931 -163.291413)
			(xy 94.604546 -163.323592) (xy 94.621199 -163.352444) (xy 94.644754 -163.376) (xy 94.673606 -163.392653)
			(xy 94.705785 -163.401268) (xy 94.722442 -163.401756) (xy 94.84868 -163.401756) (xy 94.87662 -163.373816)
			(xy 97.319846 -163.373816) (xy 97.347786 -163.401756) (xy 99.727512 -163.401756) (xy 99.795076 -163.351718)
			(xy 99.807014 -163.311332) (xy 99.815259 -163.285471) (xy 99.838044 -163.236206) (xy 99.867582 -163.190667)
			(xy 99.903275 -163.149774) (xy 99.944403 -163.114353) (xy 99.990136 -163.085117) (xy 100.03955 -163.062658)
			(xy 100.091649 -163.047428) (xy 100.14538 -163.039736) (xy 100.19966 -163.039736) (xy 100.253391 -163.047428)
			(xy 100.30549 -163.062658) (xy 100.354904 -163.085117) (xy 100.400637 -163.114353) (xy 100.441765 -163.149774)
			(xy 100.477458 -163.190667) (xy 100.506996 -163.236206) (xy 100.529781 -163.285471) (xy 100.538026 -163.311332)
			(xy 100.543182 -163.326771) (xy 100.560129 -163.354548) (xy 100.583556 -163.37713) (xy 100.611937 -163.393047)
			(xy 100.643422 -163.401261) (xy 100.659692 -163.401756) (xy 101.972872 -163.401756) (xy 101.994768 -163.401291)
			(xy 102.03791 -163.393773) (xy 102.079124 -163.378971) (xy 102.117192 -163.357324) (xy 102.150985 -163.329472)
			(xy 102.179505 -163.29624) (xy 102.201906 -163.258612) (xy 102.217527 -163.2177) (xy 102.225903 -163.174717)
			(xy 102.226872 -163.152836) (xy 102.227941 -163.124658) (xy 102.237351 -163.069062) (xy 102.254841 -163.015456)
			(xy 102.280028 -162.965008) (xy 102.312365 -162.918815) (xy 102.351149 -162.877884) (xy 102.395533 -162.843106)
			(xy 102.444552 -162.815238) (xy 102.497138 -162.794888) (xy 102.552147 -162.782497) (xy 102.60838 -162.778337)
			(xy 102.664613 -162.782497) (xy 102.719622 -162.794888) (xy 102.772208 -162.815238) (xy 102.821227 -162.843106)
			(xy 102.865611 -162.877884) (xy 102.904395 -162.918815) (xy 102.936732 -162.965008) (xy 102.961919 -163.015456)
			(xy 102.979409 -163.069062) (xy 102.988819 -163.124658) (xy 102.989888 -163.152836) (xy 102.990782 -163.174725)
			(xy 102.999149 -163.217722) (xy 103.014767 -163.258648) (xy 103.037173 -163.296288) (xy 103.065703 -163.329527)
			(xy 103.099511 -163.357381) (xy 103.137596 -163.379023) (xy 103.178828 -163.393812) (xy 103.221986 -163.40131)
			(xy 103.243888 -163.401756) (xy 106.348784 -163.401756) (xy 107.43692 -162.31362) (xy 107.43692 -159.907478)
			(xy 106.8324 -159.302704) (xy 105.303828 -159.302704) (xy 104.974898 -158.974028) (xy 103.613458 -158.974028)
			(xy 103.591684 -158.974479) (xy 103.548773 -158.981906) (xy 103.507755 -158.996536) (xy 103.469829 -159.01794)
			(xy 103.436105 -159.045494) (xy 103.407569 -159.07839) (xy 103.385055 -159.115668) (xy 103.369222 -159.156237)
			(xy 103.360533 -159.19891) (xy 103.359458 -159.220662) (xy 103.358144 -159.248647) (xy 103.348328 -159.303804)
			(xy 103.33055 -159.356932) (xy 103.305191 -159.406888) (xy 103.272797 -159.452597) (xy 103.234065 -159.493075)
			(xy 103.189829 -159.527453) (xy 103.14104 -159.554989) (xy 103.088747 -159.575092) (xy 103.034077 -159.58733)
			(xy 102.978204 -159.591439) (xy 102.922331 -159.58733) (xy 102.867661 -159.575092) (xy 102.815368 -159.554989)
			(xy 102.766579 -159.527453) (xy 102.722343 -159.493075) (xy 102.683611 -159.452597) (xy 102.651217 -159.406888)
			(xy 102.625858 -159.356932) (xy 102.60808 -159.303804) (xy 102.598264 -159.248647) (xy 102.59695 -159.220662)
			(xy 102.59588 -159.198901) (xy 102.587228 -159.156204) (xy 102.571418 -159.115608) (xy 102.548915 -159.078305)
			(xy 102.520379 -159.045387) (xy 102.486645 -159.01782) (xy 102.448702 -158.996411) (xy 102.407664 -158.98179)
			(xy 102.364733 -158.974383) (xy 102.34295 -158.974028) (xy 88.556592 -158.974028) (xy 88.25992 -158.677356)
			(xy 88.25992 -157.238954) (xy 88.27516 -157.223714) (xy 88.27516 -151.519128) (xy 86.07298 -149.316948)
			(xy 82.786728 -149.316948) (xy 82.770073 -149.317439) (xy 82.737897 -149.326057) (xy 82.70905 -149.342711)
			(xy 82.685499 -149.366266) (xy 82.668849 -149.395116) (xy 82.660237 -149.427293) (xy 82.659728 -149.443948)
			(xy 82.659728 -149.792182) (xy 82.659242 -149.819415) (xy 82.651491 -149.873327) (xy 82.636146 -149.925587)
			(xy 82.61352 -149.975131) (xy 82.584073 -150.020951) (xy 82.548406 -150.062114) (xy 82.507243 -150.097781)
			(xy 82.461423 -150.127228) (xy 82.411879 -150.149854) (xy 82.359619 -150.165199) (xy 82.305707 -150.17295)
			(xy 82.251241 -150.17295) (xy 82.197329 -150.165199) (xy 82.145069 -150.149854) (xy 82.095525 -150.127228)
			(xy 82.049705 -150.097781) (xy 82.008542 -150.062114) (xy 81.972875 -150.020951) (xy 81.943428 -149.975131)
			(xy 81.920802 -149.925587) (xy 81.905457 -149.873327) (xy 81.897706 -149.819415) (xy 81.89722 -149.792182)
			(xy 81.89722 -149.443948) (xy 81.896731 -149.427288) (xy 81.888119 -149.395101) (xy 81.871468 -149.366241)
			(xy 81.847914 -149.342674) (xy 81.819062 -149.326008) (xy 81.78688 -149.317378) (xy 81.77022 -149.316948)
			(xy 78.373986 -149.316948) (xy 77.473556 -150.217378) (xy 80.678272 -150.217378) (xy 80.682343 -150.161756)
			(xy 80.694469 -150.107319) (xy 80.714392 -150.055228) (xy 80.741688 -150.006593) (xy 80.775774 -149.96245)
			(xy 80.815923 -149.923741) (xy 80.861281 -149.89129) (xy 80.910881 -149.865789) (xy 80.963665 -149.847782)
			(xy 81.018508 -149.837652) (xy 81.074242 -149.835615) (xy 81.129679 -149.841715) (xy 81.183636 -149.855821)
			(xy 81.234965 -149.877633) (xy 81.282571 -149.906687) (xy 81.325439 -149.942362) (xy 81.362656 -149.983899)
			(xy 81.393429 -150.030412) (xy 81.417101 -150.080909) (xy 81.433169 -150.134316) (xy 81.441289 -150.189492)
			(xy 81.441798 -150.217378) (xy 81.441289 -150.245264) (xy 81.433169 -150.30044) (xy 81.417101 -150.353847)
			(xy 81.393429 -150.404344) (xy 81.362656 -150.450857) (xy 81.325439 -150.492394) (xy 81.282571 -150.528069)
			(xy 81.234965 -150.557123) (xy 81.183636 -150.578935) (xy 81.129679 -150.593041) (xy 81.074242 -150.599141)
			(xy 81.018508 -150.597104) (xy 80.963665 -150.586974) (xy 80.910881 -150.568967) (xy 80.861281 -150.543466)
			(xy 80.815923 -150.511015) (xy 80.775774 -150.472306) (xy 80.741688 -150.428163) (xy 80.714392 -150.379528)
			(xy 80.694469 -150.327437) (xy 80.682343 -150.273) (xy 80.678272 -150.217378) (xy 77.473556 -150.217378)
			(xy 77.44714 -150.243794) (xy 77.44714 -150.908258) (xy 79.87106 -150.908258) (xy 79.875131 -150.852636)
			(xy 79.887257 -150.798199) (xy 79.90718 -150.746108) (xy 79.934476 -150.697473) (xy 79.968562 -150.65333)
			(xy 80.008711 -150.614621) (xy 80.054069 -150.58217) (xy 80.103669 -150.556669) (xy 80.156453 -150.538662)
			(xy 80.211296 -150.528532) (xy 80.26703 -150.526495) (xy 80.322467 -150.532595) (xy 80.376424 -150.546701)
			(xy 80.427753 -150.568513) (xy 80.475359 -150.597567) (xy 80.518227 -150.633242) (xy 80.555444 -150.674779)
			(xy 80.586217 -150.721292) (xy 80.609889 -150.771789) (xy 80.625957 -150.825196) (xy 80.634077 -150.880372)
			(xy 80.634586 -150.908258) (xy 80.634077 -150.936144) (xy 80.625957 -150.99132) (xy 80.609889 -151.044727)
			(xy 80.586217 -151.095224) (xy 80.555444 -151.141737) (xy 80.518227 -151.183274) (xy 80.475359 -151.218949)
			(xy 80.427753 -151.248003) (xy 80.376424 -151.269815) (xy 80.322467 -151.283921) (xy 80.26703 -151.290021)
			(xy 80.211296 -151.287984) (xy 80.156453 -151.277854) (xy 80.103669 -151.259847) (xy 80.054069 -151.234346)
			(xy 80.008711 -151.201895) (xy 79.968562 -151.163186) (xy 79.934476 -151.119043) (xy 79.90718 -151.070408)
			(xy 79.887257 -151.018317) (xy 79.875131 -150.96388) (xy 79.87106 -150.908258) (xy 77.44714 -150.908258)
			(xy 77.44714 -152.195022) (xy 86.678768 -152.195022) (xy 86.682839 -152.1394) (xy 86.694965 -152.084963)
			(xy 86.714888 -152.032872) (xy 86.742184 -151.984237) (xy 86.77627 -151.940094) (xy 86.816419 -151.901385)
			(xy 86.861777 -151.868934) (xy 86.911377 -151.843433) (xy 86.964161 -151.825426) (xy 87.019004 -151.815296)
			(xy 87.074738 -151.813259) (xy 87.130175 -151.819359) (xy 87.184132 -151.833465) (xy 87.235461 -151.855277)
			(xy 87.283067 -151.884331) (xy 87.325935 -151.920006) (xy 87.363152 -151.961543) (xy 87.393925 -152.008056)
			(xy 87.417597 -152.058553) (xy 87.433665 -152.11196) (xy 87.441785 -152.167136) (xy 87.442294 -152.195022)
			(xy 87.441785 -152.222908) (xy 87.433665 -152.278084) (xy 87.417597 -152.331491) (xy 87.393925 -152.381988)
			(xy 87.363152 -152.428501) (xy 87.325935 -152.470038) (xy 87.283067 -152.505713) (xy 87.235461 -152.534767)
			(xy 87.184132 -152.556579) (xy 87.130175 -152.570685) (xy 87.074738 -152.576785) (xy 87.019004 -152.574748)
			(xy 86.964161 -152.564618) (xy 86.911377 -152.546611) (xy 86.861777 -152.52111) (xy 86.816419 -152.488659)
			(xy 86.77627 -152.44995) (xy 86.742184 -152.405807) (xy 86.714888 -152.357172) (xy 86.694965 -152.305081)
			(xy 86.682839 -152.250644) (xy 86.678768 -152.195022) (xy 77.44714 -152.195022) (xy 77.44714 -152.498298)
			(xy 77.91196 -152.963118) (xy 77.91196 -153.439114) (xy 77.912505 -153.455763) (xy 77.921124 -153.487926)
			(xy 77.937772 -153.516764) (xy 77.961315 -153.540312) (xy 77.99015 -153.556966) (xy 78.022311 -153.565592)
			(xy 78.03896 -153.566114) (xy 80.847692 -153.566114) (xy 80.92186 -153.492962) (xy 80.922368 -153.440638)
			(xy 80.923146 -153.413588) (xy 80.931398 -153.360107) (xy 80.947124 -153.308329) (xy 80.970008 -153.259291)
			(xy 80.999591 -153.21398) (xy 81.03528 -153.173303) (xy 81.076358 -153.138077) (xy 81.122002 -153.109008)
			(xy 81.171295 -153.08668) (xy 81.223248 -153.071542) (xy 81.276819 -153.063895) (xy 81.330933 -153.063895)
			(xy 81.384504 -153.071542) (xy 81.436457 -153.08668) (xy 81.48575 -153.109008) (xy 81.531394 -153.138077)
			(xy 81.572472 -153.173303) (xy 81.608161 -153.21398) (xy 81.637744 -153.259291) (xy 81.660628 -153.308329)
			(xy 81.676354 -153.360107) (xy 81.684606 -153.413588) (xy 81.685384 -153.440638) (xy 81.685892 -153.492962)
			(xy 81.76006 -153.566114) (xy 82.998818 -153.566114) (xy 83.022186 -153.565589) (xy 83.068136 -153.557053)
			(xy 83.111749 -153.540254) (xy 83.151551 -153.515758) (xy 83.1862 -153.484394) (xy 83.214526 -153.447219)
			(xy 83.235571 -153.40549) (xy 83.248627 -153.360614) (xy 83.253251 -153.314107) (xy 83.251802 -153.290778)
			(xy 83.250003 -153.263649) (xy 83.253183 -153.209374) (xy 83.264035 -153.156099) (xy 83.282341 -153.104905)
			(xy 83.307728 -153.056828) (xy 83.339682 -153.012841) (xy 83.377558 -152.973836) (xy 83.420586 -152.940603)
			(xy 83.467897 -152.913814) (xy 83.518531 -152.894012) (xy 83.571464 -152.881599) (xy 83.625622 -152.876825)
			(xy 83.67991 -152.879788) (xy 83.733227 -152.890427) (xy 83.784494 -152.908527) (xy 83.832673 -152.933722)
			(xy 83.876787 -152.9655) (xy 83.915943 -153.003219) (xy 83.949349 -153.046115) (xy 83.976327 -153.093318)
			(xy 83.996331 -153.143872) (xy 84.008956 -153.196755) (xy 84.013946 -153.250894) (xy 84.011201 -153.305193)
			(xy 84.000775 -153.358552) (xy 83.98288 -153.409891) (xy 83.970876 -153.434288) (xy 83.963904 -153.448757)
			(xy 83.956722 -153.480051) (xy 83.957584 -153.512147) (xy 83.966438 -153.54301) (xy 83.98272 -153.570683)
			(xy 83.993736 -153.58237) (xy 84.310961 -153.899595) (xy 85.880564 -153.899595) (xy 85.885813 -153.844557)
			(xy 85.898953 -153.790853) (xy 85.919707 -153.739609) (xy 85.947641 -153.691897) (xy 85.964522 -153.67)
			(xy 85.974822 -153.656282) (xy 85.988296 -153.624747) (xy 85.992891 -153.590762) (xy 85.988276 -153.556781)
			(xy 85.974783 -153.525253) (xy 85.964522 -153.511504) (xy 85.947641 -153.489607) (xy 85.919707 -153.441895)
			(xy 85.898953 -153.390651) (xy 85.885813 -153.336947) (xy 85.880564 -153.281909) (xy 85.883314 -153.226689)
			(xy 85.894007 -153.172445) (xy 85.912418 -153.120313) (xy 85.938161 -153.071384) (xy 85.970699 -153.026684)
			(xy 86.009348 -152.987149) (xy 86.053299 -152.953607) (xy 86.101631 -152.926761) (xy 86.153333 -152.907174)
			(xy 86.207321 -152.895255) (xy 86.262464 -152.891254) (xy 86.317607 -152.895255) (xy 86.371595 -152.907174)
			(xy 86.423297 -152.926761) (xy 86.471629 -152.953607) (xy 86.51558 -152.987149) (xy 86.554229 -153.026684)
			(xy 86.586767 -153.071384) (xy 86.61251 -153.120313) (xy 86.630921 -153.172445) (xy 86.641614 -153.226689)
			(xy 86.644364 -153.281909) (xy 86.639115 -153.336947) (xy 86.625975 -153.390651) (xy 86.605221 -153.441895)
			(xy 86.577287 -153.489607) (xy 86.560406 -153.511504) (xy 86.550194 -153.525283) (xy 86.536705 -153.556796)
			(xy 86.532091 -153.590762) (xy 86.536685 -153.624732) (xy 86.550156 -153.656252) (xy 86.560406 -153.67)
			(xy 86.577287 -153.691897) (xy 86.605221 -153.739609) (xy 86.625975 -153.790853) (xy 86.639115 -153.844557)
			(xy 86.644364 -153.899595) (xy 86.641614 -153.954815) (xy 86.630921 -154.009059) (xy 86.61251 -154.061191)
			(xy 86.586767 -154.11012) (xy 86.554229 -154.15482) (xy 86.51558 -154.194355) (xy 86.471629 -154.227897)
			(xy 86.423297 -154.254743) (xy 86.371595 -154.27433) (xy 86.317607 -154.286249) (xy 86.262464 -154.29025)
			(xy 86.207321 -154.286249) (xy 86.153333 -154.27433) (xy 86.101631 -154.254743) (xy 86.053299 -154.227897)
			(xy 86.009348 -154.194355) (xy 85.970699 -154.15482) (xy 85.938161 -154.11012) (xy 85.912418 -154.061191)
			(xy 85.894007 -154.009059) (xy 85.883314 -153.954815) (xy 85.880564 -153.899595) (xy 84.310961 -153.899595)
			(xy 84.8614 -154.450034) (xy 84.8614 -155.975214) (xy 85.821991 -155.975214) (xy 85.828644 -155.91954)
			(xy 85.843377 -155.865441) (xy 85.865871 -155.814082) (xy 85.895642 -155.766569) (xy 85.913468 -155.744926)
			(xy 85.922917 -155.733273) (xy 85.936539 -155.706548) (xy 85.943542 -155.67738) (xy 85.943538 -155.647384)
			(xy 85.936527 -155.618218) (xy 85.922897 -155.591497) (xy 85.913468 -155.579826) (xy 85.895642 -155.558183)
			(xy 85.865871 -155.51067) (xy 85.843377 -155.459311) (xy 85.828644 -155.405212) (xy 85.821991 -155.349538)
			(xy 85.82356 -155.293491) (xy 85.833318 -155.238277) (xy 85.851055 -155.185087) (xy 85.876388 -155.135067)
			(xy 85.908771 -155.089295) (xy 85.947506 -155.048756) (xy 85.991759 -155.014326) (xy 86.040576 -154.986746)
			(xy 86.092905 -154.96661) (xy 86.147618 -154.954352) (xy 86.203536 -154.950236) (xy 86.259454 -154.954352)
			(xy 86.314167 -154.96661) (xy 86.366496 -154.986746) (xy 86.415313 -155.014326) (xy 86.459566 -155.048756)
			(xy 86.498301 -155.089295) (xy 86.530684 -155.135067) (xy 86.556017 -155.185087) (xy 86.573754 -155.238277)
			(xy 86.583512 -155.293491) (xy 86.585081 -155.349538) (xy 86.578428 -155.405212) (xy 86.563695 -155.459311)
			(xy 86.541201 -155.51067) (xy 86.51143 -155.558183) (xy 86.493604 -155.579826) (xy 86.484196 -155.591512)
			(xy 86.470562 -155.618226) (xy 86.463549 -155.647386) (xy 86.463544 -155.677378) (xy 86.470549 -155.70654)
			(xy 86.484176 -155.733257) (xy 86.493604 -155.744926) (xy 86.51143 -155.766569) (xy 86.541201 -155.814082)
			(xy 86.563695 -155.865441) (xy 86.578428 -155.91954) (xy 86.585081 -155.975214) (xy 86.583512 -156.031261)
			(xy 86.573754 -156.086475) (xy 86.556017 -156.139665) (xy 86.530684 -156.189685) (xy 86.498301 -156.235457)
			(xy 86.459566 -156.275996) (xy 86.415313 -156.310426) (xy 86.366496 -156.338006) (xy 86.314167 -156.358142)
			(xy 86.259454 -156.3704) (xy 86.203536 -156.374516) (xy 86.147618 -156.3704) (xy 86.092905 -156.358142)
			(xy 86.040576 -156.338006) (xy 85.991759 -156.310426) (xy 85.947506 -156.275996) (xy 85.908771 -156.235457)
			(xy 85.876388 -156.189685) (xy 85.851055 -156.139665) (xy 85.833318 -156.086475) (xy 85.82356 -156.031261)
			(xy 85.821991 -155.975214) (xy 84.8614 -155.975214) (xy 84.8614 -157.79106) (xy 85.876855 -157.79106)
			(xy 85.883508 -157.735386) (xy 85.898241 -157.681287) (xy 85.920735 -157.629928) (xy 85.950506 -157.582415)
			(xy 85.968332 -157.560772) (xy 85.977739 -157.549086) (xy 85.99137 -157.522372) (xy 85.998381 -157.493212)
			(xy 85.998385 -157.463221) (xy 85.991381 -157.43406) (xy 85.977758 -157.407342) (xy 85.968332 -157.395672)
			(xy 85.950506 -157.374029) (xy 85.920735 -157.326516) (xy 85.898241 -157.275157) (xy 85.883508 -157.221058)
			(xy 85.876855 -157.165384) (xy 85.878424 -157.109337) (xy 85.888182 -157.054123) (xy 85.905919 -157.000933)
			(xy 85.931252 -156.950913) (xy 85.963635 -156.905141) (xy 86.00237 -156.864602) (xy 86.046623 -156.830172)
			(xy 86.09544 -156.802592) (xy 86.147769 -156.782456) (xy 86.202482 -156.770198) (xy 86.2584 -156.766082)
			(xy 86.314318 -156.770198) (xy 86.369031 -156.782456) (xy 86.42136 -156.802592) (xy 86.470177 -156.830172)
			(xy 86.51443 -156.864602) (xy 86.553165 -156.905141) (xy 86.585548 -156.950913) (xy 86.610881 -157.000933)
			(xy 86.628618 -157.054123) (xy 86.638376 -157.109337) (xy 86.639945 -157.165384) (xy 86.633292 -157.221058)
			(xy 86.618559 -157.275157) (xy 86.596065 -157.326516) (xy 86.566294 -157.374029) (xy 86.548468 -157.395672)
			(xy 86.539018 -157.407326) (xy 86.525392 -157.43405) (xy 86.518387 -157.463218) (xy 86.518391 -157.493215)
			(xy 86.525404 -157.522382) (xy 86.539037 -157.549102) (xy 86.548468 -157.560772) (xy 86.566294 -157.582415)
			(xy 86.596065 -157.629928) (xy 86.618559 -157.681287) (xy 86.633292 -157.735386) (xy 86.639945 -157.79106)
			(xy 86.638376 -157.847107) (xy 86.628618 -157.902321) (xy 86.610881 -157.955511) (xy 86.585548 -158.005531)
			(xy 86.553165 -158.051303) (xy 86.51443 -158.091842) (xy 86.470177 -158.126272) (xy 86.42136 -158.153852)
			(xy 86.369031 -158.173988) (xy 86.314318 -158.186246) (xy 86.2584 -158.190362) (xy 86.202482 -158.186246)
			(xy 86.147769 -158.173988) (xy 86.09544 -158.153852) (xy 86.046623 -158.126272) (xy 86.00237 -158.091842)
			(xy 85.963635 -158.051303) (xy 85.931252 -158.005531) (xy 85.905919 -157.955511) (xy 85.888182 -157.902321)
			(xy 85.878424 -157.847107) (xy 85.876855 -157.79106) (xy 84.8614 -157.79106) (xy 84.8614 -159.950658)
			(xy 91.954602 -159.950658) (xy 91.958673 -159.895036) (xy 91.970799 -159.840599) (xy 91.990722 -159.788508)
			(xy 92.018018 -159.739873) (xy 92.052104 -159.69573) (xy 92.092253 -159.657021) (xy 92.137611 -159.62457)
			(xy 92.187211 -159.599069) (xy 92.239995 -159.581062) (xy 92.294838 -159.570932) (xy 92.350572 -159.568895)
			(xy 92.406009 -159.574995) (xy 92.459966 -159.589101) (xy 92.511295 -159.610913) (xy 92.558901 -159.639967)
			(xy 92.601769 -159.675642) (xy 92.638986 -159.717179) (xy 92.669759 -159.763692) (xy 92.693431 -159.814189)
			(xy 92.709499 -159.867596) (xy 92.717619 -159.922772) (xy 92.718128 -159.950658) (xy 92.717619 -159.978544)
			(xy 92.711593 -160.019492) (xy 97.553524 -160.019492) (xy 97.557595 -159.96387) (xy 97.569721 -159.909433)
			(xy 97.589644 -159.857342) (xy 97.61694 -159.808707) (xy 97.651026 -159.764564) (xy 97.691175 -159.725855)
			(xy 97.736533 -159.693404) (xy 97.786133 -159.667903) (xy 97.838917 -159.649896) (xy 97.89376 -159.639766)
			(xy 97.949494 -159.637729) (xy 98.004931 -159.643829) (xy 98.058888 -159.657935) (xy 98.110217 -159.679747)
			(xy 98.157823 -159.708801) (xy 98.200691 -159.744476) (xy 98.237908 -159.786013) (xy 98.268681 -159.832526)
			(xy 98.292353 -159.883023) (xy 98.308421 -159.93643) (xy 98.316541 -159.991606) (xy 98.31705 -160.019492)
			(xy 98.316541 -160.047378) (xy 98.308421 -160.102554) (xy 98.292353 -160.155961) (xy 98.268681 -160.206458)
			(xy 98.237908 -160.252971) (xy 98.200691 -160.294508) (xy 98.157823 -160.330183) (xy 98.110217 -160.359237)
			(xy 98.058888 -160.381049) (xy 98.004931 -160.395155) (xy 97.949494 -160.401255) (xy 97.89376 -160.399218)
			(xy 97.838917 -160.389088) (xy 97.786133 -160.371081) (xy 97.736533 -160.34558) (xy 97.691175 -160.313129)
			(xy 97.651026 -160.27442) (xy 97.61694 -160.230277) (xy 97.589644 -160.181642) (xy 97.569721 -160.129551)
			(xy 97.557595 -160.075114) (xy 97.553524 -160.019492) (xy 92.711593 -160.019492) (xy 92.709499 -160.03372)
			(xy 92.693431 -160.087127) (xy 92.669759 -160.137624) (xy 92.638986 -160.184137) (xy 92.601769 -160.225674)
			(xy 92.558901 -160.261349) (xy 92.511295 -160.290403) (xy 92.459966 -160.312215) (xy 92.406009 -160.326321)
			(xy 92.350572 -160.332421) (xy 92.294838 -160.330384) (xy 92.239995 -160.320254) (xy 92.187211 -160.302247)
			(xy 92.137611 -160.276746) (xy 92.092253 -160.244295) (xy 92.052104 -160.205586) (xy 92.018018 -160.161443)
			(xy 91.990722 -160.112808) (xy 91.970799 -160.060717) (xy 91.958673 -160.00628) (xy 91.954602 -159.950658)
			(xy 84.8614 -159.950658) (xy 84.8614 -160.490154) (xy 102.767382 -160.490154) (xy 102.771453 -160.434532)
			(xy 102.783579 -160.380095) (xy 102.803502 -160.328004) (xy 102.830798 -160.279369) (xy 102.864884 -160.235226)
			(xy 102.905033 -160.196517) (xy 102.950391 -160.164066) (xy 102.999991 -160.138565) (xy 103.052775 -160.120558)
			(xy 103.107618 -160.110428) (xy 103.163352 -160.108391) (xy 103.218789 -160.114491) (xy 103.272746 -160.128597)
			(xy 103.324075 -160.150409) (xy 103.371681 -160.179463) (xy 103.414549 -160.215138) (xy 103.451766 -160.256675)
			(xy 103.482539 -160.303188) (xy 103.506211 -160.353685) (xy 103.522279 -160.407092) (xy 103.530399 -160.462268)
			(xy 103.530908 -160.490154) (xy 103.530399 -160.51804) (xy 103.522279 -160.573216) (xy 103.506211 -160.626623)
			(xy 103.482539 -160.67712) (xy 103.451766 -160.723633) (xy 103.414549 -160.76517) (xy 103.371681 -160.800845)
			(xy 103.324075 -160.829899) (xy 103.272746 -160.851711) (xy 103.218789 -160.865817) (xy 103.163352 -160.871917)
			(xy 103.107618 -160.86988) (xy 103.052775 -160.85975) (xy 102.999991 -160.841743) (xy 102.950391 -160.816242)
			(xy 102.905033 -160.783791) (xy 102.864884 -160.745082) (xy 102.830798 -160.700939) (xy 102.803502 -160.652304)
			(xy 102.783579 -160.600213) (xy 102.771453 -160.545776) (xy 102.767382 -160.490154) (xy 84.8614 -160.490154)
			(xy 84.8614 -161.011362) (xy 89.355674 -161.011362) (xy 89.359745 -160.95574) (xy 89.371871 -160.901303)
			(xy 89.391794 -160.849212) (xy 89.41909 -160.800577) (xy 89.453176 -160.756434) (xy 89.493325 -160.717725)
			(xy 89.538683 -160.685274) (xy 89.588283 -160.659773) (xy 89.641067 -160.641766) (xy 89.69591 -160.631636)
			(xy 89.751644 -160.629599) (xy 89.807081 -160.635699) (xy 89.861038 -160.649805) (xy 89.912367 -160.671617)
			(xy 89.959973 -160.700671) (xy 90.002841 -160.736346) (xy 90.040058 -160.777883) (xy 90.070831 -160.824396)
			(xy 90.094503 -160.874893) (xy 90.110571 -160.9283) (xy 90.118691 -160.983476) (xy 90.1192 -161.011362)
			(xy 90.118691 -161.039248) (xy 90.111058 -161.091118) (xy 94.415354 -161.091118) (xy 94.419425 -161.035496)
			(xy 94.431551 -160.981059) (xy 94.451474 -160.928968) (xy 94.47877 -160.880333) (xy 94.512856 -160.83619)
			(xy 94.553005 -160.797481) (xy 94.598363 -160.76503) (xy 94.647963 -160.739529) (xy 94.700747 -160.721522)
			(xy 94.75559 -160.711392) (xy 94.811324 -160.709355) (xy 94.866761 -160.715455) (xy 94.920718 -160.729561)
			(xy 94.972047 -160.751373) (xy 95.019653 -160.780427) (xy 95.062521 -160.816102) (xy 95.099738 -160.857639)
			(xy 95.130511 -160.904152) (xy 95.154183 -160.954649) (xy 95.170251 -161.008056) (xy 95.178371 -161.063232)
			(xy 95.17888 -161.091118) (xy 95.178371 -161.119004) (xy 95.170251 -161.17418) (xy 95.154183 -161.227587)
			(xy 95.130511 -161.278084) (xy 95.099738 -161.324597) (xy 95.062521 -161.366134) (xy 95.019653 -161.401809)
			(xy 94.972047 -161.430863) (xy 94.920718 -161.452675) (xy 94.866761 -161.466781) (xy 94.811324 -161.472881)
			(xy 94.75559 -161.470844) (xy 94.700747 -161.460714) (xy 94.647963 -161.442707) (xy 94.598363 -161.417206)
			(xy 94.553005 -161.384755) (xy 94.512856 -161.346046) (xy 94.47877 -161.301903) (xy 94.451474 -161.253268)
			(xy 94.431551 -161.201177) (xy 94.419425 -161.14674) (xy 94.415354 -161.091118) (xy 90.111058 -161.091118)
			(xy 90.110571 -161.094424) (xy 90.094503 -161.147831) (xy 90.070831 -161.198328) (xy 90.040058 -161.244841)
			(xy 90.002841 -161.286378) (xy 89.959973 -161.322053) (xy 89.912367 -161.351107) (xy 89.861038 -161.372919)
			(xy 89.807081 -161.387025) (xy 89.751644 -161.393125) (xy 89.69591 -161.391088) (xy 89.641067 -161.380958)
			(xy 89.588283 -161.362951) (xy 89.538683 -161.33745) (xy 89.493325 -161.304999) (xy 89.453176 -161.26629)
			(xy 89.41909 -161.222147) (xy 89.391794 -161.173512) (xy 89.371871 -161.121421) (xy 89.359745 -161.066984)
			(xy 89.355674 -161.011362) (xy 84.8614 -161.011362) (xy 84.8614 -162.515832) (xy 85.234165 -162.515832)
			(xy 85.235725 -162.46035) (xy 85.245309 -162.405679) (xy 85.262714 -162.352974) (xy 85.287572 -162.303348)
			(xy 85.31936 -162.257847) (xy 85.357405 -162.217433) (xy 85.400905 -162.182959) (xy 85.448942 -162.155153)
			(xy 85.500501 -162.134601) (xy 85.554494 -162.121737) (xy 85.609781 -162.116833) (xy 85.665196 -162.119992)
			(xy 85.719567 -162.131149) (xy 85.745828 -162.140138) (xy 85.768009 -162.147606) (xy 85.814175 -162.155252)
			(xy 85.860962 -162.154316) (xy 85.906786 -162.14483) (xy 85.950098 -162.127115) (xy 85.989436 -162.101769)
			(xy 86.023468 -162.06965) (xy 86.051044 -162.031842) (xy 86.071232 -161.989626) (xy 86.077806 -161.967164)
			(xy 86.085466 -161.940482) (xy 86.107422 -161.889499) (xy 86.136535 -161.842236) (xy 86.172189 -161.799691)
			(xy 86.213633 -161.762761) (xy 86.25999 -161.732227) (xy 86.310283 -161.708734) (xy 86.36345 -161.692777)
			(xy 86.418368 -161.684692) (xy 86.473878 -161.684652) (xy 86.528808 -161.692656) (xy 86.581998 -161.708536)
			(xy 86.632325 -161.731957) (xy 86.678727 -161.762423) (xy 86.720224 -161.799293) (xy 86.75594 -161.841786)
			(xy 86.785121 -161.889007) (xy 86.807151 -161.939958) (xy 86.821565 -161.993564) (xy 86.828059 -162.048693)
			(xy 86.826494 -162.104181) (xy 86.816906 -162.158856) (xy 86.799495 -162.211565) (xy 86.77463 -162.261194)
			(xy 86.742835 -162.306696) (xy 86.704782 -162.34711) (xy 86.661273 -162.381583) (xy 86.613229 -162.409387)
			(xy 86.561662 -162.429935) (xy 86.507662 -162.442793) (xy 86.452369 -162.447691) (xy 86.396949 -162.444523)
			(xy 86.342574 -162.433358) (xy 86.316312 -162.424364) (xy 86.294117 -162.416941) (xy 86.247955 -162.40929)
			(xy 86.201173 -162.41022) (xy 86.155351 -162.4197) (xy 86.11204 -162.437409) (xy 86.072704 -162.462749)
			(xy 86.038673 -162.494864) (xy 86.011097 -162.532666) (xy 85.990909 -162.574879) (xy 85.984334 -162.597338)
			(xy 85.976707 -162.624026) (xy 85.954751 -162.675003) (xy 85.92564 -162.72226) (xy 85.889988 -162.7648)
			(xy 85.848547 -162.801725) (xy 85.802194 -162.832255) (xy 85.751906 -162.855746) (xy 85.698744 -162.871701)
			(xy 85.643831 -162.879785) (xy 85.588327 -162.879825) (xy 85.533403 -162.871823) (xy 85.480218 -162.855945)
			(xy 85.429895 -162.832528) (xy 85.383497 -162.802066) (xy 85.342003 -162.765202) (xy 85.306288 -162.722714)
			(xy 85.277108 -162.675499) (xy 85.255077 -162.624555) (xy 85.240662 -162.570955) (xy 85.234165 -162.515832)
			(xy 84.8614 -162.515832) (xy 84.8614 -163.098226) (xy 84.868512 -163.118546) (xy 84.87657 -163.142886)
			(xy 84.886834 -163.193121) (xy 84.890278 -163.244277) (xy 84.88684 -163.295434) (xy 84.876582 -163.34567)
			(xy 84.868512 -163.370006) (xy 84.8614 -163.390326) (xy 84.8614 -163.55695) (xy 85.06968 -163.76523)
			(xy 86.085426 -163.76523)
		)
		(stroke
			(width 0)
			(type solid)
		)
		(fill yes)
		(layer "In6.Cu")
		(net "P12V_AUX")
	)
	(gr_poly
		(pts
			(xy 68.853558 -178.09972) (xy 68.875307 -178.098581) (xy 68.91796 -178.089797) (xy 68.95849 -178.073868)
			(xy 68.99571 -178.051261) (xy 69.02853 -178.022638) (xy 69.055988 -177.988837) (xy 69.07728 -177.950849)
			(xy 69.091782 -177.909786) (xy 69.099069 -177.866852) (xy 69.098928 -177.823305) (xy 69.09562 -177.801778)
			(xy 69.091347 -177.774373) (xy 69.089833 -177.71893) (xy 69.096361 -177.663852) (xy 69.110794 -177.6103)
			(xy 69.132828 -177.559401) (xy 69.161998 -177.512228) (xy 69.197691 -177.469775) (xy 69.239153 -177.432937)
			(xy 69.285512 -177.402489) (xy 69.335791 -177.379073) (xy 69.388929 -177.363184) (xy 69.443808 -177.355154)
			(xy 69.499272 -177.355154) (xy 69.554151 -177.363184) (xy 69.607289 -177.379073) (xy 69.657568 -177.402489)
			(xy 69.703927 -177.432937) (xy 69.745389 -177.469775) (xy 69.781082 -177.512228) (xy 69.810252 -177.559401)
			(xy 69.832286 -177.6103) (xy 69.846719 -177.663852) (xy 69.853247 -177.71893) (xy 69.851733 -177.774373)
			(xy 69.84746 -177.801778) (xy 69.844148 -177.823678) (xy 69.844257 -177.867965) (xy 69.852039 -177.911564)
			(xy 69.86726 -177.953154) (xy 69.889459 -177.991476) (xy 69.917964 -178.025371) (xy 69.951912 -178.053813)
			(xy 69.990276 -178.07594) (xy 70.031894 -178.091084) (xy 70.075506 -178.098785) (xy 70.09765 -178.099212)
			(xy 71.30542 -178.099212) (xy 71.96582 -177.438812) (xy 71.96582 -172.304964) (xy 71.625714 -171.964858)
			(xy 71.609668 -171.949478) (xy 71.573244 -171.924013) (xy 71.532949 -171.905263) (xy 71.490009 -171.8938)
			(xy 71.445731 -171.889971) (xy 71.401461 -171.893893) (xy 71.358546 -171.905447) (xy 71.31829 -171.924282)
			(xy 71.299832 -171.936664) (xy 71.276566 -171.952444) (xy 71.226357 -171.977729) (xy 71.17298 -171.995371)
			(xy 71.117592 -172.00499) (xy 71.061393 -172.006375) (xy 71.005598 -171.999499) (xy 70.951417 -171.984509)
			(xy 70.900022 -171.96173) (xy 70.852527 -171.931655) (xy 70.809959 -171.894936) (xy 70.773241 -171.852368)
			(xy 70.743167 -171.804872) (xy 70.720389 -171.753477) (xy 70.7054 -171.699295) (xy 70.698524 -171.643501)
			(xy 70.699911 -171.587301) (xy 70.70953 -171.531914) (xy 70.727173 -171.478538) (xy 70.752459 -171.428329)
			(xy 70.76821 -171.405042) (xy 70.780646 -171.386605) (xy 70.799547 -171.346355) (xy 70.811149 -171.303428)
			(xy 70.815095 -171.259136) (xy 70.811266 -171.214833) (xy 70.799778 -171.171876) (xy 70.780982 -171.131576)
			(xy 70.755454 -171.095166) (xy 70.740016 -171.07916) (xy 70.65645 -170.995594) (xy 70.644279 -170.984241)
			(xy 70.61544 -170.967652) (xy 70.583296 -170.959067) (xy 70.550026 -170.959067) (xy 70.517882 -170.967652)
			(xy 70.489043 -170.984241) (xy 70.476872 -170.995594) (xy 70.466458 -171.006008) (xy 70.456044 -171.022518)
			(xy 70.45198 -171.028614) (xy 70.436777 -171.050658) (xy 70.401178 -171.090661) (xy 70.360331 -171.12529)
			(xy 70.315041 -171.153861) (xy 70.266199 -171.175815) (xy 70.214765 -171.190718) (xy 70.188328 -171.194984)
			(xy 70.15607 -171.199556) (xy 70.048628 -171.280328) (xy 70.035166 -171.310046) (xy 70.023265 -171.335193)
			(xy 69.993259 -171.38204) (xy 69.956767 -171.424032) (xy 69.914564 -171.46028) (xy 69.867544 -171.490014)
			(xy 69.816704 -171.512604) (xy 69.763123 -171.527572) (xy 69.707936 -171.534599) (xy 69.652313 -171.533537)
			(xy 69.597434 -171.524407) (xy 69.544463 -171.507405) (xy 69.494523 -171.48289) (xy 69.448673 -171.451382)
			(xy 69.407884 -171.41355) (xy 69.373023 -171.370195) (xy 69.344827 -171.322236) (xy 69.323896 -171.270691)
			(xy 69.310672 -171.216653) (xy 69.305436 -171.161267) (xy 69.3083 -171.105708) (xy 69.319202 -171.051154)
			(xy 69.337911 -170.998762) (xy 69.364031 -170.949642) (xy 69.397007 -170.904836) (xy 69.436141 -170.865294)
			(xy 69.480603 -170.831856) (xy 69.529449 -170.805228) (xy 69.581645 -170.785977) (xy 69.636084 -170.774511)
			(xy 69.663818 -170.772328) (xy 69.678541 -170.77095) (xy 69.706813 -170.762311) (xy 69.732341 -170.747403)
			(xy 69.753758 -170.727026) (xy 69.769918 -170.702271) (xy 69.775324 -170.688508) (xy 69.784871 -170.663264)
			(xy 69.810065 -170.615534) (xy 69.841738 -170.571834) (xy 69.86016 -170.55211) (xy 69.875032 -170.536007)
			(xy 69.899577 -170.499694) (xy 69.917535 -170.459712) (xy 69.928375 -170.417244) (xy 69.931776 -170.373546)
			(xy 69.927636 -170.329911) (xy 69.91608 -170.287632) (xy 69.897448 -170.247959) (xy 69.872293 -170.212067)
			(xy 69.857112 -170.196256) (xy 69.054726 -169.39387) (xy 69.042104 -169.382029) (xy 69.011998 -169.36499)
			(xy 68.97842 -169.356667) (xy 68.943841 -169.357671) (xy 68.910804 -169.367929) (xy 68.895976 -169.376852)
			(xy 68.872797 -169.39125) (xy 68.823196 -169.413993) (xy 68.770861 -169.429436) (xy 68.716859 -169.437265)
			(xy 68.662293 -169.437319) (xy 68.608276 -169.429597) (xy 68.55591 -169.414257) (xy 68.506265 -169.391612)
			(xy 68.460353 -169.362124) (xy 68.419111 -169.326394) (xy 68.383381 -169.285153) (xy 68.353892 -169.239242)
			(xy 68.331246 -169.189597) (xy 68.315905 -169.137231) (xy 68.308182 -169.083214) (xy 68.308235 -169.028648)
			(xy 68.316062 -168.974646) (xy 68.331504 -168.922311) (xy 68.354247 -168.87271) (xy 68.368672 -168.849548)
			(xy 68.393056 -168.811702) (xy 68.383404 -168.722548) (xy 68.351654 -168.690798) (xy 66.51244 -166.851584)
			(xy 66.51244 -159.962342) (xy 66.511951 -159.945682) (xy 66.503337 -159.913494) (xy 66.486686 -159.884632)
			(xy 66.463133 -159.861064) (xy 66.434282 -159.844394) (xy 66.4021 -159.83576) (xy 66.38544 -159.835342)
			(xy 63.76416 -159.835342) (xy 63.70574 -159.86887) (xy 63.688722 -159.898334) (xy 63.67158 -159.92675)
			(xy 63.631041 -159.979291) (xy 63.584007 -160.026107) (xy 63.531277 -160.0664) (xy 63.473749 -160.099484)
			(xy 63.412404 -160.124797) (xy 63.348284 -160.141906) (xy 63.282483 -160.150521) (xy 63.249302 -160.151064)
			(xy 62.505336 -160.151064) (xy 62.483716 -160.151471) (xy 62.441093 -160.158739) (xy 62.400317 -160.173123)
			(xy 62.362566 -160.194206) (xy 62.328933 -160.221379) (xy 62.300389 -160.253858) (xy 62.27776 -160.290702)
			(xy 62.261699 -160.330847) (xy 62.252671 -160.373132) (xy 62.250936 -160.416336) (xy 62.256545 -160.45921)
			(xy 62.262512 -160.479994) (xy 62.270299 -160.506892) (xy 62.278814 -160.562236) (xy 62.279147 -160.61823)
			(xy 62.271291 -160.673672) (xy 62.255415 -160.72737) (xy 62.231859 -160.77817) (xy 62.20113 -160.82498)
			(xy 62.163889 -160.866796) (xy 62.120934 -160.902718) (xy 62.07319 -160.931975) (xy 62.021682 -160.953939)
			(xy 61.967516 -160.968136) (xy 61.911857 -160.974263) (xy 61.8559 -160.972188) (xy 61.800847 -160.961954)
			(xy 61.747882 -160.943783) (xy 61.698142 -160.918064) (xy 61.652697 -160.88535) (xy 61.612521 -160.846345)
			(xy 61.57848 -160.801885) (xy 61.551304 -160.752926) (xy 61.531576 -160.700521) (xy 61.519721 -160.645795)
			(xy 61.515994 -160.589923) (xy 61.520475 -160.534108) (xy 61.533066 -160.479546) (xy 61.553499 -160.427412)
			(xy 61.581333 -160.378824) (xy 61.598302 -160.35655) (xy 61.62548 -160.322006) (xy 61.62548 -160.278064)
			(xy 61.624932 -160.26142) (xy 61.616308 -160.229267) (xy 61.599657 -160.200443) (xy 61.576113 -160.176909)
			(xy 61.547281 -160.16027) (xy 61.515125 -160.15166) (xy 61.49848 -160.151064) (xy 61.450728 -160.151064)
			(xy 61.135006 -159.835342) (xy 60.577476 -159.835342) (xy 60.470796 -159.89554) (xy 60.454286 -159.919162)
			(xy 60.437685 -159.941877) (xy 60.398902 -159.982634) (xy 60.354556 -160.017256) (xy 60.305609 -160.044995)
			(xy 60.253121 -160.065249) (xy 60.198228 -160.07758) (xy 60.14212 -160.08172) (xy 60.086012 -160.07758)
			(xy 60.031119 -160.065249) (xy 59.978631 -160.044995) (xy 59.929684 -160.017256) (xy 59.885338 -159.982634)
			(xy 59.846555 -159.941877) (xy 59.829954 -159.919162) (xy 59.813444 -159.89554) (xy 59.706764 -159.835342)
			(xy 58.613802 -159.835342) (xy 58.591274 -159.83582) (xy 58.546922 -159.843754) (xy 58.504667 -159.859392)
			(xy 58.465836 -159.882243) (xy 58.431647 -159.911588) (xy 58.403174 -159.946507) (xy 58.381312 -159.985904)
			(xy 58.366746 -160.02854) (xy 58.36285 -160.050734) (xy 58.358211 -160.077798) (xy 58.342185 -160.130316)
			(xy 58.318799 -160.179996) (xy 58.288535 -160.225811) (xy 58.252018 -160.266817) (xy 58.210001 -160.302167)
			(xy 58.163353 -160.331131) (xy 58.113035 -160.353111) (xy 58.060087 -160.367654) (xy 58.032904 -160.371536)
			(xy 57.988962 -160.37687) (xy 57.866534 -160.50133) (xy 57.866534 -161.97199) (xy 59.180982 -161.97199)
			(xy 59.185053 -161.916368) (xy 59.197179 -161.861931) (xy 59.217102 -161.80984) (xy 59.244398 -161.761205)
			(xy 59.278484 -161.717062) (xy 59.318633 -161.678353) (xy 59.363991 -161.645902) (xy 59.413591 -161.620401)
			(xy 59.466375 -161.602394) (xy 59.521218 -161.592264) (xy 59.576952 -161.590227) (xy 59.632389 -161.596327)
			(xy 59.686346 -161.610433) (xy 59.737675 -161.632245) (xy 59.785281 -161.661299) (xy 59.828149 -161.696974)
			(xy 59.865366 -161.738511) (xy 59.896139 -161.785024) (xy 59.919811 -161.835521) (xy 59.935879 -161.888928)
			(xy 59.943999 -161.944104) (xy 59.944508 -161.97199) (xy 59.943999 -161.999876) (xy 59.935879 -162.055052)
			(xy 59.919811 -162.108459) (xy 59.896139 -162.158956) (xy 59.865366 -162.205469) (xy 59.828149 -162.247006)
			(xy 59.785281 -162.282681) (xy 59.737675 -162.311735) (xy 59.686346 -162.333547) (xy 59.632389 -162.347653)
			(xy 59.576952 -162.353753) (xy 59.521218 -162.351716) (xy 59.466375 -162.341586) (xy 59.413591 -162.323579)
			(xy 59.363991 -162.298078) (xy 59.318633 -162.265627) (xy 59.278484 -162.226918) (xy 59.244398 -162.182775)
			(xy 59.217102 -162.13414) (xy 59.197179 -162.082049) (xy 59.185053 -162.027612) (xy 59.180982 -161.97199)
			(xy 57.866534 -161.97199) (xy 57.866534 -162.485578) (xy 57.866983 -162.507466) (xy 57.874472 -162.550598)
			(xy 57.889248 -162.591805) (xy 57.910874 -162.629867) (xy 57.938709 -162.663655) (xy 57.971927 -162.692167)
			(xy 58.009543 -162.714559) (xy 58.050443 -162.730165) (xy 58.093414 -162.738525) (xy 58.137182 -162.739389)
			(xy 58.158888 -162.73653) (xy 58.18604 -162.732861) (xy 58.240828 -162.73242) (xy 58.295115 -162.739821)
			(xy 58.347786 -162.75491) (xy 58.397756 -162.777378) (xy 58.443999 -162.806763) (xy 58.485564 -162.84246)
			(xy 58.521595 -162.883736) (xy 58.551351 -162.929741) (xy 58.574221 -162.979529) (xy 58.589734 -163.032076)
			(xy 58.597572 -163.086302) (xy 58.597572 -163.105592) (xy 60.176662 -163.105592) (xy 60.180733 -163.04997)
			(xy 60.192859 -162.995533) (xy 60.212782 -162.943442) (xy 60.240078 -162.894807) (xy 60.274164 -162.850664)
			(xy 60.314313 -162.811955) (xy 60.359671 -162.779504) (xy 60.409271 -162.754003) (xy 60.462055 -162.735996)
			(xy 60.516898 -162.725866) (xy 60.572632 -162.723829) (xy 60.628069 -162.729929) (xy 60.682026 -162.744035)
			(xy 60.733355 -162.765847) (xy 60.780961 -162.794901) (xy 60.823829 -162.830576) (xy 60.861046 -162.872113)
			(xy 60.891819 -162.918626) (xy 60.915491 -162.969123) (xy 60.931559 -163.02253) (xy 60.939679 -163.077706)
			(xy 60.940188 -163.105592) (xy 60.939679 -163.133478) (xy 60.931559 -163.188654) (xy 60.915491 -163.242061)
			(xy 60.891819 -163.292558) (xy 60.861046 -163.339071) (xy 60.823829 -163.380608) (xy 60.780961 -163.416283)
			(xy 60.733355 -163.445337) (xy 60.682026 -163.467149) (xy 60.628069 -163.481255) (xy 60.572632 -163.487355)
			(xy 60.516898 -163.485318) (xy 60.462055 -163.475188) (xy 60.409271 -163.457181) (xy 60.359671 -163.43168)
			(xy 60.314313 -163.399229) (xy 60.274164 -163.36052) (xy 60.240078 -163.316377) (xy 60.212782 -163.267742)
			(xy 60.192859 -163.215651) (xy 60.180733 -163.161214) (xy 60.176662 -163.105592) (xy 58.597572 -163.105592)
			(xy 58.597572 -163.141092) (xy 58.589735 -163.195318) (xy 58.574223 -163.247866) (xy 58.551354 -163.297654)
			(xy 58.521598 -163.343659) (xy 58.485568 -163.384935) (xy 58.444004 -163.420633) (xy 58.397762 -163.450019)
			(xy 58.347791 -163.472488) (xy 58.295121 -163.487578) (xy 58.240834 -163.494979) (xy 58.186046 -163.49454)
			(xy 58.158888 -163.49091) (xy 58.137188 -163.488064) (xy 58.093436 -163.488977) (xy 58.050486 -163.497369)
			(xy 58.009609 -163.512992) (xy 57.972011 -163.535386) (xy 57.938804 -163.563888) (xy 57.910968 -163.597656)
			(xy 57.889328 -163.635693) (xy 57.874521 -163.676873) (xy 57.866986 -163.719982) (xy 57.866534 -163.741862)
			(xy 57.866534 -164.689282) (xy 62.98133 -164.689282) (xy 62.985401 -164.63366) (xy 62.997527 -164.579223)
			(xy 63.01745 -164.527132) (xy 63.044746 -164.478497) (xy 63.078832 -164.434354) (xy 63.118981 -164.395645)
			(xy 63.164339 -164.363194) (xy 63.213939 -164.337693) (xy 63.266723 -164.319686) (xy 63.321566 -164.309556)
			(xy 63.3773 -164.307519) (xy 63.432737 -164.313619) (xy 63.486694 -164.327725) (xy 63.538023 -164.349537)
			(xy 63.585629 -164.378591) (xy 63.628497 -164.414266) (xy 63.665714 -164.455803) (xy 63.696487 -164.502316)
			(xy 63.720159 -164.552813) (xy 63.736227 -164.60622) (xy 63.744347 -164.661396) (xy 63.744856 -164.689282)
			(xy 63.744347 -164.717168) (xy 63.736227 -164.772344) (xy 63.720159 -164.825751) (xy 63.696487 -164.876248)
			(xy 63.665714 -164.922761) (xy 63.628497 -164.964298) (xy 63.585629 -164.999973) (xy 63.538023 -165.029027)
			(xy 63.486694 -165.050839) (xy 63.432737 -165.064945) (xy 63.3773 -165.071045) (xy 63.321566 -165.069008)
			(xy 63.266723 -165.058878) (xy 63.213939 -165.040871) (xy 63.164339 -165.01537) (xy 63.118981 -164.982919)
			(xy 63.078832 -164.94421) (xy 63.044746 -164.900067) (xy 63.01745 -164.851432) (xy 62.997527 -164.799341)
			(xy 62.985401 -164.744904) (xy 62.98133 -164.689282) (xy 57.866534 -164.689282) (xy 57.866534 -165.17239)
			(xy 57.866985 -165.194118) (xy 57.874389 -165.236939) (xy 57.888966 -165.277878) (xy 57.910292 -165.315743)
			(xy 57.937745 -165.349429) (xy 57.970526 -165.377958) (xy 58.007681 -165.400497) (xy 58.048127 -165.416391)
			(xy 58.090686 -165.425177) (xy 58.13412 -165.426598) (xy 58.177162 -165.420613) (xy 58.198004 -165.414452)
			(xy 58.225418 -165.406214) (xy 58.281929 -165.397103) (xy 58.339167 -165.396539) (xy 58.395846 -165.404535)
			(xy 58.450695 -165.420911) (xy 58.50248 -165.445299) (xy 58.550039 -165.477152) (xy 58.592305 -165.515754)
			(xy 58.610754 -165.537642) (xy 58.626001 -165.555625) (xy 58.661936 -165.58614) (xy 58.70288 -165.609509)
			(xy 58.747429 -165.62493) (xy 58.794058 -165.631875) (xy 58.841168 -165.630106) (xy 58.887144 -165.619685)
			(xy 58.930412 -165.600967) (xy 58.969488 -165.574594) (xy 59.003034 -165.541471) (xy 59.0169 -165.522402)
			(xy 59.033312 -165.499619) (xy 59.071734 -165.458674) (xy 59.115741 -165.423802) (xy 59.164384 -165.395756)
			(xy 59.216612 -165.375142) (xy 59.271297 -165.362404) (xy 59.327258 -165.357818) (xy 59.383287 -165.361483)
			(xy 59.438174 -165.37332) (xy 59.490734 -165.393073) (xy 59.539831 -165.420315) (xy 59.584406 -165.454458)
			(xy 59.623496 -165.494766) (xy 59.640216 -165.517322) (xy 59.65373 -165.535344) (xy 59.686014 -165.566753)
			(xy 59.72333 -165.591977) (xy 59.764509 -165.610226) (xy 59.808261 -165.620928) (xy 59.853214 -165.623747)
			(xy 59.89796 -165.618595) (xy 59.941097 -165.605634) (xy 59.981272 -165.585269) (xy 60.017226 -165.55814)
			(xy 60.0329 -165.54196) (xy 60.052008 -165.522082) (xy 60.09494 -165.487485) (xy 60.142407 -165.459431)
			(xy 60.193418 -165.438503) (xy 60.24691 -165.425139) (xy 60.30177 -165.419615) (xy 60.356853 -165.422049)
			(xy 60.411012 -165.432388) (xy 60.463118 -165.450417) (xy 60.512085 -165.475762) (xy 60.556893 -165.507892)
			(xy 60.596607 -165.54614) (xy 60.6304 -165.589707) (xy 60.657568 -165.637686) (xy 60.677545 -165.689077)
			(xy 60.689914 -165.742808) (xy 60.690481 -165.749732) (xy 61.002162 -165.749732) (xy 61.006233 -165.69411)
			(xy 61.018359 -165.639673) (xy 61.038282 -165.587582) (xy 61.065578 -165.538947) (xy 61.099664 -165.494804)
			(xy 61.139813 -165.456095) (xy 61.185171 -165.423644) (xy 61.234771 -165.398143) (xy 61.287555 -165.380136)
			(xy 61.342398 -165.370006) (xy 61.398132 -165.367969) (xy 61.453569 -165.374069) (xy 61.507526 -165.388175)
			(xy 61.558855 -165.409987) (xy 61.606461 -165.439041) (xy 61.649329 -165.474716) (xy 61.686546 -165.516253)
			(xy 61.717319 -165.562766) (xy 61.740991 -165.613263) (xy 61.757059 -165.66667) (xy 61.765179 -165.721846)
			(xy 61.765688 -165.749732) (xy 61.765179 -165.777618) (xy 61.757059 -165.832794) (xy 61.740991 -165.886201)
			(xy 61.717319 -165.936698) (xy 61.686546 -165.983211) (xy 61.649329 -166.024748) (xy 61.606461 -166.060423)
			(xy 61.558855 -166.089477) (xy 61.507526 -166.111289) (xy 61.453569 -166.125395) (xy 61.398132 -166.131495)
			(xy 61.342398 -166.129458) (xy 61.287555 -166.119328) (xy 61.234771 -166.101321) (xy 61.185171 -166.07582)
			(xy 61.139813 -166.043369) (xy 61.099664 -166.00466) (xy 61.065578 -165.960517) (xy 61.038282 -165.911882)
			(xy 61.018359 -165.859791) (xy 61.006233 -165.805354) (xy 61.002162 -165.749732) (xy 60.690481 -165.749732)
			(xy 60.694418 -165.797761) (xy 60.690962 -165.85279) (xy 60.679619 -165.906747) (xy 60.660625 -165.95851)
			(xy 60.634376 -166.006997) (xy 60.601419 -166.051201) (xy 60.562441 -166.090198) (xy 60.518254 -166.123176)
			(xy 60.469778 -166.149449) (xy 60.418026 -166.168468) (xy 60.364073 -166.179837) (xy 60.309046 -166.18332)
			(xy 60.254092 -166.178843) (xy 60.200354 -166.1665) (xy 60.148953 -166.146548) (xy 60.100961 -166.119403)
			(xy 60.057378 -166.085631) (xy 60.019111 -166.045935) (xy 60.002674 -166.023798) (xy 59.98916 -166.005776)
			(xy 59.956878 -165.974366) (xy 59.919563 -165.949141) (xy 59.878384 -165.930893) (xy 59.834632 -165.920191)
			(xy 59.789679 -165.917373) (xy 59.744934 -165.922526) (xy 59.701798 -165.93549) (xy 59.661624 -165.955856)
			(xy 59.625672 -165.982988) (xy 59.60999 -165.99916) (xy 59.591113 -166.018803) (xy 59.548765 -166.053071)
			(xy 59.501972 -166.080967) (xy 59.451686 -166.101921) (xy 59.398931 -166.115507) (xy 59.344779 -166.121449)
			(xy 59.290333 -166.119627) (xy 59.236699 -166.110077) (xy 59.184971 -166.092993) (xy 59.136199 -166.068723)
			(xy 59.091376 -166.037761) (xy 59.051414 -166.000737) (xy 59.033918 -165.979856) (xy 59.018671 -165.961875)
			(xy 58.982737 -165.931366) (xy 58.941795 -165.908003) (xy 58.897249 -165.892586) (xy 58.850624 -165.885645)
			(xy 58.803519 -165.887416) (xy 58.757547 -165.89784) (xy 58.714284 -165.916559) (xy 58.675213 -165.942931)
			(xy 58.641672 -165.976053) (xy 58.627772 -165.995096) (xy 58.61199 -166.01703) (xy 58.57524 -166.056643)
			(xy 58.533266 -166.090672) (xy 58.486908 -166.118435) (xy 58.437096 -166.139376) (xy 58.384826 -166.153075)
			(xy 58.331146 -166.159259) (xy 58.27713 -166.157803) (xy 58.223861 -166.148737) (xy 58.198004 -166.140892)
			(xy 58.177169 -166.134681) (xy 58.134115 -166.128654) (xy 58.090664 -166.130045) (xy 58.048084 -166.138814)
			(xy 58.007618 -166.154704) (xy 57.970449 -166.177251) (xy 57.937661 -166.205798) (xy 57.910212 -166.23951)
			(xy 57.888903 -166.277403) (xy 57.874357 -166.318371) (xy 57.866999 -166.361217) (xy 57.866534 -166.382954)
			(xy 57.866534 -168.849294) (xy 66.138042 -168.849294) (xy 66.142113 -168.793672) (xy 66.154239 -168.739235)
			(xy 66.174162 -168.687144) (xy 66.201458 -168.638509) (xy 66.235544 -168.594366) (xy 66.275693 -168.555657)
			(xy 66.321051 -168.523206) (xy 66.370651 -168.497705) (xy 66.423435 -168.479698) (xy 66.478278 -168.469568)
			(xy 66.534012 -168.467531) (xy 66.589449 -168.473631) (xy 66.643406 -168.487737) (xy 66.694735 -168.509549)
			(xy 66.742341 -168.538603) (xy 66.785209 -168.574278) (xy 66.822426 -168.615815) (xy 66.853199 -168.662328)
			(xy 66.876871 -168.712825) (xy 66.892939 -168.766232) (xy 66.901059 -168.821408) (xy 66.901568 -168.849294)
			(xy 66.901059 -168.87718) (xy 66.892939 -168.932356) (xy 66.876871 -168.985763) (xy 66.853199 -169.03626)
			(xy 66.822426 -169.082773) (xy 66.785209 -169.12431) (xy 66.742341 -169.159985) (xy 66.694735 -169.189039)
			(xy 66.643406 -169.210851) (xy 66.589449 -169.224957) (xy 66.534012 -169.231057) (xy 66.478278 -169.22902)
			(xy 66.423435 -169.21889) (xy 66.370651 -169.200883) (xy 66.321051 -169.175382) (xy 66.275693 -169.142931)
			(xy 66.235544 -169.104222) (xy 66.201458 -169.060079) (xy 66.174162 -169.011444) (xy 66.154239 -168.959353)
			(xy 66.142113 -168.904916) (xy 66.138042 -168.849294) (xy 57.866534 -168.849294) (xy 57.866534 -169.798086)
			(xy 67.068135 -169.798086) (xy 67.069131 -169.742953) (xy 67.078054 -169.688538) (xy 67.094717 -169.635974)
			(xy 67.118774 -169.586357) (xy 67.149723 -169.54072) (xy 67.186921 -169.500014) (xy 67.22959 -169.465088)
			(xy 67.276844 -169.436668) (xy 67.327697 -169.415346) (xy 67.381089 -169.401568) (xy 67.435909 -169.39562)
			(xy 67.491014 -169.397626) (xy 67.545256 -169.407545) (xy 67.597506 -169.425168) (xy 67.646674 -169.450131)
			(xy 67.691736 -169.481911) (xy 67.731753 -169.519848) (xy 67.765892 -169.563151) (xy 67.793441 -169.610918)
			(xy 67.813827 -169.662153) (xy 67.826624 -169.715789) (xy 67.831567 -169.770708) (xy 67.828551 -169.825767)
			(xy 67.81764 -169.879819) (xy 67.799062 -169.931736) (xy 67.773202 -169.980439) (xy 67.757294 -170.002962)
			(xy 67.743737 -170.022214) (xy 67.723361 -170.06466) (xy 67.711145 -170.110131) (xy 67.707507 -170.157074)
			(xy 67.712571 -170.203885) (xy 67.726164 -170.248963) (xy 67.747822 -170.29077) (xy 67.776804 -170.327877)
			(xy 67.794124 -170.34383) (xy 67.81173 -170.359796) (xy 67.843237 -170.395382) (xy 67.87006 -170.43462)
			(xy 67.881246 -170.45559) (xy 67.892017 -170.475411) (xy 67.919386 -170.511265) (xy 67.952657 -170.54172)
			(xy 67.990784 -170.565821) (xy 68.032569 -170.582808) (xy 68.076697 -170.592149) (xy 68.121781 -170.593548)
			(xy 68.166403 -170.586963) (xy 68.20916 -170.5726) (xy 68.248709 -170.55091) (xy 68.266564 -170.537124)
			(xy 68.288333 -170.520152) (xy 68.335844 -170.492049) (xy 68.386908 -170.471086) (xy 68.44046 -170.4577)
			(xy 68.495382 -170.452169) (xy 68.550528 -170.454611) (xy 68.604746 -170.464973) (xy 68.656906 -170.48304)
			(xy 68.705917 -170.508433) (xy 68.750759 -170.540624) (xy 68.790494 -170.578941) (xy 68.824292 -170.622583)
			(xy 68.85145 -170.67064) (xy 68.8714 -170.722109) (xy 68.883725 -170.775915) (xy 68.888168 -170.830936)
			(xy 68.884637 -170.886022) (xy 68.873204 -170.940025) (xy 68.85411 -170.991817) (xy 68.827752 -171.040317)
			(xy 68.794681 -171.084513) (xy 68.755586 -171.123483) (xy 68.711284 -171.156412) (xy 68.6627 -171.182614)
			(xy 68.610847 -171.201542) (xy 68.556807 -171.212801) (xy 68.50171 -171.216156) (xy 68.446704 -171.211536)
			(xy 68.392937 -171.199038) (xy 68.341533 -171.178924) (xy 68.293563 -171.151612) (xy 68.25003 -171.117673)
			(xy 68.211841 -171.077816) (xy 68.179794 -171.032872) (xy 68.166742 -171.008548) (xy 68.155977 -170.988722)
			(xy 68.12861 -170.952864) (xy 68.09534 -170.922405) (xy 68.057212 -170.898302) (xy 68.015425 -170.881313)
			(xy 67.971295 -170.871972) (xy 67.926209 -170.870574) (xy 67.881585 -170.877163) (xy 67.838826 -170.89153)
			(xy 67.799278 -170.913225) (xy 67.781424 -170.927014) (xy 67.759773 -170.943975) (xy 67.712443 -170.971995)
			(xy 67.66158 -170.992927) (xy 67.608238 -171.006339) (xy 67.553523 -171.011951) (xy 67.498569 -171.009648)
			(xy 67.444515 -170.999477) (xy 67.392482 -170.98165) (xy 67.343549 -170.956535) (xy 67.298729 -170.924654)
			(xy 67.258952 -170.886667) (xy 67.225042 -170.843361) (xy 67.197702 -170.795635) (xy 67.1775 -170.744478)
			(xy 67.164853 -170.69095) (xy 67.160023 -170.63616) (xy 67.163112 -170.581245) (xy 67.174055 -170.527342)
			(xy 67.192625 -170.475569) (xy 67.218437 -170.427) (xy 67.234308 -170.404536) (xy 67.247761 -170.385215)
			(xy 67.268145 -170.342786) (xy 67.280371 -170.29733) (xy 67.284022 -170.2504) (xy 67.278972 -170.2036)
			(xy 67.265395 -170.158529) (xy 67.243754 -170.116727) (xy 67.214789 -170.079622) (xy 67.197478 -170.063668)
			(xy 67.177075 -170.045119) (xy 67.141372 -170.003096) (xy 67.112091 -169.956372) (xy 67.089841 -169.905918)
			(xy 67.075087 -169.852787) (xy 67.068135 -169.798086) (xy 57.866534 -169.798086) (xy 57.866534 -170.030648)
			(xy 57.867052 -170.053923) (xy 57.875521 -170.099696) (xy 57.892185 -170.143162) (xy 57.916487 -170.182865)
			(xy 57.947614 -170.217477) (xy 57.984524 -170.245842) (xy 58.025983 -170.267009) (xy 58.070604 -170.280271)
			(xy 58.116894 -170.285184) (xy 58.163305 -170.281585) (xy 58.208284 -170.269592) (xy 58.2295 -170.26001)
			(xy 58.254515 -170.248652) (xy 58.307004 -170.232431) (xy 58.361276 -170.223903) (xy 58.41621 -170.223247)
			(xy 58.470671 -170.230474) (xy 58.523532 -170.245435) (xy 58.573702 -170.267822) (xy 58.620143 -170.297172)
			(xy 58.661896 -170.332877) (xy 58.698098 -170.3742) (xy 58.727999 -170.420288) (xy 58.750984 -170.470187)
			(xy 58.766576 -170.522866) (xy 58.774453 -170.577236) (xy 58.774453 -170.604688) (xy 60.366654 -170.604688)
			(xy 60.370725 -170.549066) (xy 60.382851 -170.494629) (xy 60.402774 -170.442538) (xy 60.43007 -170.393903)
			(xy 60.464156 -170.34976) (xy 60.504305 -170.311051) (xy 60.549663 -170.2786) (xy 60.599263 -170.253099)
			(xy 60.652047 -170.235092) (xy 60.70689 -170.224962) (xy 60.762624 -170.222925) (xy 60.818061 -170.229025)
			(xy 60.872018 -170.243131) (xy 60.923347 -170.264943) (xy 60.970953 -170.293997) (xy 61.013821 -170.329672)
			(xy 61.051038 -170.371209) (xy 61.081811 -170.417722) (xy 61.105483 -170.468219) (xy 61.121551 -170.521626)
			(xy 61.129671 -170.576802) (xy 61.13018 -170.604688) (xy 61.129716 -170.630088) (xy 61.491366 -170.630088)
			(xy 61.495437 -170.574466) (xy 61.507563 -170.520029) (xy 61.527486 -170.467938) (xy 61.554782 -170.419303)
			(xy 61.588868 -170.37516) (xy 61.629017 -170.336451) (xy 61.674375 -170.304) (xy 61.723975 -170.278499)
			(xy 61.776759 -170.260492) (xy 61.831602 -170.250362) (xy 61.887336 -170.248325) (xy 61.942773 -170.254425)
			(xy 61.99673 -170.268531) (xy 62.048059 -170.290343) (xy 62.095665 -170.319397) (xy 62.138533 -170.355072)
			(xy 62.17575 -170.396609) (xy 62.206523 -170.443122) (xy 62.230195 -170.493619) (xy 62.246263 -170.547026)
			(xy 62.254383 -170.602202) (xy 62.254892 -170.630088) (xy 63.749426 -170.630088) (xy 63.753497 -170.574466)
			(xy 63.765623 -170.520029) (xy 63.785546 -170.467938) (xy 63.812842 -170.419303) (xy 63.846928 -170.37516)
			(xy 63.887077 -170.336451) (xy 63.932435 -170.304) (xy 63.982035 -170.278499) (xy 64.034819 -170.260492)
			(xy 64.089662 -170.250362) (xy 64.145396 -170.248325) (xy 64.200833 -170.254425) (xy 64.25479 -170.268531)
			(xy 64.306119 -170.290343) (xy 64.353725 -170.319397) (xy 64.396593 -170.355072) (xy 64.43381 -170.396609)
			(xy 64.464583 -170.443122) (xy 64.488255 -170.493619) (xy 64.504323 -170.547026) (xy 64.512443 -170.602202)
			(xy 64.512952 -170.630088) (xy 64.964816 -170.630088) (xy 64.968887 -170.574466) (xy 64.981013 -170.520029)
			(xy 65.000936 -170.467938) (xy 65.028232 -170.419303) (xy 65.062318 -170.37516) (xy 65.102467 -170.336451)
			(xy 65.147825 -170.304) (xy 65.197425 -170.278499) (xy 65.250209 -170.260492) (xy 65.305052 -170.250362)
			(xy 65.360786 -170.248325) (xy 65.416223 -170.254425) (xy 65.47018 -170.268531) (xy 65.521509 -170.290343)
			(xy 65.569115 -170.319397) (xy 65.611983 -170.355072) (xy 65.6492 -170.396609) (xy 65.679973 -170.443122)
			(xy 65.703645 -170.493619) (xy 65.719713 -170.547026) (xy 65.727833 -170.602202) (xy 65.728342 -170.630088)
			(xy 65.727833 -170.657974) (xy 65.719713 -170.71315) (xy 65.703645 -170.766557) (xy 65.679973 -170.817054)
			(xy 65.6492 -170.863567) (xy 65.611983 -170.905104) (xy 65.569115 -170.940779) (xy 65.521509 -170.969833)
			(xy 65.47018 -170.991645) (xy 65.416223 -171.005751) (xy 65.360786 -171.011851) (xy 65.305052 -171.009814)
			(xy 65.250209 -170.999684) (xy 65.197425 -170.981677) (xy 65.147825 -170.956176) (xy 65.102467 -170.923725)
			(xy 65.062318 -170.885016) (xy 65.028232 -170.840873) (xy 65.000936 -170.792238) (xy 64.981013 -170.740147)
			(xy 64.968887 -170.68571) (xy 64.964816 -170.630088) (xy 64.512952 -170.630088) (xy 64.512443 -170.657974)
			(xy 64.504323 -170.71315) (xy 64.488255 -170.766557) (xy 64.464583 -170.817054) (xy 64.43381 -170.863567)
			(xy 64.396593 -170.905104) (xy 64.353725 -170.940779) (xy 64.306119 -170.969833) (xy 64.25479 -170.991645)
			(xy 64.200833 -171.005751) (xy 64.145396 -171.011851) (xy 64.089662 -171.009814) (xy 64.034819 -170.999684)
			(xy 63.982035 -170.981677) (xy 63.932435 -170.956176) (xy 63.887077 -170.923725) (xy 63.846928 -170.885016)
			(xy 63.812842 -170.840873) (xy 63.785546 -170.792238) (xy 63.765623 -170.740147) (xy 63.753497 -170.68571)
			(xy 63.749426 -170.630088) (xy 62.254892 -170.630088) (xy 62.254383 -170.657974) (xy 62.246263 -170.71315)
			(xy 62.230195 -170.766557) (xy 62.206523 -170.817054) (xy 62.17575 -170.863567) (xy 62.138533 -170.905104)
			(xy 62.095665 -170.940779) (xy 62.048059 -170.969833) (xy 61.99673 -170.991645) (xy 61.942773 -171.005751)
			(xy 61.887336 -171.011851) (xy 61.831602 -171.009814) (xy 61.776759 -170.999684) (xy 61.723975 -170.981677)
			(xy 61.674375 -170.956176) (xy 61.629017 -170.923725) (xy 61.588868 -170.885016) (xy 61.554782 -170.840873)
			(xy 61.527486 -170.792238) (xy 61.507563 -170.740147) (xy 61.495437 -170.68571) (xy 61.491366 -170.630088)
			(xy 61.129716 -170.630088) (xy 61.129671 -170.632574) (xy 61.121551 -170.68775) (xy 61.105483 -170.741157)
			(xy 61.081811 -170.791654) (xy 61.051038 -170.838167) (xy 61.013821 -170.879704) (xy 60.970953 -170.915379)
			(xy 60.923347 -170.944433) (xy 60.872018 -170.966245) (xy 60.818061 -170.980351) (xy 60.762624 -170.986451)
			(xy 60.70689 -170.984414) (xy 60.652047 -170.974284) (xy 60.599263 -170.956277) (xy 60.549663 -170.930776)
			(xy 60.504305 -170.898325) (xy 60.464156 -170.859616) (xy 60.43007 -170.815473) (xy 60.402774 -170.766838)
			(xy 60.382851 -170.714747) (xy 60.370725 -170.66031) (xy 60.366654 -170.604688) (xy 58.774453 -170.604688)
			(xy 58.774452 -170.632174) (xy 58.766573 -170.686544) (xy 58.75098 -170.739223) (xy 58.727994 -170.789121)
			(xy 58.698091 -170.835208) (xy 58.661889 -170.87653) (xy 58.620135 -170.912235) (xy 58.573693 -170.941583)
			(xy 58.523522 -170.963968) (xy 58.470661 -170.978928) (xy 58.4162 -170.986154) (xy 58.361266 -170.985496)
			(xy 58.306994 -170.976967) (xy 58.254506 -170.960744) (xy 58.2295 -170.949366) (xy 58.208256 -170.939851)
			(xy 58.163284 -170.927867) (xy 58.116881 -170.924272) (xy 58.070599 -170.929185) (xy 58.025985 -170.942443)
			(xy 57.984531 -170.963602) (xy 57.947622 -170.991956) (xy 57.916492 -171.026555) (xy 57.892183 -171.066244)
			(xy 57.875506 -171.109695) (xy 57.867019 -171.155457) (xy 57.866534 -171.178728) (xy 57.866534 -171.973748)
			(xy 68.050662 -171.973748) (xy 68.054733 -171.918126) (xy 68.066859 -171.863689) (xy 68.086782 -171.811598)
			(xy 68.114078 -171.762963) (xy 68.148164 -171.71882) (xy 68.188313 -171.680111) (xy 68.233671 -171.64766)
			(xy 68.283271 -171.622159) (xy 68.336055 -171.604152) (xy 68.390898 -171.594022) (xy 68.446632 -171.591985)
			(xy 68.502069 -171.598085) (xy 68.556026 -171.612191) (xy 68.607355 -171.634003) (xy 68.654961 -171.663057)
			(xy 68.697829 -171.698732) (xy 68.735046 -171.740269) (xy 68.765819 -171.786782) (xy 68.789491 -171.837279)
			(xy 68.805559 -171.890686) (xy 68.813679 -171.945862) (xy 68.814188 -171.973748) (xy 68.813679 -172.001634)
			(xy 68.805559 -172.05681) (xy 68.789491 -172.110217) (xy 68.765819 -172.160714) (xy 68.735046 -172.207227)
			(xy 68.697829 -172.248764) (xy 68.654961 -172.284439) (xy 68.607355 -172.313493) (xy 68.556026 -172.335305)
			(xy 68.502069 -172.349411) (xy 68.446632 -172.355511) (xy 68.390898 -172.353474) (xy 68.336055 -172.343344)
			(xy 68.283271 -172.325337) (xy 68.233671 -172.299836) (xy 68.188313 -172.267385) (xy 68.148164 -172.228676)
			(xy 68.114078 -172.184533) (xy 68.086782 -172.135898) (xy 68.066859 -172.083807) (xy 68.054733 -172.02937)
			(xy 68.050662 -171.973748) (xy 57.866534 -171.973748) (xy 57.866534 -172.620686) (xy 59.885832 -172.620686)
			(xy 59.889903 -172.565064) (xy 59.902029 -172.510627) (xy 59.921952 -172.458536) (xy 59.949248 -172.409901)
			(xy 59.983334 -172.365758) (xy 60.023483 -172.327049) (xy 60.068841 -172.294598) (xy 60.118441 -172.269097)
			(xy 60.171225 -172.25109) (xy 60.226068 -172.24096) (xy 60.281802 -172.238923) (xy 60.337239 -172.245023)
			(xy 60.391196 -172.259129) (xy 60.442525 -172.280941) (xy 60.490131 -172.309995) (xy 60.532999 -172.34567)
			(xy 60.570216 -172.387207) (xy 60.600989 -172.43372) (xy 60.624661 -172.484217) (xy 60.640729 -172.537624)
			(xy 60.648849 -172.5928) (xy 60.649358 -172.620686) (xy 60.648849 -172.648572) (xy 60.640729 -172.703748)
			(xy 60.624661 -172.757155) (xy 60.600989 -172.807652) (xy 60.570216 -172.854165) (xy 60.532999 -172.895702)
			(xy 60.490131 -172.931377) (xy 60.442525 -172.960431) (xy 60.391196 -172.982243) (xy 60.337239 -172.996349)
			(xy 60.281802 -173.002449) (xy 60.226068 -173.000412) (xy 60.171225 -172.990282) (xy 60.118441 -172.972275)
			(xy 60.068841 -172.946774) (xy 60.023483 -172.914323) (xy 59.983334 -172.875614) (xy 59.949248 -172.831471)
			(xy 59.921952 -172.782836) (xy 59.902029 -172.730745) (xy 59.889903 -172.676308) (xy 59.885832 -172.620686)
			(xy 57.866534 -172.620686) (xy 57.866534 -173.360334) (xy 61.792102 -173.360334) (xy 61.796173 -173.304712)
			(xy 61.808299 -173.250275) (xy 61.828222 -173.198184) (xy 61.855518 -173.149549) (xy 61.889604 -173.105406)
			(xy 61.929753 -173.066697) (xy 61.975111 -173.034246) (xy 62.024711 -173.008745) (xy 62.077495 -172.990738)
			(xy 62.132338 -172.980608) (xy 62.188072 -172.978571) (xy 62.243509 -172.984671) (xy 62.297466 -172.998777)
			(xy 62.348795 -173.020589) (xy 62.396401 -173.049643) (xy 62.439269 -173.085318) (xy 62.476486 -173.126855)
			(xy 62.507259 -173.173368) (xy 62.530931 -173.223865) (xy 62.546999 -173.277272) (xy 62.555119 -173.332448)
			(xy 62.555619 -173.359826) (xy 67.496942 -173.359826) (xy 67.501013 -173.304204) (xy 67.513139 -173.249767)
			(xy 67.533062 -173.197676) (xy 67.560358 -173.149041) (xy 67.594444 -173.104898) (xy 67.634593 -173.066189)
			(xy 67.679951 -173.033738) (xy 67.729551 -173.008237) (xy 67.782335 -172.99023) (xy 67.837178 -172.9801)
			(xy 67.892912 -172.978063) (xy 67.948349 -172.984163) (xy 68.002306 -172.998269) (xy 68.053635 -173.020081)
			(xy 68.101241 -173.049135) (xy 68.144109 -173.08481) (xy 68.17978 -173.124622) (xy 69.648322 -173.124622)
			(xy 69.652393 -173.069) (xy 69.664519 -173.014563) (xy 69.684442 -172.962472) (xy 69.711738 -172.913837)
			(xy 69.745824 -172.869694) (xy 69.785973 -172.830985) (xy 69.831331 -172.798534) (xy 69.880931 -172.773033)
			(xy 69.933715 -172.755026) (xy 69.988558 -172.744896) (xy 70.044292 -172.742859) (xy 70.099729 -172.748959)
			(xy 70.153686 -172.763065) (xy 70.205015 -172.784877) (xy 70.252621 -172.813931) (xy 70.295489 -172.849606)
			(xy 70.332706 -172.891143) (xy 70.363479 -172.937656) (xy 70.387151 -172.988153) (xy 70.403219 -173.04156)
			(xy 70.411339 -173.096736) (xy 70.411848 -173.124622) (xy 70.411339 -173.152508) (xy 70.403219 -173.207684)
			(xy 70.387151 -173.261091) (xy 70.363479 -173.311588) (xy 70.332706 -173.358101) (xy 70.295489 -173.399638)
			(xy 70.252621 -173.435313) (xy 70.205015 -173.464367) (xy 70.153686 -173.486179) (xy 70.099729 -173.500285)
			(xy 70.044292 -173.506385) (xy 69.988558 -173.504348) (xy 69.933715 -173.494218) (xy 69.880931 -173.476211)
			(xy 69.831331 -173.45071) (xy 69.785973 -173.418259) (xy 69.745824 -173.37955) (xy 69.711738 -173.335407)
			(xy 69.684442 -173.286772) (xy 69.664519 -173.234681) (xy 69.652393 -173.180244) (xy 69.648322 -173.124622)
			(xy 68.17978 -173.124622) (xy 68.181326 -173.126347) (xy 68.212099 -173.17286) (xy 68.235771 -173.223357)
			(xy 68.251839 -173.276764) (xy 68.259959 -173.33194) (xy 68.260468 -173.359826) (xy 68.259959 -173.387712)
			(xy 68.251839 -173.442888) (xy 68.235771 -173.496295) (xy 68.212099 -173.546792) (xy 68.181326 -173.593305)
			(xy 68.144109 -173.634842) (xy 68.101241 -173.670517) (xy 68.053635 -173.699571) (xy 68.002306 -173.721383)
			(xy 67.948349 -173.735489) (xy 67.892912 -173.741589) (xy 67.837178 -173.739552) (xy 67.782335 -173.729422)
			(xy 67.729551 -173.711415) (xy 67.679951 -173.685914) (xy 67.634593 -173.653463) (xy 67.594444 -173.614754)
			(xy 67.560358 -173.570611) (xy 67.533062 -173.521976) (xy 67.513139 -173.469885) (xy 67.501013 -173.415448)
			(xy 67.496942 -173.359826) (xy 62.555619 -173.359826) (xy 62.555628 -173.360334) (xy 62.555119 -173.38822)
			(xy 62.546999 -173.443396) (xy 62.530931 -173.496803) (xy 62.507259 -173.5473) (xy 62.476486 -173.593813)
			(xy 62.439269 -173.63535) (xy 62.396401 -173.671025) (xy 62.348795 -173.700079) (xy 62.297466 -173.721891)
			(xy 62.243509 -173.735997) (xy 62.188072 -173.742097) (xy 62.132338 -173.74006) (xy 62.077495 -173.72993)
			(xy 62.024711 -173.711923) (xy 61.975111 -173.686422) (xy 61.929753 -173.653971) (xy 61.889604 -173.615262)
			(xy 61.855518 -173.571119) (xy 61.828222 -173.522484) (xy 61.808299 -173.470393) (xy 61.796173 -173.415956)
			(xy 61.792102 -173.360334) (xy 57.866534 -173.360334) (xy 57.866534 -174.576486) (xy 70.318882 -174.576486)
			(xy 70.322953 -174.520864) (xy 70.335079 -174.466427) (xy 70.355002 -174.414336) (xy 70.382298 -174.365701)
			(xy 70.416384 -174.321558) (xy 70.456533 -174.282849) (xy 70.501891 -174.250398) (xy 70.551491 -174.224897)
			(xy 70.604275 -174.20689) (xy 70.659118 -174.19676) (xy 70.714852 -174.194723) (xy 70.770289 -174.200823)
			(xy 70.824246 -174.214929) (xy 70.875575 -174.236741) (xy 70.923181 -174.265795) (xy 70.966049 -174.30147)
			(xy 71.003266 -174.343007) (xy 71.034039 -174.38952) (xy 71.057711 -174.440017) (xy 71.073779 -174.493424)
			(xy 71.081899 -174.5486) (xy 71.082408 -174.576486) (xy 71.081899 -174.604372) (xy 71.073779 -174.659548)
			(xy 71.057711 -174.712955) (xy 71.034039 -174.763452) (xy 71.003266 -174.809965) (xy 70.966049 -174.851502)
			(xy 70.923181 -174.887177) (xy 70.875575 -174.916231) (xy 70.824246 -174.938043) (xy 70.770289 -174.952149)
			(xy 70.714852 -174.958249) (xy 70.659118 -174.956212) (xy 70.604275 -174.946082) (xy 70.551491 -174.928075)
			(xy 70.501891 -174.902574) (xy 70.456533 -174.870123) (xy 70.416384 -174.831414) (xy 70.382298 -174.787271)
			(xy 70.355002 -174.738636) (xy 70.335079 -174.686545) (xy 70.322953 -174.632108) (xy 70.318882 -174.576486)
			(xy 57.866534 -174.576486) (xy 57.866534 -176.613566) (xy 57.867025 -176.630222) (xy 57.875641 -176.6624)
			(xy 57.892294 -176.691251) (xy 57.915849 -176.714806) (xy 57.9447 -176.731459) (xy 57.976878 -176.740075)
			(xy 57.993534 -176.740566) (xy 60.276232 -176.740566) (xy 60.293569 -176.740041) (xy 60.326962 -176.730704)
			(xy 60.356598 -176.712703) (xy 60.380278 -176.687374) (xy 60.388754 -176.67224) (xy 60.400283 -176.650852)
			(xy 60.427961 -176.610916) (xy 60.460485 -176.574817) (xy 60.47867 -176.558702) (xy 60.49776 -176.542821)
			(xy 60.539296 -176.515605) (xy 60.584005 -176.493992) (xy 60.607448 -176.485804) (xy 60.628241 -176.478407)
			(xy 60.667094 -176.457485) (xy 60.701747 -176.430162) (xy 60.731157 -176.397263) (xy 60.754439 -176.359777)
			(xy 60.770894 -176.318831) (xy 60.780025 -176.275657) (xy 60.781559 -176.231556) (xy 60.775448 -176.187852)
			(xy 60.761877 -176.145862) (xy 60.751974 -176.12614) (xy 60.738725 -176.101374) (xy 60.718843 -176.048847)
			(xy 60.706874 -175.993972) (xy 60.703079 -175.937936) (xy 60.707538 -175.881949) (xy 60.720156 -175.82722)
			(xy 60.740659 -175.774932) (xy 60.768606 -175.726214) (xy 60.803392 -175.682118) (xy 60.844266 -175.643598)
			(xy 60.890345 -175.611485) (xy 60.940633 -175.586474) (xy 60.994044 -175.569104) (xy 61.049424 -175.55975)
			(xy 61.105577 -175.558616) (xy 61.16129 -175.565724) (xy 61.215359 -175.580922) (xy 61.241178 -175.591978)
			(xy 61.265587 -175.603421) (xy 61.311194 -175.632163) (xy 61.352302 -175.667039) (xy 61.388091 -175.707354)
			(xy 61.417849 -175.752305) (xy 61.440984 -175.800997) (xy 61.457036 -175.85246) (xy 61.458047 -175.858678)
			(xy 63.981074 -175.858678) (xy 63.985145 -175.803056) (xy 63.997271 -175.748619) (xy 64.017194 -175.696528)
			(xy 64.04449 -175.647893) (xy 64.078576 -175.60375) (xy 64.118725 -175.565041) (xy 64.164083 -175.53259)
			(xy 64.213683 -175.507089) (xy 64.266467 -175.489082) (xy 64.32131 -175.478952) (xy 64.377044 -175.476915)
			(xy 64.432481 -175.483015) (xy 64.486438 -175.497121) (xy 64.537767 -175.518933) (xy 64.545499 -175.523652)
			(xy 68.233542 -175.523652) (xy 68.237613 -175.46803) (xy 68.249739 -175.413593) (xy 68.269662 -175.361502)
			(xy 68.296958 -175.312867) (xy 68.331044 -175.268724) (xy 68.371193 -175.230015) (xy 68.416551 -175.197564)
			(xy 68.466151 -175.172063) (xy 68.518935 -175.154056) (xy 68.573778 -175.143926) (xy 68.629512 -175.141889)
			(xy 68.684949 -175.147989) (xy 68.738906 -175.162095) (xy 68.790235 -175.183907) (xy 68.837841 -175.212961)
			(xy 68.880709 -175.248636) (xy 68.917926 -175.290173) (xy 68.948699 -175.336686) (xy 68.972371 -175.387183)
			(xy 68.988439 -175.44059) (xy 68.996559 -175.495766) (xy 68.997068 -175.523652) (xy 68.996559 -175.551538)
			(xy 68.988439 -175.606714) (xy 68.972371 -175.660121) (xy 68.948699 -175.710618) (xy 68.917926 -175.757131)
			(xy 68.880709 -175.798668) (xy 68.837841 -175.834343) (xy 68.790235 -175.863397) (xy 68.738906 -175.885209)
			(xy 68.684949 -175.899315) (xy 68.629512 -175.905415) (xy 68.573778 -175.903378) (xy 68.518935 -175.893248)
			(xy 68.466151 -175.875241) (xy 68.416551 -175.84974) (xy 68.371193 -175.817289) (xy 68.331044 -175.77858)
			(xy 68.296958 -175.734437) (xy 68.269662 -175.685802) (xy 68.249739 -175.633711) (xy 68.237613 -175.579274)
			(xy 68.233542 -175.523652) (xy 64.545499 -175.523652) (xy 64.585373 -175.547987) (xy 64.628241 -175.583662)
			(xy 64.665458 -175.625199) (xy 64.696231 -175.671712) (xy 64.719903 -175.722209) (xy 64.735971 -175.775616)
			(xy 64.744091 -175.830792) (xy 64.7446 -175.858678) (xy 64.744091 -175.886564) (xy 64.735971 -175.94174)
			(xy 64.719903 -175.995147) (xy 64.696231 -176.045644) (xy 64.665458 -176.092157) (xy 64.628241 -176.133694)
			(xy 64.585373 -176.169369) (xy 64.537767 -176.198423) (xy 64.486438 -176.220235) (xy 64.432481 -176.234341)
			(xy 64.377044 -176.240441) (xy 64.32131 -176.238404) (xy 64.266467 -176.228274) (xy 64.213683 -176.210267)
			(xy 64.164083 -176.184766) (xy 64.118725 -176.152315) (xy 64.078576 -176.113606) (xy 64.04449 -176.069463)
			(xy 64.017194 -176.020828) (xy 63.997271 -175.968737) (xy 63.985145 -175.9143) (xy 63.981074 -175.858678)
			(xy 61.458047 -175.858678) (xy 61.465684 -175.905671) (xy 61.466756 -175.959569) (xy 61.460231 -176.013081)
			(xy 61.446239 -176.065142) (xy 61.425059 -176.114716) (xy 61.397112 -176.160815) (xy 61.362955 -176.202521)
			(xy 61.323267 -176.239004) (xy 61.278839 -176.269538) (xy 61.230556 -176.293515) (xy 61.20511 -176.302416)
			(xy 61.184321 -176.309815) (xy 61.145477 -176.330742) (xy 61.110832 -176.358065) (xy 61.08143 -176.390964)
			(xy 61.058155 -176.428448) (xy 61.041706 -176.46939) (xy 61.032579 -176.512558) (xy 61.031048 -176.556654)
			(xy 61.037159 -176.600352) (xy 61.050729 -176.642336) (xy 61.060584 -176.66208) (xy 61.06541 -176.671224)
			(xy 61.073847 -176.686529) (xy 61.097576 -176.712172) (xy 61.127359 -176.730436) (xy 61.160973 -176.739959)
			(xy 61.17844 -176.740566) (xy 66.971672 -176.740566) (xy 66.993869 -176.740112) (xy 67.037588 -176.732402)
			(xy 67.079302 -176.717211) (xy 67.117741 -176.695003) (xy 67.151736 -176.666452) (xy 67.180252 -176.632428)
			(xy 67.202421 -176.593966) (xy 67.217569 -176.552236) (xy 67.225235 -176.508509) (xy 67.225672 -176.486312)
			(xy 67.225672 -176.48174) (xy 67.226419 -176.454931) (xy 67.234505 -176.401914) (xy 67.249934 -176.350551)
			(xy 67.272402 -176.301854) (xy 67.301466 -176.256781) (xy 67.336554 -176.216222) (xy 67.376975 -176.180974)
			(xy 67.421932 -176.151732) (xy 67.47054 -176.129072) (xy 67.521842 -176.11344) (xy 67.574827 -176.105144)
			(xy 67.628451 -176.104348) (xy 67.681659 -176.111066) (xy 67.733402 -176.125168) (xy 67.782662 -176.146374)
			(xy 67.805808 -176.159922) (xy 67.828963 -176.174581) (xy 67.871206 -176.209493) (xy 67.908019 -176.250089)
			(xy 67.938647 -176.295534) (xy 67.962458 -176.344893) (xy 67.978963 -176.39715) (xy 67.987822 -176.451232)
			(xy 67.988853 -176.506024) (xy 67.982035 -176.560401) (xy 67.967509 -176.613242) (xy 67.945572 -176.663462)
			(xy 67.916676 -176.710028) (xy 67.913638 -176.713642) (xy 70.096632 -176.713642) (xy 70.100703 -176.65802)
			(xy 70.112829 -176.603583) (xy 70.132752 -176.551492) (xy 70.160048 -176.502857) (xy 70.194134 -176.458714)
			(xy 70.234283 -176.420005) (xy 70.279641 -176.387554) (xy 70.329241 -176.362053) (xy 70.382025 -176.344046)
			(xy 70.436868 -176.333916) (xy 70.492602 -176.331879) (xy 70.548039 -176.337979) (xy 70.601996 -176.352085)
			(xy 70.653325 -176.373897) (xy 70.700931 -176.402951) (xy 70.743799 -176.438626) (xy 70.781016 -176.480163)
			(xy 70.811789 -176.526676) (xy 70.835461 -176.577173) (xy 70.851529 -176.63058) (xy 70.859649 -176.685756)
			(xy 70.860158 -176.713642) (xy 70.859649 -176.741528) (xy 70.851529 -176.796704) (xy 70.835461 -176.850111)
			(xy 70.811789 -176.900608) (xy 70.781016 -176.947121) (xy 70.743799 -176.988658) (xy 70.700931 -177.024333)
			(xy 70.653325 -177.053387) (xy 70.601996 -177.075199) (xy 70.548039 -177.089305) (xy 70.492602 -177.095405)
			(xy 70.436868 -177.093368) (xy 70.382025 -177.083238) (xy 70.329241 -177.065231) (xy 70.279641 -177.03973)
			(xy 70.234283 -177.007279) (xy 70.194134 -176.96857) (xy 70.160048 -176.924427) (xy 70.132752 -176.875792)
			(xy 70.112829 -176.823701) (xy 70.100703 -176.769264) (xy 70.096632 -176.713642) (xy 67.913638 -176.713642)
			(xy 67.881416 -176.75198) (xy 67.840518 -176.788457) (xy 67.794821 -176.818708) (xy 67.745267 -176.84211)
			(xy 67.719194 -176.850548) (xy 67.698492 -176.857382) (xy 67.659621 -176.877112) (xy 67.624688 -176.903189)
			(xy 67.594719 -176.934846) (xy 67.570593 -176.971153) (xy 67.553019 -177.011046) (xy 67.542512 -177.053354)
			(xy 67.539382 -177.096833) (xy 67.543719 -177.140209) (xy 67.555396 -177.182208) (xy 67.574071 -177.221598)
			(xy 67.599196 -177.257222) (xy 67.614292 -177.27295) (xy 68.40347 -178.062382) (xy 68.415603 -178.073845)
			(xy 68.44448 -178.090564) (xy 68.476702 -178.099235) (xy 68.493386 -178.09972)
		)
		(stroke
			(width 0)
			(type solid)
		)
		(fill yes)
		(layer "In6.Cu")
		(net "P5V_NODE1")
	)
	(gr_poly
		(pts
			(xy 32.159956 -108.521246) (xy 32.182999 -108.520714) (xy 32.22832 -108.512345) (xy 32.271391 -108.495945)
			(xy 32.310802 -108.472052) (xy 32.345261 -108.441448) (xy 32.373641 -108.405135) (xy 32.395012 -108.364303)
			(xy 32.408675 -108.320287) (xy 32.414182 -108.27453) (xy 32.411353 -108.228529) (xy 32.406336 -108.206032)
			(xy 32.399291 -108.179781) (xy 32.391842 -108.125944) (xy 32.392106 -108.071594) (xy 32.400079 -108.017832)
			(xy 32.415598 -107.965744) (xy 32.438351 -107.916385) (xy 32.467876 -107.870754) (xy 32.503577 -107.829773)
			(xy 32.544731 -107.794272) (xy 32.590505 -107.764969) (xy 32.639974 -107.742457) (xy 32.692136 -107.72719)
			(xy 32.745937 -107.719479) (xy 32.800287 -107.719479) (xy 32.854088 -107.72719) (xy 32.90625 -107.742457)
			(xy 32.955719 -107.764969) (xy 33.001493 -107.794272) (xy 33.042647 -107.829773) (xy 33.078348 -107.870754)
			(xy 33.107873 -107.916385) (xy 33.130626 -107.965744) (xy 33.146145 -108.017832) (xy 33.154118 -108.071594)
			(xy 33.154382 -108.125944) (xy 33.146933 -108.179781) (xy 33.139888 -108.206032) (xy 33.134814 -108.228527)
			(xy 33.131948 -108.274548) (xy 33.13743 -108.320331) (xy 33.151081 -108.364374) (xy 33.172453 -108.405232)
			(xy 33.200845 -108.441564) (xy 33.235326 -108.472178) (xy 33.274763 -108.49607) (xy 33.317864 -108.512456)
			(xy 33.363213 -108.520797) (xy 33.386268 -108.521246) (xy 34.843212 -108.521246) (xy 34.864897 -108.520779)
			(xy 34.90763 -108.513363) (xy 34.948484 -108.498799) (xy 34.986271 -108.477511) (xy 35.019896 -108.450116)
			(xy 35.048382 -108.417411) (xy 35.070901 -108.380344) (xy 35.086801 -108.339991) (xy 35.095618 -108.297525)
			(xy 35.097098 -108.254179) (xy 35.091197 -108.211211) (xy 35.078086 -108.169868) (xy 35.06851 -108.150406)
			(xy 35.060128 -108.133388) (xy 35.049057 -108.108394) (xy 35.033378 -108.056027) (xy 35.025332 -108.001959)
			(xy 35.025084 -107.947295) (xy 35.032639 -107.893156) (xy 35.047844 -107.840649) (xy 35.070385 -107.790849)
			(xy 35.099803 -107.744776) (xy 35.135494 -107.703372) (xy 35.176729 -107.667485) (xy 35.222662 -107.63785)
			(xy 35.272355 -107.615073) (xy 35.32479 -107.599621) (xy 35.378892 -107.591809) (xy 35.433556 -107.591798)
			(xy 35.460686 -107.595162) (xy 35.483408 -107.597962) (xy 35.529156 -107.596303) (xy 35.573866 -107.586474)
			(xy 35.616091 -107.568792) (xy 35.654464 -107.543829) (xy 35.687743 -107.512395) (xy 35.71485 -107.475506)
			(xy 35.734908 -107.434356) (xy 35.747268 -107.390279) (xy 35.75153 -107.3447) (xy 35.749992 -107.321858)
			(xy 35.747105 -107.293928) (xy 35.748584 -107.237798) (xy 35.758272 -107.18249) (xy 35.775961 -107.1292)
			(xy 35.801268 -107.079077) (xy 35.833648 -107.033204) (xy 35.8724 -106.992571) (xy 35.916688 -106.958056)
			(xy 35.965557 -106.930403) (xy 36.01795 -106.910211) (xy 36.072736 -106.897914) (xy 36.128733 -106.893779)
			(xy 36.184732 -106.897895) (xy 36.239522 -106.910172) (xy 36.291923 -106.930346) (xy 36.340801 -106.957982)
			(xy 36.385101 -106.992482) (xy 36.404804 -107.012486) (xy 36.423633 -107.032942) (xy 36.455773 -107.078305)
			(xy 36.480989 -107.127852) (xy 36.498746 -107.180535) (xy 36.50867 -107.235236) (xy 36.51055 -107.2908)
			(xy 36.504345 -107.346047) (xy 36.490188 -107.399809) (xy 36.468378 -107.450947) (xy 36.439377 -107.498379)
			(xy 36.403799 -107.541099) (xy 36.362398 -107.578203) (xy 36.31605 -107.608905) (xy 36.265737 -107.632556)
			(xy 36.212523 -107.648654) (xy 36.157537 -107.656858) (xy 36.101943 -107.656995) (xy 36.07435 -107.653582)
			(xy 36.051633 -107.650788) (xy 36.005897 -107.652456) (xy 35.9612 -107.662293) (xy 35.918989 -107.679979)
			(xy 35.880631 -107.704943) (xy 35.847366 -107.736376) (xy 35.820272 -107.77326) (xy 35.800226 -107.814403)
			(xy 35.787877 -107.858472) (xy 35.783623 -107.90404) (xy 35.785044 -107.926886) (xy 35.788014 -107.955594)
			(xy 35.786296 -108.01328) (xy 35.775908 -108.07005) (xy 35.757087 -108.124607) (xy 35.74415 -108.150406)
			(xy 35.73457 -108.169865) (xy 35.721456 -108.211205) (xy 35.715553 -108.254172) (xy 35.717032 -108.297517)
			(xy 35.725849 -108.339982) (xy 35.74175 -108.380332) (xy 35.764271 -108.417397) (xy 35.792759 -108.450099)
			(xy 35.826386 -108.477489) (xy 35.864176 -108.49877) (xy 35.90503 -108.513326) (xy 35.947763 -108.520733)
			(xy 35.969448 -108.521246) (xy 43.100498 -108.521246) (xy 43.12412 -108.51134) (xy 43.152308 -108.500149)
			(xy 43.21124 -108.485832) (xy 43.271694 -108.481019) (xy 43.332148 -108.485832) (xy 43.39108 -108.500149)
			(xy 43.419268 -108.51134) (xy 43.44289 -108.521246) (xy 43.514518 -108.521246) (xy 43.529235 -108.520825)
			(xy 43.557884 -108.514076) (xy 43.584223 -108.500941) (xy 43.606852 -108.48212) (xy 43.624566 -108.458613)
			(xy 43.63085 -108.4453) (xy 43.641469 -108.422048) (xy 43.668029 -108.378372) (xy 43.700189 -108.338639)
			(xy 43.737373 -108.303561) (xy 43.778911 -108.273769) (xy 43.801284 -108.261404) (xy 43.828208 -108.24718)
			(xy 43.864022 -108.195872) (xy 43.873168 -108.181939) (xy 43.884646 -108.150664) (xy 43.88764 -108.117484)
			(xy 43.881946 -108.084659) (xy 43.867953 -108.054426) (xy 43.846613 -108.028843) (xy 43.833288 -108.018834)
			(xy 43.829224 -108.01604) (xy 43.824652 -108.0135) (xy 43.806036 -108.003033) (xy 43.766141 -107.9878)
			(xy 43.72426 -107.97945) (xy 43.681574 -107.978218) (xy 43.639281 -107.984139) (xy 43.598574 -107.997046)
			(xy 43.560597 -108.016577) (xy 43.54322 -108.028994) (xy 43.521851 -108.0451) (xy 43.47548 -108.071804)
			(xy 43.425831 -108.091762) (xy 43.373879 -108.104583) (xy 43.320645 -108.110015) (xy 43.267175 -108.107951)
			(xy 43.214518 -108.098432) (xy 43.163709 -108.081644) (xy 43.115746 -108.057918) (xy 43.093386 -108.043218)
			(xy 43.068054 -108.025164) (xy 43.023059 -107.982213) (xy 42.985609 -107.932546) (xy 42.95669 -107.877474)
			(xy 42.94632 -107.848146) (xy 42.938079 -107.821656) (xy 42.928464 -107.76702) (xy 42.926863 -107.711567)
			(xy 42.933311 -107.656467) (xy 42.947671 -107.602883) (xy 42.969642 -107.551943) (xy 42.998758 -107.504722)
			(xy 43.034408 -107.462217) (xy 43.075837 -107.425323) (xy 43.122174 -107.394819) (xy 43.17244 -107.371348)
			(xy 43.225575 -107.355406) (xy 43.280459 -107.347327) (xy 43.335935 -107.347283) (xy 43.390832 -107.355274)
			(xy 43.443993 -107.371133) (xy 43.494296 -107.394524) (xy 43.51782 -107.409234) (xy 43.53655 -107.420326)
			(xy 43.576907 -107.43663) (xy 43.619453 -107.445818) (xy 43.662942 -107.447621) (xy 43.706102 -107.441986)
			(xy 43.74767 -107.429079) (xy 43.786431 -107.409276) (xy 43.804078 -107.396534) (xy 43.82655 -107.379637)
			(xy 43.875473 -107.351933) (xy 43.927931 -107.331707) (xy 43.982789 -107.319397) (xy 44.03886 -107.31527)
			(xy 44.094929 -107.319415) (xy 44.149784 -107.331742) (xy 44.202236 -107.351984) (xy 44.25115 -107.379704)
			(xy 44.295467 -107.4143) (xy 44.334228 -107.455025) (xy 44.366594 -107.500997) (xy 44.391865 -107.55122)
			(xy 44.409493 -107.604608) (xy 44.419096 -107.660004) (xy 44.420203 -107.705367) (xy 45.226778 -107.705367)
			(xy 45.229437 -107.650286) (xy 45.239999 -107.596162) (xy 45.258242 -107.544122) (xy 45.283788 -107.495251)
			(xy 45.316104 -107.450567) (xy 45.354516 -107.411) (xy 45.398224 -107.377377) (xy 45.446318 -107.350396)
			(xy 45.497796 -107.33062) (xy 45.551584 -107.318462) (xy 45.606562 -107.314174) (xy 45.661585 -107.317846)
			(xy 45.715506 -107.329402) (xy 45.767201 -107.3486) (xy 45.815594 -107.375041) (xy 45.859676 -107.408173)
			(xy 45.898529 -107.447307) (xy 45.915326 -107.469178) (xy 45.925841 -107.482439) (xy 45.952374 -107.503421)
			(xy 45.983491 -107.516689) (xy 46.017001 -107.521307) (xy 46.050547 -107.516951) (xy 46.081766 -107.503928)
			(xy 46.108463 -107.483153) (xy 46.119034 -107.46994) (xy 46.125892 -107.46105) (xy 46.136147 -107.447301)
			(xy 46.14963 -107.415777) (xy 46.154236 -107.381802) (xy 46.149631 -107.347826) (xy 46.136148 -107.316302)
			(xy 46.125892 -107.302554) (xy 46.10866 -107.280179) (xy 46.080246 -107.231374) (xy 46.059341 -107.178913)
			(xy 46.046403 -107.123941) (xy 46.041716 -107.067663) (xy 46.045382 -107.011308) (xy 46.05732 -106.956111)
			(xy 46.07727 -106.903279) (xy 46.090586 -106.878374) (xy 46.101085 -106.858527) (xy 46.115739 -106.816092)
			(xy 46.122705 -106.771742) (xy 46.121766 -106.726858) (xy 46.112951 -106.682837) (xy 46.096535 -106.641052)
			(xy 46.073029 -106.602804) (xy 46.043165 -106.569283) (xy 46.025816 -106.555032) (xy 46.004081 -106.537293)
			(xy 45.965522 -106.496544) (xy 45.933346 -106.450589) (xy 45.908245 -106.400417) (xy 45.890762 -106.347111)
			(xy 45.881271 -106.291819) (xy 45.879979 -106.235734) (xy 45.886913 -106.180064) (xy 45.901924 -106.126009)
			(xy 45.924687 -106.074735) (xy 45.954713 -106.027346) (xy 45.991355 -105.984865) (xy 46.033821 -105.948206)
			(xy 46.081197 -105.918161) (xy 46.132462 -105.895377) (xy 46.186511 -105.880344) (xy 46.242178 -105.873387)
			(xy 46.298264 -105.874656) (xy 46.353559 -105.884124) (xy 46.406873 -105.901586) (xy 46.457055 -105.926666)
			(xy 46.503023 -105.958824) (xy 46.543788 -105.997366) (xy 46.57847 -106.041461) (xy 46.606322 -106.090159)
			(xy 46.626743 -106.142411) (xy 46.639293 -106.197089) (xy 46.643702 -106.253016) (xy 46.643597 -106.25455)
			(xy 48.055782 -106.25455) (xy 48.059853 -106.198928) (xy 48.071979 -106.144491) (xy 48.091902 -106.0924)
			(xy 48.119198 -106.043765) (xy 48.153284 -105.999622) (xy 48.193433 -105.960913) (xy 48.238791 -105.928462)
			(xy 48.288391 -105.902961) (xy 48.341175 -105.884954) (xy 48.396018 -105.874824) (xy 48.451752 -105.872787)
			(xy 48.507189 -105.878887) (xy 48.561146 -105.892993) (xy 48.612475 -105.914805) (xy 48.660081 -105.943859)
			(xy 48.702949 -105.979534) (xy 48.740166 -106.021071) (xy 48.770939 -106.067584) (xy 48.794611 -106.118081)
			(xy 48.810679 -106.171488) (xy 48.810866 -106.172762) (xy 56.699402 -106.172762) (xy 56.703473 -106.11714)
			(xy 56.715599 -106.062703) (xy 56.735522 -106.010612) (xy 56.762818 -105.961977) (xy 56.796904 -105.917834)
			(xy 56.837053 -105.879125) (xy 56.882411 -105.846674) (xy 56.932011 -105.821173) (xy 56.984795 -105.803166)
			(xy 57.039638 -105.793036) (xy 57.095372 -105.790999) (xy 57.150809 -105.797099) (xy 57.204766 -105.811205)
			(xy 57.256095 -105.833017) (xy 57.303701 -105.862071) (xy 57.346569 -105.897746) (xy 57.383786 -105.939283)
			(xy 57.414559 -105.985796) (xy 57.438231 -106.036293) (xy 57.454299 -106.0897) (xy 57.462419 -106.144876)
			(xy 57.462928 -106.172762) (xy 57.462419 -106.200648) (xy 57.454299 -106.255824) (xy 57.438231 -106.309231)
			(xy 57.414559 -106.359728) (xy 57.383786 -106.406241) (xy 57.346569 -106.447778) (xy 57.303701 -106.483453)
			(xy 57.256095 -106.512507) (xy 57.204766 -106.534319) (xy 57.150809 -106.548425) (xy 57.095372 -106.554525)
			(xy 57.039638 -106.552488) (xy 56.984795 -106.542358) (xy 56.932011 -106.524351) (xy 56.882411 -106.49885)
			(xy 56.837053 -106.466399) (xy 56.796904 -106.42769) (xy 56.762818 -106.383547) (xy 56.735522 -106.334912)
			(xy 56.715599 -106.282821) (xy 56.703473 -106.228384) (xy 56.699402 -106.172762) (xy 48.810866 -106.172762)
			(xy 48.818799 -106.226664) (xy 48.819308 -106.25455) (xy 48.818799 -106.282436) (xy 48.810679 -106.337612)
			(xy 48.794611 -106.391019) (xy 48.770939 -106.441516) (xy 48.740166 -106.488029) (xy 48.702949 -106.529566)
			(xy 48.667193 -106.559322) (xy 57.711185 -106.559322) (xy 57.715077 -106.504967) (xy 57.726665 -106.45172)
			(xy 57.745713 -106.400664) (xy 57.771834 -106.352838) (xy 57.787794 -106.33075) (xy 57.801343 -106.311706)
			(xy 57.82208 -106.269831) (xy 57.834812 -106.224871) (xy 57.839109 -106.17834) (xy 57.834827 -106.131808)
			(xy 57.822109 -106.086843) (xy 57.801385 -106.044962) (xy 57.787794 -106.02595) (xy 57.771834 -106.003862)
			(xy 57.745713 -105.956036) (xy 57.726665 -105.90498) (xy 57.715077 -105.851733) (xy 57.711185 -105.797378)
			(xy 57.715069 -105.743023) (xy 57.726649 -105.689774) (xy 57.74569 -105.638715) (xy 57.771804 -105.590885)
			(xy 57.804459 -105.547259) (xy 57.84299 -105.508725) (xy 57.886614 -105.476067) (xy 57.934441 -105.44995)
			(xy 57.985499 -105.430905) (xy 58.038747 -105.419321) (xy 58.093102 -105.415433) (xy 58.147457 -105.419321)
			(xy 58.200705 -105.430905) (xy 58.251763 -105.44995) (xy 58.29959 -105.476067) (xy 58.343214 -105.508725)
			(xy 58.381745 -105.547259) (xy 58.4144 -105.590885) (xy 58.440514 -105.638715) (xy 58.459555 -105.689774)
			(xy 58.471135 -105.743023) (xy 58.475019 -105.797378) (xy 58.471127 -105.851733) (xy 58.459539 -105.90498)
			(xy 58.440491 -105.956036) (xy 58.41437 -106.003862) (xy 58.39841 -106.02595) (xy 58.384767 -106.04493)
			(xy 58.364038 -106.086822) (xy 58.351317 -106.131797) (xy 58.347034 -106.17834) (xy 58.351332 -106.224882)
			(xy 58.364067 -106.269853) (xy 58.384809 -106.311738) (xy 58.39841 -106.33075) (xy 58.41437 -106.352838)
			(xy 58.440491 -106.400664) (xy 58.459539 -106.45172) (xy 58.471127 -106.504967) (xy 58.475019 -106.559322)
			(xy 58.474715 -106.563578) (xy 61.644239 -106.563578) (xy 61.650892 -106.507904) (xy 61.665625 -106.453805)
			(xy 61.688119 -106.402446) (xy 61.71789 -106.354933) (xy 61.735716 -106.33329) (xy 61.745107 -106.321591)
			(xy 61.758741 -106.294881) (xy 61.765755 -106.265725) (xy 61.765762 -106.235736) (xy 61.758762 -106.206576)
			(xy 61.745141 -106.179859) (xy 61.735716 -106.16819) (xy 61.71789 -106.146547) (xy 61.688119 -106.099034)
			(xy 61.665625 -106.047675) (xy 61.650892 -105.993576) (xy 61.644239 -105.937902) (xy 61.645808 -105.881855)
			(xy 61.655566 -105.826641) (xy 61.673303 -105.773451) (xy 61.698636 -105.723431) (xy 61.731019 -105.677659)
			(xy 61.769754 -105.63712) (xy 61.814007 -105.60269) (xy 61.862824 -105.57511) (xy 61.915153 -105.554974)
			(xy 61.969866 -105.542716) (xy 62.025784 -105.5386) (xy 62.081702 -105.542716) (xy 62.136415 -105.554974)
			(xy 62.188744 -105.57511) (xy 62.237561 -105.60269) (xy 62.281814 -105.63712) (xy 62.320549 -105.677659)
			(xy 62.352932 -105.723431) (xy 62.378265 -105.773451) (xy 62.396002 -105.826641) (xy 62.40576 -105.881855)
			(xy 62.407329 -105.937902) (xy 62.400676 -105.993576) (xy 62.385943 -106.047675) (xy 62.368287 -106.087987)
			(xy 64.336982 -106.087987) (xy 64.343307 -106.032267) (xy 64.357721 -105.978074) (xy 64.379914 -105.926574)
			(xy 64.409407 -105.878878) (xy 64.445565 -105.836014) (xy 64.487609 -105.798906) (xy 64.534633 -105.768352)
			(xy 64.585622 -105.745011) (xy 64.63948 -105.729387) (xy 64.695044 -105.721816) (xy 64.751118 -105.722461)
			(xy 64.806494 -105.731308) (xy 64.859978 -105.748166) (xy 64.910417 -105.772673) (xy 64.956726 -105.804301)
			(xy 64.997905 -105.842366) (xy 65.015872 -105.863898) (xy 65.031039 -105.881952) (xy 65.066848 -105.912621)
			(xy 65.107699 -105.936159) (xy 65.15219 -105.951759) (xy 65.198796 -105.958885) (xy 65.245916 -105.957293)
			(xy 65.291935 -105.947038) (xy 65.335272 -105.928471) (xy 65.374441 -105.90223) (xy 65.408099 -105.869215)
			(xy 65.422018 -105.850182) (xy 65.438473 -105.827473) (xy 65.47698 -105.786705) (xy 65.521041 -105.752013)
			(xy 65.569706 -105.724145) (xy 65.621926 -105.703703) (xy 65.676577 -105.691125) (xy 65.73248 -105.686684)
			(xy 65.788431 -105.690475) (xy 65.843224 -105.702416) (xy 65.895678 -105.722251) (xy 65.944664 -105.749551)
			(xy 65.989125 -105.783728) (xy 66.028103 -105.824046) (xy 66.060759 -105.869636) (xy 66.086389 -105.919516)
			(xy 66.10444 -105.972611) (xy 66.114524 -106.027776) (xy 66.116423 -106.083823) (xy 66.110096 -106.139544)
			(xy 66.109165 -106.143044) (xy 66.368674 -106.143044) (xy 66.372745 -106.087422) (xy 66.384871 -106.032985)
			(xy 66.404794 -105.980894) (xy 66.43209 -105.932259) (xy 66.466176 -105.888116) (xy 66.506325 -105.849407)
			(xy 66.551683 -105.816956) (xy 66.601283 -105.791455) (xy 66.654067 -105.773448) (xy 66.70891 -105.763318)
			(xy 66.764644 -105.761281) (xy 66.820081 -105.767381) (xy 66.874038 -105.781487) (xy 66.925367 -105.803299)
			(xy 66.972973 -105.832353) (xy 67.015841 -105.868028) (xy 67.053058 -105.909565) (xy 67.083831 -105.956078)
			(xy 67.107503 -106.006575) (xy 67.123571 -106.059982) (xy 67.131691 -106.115158) (xy 67.1322 -106.143044)
			(xy 67.131691 -106.17093) (xy 67.123571 -106.226106) (xy 67.107503 -106.279513) (xy 67.083831 -106.33001)
			(xy 67.053058 -106.376523) (xy 67.015841 -106.41806) (xy 66.972973 -106.453735) (xy 66.925367 -106.482789)
			(xy 66.874038 -106.504601) (xy 66.820081 -106.518707) (xy 66.764644 -106.524807) (xy 66.70891 -106.52277)
			(xy 66.654067 -106.51264) (xy 66.601283 -106.494633) (xy 66.551683 -106.469132) (xy 66.506325 -106.436681)
			(xy 66.466176 -106.397972) (xy 66.43209 -106.353829) (xy 66.404794 -106.305194) (xy 66.384871 -106.253103)
			(xy 66.372745 -106.198666) (xy 66.368674 -106.143044) (xy 66.109165 -106.143044) (xy 66.09568 -106.193739)
			(xy 66.073485 -106.245239) (xy 66.043989 -106.292935) (xy 66.007829 -106.335799) (xy 65.965783 -106.372907)
			(xy 65.918757 -106.403459) (xy 65.867766 -106.426799) (xy 65.813906 -106.442421) (xy 65.75834 -106.44999)
			(xy 65.702265 -106.449343) (xy 65.646888 -106.440493) (xy 65.593404 -106.423632) (xy 65.542965 -106.399122)
			(xy 65.496657 -106.367492) (xy 65.455479 -106.329423) (xy 65.437512 -106.30789) (xy 65.422363 -106.289821)
			(xy 65.38655 -106.259154) (xy 65.345696 -106.235617) (xy 65.301202 -106.220019) (xy 65.254595 -106.212894)
			(xy 65.207473 -106.214488) (xy 65.161453 -106.224745) (xy 65.118115 -106.243313) (xy 65.078944 -106.269556)
			(xy 65.045285 -106.302573) (xy 65.031366 -106.321606) (xy 65.014924 -106.344323) (xy 64.976418 -106.385091)
			(xy 64.932358 -106.419782) (xy 64.883695 -106.447649) (xy 64.831475 -106.468092) (xy 64.776826 -106.480669)
			(xy 64.720924 -106.485111) (xy 64.664975 -106.481321) (xy 64.610183 -106.46938) (xy 64.557729 -106.449547)
			(xy 64.508744 -106.422249) (xy 64.464284 -106.388073) (xy 64.425305 -106.347756) (xy 64.392649 -106.302168)
			(xy 64.367019 -106.25229) (xy 64.348967 -106.199197) (xy 64.338882 -106.144033) (xy 64.336982 -106.087987)
			(xy 62.368287 -106.087987) (xy 62.363449 -106.099034) (xy 62.333678 -106.146547) (xy 62.315852 -106.16819)
			(xy 62.306386 -106.179831) (xy 62.292763 -106.206559) (xy 62.285762 -106.235731) (xy 62.285769 -106.26573)
			(xy 62.292784 -106.294898) (xy 62.30642 -106.321619) (xy 62.315852 -106.33329) (xy 62.333678 -106.354933)
			(xy 62.363449 -106.402446) (xy 62.385943 -106.453805) (xy 62.400676 -106.507904) (xy 62.407329 -106.563578)
			(xy 62.40576 -106.619625) (xy 62.396002 -106.674839) (xy 62.378265 -106.728029) (xy 62.352932 -106.778049)
			(xy 62.320549 -106.823821) (xy 62.281814 -106.86436) (xy 62.237561 -106.89879) (xy 62.188744 -106.92637)
			(xy 62.136415 -106.946506) (xy 62.081702 -106.958764) (xy 62.025784 -106.96288) (xy 61.969866 -106.958764)
			(xy 61.915153 -106.946506) (xy 61.862824 -106.92637) (xy 61.814007 -106.89879) (xy 61.769754 -106.86436)
			(xy 61.731019 -106.823821) (xy 61.698636 -106.778049) (xy 61.673303 -106.728029) (xy 61.655566 -106.674839)
			(xy 61.645808 -106.619625) (xy 61.644239 -106.563578) (xy 58.474715 -106.563578) (xy 58.471135 -106.613677)
			(xy 58.459555 -106.666926) (xy 58.440514 -106.717985) (xy 58.4144 -106.765815) (xy 58.381745 -106.809441)
			(xy 58.343214 -106.847975) (xy 58.29959 -106.880633) (xy 58.251763 -106.90675) (xy 58.200705 -106.925795)
			(xy 58.147457 -106.937379) (xy 58.093102 -106.941267) (xy 58.038747 -106.937379) (xy 57.985499 -106.925795)
			(xy 57.934441 -106.90675) (xy 57.886614 -106.880633) (xy 57.84299 -106.847975) (xy 57.804459 -106.809441)
			(xy 57.771804 -106.765815) (xy 57.74569 -106.717985) (xy 57.726649 -106.666926) (xy 57.715069 -106.613677)
			(xy 57.711185 -106.559322) (xy 48.667193 -106.559322) (xy 48.660081 -106.565241) (xy 48.612475 -106.594295)
			(xy 48.561146 -106.616107) (xy 48.507189 -106.630213) (xy 48.451752 -106.636313) (xy 48.396018 -106.634276)
			(xy 48.341175 -106.624146) (xy 48.288391 -106.606139) (xy 48.238791 -106.580638) (xy 48.193433 -106.548187)
			(xy 48.153284 -106.509478) (xy 48.119198 -106.465335) (xy 48.091902 -106.4167) (xy 48.071979 -106.364609)
			(xy 48.059853 -106.310172) (xy 48.055782 -106.25455) (xy 46.643597 -106.25455) (xy 46.639874 -106.308985)
			(xy 46.627892 -106.363791) (xy 46.608015 -106.416252) (xy 46.594776 -106.440986) (xy 46.584196 -106.460793)
			(xy 46.569544 -106.503239) (xy 46.562583 -106.5476) (xy 46.563531 -106.592493) (xy 46.572357 -106.636521)
			(xy 46.588787 -106.678311) (xy 46.612308 -106.716561) (xy 46.642188 -106.750079) (xy 46.659546 -106.764328)
			(xy 46.662086 -106.76636) (xy 46.675834 -106.776616) (xy 46.707359 -106.790096) (xy 46.741334 -106.7947)
			(xy 46.775309 -106.790096) (xy 46.806834 -106.776616) (xy 46.820582 -106.76636) (xy 46.842628 -106.749318)
			(xy 46.890747 -106.721222) (xy 46.942442 -106.700425) (xy 46.996612 -106.687369) (xy 47.052106 -106.682332)
			(xy 47.107741 -106.685422) (xy 47.162336 -106.696571) (xy 47.214728 -106.715544) (xy 47.263802 -106.741937)
			(xy 47.308516 -106.775187) (xy 47.347916 -106.814589) (xy 47.381166 -106.859302) (xy 47.407558 -106.908377)
			(xy 47.42653 -106.960769) (xy 47.437679 -107.015364) (xy 47.440768 -107.071) (xy 47.43573 -107.126493)
			(xy 47.422673 -107.180663) (xy 47.401875 -107.232358) (xy 47.373779 -107.280477) (xy 47.356776 -107.302554)
			(xy 47.346519 -107.316301) (xy 47.33304 -107.347826) (xy 47.332394 -107.352592) (xy 67.06311 -107.352592)
			(xy 67.067181 -107.29697) (xy 67.079307 -107.242533) (xy 67.09923 -107.190442) (xy 67.126526 -107.141807)
			(xy 67.160612 -107.097664) (xy 67.200761 -107.058955) (xy 67.246119 -107.026504) (xy 67.295719 -107.001003)
			(xy 67.348503 -106.982996) (xy 67.403346 -106.972866) (xy 67.45908 -106.970829) (xy 67.514517 -106.976929)
			(xy 67.568474 -106.991035) (xy 67.619803 -107.012847) (xy 67.667409 -107.041901) (xy 67.710277 -107.077576)
			(xy 67.747494 -107.119113) (xy 67.778267 -107.165626) (xy 67.801939 -107.216123) (xy 67.818007 -107.26953)
			(xy 67.826127 -107.324706) (xy 67.826636 -107.352592) (xy 67.826127 -107.380478) (xy 67.818007 -107.435654)
			(xy 67.801939 -107.489061) (xy 67.778267 -107.539558) (xy 67.747494 -107.586071) (xy 67.710277 -107.627608)
			(xy 67.667409 -107.663283) (xy 67.619803 -107.692337) (xy 67.568474 -107.714149) (xy 67.514517 -107.728255)
			(xy 67.45908 -107.734355) (xy 67.403346 -107.732318) (xy 67.348503 -107.722188) (xy 67.295719 -107.704181)
			(xy 67.246119 -107.67868) (xy 67.200761 -107.646229) (xy 67.160612 -107.60752) (xy 67.126526 -107.563377)
			(xy 67.09923 -107.514742) (xy 67.079307 -107.462651) (xy 67.067181 -107.408214) (xy 67.06311 -107.352592)
			(xy 47.332394 -107.352592) (xy 47.328436 -107.381802) (xy 47.333041 -107.415777) (xy 47.346521 -107.447301)
			(xy 47.356776 -107.46105) (xy 47.373741 -107.483152) (xy 47.401834 -107.531265) (xy 47.422629 -107.582953)
			(xy 47.435683 -107.637117) (xy 47.44072 -107.692603) (xy 47.437632 -107.748231) (xy 47.426484 -107.802819)
			(xy 47.407514 -107.855204) (xy 47.381126 -107.904273) (xy 47.34788 -107.948981) (xy 47.308485 -107.988377)
			(xy 47.263777 -108.021623) (xy 47.214709 -108.048012) (xy 47.162324 -108.066983) (xy 47.107736 -108.078131)
			(xy 47.052108 -108.08122) (xy 46.996622 -108.076184) (xy 46.942458 -108.06313) (xy 46.89077 -108.042336)
			(xy 46.842656 -108.014244) (xy 46.820582 -107.997244) (xy 46.806834 -107.986988) (xy 46.775309 -107.973508)
			(xy 46.741334 -107.968904) (xy 46.707359 -107.973508) (xy 46.675834 -107.986988) (xy 46.662086 -107.997244)
			(xy 46.638957 -108.015004) (xy 46.588426 -108.044101) (xy 46.534054 -108.065165) (xy 46.477109 -108.077705)
			(xy 46.418918 -108.081428) (xy 46.360839 -108.076248) (xy 46.304225 -108.062286) (xy 46.250398 -108.039867)
			(xy 46.200611 -108.009514) (xy 46.177962 -107.991148) (xy 46.160751 -107.977266) (xy 46.122508 -107.955081)
			(xy 46.081001 -107.939849) (xy 46.037486 -107.93203) (xy 45.993273 -107.931859) (xy 45.949698 -107.939342)
			(xy 45.908076 -107.954253) (xy 45.869662 -107.976142) (xy 45.852334 -107.989878) (xy 45.830765 -108.007063)
			(xy 45.783696 -108.035795) (xy 45.732981 -108.057451) (xy 45.679677 -108.071581) (xy 45.624894 -108.077888)
			(xy 45.569773 -108.076243) (xy 45.515464 -108.06668) (xy 45.463097 -108.049397) (xy 45.413764 -108.024755)
			(xy 45.368492 -107.993267) (xy 45.328226 -107.955589) (xy 45.293804 -107.912507) (xy 45.265942 -107.864917)
			(xy 45.245223 -107.813813) (xy 45.232077 -107.760257) (xy 45.226778 -107.705367) (xy 44.420203 -107.705367)
			(xy 44.420467 -107.716209) (xy 44.413576 -107.772008) (xy 44.398572 -107.826191) (xy 44.375781 -107.877587)
			(xy 44.345695 -107.925082) (xy 44.308965 -107.967648) (xy 44.287948 -107.986322) (xy 44.271771 -108.001216)
			(xy 44.2443 -108.035548) (xy 44.223153 -108.074098) (xy 44.208961 -108.115714) (xy 44.202148 -108.159153)
			(xy 44.202917 -108.203115) (xy 44.211246 -108.246289) (xy 44.226886 -108.287383) (xy 44.249369 -108.325169)
			(xy 44.26331 -108.342176) (xy 44.283542 -108.365455) (xy 44.31699 -108.417271) (xy 44.329858 -108.4453)
			(xy 44.336157 -108.458608) (xy 44.353854 -108.482128) (xy 44.376478 -108.500957) (xy 44.402819 -108.514091)
			(xy 44.431473 -108.520827) (xy 44.44619 -108.521246) (xy 57.400952 -108.521246) (xy 57.46496 -108.457238)
			(xy 57.71134 -108.457238) (xy 57.817004 -108.398564) (xy 57.83326 -108.376212) (xy 57.83453 -108.374688)
			(xy 57.840118 -108.367068) (xy 57.852854 -108.348442) (xy 57.872229 -108.307697) (xy 57.884106 -108.264172)
			(xy 57.888111 -108.219233) (xy 57.884118 -108.174293) (xy 57.872252 -108.130764) (xy 57.852887 -108.090014)
			(xy 57.840118 -108.071412) (xy 57.823726 -108.049403) (xy 57.796759 -108.001609) (xy 57.776916 -107.950445)
			(xy 57.764609 -107.896966) (xy 57.76009 -107.842275) (xy 57.763452 -107.787501) (xy 57.774628 -107.733774)
			(xy 57.793385 -107.682203) (xy 57.819337 -107.63385) (xy 57.851949 -107.589714) (xy 57.890547 -107.550706)
			(xy 57.934336 -107.51763) (xy 57.982412 -107.491168) (xy 58.033783 -107.471868) (xy 58.087389 -107.460125)
			(xy 58.142124 -107.456184) (xy 58.196859 -107.460125) (xy 58.250465 -107.471868) (xy 58.301836 -107.491168)
			(xy 58.349912 -107.51763) (xy 58.393701 -107.550706) (xy 58.432299 -107.589714) (xy 58.464911 -107.63385)
			(xy 58.490863 -107.682203) (xy 58.50962 -107.733774) (xy 58.520796 -107.787501) (xy 58.524158 -107.842275)
			(xy 58.519639 -107.896966) (xy 58.507332 -107.950445) (xy 58.487489 -108.001609) (xy 58.460522 -108.049403)
			(xy 58.44413 -108.071412) (xy 58.431399 -108.090037) (xy 58.412034 -108.130779) (xy 58.400169 -108.1743)
			(xy 58.396175 -108.219233) (xy 58.40018 -108.264164) (xy 58.412057 -108.307682) (xy 58.431433 -108.348419)
			(xy 58.44413 -108.367068) (xy 58.45556 -108.382816) (xy 58.465974 -108.39831) (xy 58.4835 -108.425996)
			(xy 58.540396 -108.457238) (xy 61.638434 -108.457238) (xy 61.693552 -108.423202) (xy 61.709046 -108.400342)
			(xy 61.715266 -108.391247) (xy 61.72861 -108.373711) (xy 61.735716 -108.36529) (xy 61.74515 -108.35362)
			(xy 61.758789 -108.326899) (xy 61.765807 -108.297731) (xy 61.765814 -108.26773) (xy 61.758811 -108.238558)
			(xy 61.745184 -108.21183) (xy 61.735716 -108.20019) (xy 61.71789 -108.178547) (xy 61.688119 -108.131034)
			(xy 61.665625 -108.079675) (xy 61.650892 -108.025576) (xy 61.644239 -107.969902) (xy 61.645808 -107.913855)
			(xy 61.655566 -107.858641) (xy 61.673303 -107.805451) (xy 61.698636 -107.755431) (xy 61.731019 -107.709659)
			(xy 61.769754 -107.66912) (xy 61.814007 -107.63469) (xy 61.862824 -107.60711) (xy 61.915153 -107.586974)
			(xy 61.969866 -107.574716) (xy 62.025784 -107.5706) (xy 62.081702 -107.574716) (xy 62.136415 -107.586974)
			(xy 62.188744 -107.60711) (xy 62.237561 -107.63469) (xy 62.281814 -107.66912) (xy 62.320549 -107.709659)
			(xy 62.352932 -107.755431) (xy 62.378265 -107.805451) (xy 62.396002 -107.858641) (xy 62.40576 -107.913855)
			(xy 62.407329 -107.969902) (xy 62.400676 -108.025576) (xy 62.385943 -108.079675) (xy 62.363449 -108.131034)
			(xy 62.333678 -108.178547) (xy 62.315852 -108.20019) (xy 62.306429 -108.21186) (xy 62.292812 -108.238577)
			(xy 62.285813 -108.267737) (xy 62.28582 -108.297724) (xy 62.292833 -108.32688) (xy 62.306463 -108.353591)
			(xy 62.315852 -108.36529) (xy 62.323036 -108.373828) (xy 62.336507 -108.39162) (xy 62.342776 -108.40085)
			(xy 62.36081 -108.42752) (xy 62.416436 -108.457238) (xy 64.23152 -108.457238) (xy 64.248157 -108.456695)
			(xy 64.280301 -108.448093) (xy 64.309131 -108.431477) (xy 64.332688 -108.407977) (xy 64.349374 -108.379188)
			(xy 64.354202 -108.363258) (xy 64.361763 -108.336997) (xy 64.383366 -108.286802) (xy 64.411911 -108.240203)
			(xy 64.446814 -108.198154) (xy 64.48736 -108.161517) (xy 64.53272 -108.131041) (xy 64.581964 -108.10735)
			(xy 64.634086 -108.09093) (xy 64.688017 -108.082115) (xy 64.742654 -108.081087) (xy 64.796879 -108.087867)
			(xy 64.849581 -108.102316) (xy 64.899682 -108.124139) (xy 64.946155 -108.152887) (xy 64.98805 -108.187974)
			(xy 65.02451 -108.22868) (xy 65.054787 -108.274173) (xy 65.078262 -108.323521) (xy 65.094454 -108.375713)
			(xy 65.099184 -108.402628) (xy 65.170304 -108.457238) (xy 71.148956 -108.457238) (xy 72.65162 -106.954574)
			(xy 72.65162 -103.884222) (xy 71.350124 -102.582726) (xy 71.316088 -102.57409) (xy 71.287859 -102.566364)
			(xy 71.234005 -102.543452) (xy 71.184282 -102.512585) (xy 71.139855 -102.474488) (xy 71.101767 -102.430053)
			(xy 71.070911 -102.380323) (xy 71.04801 -102.326465) (xy 71.040244 -102.298246) (xy 71.031608 -102.26421)
			(xy 70.47865 -101.711252) (xy 69.77888 -101.711252) (xy 69.757236 -101.711683) (xy 69.714572 -101.71901)
			(xy 69.67377 -101.733467) (xy 69.636009 -101.754634) (xy 69.602386 -101.781897) (xy 69.573872 -101.814468)
			(xy 69.551296 -101.851403) (xy 69.53531 -101.891631) (xy 69.526377 -101.933987) (xy 69.525134 -101.9556)
			(xy 69.52357 -101.983422) (xy 69.513378 -102.038204) (xy 69.495326 -102.090921) (xy 69.469797 -102.140452)
			(xy 69.437334 -102.185741) (xy 69.398629 -102.225827) (xy 69.354504 -102.259856) (xy 69.305898 -102.287105)
			(xy 69.253846 -102.306993) (xy 69.199454 -102.319098) (xy 69.14388 -102.323161) (xy 69.088306 -102.319098)
			(xy 69.033914 -102.306993) (xy 68.981862 -102.287105) (xy 68.933256 -102.259856) (xy 68.889131 -102.225827)
			(xy 68.850426 -102.185741) (xy 68.817963 -102.140452) (xy 68.792434 -102.090921) (xy 68.774382 -102.038204)
			(xy 68.76419 -101.983422) (xy 68.762626 -101.9556) (xy 68.761363 -101.933994) (xy 68.752408 -101.891654)
			(xy 68.736407 -101.851444) (xy 68.713826 -101.814526) (xy 68.685315 -101.781968) (xy 68.651701 -101.754711)
			(xy 68.613954 -101.733544) (xy 68.573167 -101.719078) (xy 68.530518 -101.711732) (xy 68.50888 -101.711252)
			(xy 67.986656 -101.711252) (xy 67.964745 -101.711716) (xy 67.921573 -101.71924) (xy 67.880332 -101.734058)
			(xy 67.842243 -101.755731) (xy 67.808437 -101.783615) (xy 67.779915 -101.816886) (xy 67.757522 -101.854555)
			(xy 67.741922 -101.895507) (xy 67.733579 -101.938528) (xy 67.732656 -101.960426) (xy 67.731622 -101.988628)
			(xy 67.722271 -102.044282) (xy 67.704825 -102.097951) (xy 67.679665 -102.148466) (xy 67.647339 -102.194724)
			(xy 67.608552 -102.235716) (xy 67.564151 -102.270548) (xy 67.515103 -102.298461) (xy 67.46248 -102.318845)
			(xy 67.407428 -102.331256) (xy 67.351148 -102.335423) (xy 67.294868 -102.331256) (xy 67.239816 -102.318845)
			(xy 67.187193 -102.298461) (xy 67.138145 -102.270548) (xy 67.093744 -102.235716) (xy 67.054957 -102.194724)
			(xy 67.022631 -102.148466) (xy 66.997471 -102.097951) (xy 66.980025 -102.044282) (xy 66.970674 -101.988628)
			(xy 66.96964 -101.960426) (xy 66.968768 -101.938521) (xy 66.960434 -101.895487) (xy 66.94484 -101.85452)
			(xy 66.922445 -101.816838) (xy 66.893917 -101.783558) (xy 66.8601 -101.755668) (xy 66.821998 -101.733995)
			(xy 66.780743 -101.719183) (xy 66.737557 -101.711671) (xy 66.71564 -101.711252) (xy 57.295542 -101.711252)
			(xy 57.271861 -101.711775) (xy 57.225318 -101.720546) (xy 57.181207 -101.737791) (xy 57.141056 -101.762913)
			(xy 57.106258 -101.795042) (xy 57.078017 -101.833064) (xy 57.057313 -101.875661) (xy 57.044863 -101.921358)
			(xy 57.041098 -101.96857) (xy 57.043066 -101.992176) (xy 57.045491 -102.019896) (xy 57.043244 -102.075494)
			(xy 57.032946 -102.130177) (xy 57.014816 -102.182783) (xy 56.989237 -102.232199) (xy 56.956753 -102.277376)
			(xy 56.918051 -102.317355) (xy 56.873953 -102.35129) (xy 56.825395 -102.378461) (xy 56.773405 -102.398291)
			(xy 56.719086 -102.410359) (xy 56.66359 -102.414411) (xy 56.608094 -102.410359) (xy 56.553775 -102.398291)
			(xy 56.501785 -102.378461) (xy 56.453227 -102.35129) (xy 56.409129 -102.317355) (xy 56.370427 -102.277376)
			(xy 56.337943 -102.232199) (xy 56.312364 -102.182783) (xy 56.294234 -102.130177) (xy 56.283936 -102.075494)
			(xy 56.281689 -102.019896) (xy 56.284114 -101.992176) (xy 56.286097 -101.968576) (xy 56.2823 -101.921375)
			(xy 56.269829 -101.875693) (xy 56.249114 -101.83311) (xy 56.220872 -101.795099) (xy 56.186081 -101.762976)
			(xy 56.145942 -101.737851) (xy 56.101845 -101.720593) (xy 56.055315 -101.711798) (xy 56.031638 -101.711252)
			(xy 55.002176 -101.711252) (xy 54.951376 -101.735128) (xy 54.933088 -101.756718) (xy 54.914506 -101.778158)
			(xy 54.87209 -101.815835) (xy 54.824557 -101.84681) (xy 54.798976 -101.85908) (xy 54.779121 -101.869573)
			(xy 54.74314 -101.896439) (xy 54.712433 -101.929204) (xy 54.687955 -101.96685) (xy 54.670464 -102.008208)
			(xy 54.660505 -102.051994) (xy 54.658386 -102.096849) (xy 54.6608 -102.119176) (xy 54.663865 -102.146521)
			(xy 54.663038 -102.201538) (xy 54.654312 -102.255865) (xy 54.63787 -102.308374) (xy 54.614053 -102.357975)
			(xy 54.583355 -102.403639) (xy 54.546413 -102.444417) (xy 54.503994 -102.479463) (xy 54.45698 -102.508049)
			(xy 54.406345 -102.529582) (xy 54.353141 -102.543615) (xy 54.298473 -102.549857) (xy 54.243476 -102.548178)
			(xy 54.2163 -102.543864) (xy 54.189652 -102.538691) (xy 54.138062 -102.521808) (xy 54.089382 -102.497791)
			(xy 54.044593 -102.467124) (xy 54.024276 -102.449122) (xy 54.011652 -102.438222) (xy 53.982078 -102.422822)
			(xy 53.949526 -102.415605) (xy 53.916215 -102.417061) (xy 53.884416 -102.427092) (xy 53.8563 -102.445014)
			(xy 53.844698 -102.456996) (xy 53.82691 -102.475741) (xy 53.787148 -102.508747) (xy 53.76545 -102.522782)
			(xy 53.741318 -102.537242) (xy 53.689731 -102.559684) (xy 53.635408 -102.574308) (xy 53.579527 -102.580799)
			(xy 53.523298 -102.579014) (xy 53.467941 -102.568994) (xy 53.414654 -102.550955) (xy 53.364594 -102.525287)
			(xy 53.318844 -102.492549) (xy 53.278397 -102.453448) (xy 53.244129 -102.408832) (xy 53.216783 -102.359669)
			(xy 53.196951 -102.307023) (xy 53.185063 -102.252037) (xy 53.181378 -102.195901) (xy 53.185973 -102.139832)
			(xy 53.198752 -102.085045) (xy 53.208682 -102.058724) (xy 53.216516 -102.037629) (xy 53.225457 -101.993533)
			(xy 53.226493 -101.94855) (xy 53.219593 -101.904088) (xy 53.204973 -101.861536) (xy 53.183088 -101.822223)
			(xy 53.154623 -101.787377) (xy 53.120467 -101.758088) (xy 53.081688 -101.73527) (xy 53.039497 -101.719637)
			(xy 52.995213 -101.711677) (xy 52.972716 -101.711252) (xy 52.814982 -101.711252) (xy 52.798333 -101.711797)
			(xy 52.76617 -101.720417) (xy 52.737332 -101.737065) (xy 52.713784 -101.760608) (xy 52.697129 -101.789442)
			(xy 52.688501 -101.821603) (xy 52.687982 -101.838252) (xy 52.687982 -101.883464) (xy 52.71643 -101.918262)
			(xy 52.738782 -101.948742) (xy 52.75343 -101.971747) (xy 52.776715 -102.021063) (xy 52.792741 -102.073193)
			(xy 52.80118 -102.127073) (xy 52.801862 -102.181606) (xy 52.794771 -102.235681) (xy 52.780052 -102.288194)
			(xy 52.758006 -102.338077) (xy 52.729082 -102.384312) (xy 52.693869 -102.425957) (xy 52.653084 -102.462164)
			(xy 52.60756 -102.492195) (xy 52.558223 -102.515437) (xy 52.506079 -102.531416) (xy 52.479194 -102.53599)
			(xy 52.451501 -102.539808) (xy 52.395601 -102.540256) (xy 52.340235 -102.532539) (xy 52.286588 -102.516825)
			(xy 52.235809 -102.493448) (xy 52.188986 -102.46291) (xy 52.147121 -102.425865) (xy 52.111112 -102.383106)
			(xy 52.08173 -102.335549) (xy 52.059604 -102.284213) (xy 52.045207 -102.230197) (xy 52.038849 -102.174659)
			(xy 52.040665 -102.118787) (xy 52.050617 -102.063778) (xy 52.059078 -102.037134) (xy 52.06526 -102.014332)
			(xy 52.070019 -101.967334) (xy 52.066011 -101.920266) (xy 52.053375 -101.874748) (xy 52.032545 -101.83235)
			(xy 52.004239 -101.794532) (xy 51.969431 -101.762595) (xy 51.929322 -101.737641) (xy 51.885292 -101.720528)
			(xy 51.838858 -101.711847) (xy 51.815238 -101.711252) (xy 47.170594 -101.711252) (xy 46.55015 -102.331696)
			(xy 48.55824 -102.331696) (xy 48.565094 -102.277203) (xy 48.579692 -102.224257) (xy 48.601732 -102.17395)
			(xy 48.630758 -102.127325) (xy 48.666171 -102.085343) (xy 48.707238 -102.048874) (xy 48.75311 -102.018671)
			(xy 48.802839 -101.995359) (xy 48.855397 -101.979419) (xy 48.909698 -101.97118) (xy 48.964619 -101.970814)
			(xy 49.019025 -101.978327) (xy 49.071792 -101.993565) (xy 49.121827 -102.016212) (xy 49.168098 -102.045801)
			(xy 49.209648 -102.081719) (xy 49.227994 -102.102158) (xy 49.243185 -102.119038) (xy 49.278536 -102.147538)
			(xy 49.318388 -102.169305) (xy 49.361473 -102.183645) (xy 49.40642 -102.190102) (xy 49.4518 -102.18847)
			(xy 49.496168 -102.178802) (xy 49.538112 -102.161405) (xy 49.576298 -102.136833) (xy 49.593246 -102.121716)
			(xy 49.613614 -102.103297) (xy 49.658738 -102.072) (xy 49.707884 -102.047497) (xy 49.760036 -102.030295)
			(xy 49.814116 -102.020749) (xy 49.869005 -102.019057) (xy 49.92357 -102.025253) (xy 49.976682 -102.03921)
			(xy 50.027245 -102.060639) (xy 50.074211 -102.089097) (xy 50.116612 -102.123996) (xy 50.153569 -102.164614)
			(xy 50.184321 -102.210112) (xy 50.20823 -102.25955) (xy 50.224802 -102.311906) (xy 50.233696 -102.366096)
			(xy 50.234726 -102.421002) (xy 50.232755 -102.436676) (xy 50.7398 -102.436676) (xy 50.743871 -102.381054)
			(xy 50.755997 -102.326617) (xy 50.77592 -102.274526) (xy 50.803216 -102.225891) (xy 50.837302 -102.181748)
			(xy 50.877451 -102.143039) (xy 50.922809 -102.110588) (xy 50.972409 -102.085087) (xy 51.025193 -102.06708)
			(xy 51.080036 -102.05695) (xy 51.13577 -102.054913) (xy 51.191207 -102.061013) (xy 51.245164 -102.075119)
			(xy 51.296493 -102.096931) (xy 51.344099 -102.125985) (xy 51.386967 -102.16166) (xy 51.424184 -102.203197)
			(xy 51.454957 -102.24971) (xy 51.478629 -102.300207) (xy 51.494697 -102.353614) (xy 51.502817 -102.40879)
			(xy 51.503326 -102.436676) (xy 51.502817 -102.464562) (xy 51.494697 -102.519738) (xy 51.478629 -102.573145)
			(xy 51.454957 -102.623642) (xy 51.424184 -102.670155) (xy 51.386967 -102.711692) (xy 51.344099 -102.747367)
			(xy 51.296493 -102.776421) (xy 51.245164 -102.798233) (xy 51.191207 -102.812339) (xy 51.13577 -102.818439)
			(xy 51.080036 -102.816402) (xy 51.025193 -102.806272) (xy 50.972409 -102.788265) (xy 50.922809 -102.762764)
			(xy 50.877451 -102.730313) (xy 50.837302 -102.691604) (xy 50.803216 -102.647461) (xy 50.77592 -102.598826)
			(xy 50.755997 -102.546735) (xy 50.743871 -102.492298) (xy 50.7398 -102.436676) (xy 50.232755 -102.436676)
			(xy 50.227873 -102.475488) (xy 50.213277 -102.528429) (xy 50.191241 -102.578729) (xy 50.162219 -102.62535)
			(xy 50.126812 -102.667326) (xy 50.085751 -102.703792) (xy 50.039885 -102.733993) (xy 49.990163 -102.757304)
			(xy 49.937612 -102.773245) (xy 49.883318 -102.781485) (xy 49.828404 -102.781854) (xy 49.774004 -102.774345)
			(xy 49.721243 -102.759112) (xy 49.671212 -102.736471) (xy 49.624945 -102.70689) (xy 49.583398 -102.670979)
			(xy 49.565052 -102.650544) (xy 49.549815 -102.633708) (xy 49.514473 -102.605207) (xy 49.474628 -102.583438)
			(xy 49.431551 -102.569094) (xy 49.38661 -102.562633) (xy 49.341236 -102.564258) (xy 49.296873 -102.57392)
			(xy 49.254932 -102.591309) (xy 49.216748 -102.615874) (xy 49.1998 -102.630986) (xy 49.179432 -102.64941)
			(xy 49.134304 -102.680714) (xy 49.085154 -102.705224) (xy 49.032997 -102.722432) (xy 48.978911 -102.731982)
			(xy 48.924015 -102.733678) (xy 48.869443 -102.727483) (xy 48.816324 -102.713527) (xy 48.765754 -102.692098)
			(xy 48.718781 -102.663638) (xy 48.676374 -102.628737) (xy 48.63941 -102.588114) (xy 48.608654 -102.542611)
			(xy 48.584742 -102.493168) (xy 48.568166 -102.440806) (xy 48.559271 -102.386609) (xy 48.55824 -102.331696)
			(xy 46.55015 -102.331696) (xy 44.77258 -104.109266) (xy 34.25444 -104.109266) (xy 34.049716 -103.904796)
			(xy 33.91535 -103.904796) (xy 33.009332 -102.998778) (xy 33.009332 -102.864412) (xy 31.989522 -101.844348)
			(xy 31.977372 -101.833001) (xy 31.948576 -101.816417) (xy 31.916475 -101.807826) (xy 31.89986 -101.807264)
			(xy 29.85008 -101.807264) (xy 29.218382 -102.439216) (xy 27.780234 -102.439216) (xy 27.61742 -102.601776)
			(xy 27.22118 -102.998016) (xy 27.22118 -104.44353) (xy 27.22118 -104.477566) (xy 27.22118 -106.149112)
			(xy 28.626661 -106.149112) (xy 28.630553 -106.094757) (xy 28.642141 -106.04151) (xy 28.661189 -105.990454)
			(xy 28.68731 -105.942628) (xy 28.70327 -105.92054) (xy 28.71683 -105.901503) (xy 28.737568 -105.859627)
			(xy 28.7503 -105.814664) (xy 28.754596 -105.768132) (xy 28.750312 -105.721599) (xy 28.737591 -105.676633)
			(xy 28.716863 -105.634751) (xy 28.70327 -105.61574) (xy 28.68731 -105.593652) (xy 28.661189 -105.545826)
			(xy 28.642141 -105.49477) (xy 28.630553 -105.441523) (xy 28.626661 -105.387168) (xy 28.630545 -105.332813)
			(xy 28.642125 -105.279564) (xy 28.661166 -105.228505) (xy 28.68728 -105.180675) (xy 28.719935 -105.137049)
			(xy 28.758466 -105.098515) (xy 28.80209 -105.065857) (xy 28.849917 -105.03974) (xy 28.900975 -105.020695)
			(xy 28.954223 -105.009111) (xy 29.008578 -105.005223) (xy 29.062933 -105.009111) (xy 29.116181 -105.020695)
			(xy 29.167239 -105.03974) (xy 29.215066 -105.065857) (xy 29.25869 -105.098515) (xy 29.297041 -105.136869)
			(xy 30.917438 -105.136869) (xy 30.921443 -105.081731) (xy 30.933366 -105.027749) (xy 30.952956 -104.976054)
			(xy 30.979803 -104.927728) (xy 31.013346 -104.883784) (xy 31.05288 -104.845142) (xy 31.097579 -104.812611)
			(xy 31.146505 -104.786874) (xy 31.198635 -104.768469) (xy 31.252875 -104.757782) (xy 31.308089 -104.755037)
			(xy 31.363122 -104.760291) (xy 31.41682 -104.773434) (xy 31.468058 -104.794191) (xy 31.515763 -104.822127)
			(xy 31.537656 -104.839008) (xy 31.551404 -104.849264) (xy 31.582929 -104.862744) (xy 31.616904 -104.867348)
			(xy 31.650879 -104.862744) (xy 31.682404 -104.849264) (xy 31.696152 -104.839008) (xy 31.718813 -104.821541)
			(xy 31.768333 -104.792883) (xy 31.821576 -104.771941) (xy 31.87735 -104.759185) (xy 31.934404 -104.7549)
			(xy 31.991458 -104.759185) (xy 32.047232 -104.771941) (xy 32.100475 -104.792883) (xy 32.149995 -104.821541)
			(xy 32.172656 -104.839008) (xy 32.186404 -104.849264) (xy 32.217929 -104.862744) (xy 32.251904 -104.867348)
			(xy 32.285879 -104.862744) (xy 32.317404 -104.849264) (xy 32.331152 -104.839008) (xy 32.353001 -104.822063)
			(xy 32.400715 -104.794122) (xy 32.451963 -104.773362) (xy 32.505671 -104.760217) (xy 32.560714 -104.754963)
			(xy 32.615938 -104.75771) (xy 32.670188 -104.768399) (xy 32.722327 -104.786808) (xy 32.771262 -104.81255)
			(xy 32.815969 -104.845087) (xy 32.855511 -104.883736) (xy 32.889059 -104.927689) (xy 32.915911 -104.976024)
			(xy 32.935505 -105.027729) (xy 32.94743 -105.081721) (xy 32.951436 -105.136869) (xy 32.947439 -105.192017)
			(xy 32.935523 -105.246011) (xy 32.915938 -105.297719) (xy 32.889093 -105.346059) (xy 32.855552 -105.390017)
			(xy 32.854858 -105.390696) (xy 44.320204 -105.390696) (xy 44.324275 -105.335074) (xy 44.336401 -105.280637)
			(xy 44.356324 -105.228546) (xy 44.38362 -105.179911) (xy 44.417706 -105.135768) (xy 44.457855 -105.097059)
			(xy 44.503213 -105.064608) (xy 44.552813 -105.039107) (xy 44.605597 -105.0211) (xy 44.66044 -105.01097)
			(xy 44.716174 -105.008933) (xy 44.771611 -105.015033) (xy 44.825568 -105.029139) (xy 44.876897 -105.050951)
			(xy 44.924503 -105.080005) (xy 44.967371 -105.11568) (xy 45.004588 -105.157217) (xy 45.035361 -105.20373)
			(xy 45.059033 -105.254227) (xy 45.075101 -105.307634) (xy 45.083221 -105.36281) (xy 45.08373 -105.390696)
			(xy 45.083221 -105.418582) (xy 45.075101 -105.473758) (xy 45.059033 -105.527165) (xy 45.035361 -105.577662)
			(xy 45.004588 -105.624175) (xy 44.967371 -105.665712) (xy 44.924503 -105.701387) (xy 44.876897 -105.730441)
			(xy 44.825568 -105.752253) (xy 44.771611 -105.766359) (xy 44.716174 -105.772459) (xy 44.66044 -105.770422)
			(xy 44.605597 -105.760292) (xy 44.552813 -105.742285) (xy 44.503213 -105.716784) (xy 44.457855 -105.684333)
			(xy 44.417706 -105.645624) (xy 44.38362 -105.601481) (xy 44.356324 -105.552846) (xy 44.336401 -105.500755)
			(xy 44.324275 -105.446318) (xy 44.320204 -105.390696) (xy 32.854858 -105.390696) (xy 32.816017 -105.428673)
			(xy 32.771315 -105.461217) (xy 32.722384 -105.486967) (xy 32.670249 -105.505384) (xy 32.616 -105.516083)
			(xy 32.560776 -105.518838) (xy 32.505732 -105.513593) (xy 32.452022 -105.500457) (xy 32.400771 -105.479705)
			(xy 32.353052 -105.451773) (xy 32.331152 -105.434892) (xy 32.317404 -105.424636) (xy 32.285879 -105.411156)
			(xy 32.251904 -105.406552) (xy 32.217929 -105.411156) (xy 32.186404 -105.424636) (xy 32.172656 -105.434892)
			(xy 32.149995 -105.452359) (xy 32.100475 -105.481017) (xy 32.047232 -105.501959) (xy 31.991458 -105.514715)
			(xy 31.934404 -105.519) (xy 31.87735 -105.514715) (xy 31.821576 -105.501959) (xy 31.768333 -105.481017)
			(xy 31.718813 -105.452359) (xy 31.696152 -105.434892) (xy 31.682404 -105.424636) (xy 31.650879 -105.411156)
			(xy 31.616904 -105.406552) (xy 31.582929 -105.411156) (xy 31.551404 -105.424636) (xy 31.537656 -105.434892)
			(xy 31.515711 -105.451709) (xy 31.468002 -105.479637) (xy 31.41676 -105.500385) (xy 31.36306 -105.51352)
			(xy 31.308027 -105.518764) (xy 31.252813 -105.51601) (xy 31.198574 -105.505314) (xy 31.146448 -105.486901)
			(xy 31.097526 -105.461156) (xy 31.052833 -105.428618) (xy 31.013304 -105.38997) (xy 30.979769 -105.34602)
			(xy 30.95293 -105.297689) (xy 30.933348 -105.245991) (xy 30.921434 -105.192007) (xy 30.917438 -105.136869)
			(xy 29.297041 -105.136869) (xy 29.297221 -105.137049) (xy 29.329876 -105.180675) (xy 29.35599 -105.228505)
			(xy 29.375031 -105.279564) (xy 29.386611 -105.332813) (xy 29.390495 -105.387168) (xy 29.386603 -105.441523)
			(xy 29.375015 -105.49477) (xy 29.355967 -105.545826) (xy 29.329846 -105.593652) (xy 29.313886 -105.61574)
			(xy 29.300254 -105.634727) (xy 29.279526 -105.676617) (xy 29.266805 -105.721591) (xy 29.262521 -105.768132)
			(xy 29.266817 -105.814672) (xy 29.279549 -105.859643) (xy 29.300288 -105.901528) (xy 29.313886 -105.92054)
			(xy 29.329846 -105.942628) (xy 29.355967 -105.990454) (xy 29.375015 -106.04151) (xy 29.386603 -106.094757)
			(xy 29.390495 -106.149112) (xy 29.386611 -106.203467) (xy 29.375031 -106.256716) (xy 29.35599 -106.307775)
			(xy 29.329876 -106.355605) (xy 29.297221 -106.399231) (xy 29.25869 -106.437765) (xy 29.215066 -106.470423)
			(xy 29.167239 -106.49654) (xy 29.116181 -106.515585) (xy 29.062933 -106.527169) (xy 29.008578 -106.531057)
			(xy 28.954223 -106.527169) (xy 28.900975 -106.515585) (xy 28.849917 -106.49654) (xy 28.80209 -106.470423)
			(xy 28.758466 -106.437765) (xy 28.719935 -106.399231) (xy 28.68728 -106.355605) (xy 28.661166 -106.307775)
			(xy 28.642125 -106.256716) (xy 28.630545 -106.203467) (xy 28.626661 -106.149112) (xy 27.22118 -106.149112)
			(xy 27.22118 -106.858816) (xy 27.389582 -107.027218) (xy 34.03676 -107.027218) (xy 34.040831 -106.971596)
			(xy 34.052957 -106.917159) (xy 34.07288 -106.865068) (xy 34.100176 -106.816433) (xy 34.134262 -106.77229)
			(xy 34.174411 -106.733581) (xy 34.219769 -106.70113) (xy 34.269369 -106.675629) (xy 34.322153 -106.657622)
			(xy 34.376996 -106.647492) (xy 34.43273 -106.645455) (xy 34.488167 -106.651555) (xy 34.542124 -106.665661)
			(xy 34.593453 -106.687473) (xy 34.641059 -106.716527) (xy 34.678964 -106.748072) (xy 42.16984 -106.748072)
			(xy 42.173911 -106.69245) (xy 42.186037 -106.638013) (xy 42.20596 -106.585922) (xy 42.233256 -106.537287)
			(xy 42.267342 -106.493144) (xy 42.307491 -106.454435) (xy 42.352849 -106.421984) (xy 42.402449 -106.396483)
			(xy 42.455233 -106.378476) (xy 42.510076 -106.368346) (xy 42.56581 -106.366309) (xy 42.621247 -106.372409)
			(xy 42.675204 -106.386515) (xy 42.726533 -106.408327) (xy 42.774139 -106.437381) (xy 42.817007 -106.473056)
			(xy 42.854224 -106.514593) (xy 42.884997 -106.561106) (xy 42.908669 -106.611603) (xy 42.924737 -106.66501)
			(xy 42.932857 -106.720186) (xy 42.933366 -106.748072) (xy 42.932857 -106.775958) (xy 42.924737 -106.831134)
			(xy 42.908669 -106.884541) (xy 42.884997 -106.935038) (xy 42.854224 -106.981551) (xy 42.817007 -107.023088)
			(xy 42.774139 -107.058763) (xy 42.726533 -107.087817) (xy 42.675204 -107.109629) (xy 42.621247 -107.123735)
			(xy 42.56581 -107.129835) (xy 42.510076 -107.127798) (xy 42.455233 -107.117668) (xy 42.402449 -107.099661)
			(xy 42.352849 -107.07416) (xy 42.307491 -107.041709) (xy 42.267342 -107.003) (xy 42.233256 -106.958857)
			(xy 42.20596 -106.910222) (xy 42.186037 -106.858131) (xy 42.173911 -106.803694) (xy 42.16984 -106.748072)
			(xy 34.678964 -106.748072) (xy 34.683927 -106.752202) (xy 34.721144 -106.793739) (xy 34.751917 -106.840252)
			(xy 34.775589 -106.890749) (xy 34.791657 -106.944156) (xy 34.799777 -106.999332) (xy 34.800286 -107.027218)
			(xy 34.799777 -107.055104) (xy 34.791657 -107.11028) (xy 34.775589 -107.163687) (xy 34.751917 -107.214184)
			(xy 34.721144 -107.260697) (xy 34.683927 -107.302234) (xy 34.641059 -107.337909) (xy 34.593453 -107.366963)
			(xy 34.542124 -107.388775) (xy 34.488167 -107.402881) (xy 34.43273 -107.408981) (xy 34.376996 -107.406944)
			(xy 34.322153 -107.396814) (xy 34.269369 -107.378807) (xy 34.219769 -107.353306) (xy 34.174411 -107.320855)
			(xy 34.134262 -107.282146) (xy 34.100176 -107.238003) (xy 34.07288 -107.189368) (xy 34.052957 -107.137277)
			(xy 34.040831 -107.08284) (xy 34.03676 -107.027218) (xy 27.389582 -107.027218) (xy 28.88361 -108.521246)
		)
		(stroke
			(width 0)
			(type solid)
		)
		(fill yes)
		(layer "In6.Cu")
		(net "P1V8_STB_NODE1")
	)
	(gr_poly
		(pts
			(xy 145.7071 -147.821396) (xy 145.722296 -147.805534) (xy 145.747539 -147.769588) (xy 145.766223 -147.729836)
			(xy 145.777791 -147.687463) (xy 145.781898 -147.643732) (xy 145.778421 -147.599946) (xy 145.767465 -147.55741)
			(xy 145.749355 -147.517394) (xy 145.724632 -147.481088) (xy 145.70964 -147.465034) (xy 145.691149 -147.4453)
			(xy 145.659349 -147.40156) (xy 145.634046 -147.353767) (xy 145.615746 -147.30288) (xy 145.604816 -147.249917)
			(xy 145.601476 -147.195943) (xy 145.605793 -147.142037) (xy 145.617679 -147.089281) (xy 145.636898 -147.038733)
			(xy 145.663062 -146.991406) (xy 145.695649 -146.948249) (xy 145.734004 -146.910126) (xy 145.75536 -146.893534)
			(xy 145.773301 -146.879541) (xy 145.804365 -146.846303) (xy 145.829012 -146.808064) (xy 145.846455 -146.766047)
			(xy 145.856136 -146.721594) (xy 145.857745 -146.676129) (xy 145.85123 -146.631103) (xy 145.836801 -146.587958)
			(xy 145.814919 -146.548073) (xy 145.786282 -146.512722) (xy 145.76933 -146.497548) (xy 145.748132 -146.478552)
			(xy 145.71105 -146.435369) (xy 145.680794 -146.387157) (xy 145.658035 -146.334985) (xy 145.643278 -146.280012)
			(xy 145.63685 -146.223457) (xy 145.638894 -146.166574) (xy 145.649365 -146.110626) (xy 145.668029 -146.056854)
			(xy 145.694474 -146.006451) (xy 145.728112 -145.960535) (xy 145.768198 -145.920125) (xy 145.813841 -145.886117)
			(xy 145.838672 -145.8722) (xy 145.858836 -145.860807) (xy 145.895008 -145.83189) (xy 145.925344 -145.796901)
			(xy 145.94884 -145.756995) (xy 145.96472 -145.713493) (xy 145.972457 -145.667835) (xy 145.971797 -145.621531)
			(xy 145.96276 -145.576112) (xy 145.945646 -145.533081) (xy 145.92102 -145.493862) (xy 145.905728 -145.476468)
			(xy 145.887228 -145.455606) (xy 145.855853 -145.409514) (xy 145.831519 -145.359346) (xy 145.814745 -145.306171)
			(xy 145.805887 -145.251122) (xy 145.805134 -145.195369) (xy 145.812502 -145.140101) (xy 145.827835 -145.086493)
			(xy 145.850805 -145.035686) (xy 145.880924 -144.988763) (xy 145.917551 -144.946723) (xy 145.959905 -144.91046)
			(xy 146.007086 -144.880746) (xy 146.058088 -144.858214) (xy 146.111826 -144.843344) (xy 146.167156 -144.836452)
			(xy 146.2229 -144.837685) (xy 146.277872 -144.847017) (xy 146.3309 -144.864249) (xy 146.380856 -144.889014)
			(xy 146.426676 -144.920785) (xy 146.467386 -144.958885) (xy 146.502118 -145.002504) (xy 146.530132 -145.050713)
			(xy 146.550834 -145.102485) (xy 146.563781 -145.156719) (xy 146.568698 -145.212259) (xy 146.565481 -145.267924)
			(xy 146.554197 -145.322528) (xy 146.535088 -145.374909) (xy 146.50856 -145.423951) (xy 146.475178 -145.468611)
			(xy 146.435652 -145.507938) (xy 146.390823 -145.541095) (xy 146.366484 -145.5547) (xy 146.346316 -145.566091)
			(xy 146.310137 -145.595003) (xy 146.279794 -145.629992) (xy 146.256292 -145.669899) (xy 146.240408 -145.713404)
			(xy 146.232669 -145.759066) (xy 146.23333 -145.805374) (xy 146.24237 -145.850796) (xy 146.259489 -145.89383)
			(xy 146.284121 -145.933049) (xy 146.299428 -145.950432) (xy 146.317111 -145.970337) (xy 146.347359 -146.014151)
			(xy 146.37122 -146.061747) (xy 146.388231 -146.112197) (xy 146.398061 -146.164524) (xy 146.400518 -146.217709)
			(xy 146.395555 -146.270718) (xy 146.383269 -146.322523) (xy 146.363897 -146.372116) (xy 146.337818 -146.418532)
			(xy 146.305537 -146.460872) (xy 146.267682 -146.49831) (xy 146.246596 -146.514566) (xy 146.228658 -146.528561)
			(xy 146.197599 -146.5618) (xy 146.172956 -146.60004) (xy 146.155516 -146.642056) (xy 146.145838 -146.686507)
			(xy 146.144229 -146.73197) (xy 146.150742 -146.776994) (xy 146.165168 -146.820138) (xy 146.187047 -146.860023)
			(xy 146.215678 -146.895375) (xy 146.232626 -146.910552) (xy 146.249136 -146.925538) (xy 146.265226 -146.940476)
			(xy 146.301539 -146.965148) (xy 146.34155 -146.983218) (xy 146.384069 -146.99415) (xy 146.427833 -146.997618)
			(xy 146.471543 -146.99352) (xy 146.5139 -146.981978) (xy 146.553646 -146.963334) (xy 146.5896 -146.938142)
			(xy 146.605498 -146.922998) (xy 147.700492 -145.828004) (xy 147.716653 -145.81108) (xy 147.743112 -145.772489)
			(xy 147.762058 -145.729707) (xy 147.77285 -145.684179) (xy 147.775123 -145.637444) (xy 147.768801 -145.591083)
			(xy 147.754097 -145.546664) (xy 147.731509 -145.505688) (xy 147.7018 -145.46954) (xy 147.665974 -145.439443)
			(xy 147.645882 -145.427446) (xy 147.622488 -145.413649) (xy 147.5795 -145.380459) (xy 147.541653 -145.341508)
			(xy 147.50971 -145.297585) (xy 147.484319 -145.249576) (xy 147.46599 -145.198453) (xy 147.455095 -145.145247)
			(xy 147.451855 -145.091034) (xy 147.456334 -145.036909) (xy 147.468441 -144.983966) (xy 147.487934 -144.933274)
			(xy 147.514416 -144.885858) (xy 147.547354 -144.842677) (xy 147.586082 -144.804601) (xy 147.629817 -144.772402)
			(xy 147.677676 -144.746729) (xy 147.728691 -144.728101) (xy 147.781832 -144.716894) (xy 147.836026 -144.713336)
			(xy 147.890176 -144.717497) (xy 147.943189 -144.729294) (xy 147.993994 -144.748489) (xy 148.017992 -144.761204)
			(xy 148.037454 -144.771381) (xy 148.078998 -144.785617) (xy 148.122371 -144.792498) (xy 148.166281 -144.791818)
			(xy 148.209419 -144.783597) (xy 148.250502 -144.768081) (xy 148.288305 -144.745732) (xy 148.321702 -144.717216)
			(xy 148.349698 -144.683381) (xy 148.371459 -144.645237) (xy 148.386337 -144.603919) (xy 148.393888 -144.560658)
			(xy 148.39442 -144.5387) (xy 148.39442 -143.53032) (xy 148.393966 -143.514782) (xy 148.386436 -143.48463)
			(xy 148.371841 -143.457193) (xy 148.351048 -143.434096) (xy 148.325289 -143.41671) (xy 148.310854 -143.41094)
			(xy 148.285205 -143.401131) (xy 148.236798 -143.375203) (xy 148.19261 -143.342603) (xy 148.153551 -143.304004)
			(xy 148.120431 -143.260203) (xy 148.093933 -143.212107) (xy 148.074605 -143.160707) (xy 148.062847 -143.107068)
			(xy 148.0589 -143.052297) (xy 148.062847 -142.997526) (xy 148.074607 -142.943887) (xy 148.093936 -142.892488)
			(xy 148.120434 -142.844392) (xy 148.153555 -142.800592) (xy 148.192614 -142.761993) (xy 148.236803 -142.729394)
			(xy 148.28521 -142.703467) (xy 148.310854 -142.693644) (xy 148.325314 -142.687915) (xy 148.3511 -142.670539)
			(xy 148.371913 -142.647437) (xy 148.386513 -142.619983) (xy 148.394032 -142.589811) (xy 148.39442 -142.574264)
			(xy 148.39442 -140.895832) (xy 148.393925 -140.87284) (xy 148.385652 -140.827605) (xy 148.369369 -140.784599)
			(xy 148.34561 -140.745228) (xy 148.31515 -140.710778) (xy 148.278985 -140.682375) (xy 148.238298 -140.660947)
			(xy 148.194418 -140.647195) (xy 148.171662 -140.643864) (xy 148.144302 -140.639973) (xy 148.091016 -140.625324)
			(xy 148.0404 -140.603144) (xy 147.993512 -140.573896) (xy 147.951332 -140.538192) (xy 147.914743 -140.496778)
			(xy 147.884508 -140.45052) (xy 147.861261 -140.400385) (xy 147.845487 -140.347422) (xy 147.837516 -140.292737)
			(xy 147.837516 -140.237475) (xy 147.845485 -140.18279) (xy 147.861257 -140.129826) (xy 147.884502 -140.079691)
			(xy 147.914735 -140.033432) (xy 147.951324 -139.992017) (xy 147.993502 -139.956311) (xy 148.040389 -139.927062)
			(xy 148.091005 -139.90488) (xy 148.14429 -139.89023) (xy 148.171662 -139.886436) (xy 148.194411 -139.883107)
			(xy 148.238269 -139.869321) (xy 148.278932 -139.847874) (xy 148.315076 -139.819465) (xy 148.345523 -139.78502)
			(xy 148.36928 -139.745661) (xy 148.385572 -139.702672) (xy 148.393868 -139.657454) (xy 148.39442 -139.634468)
			(xy 148.39442 -139.571984) (xy 148.393787 -139.5534) (xy 148.383095 -139.517805) (xy 148.362595 -139.486803)
			(xy 148.3487 -139.474448) (xy 148.327661 -139.456218) (xy 148.290576 -139.414704) (xy 148.259917 -139.368241)
			(xy 148.236335 -139.317816) (xy 148.22033 -139.2645) (xy 148.212243 -139.209424) (xy 148.212244 -139.153758)
			(xy 148.220334 -139.098682) (xy 148.236341 -139.045367) (xy 148.259926 -138.994943) (xy 148.290587 -138.948482)
			(xy 148.327674 -138.906969) (xy 148.3487 -138.888724) (xy 148.362559 -138.876336) (xy 148.383047 -138.845342)
			(xy 148.393756 -138.809765) (xy 148.39442 -138.791188) (xy 148.39442 -138.194796) (xy 146.33829 -136.138666)
			(xy 143.461486 -136.138666) (xy 143.439774 -136.139085) (xy 143.396976 -136.146424) (xy 143.35605 -136.160937)
			(xy 143.318189 -136.1822) (xy 143.284498 -136.209594) (xy 143.255958 -136.242321) (xy 143.233401 -136.279425)
			(xy 143.217485 -136.319826) (xy 143.208675 -136.362346) (xy 143.207486 -136.38403) (xy 143.20598 -136.412934)
			(xy 143.19533 -136.469821) (xy 143.176218 -136.52445) (xy 143.149082 -136.57557) (xy 143.114544 -136.62201)
			(xy 143.073393 -136.662707) (xy 143.026573 -136.696728) (xy 142.975156 -136.723296) (xy 142.947898 -136.733026)
			(xy 142.925526 -136.741099) (xy 142.884044 -136.76435) (xy 142.84761 -136.794912) (xy 142.817496 -136.831717)
			(xy 142.794754 -136.873481) (xy 142.780177 -136.918746) (xy 142.774273 -136.965933) (xy 142.77725 -137.013395)
			(xy 142.789003 -137.059474) (xy 142.798546 -137.08126) (xy 142.808429 -137.103298) (xy 142.823199 -137.149285)
			(xy 142.82801 -137.172954) (xy 142.83155 -137.189336) (xy 142.845999 -137.219565) (xy 142.86782 -137.244991)
			(xy 142.895506 -137.26386) (xy 142.92715 -137.274872) (xy 142.960569 -137.277266) (xy 142.977108 -137.274554)
			(xy 143.004403 -137.269769) (xy 143.059758 -137.267207) (xy 143.1149 -137.272679) (xy 143.168672 -137.286072)
			(xy 143.219939 -137.307103) (xy 143.267625 -137.335329) (xy 143.310726 -137.370157) (xy 143.348335 -137.410855)
			(xy 143.37966 -137.456565) (xy 143.404043 -137.506326) (xy 143.420971 -137.559091) (xy 143.430087 -137.613749)
			(xy 143.431199 -137.669152) (xy 143.424285 -137.724133) (xy 143.409489 -137.777535) (xy 143.387123 -137.828234)
			(xy 143.357658 -137.875165) (xy 143.321714 -137.917339) (xy 143.280046 -137.95387) (xy 143.233531 -137.983988)
			(xy 143.183149 -138.00706) (xy 143.129959 -138.0226) (xy 143.102584 -138.026902) (xy 143.079828 -138.030587)
			(xy 143.036073 -138.045087) (xy 142.995644 -138.06723) (xy 142.959865 -138.096291) (xy 142.929905 -138.131322)
			(xy 142.906743 -138.171175) (xy 142.891138 -138.214548) (xy 142.886938 -138.237214) (xy 142.882013 -138.264248)
			(xy 142.865421 -138.316633) (xy 142.841485 -138.366095) (xy 142.8107 -138.411612) (xy 142.773702 -138.45224)
			(xy 142.731259 -138.48714) (xy 142.684246 -138.515588) (xy 142.633639 -138.536997) (xy 142.580483 -138.550924)
			(xy 142.525879 -138.55708) (xy 142.470957 -138.555337) (xy 142.416854 -138.545733) (xy 142.364688 -138.528465)
			(xy 142.315539 -138.503891) (xy 142.270425 -138.472519) (xy 142.230278 -138.434999) (xy 142.195931 -138.392108)
			(xy 142.168093 -138.344731) (xy 142.14734 -138.293851) (xy 142.134102 -138.24052) (xy 142.128653 -138.185841)
			(xy 142.131106 -138.130946) (xy 142.14141 -138.076971) (xy 142.159351 -138.025033) (xy 142.184559 -137.976206)
			(xy 142.216511 -137.931501) (xy 142.235174 -137.911332) (xy 142.250931 -137.894118) (xy 142.276515 -137.855096)
			(xy 142.294548 -137.812061) (xy 142.304423 -137.766456) (xy 142.30581 -137.719816) (xy 142.298662 -137.673706)
			(xy 142.283219 -137.629674) (xy 142.259999 -137.589201) (xy 142.229783 -137.553645) (xy 142.21206 -137.53846)
			(xy 142.191306 -137.520947) (xy 142.154479 -137.481041) (xy 142.12368 -137.436317) (xy 142.099532 -137.38768)
			(xy 142.082522 -137.33611) (xy 142.072994 -137.28265) (xy 142.07114 -137.228379) (xy 142.076997 -137.174393)
			(xy 142.090448 -137.121783) (xy 142.11122 -137.071611) (xy 142.138895 -137.024889) (xy 142.172912 -136.982562)
			(xy 142.212586 -136.945485) (xy 142.257115 -136.914406) (xy 142.3056 -136.889952) (xy 142.331186 -136.880854)
			(xy 142.353557 -136.872782) (xy 142.39504 -136.849532) (xy 142.431474 -136.818971) (xy 142.461586 -136.782166)
			(xy 142.484327 -136.740402) (xy 142.498902 -136.695137) (xy 142.504803 -136.64795) (xy 142.501823 -136.60049)
			(xy 142.490067 -136.554412) (xy 142.480538 -136.53262) (xy 142.470072 -136.509201) (xy 142.454812 -136.460227)
			(xy 142.446255 -136.40965) (xy 142.444978 -136.38403) (xy 142.443788 -136.362352) (xy 142.434941 -136.319851)
			(xy 142.419003 -136.279471) (xy 142.396437 -136.242385) (xy 142.367898 -136.209672) (xy 142.334217 -136.182283)
			(xy 142.296373 -136.161013) (xy 142.255465 -136.146481) (xy 142.212684 -136.13911) (xy 142.190978 -136.138666)
			(xy 139.48664 -136.138666) (xy 138.809222 -136.816084) (xy 138.794998 -136.89457) (xy 138.811762 -136.930892)
			(xy 138.82274 -136.955899) (xy 138.838235 -137.008267) (xy 138.846105 -137.06231) (xy 138.846189 -137.116923)
			(xy 138.838485 -137.170989) (xy 138.82315 -137.223405) (xy 138.800497 -137.273098) (xy 138.770991 -137.319053)
			(xy 138.735233 -137.360332) (xy 138.693954 -137.39609) (xy 138.647999 -137.425597) (xy 138.598306 -137.448249)
			(xy 138.54589 -137.463584) (xy 138.491824 -137.471289) (xy 138.437211 -137.471205) (xy 138.383168 -137.463336)
			(xy 138.3308 -137.44784) (xy 138.305794 -137.43686) (xy 138.269472 -137.420096) (xy 138.190986 -137.43432)
			(xy 138.07186 -137.553446) (xy 138.07186 -138.579098) (xy 138.072337 -138.60112) (xy 138.079941 -138.644504)
			(xy 138.094905 -138.68593) (xy 138.116781 -138.724158) (xy 138.144916 -138.758046) (xy 138.178468 -138.786581)
			(xy 138.216434 -138.80891) (xy 138.257679 -138.824364) (xy 138.30097 -138.832483) (xy 138.345012 -138.833023)
			(xy 138.388488 -138.825967) (xy 138.409426 -138.819128) (xy 138.436005 -138.810389) (xy 138.490961 -138.799899)
			(xy 138.54686 -138.797551) (xy 138.602502 -138.803394) (xy 138.656694 -138.817303) (xy 138.708272 -138.83898)
			(xy 138.75613 -138.867959) (xy 138.799241 -138.90362) (xy 138.836679 -138.945196) (xy 138.858668 -138.978289)
			(xy 139.612918 -138.978289) (xy 139.616592 -138.922681) (xy 139.628318 -138.868199) (xy 139.647846 -138.816004)
			(xy 139.674761 -138.767205) (xy 139.70849 -138.722842) (xy 139.748315 -138.683858) (xy 139.793388 -138.651084)
			(xy 139.84275 -138.625217) (xy 139.895351 -138.606808) (xy 139.95007 -138.596248) (xy 140.005744 -138.593762)
			(xy 140.061187 -138.599404) (xy 140.115219 -138.613052) (xy 140.16669 -138.634417) (xy 140.214504 -138.663044)
			(xy 140.257645 -138.698323) (xy 140.295193 -138.739504) (xy 140.32635 -138.78571) (xy 140.350452 -138.835957)
			(xy 140.366987 -138.889177) (xy 140.375602 -138.944236) (xy 140.376114 -138.999963) (xy 140.368512 -139.055171)
			(xy 140.352958 -139.108686) (xy 140.329784 -139.159368) (xy 140.299481 -139.206138) (xy 140.262696 -139.248002)
			(xy 140.241782 -139.266422) (xy 140.224464 -139.281835) (xy 140.201407 -139.31011) (xy 143.457674 -139.31011)
			(xy 143.461745 -139.254488) (xy 143.473871 -139.200051) (xy 143.493794 -139.14796) (xy 143.52109 -139.099325)
			(xy 143.555176 -139.055182) (xy 143.595325 -139.016473) (xy 143.640683 -138.984022) (xy 143.690283 -138.958521)
			(xy 143.743067 -138.940514) (xy 143.79791 -138.930384) (xy 143.853644 -138.928347) (xy 143.909081 -138.934447)
			(xy 143.963038 -138.948553) (xy 144.014367 -138.970365) (xy 144.061973 -138.999419) (xy 144.104841 -139.035094)
			(xy 144.142058 -139.076631) (xy 144.172831 -139.123144) (xy 144.196503 -139.173641) (xy 144.212571 -139.227048)
			(xy 144.220691 -139.282224) (xy 144.2212 -139.31011) (xy 144.220691 -139.337996) (xy 144.212571 -139.393172)
			(xy 144.196503 -139.446579) (xy 144.172831 -139.497076) (xy 144.142058 -139.543589) (xy 144.104841 -139.585126)
			(xy 144.061973 -139.620801) (xy 144.014367 -139.649855) (xy 143.963038 -139.671667) (xy 143.909081 -139.685773)
			(xy 143.853644 -139.691873) (xy 143.79791 -139.689836) (xy 143.743067 -139.679706) (xy 143.690283 -139.661699)
			(xy 143.640683 -139.636198) (xy 143.595325 -139.603747) (xy 143.555176 -139.565038) (xy 143.52109 -139.520895)
			(xy 143.493794 -139.47226) (xy 143.473871 -139.420169) (xy 143.461745 -139.365732) (xy 143.457674 -139.31011)
			(xy 140.201407 -139.31011) (xy 140.195169 -139.31776) (xy 140.17287 -139.3584) (xy 140.158306 -139.402408)
			(xy 140.151958 -139.448326) (xy 140.154038 -139.494635) (xy 140.164476 -139.5398) (xy 140.182927 -139.582325)
			(xy 140.208779 -139.620802) (xy 140.241177 -139.653957) (xy 140.259816 -139.667742) (xy 140.282265 -139.684255)
			(xy 140.322629 -139.722676) (xy 140.356973 -139.76656) (xy 140.384566 -139.814975) (xy 140.404822 -139.866889)
			(xy 140.417308 -139.921198) (xy 140.421759 -139.976746) (xy 140.41808 -140.03235) (xy 140.40635 -140.086827)
			(xy 140.386818 -140.139018) (xy 140.3599 -140.187812) (xy 140.326169 -140.232169) (xy 140.286343 -140.271147)
			(xy 140.241269 -140.303914) (xy 140.191907 -140.329775) (xy 140.139308 -140.348179) (xy 140.084591 -140.358733)
			(xy 140.02892 -140.361213) (xy 139.973481 -140.355567) (xy 139.919454 -140.341914) (xy 139.867988 -140.320545)
			(xy 139.820178 -140.291915) (xy 139.777044 -140.256634) (xy 139.739502 -140.215452) (xy 139.708351 -140.169245)
			(xy 139.684256 -140.118998) (xy 139.667728 -140.06578) (xy 139.659119 -140.010723) (xy 139.658612 -139.955)
			(xy 139.666219 -139.899796) (xy 139.681778 -139.846286) (xy 139.704956 -139.795609) (xy 139.735262 -139.748844)
			(xy 139.772049 -139.706987) (xy 139.792964 -139.68857) (xy 139.810296 -139.67317) (xy 139.839598 -139.637245)
			(xy 139.861901 -139.596604) (xy 139.876469 -139.552593) (xy 139.882817 -139.50667) (xy 139.880736 -139.460358)
			(xy 139.870294 -139.41519) (xy 139.851838 -139.372663) (xy 139.825979 -139.334185) (xy 139.793574 -139.301033)
			(xy 139.77493 -139.28725) (xy 139.752446 -139.270784) (xy 139.712076 -139.232365) (xy 139.677726 -139.188481)
			(xy 139.650127 -139.140066) (xy 139.629866 -139.08815) (xy 139.617374 -139.033839) (xy 139.612918 -138.978289)
			(xy 138.858668 -138.978289) (xy 138.867642 -138.991795) (xy 138.891465 -139.042418) (xy 138.907637 -139.095978)
			(xy 138.915811 -139.151326) (xy 138.915811 -139.207274) (xy 138.907637 -139.262622) (xy 138.891465 -139.316182)
			(xy 138.867642 -139.366805) (xy 138.836679 -139.413404) (xy 138.799241 -139.45498) (xy 138.75613 -139.490641)
			(xy 138.708272 -139.51962) (xy 138.656694 -139.541297) (xy 138.602502 -139.555206) (xy 138.54686 -139.561049)
			(xy 138.490961 -139.558701) (xy 138.436005 -139.548211) (xy 138.409426 -139.539472) (xy 138.388468 -139.532662)
			(xy 138.344982 -139.525549) (xy 138.300921 -139.526044) (xy 138.257606 -139.534133) (xy 138.216335 -139.549572)
			(xy 138.178347 -139.571899) (xy 138.14478 -139.600445) (xy 138.11664 -139.634353) (xy 138.094772 -139.672607)
			(xy 138.07983 -139.714061) (xy 138.072263 -139.75747) (xy 138.07186 -139.779502) (xy 138.07186 -140.42009)
			(xy 137.71626 -140.77569) (xy 143.467834 -140.77569) (xy 143.471905 -140.720068) (xy 143.484031 -140.665631)
			(xy 143.503954 -140.61354) (xy 143.53125 -140.564905) (xy 143.565336 -140.520762) (xy 143.605485 -140.482053)
			(xy 143.650843 -140.449602) (xy 143.700443 -140.424101) (xy 143.753227 -140.406094) (xy 143.80807 -140.395964)
			(xy 143.863804 -140.393927) (xy 143.919241 -140.400027) (xy 143.973198 -140.414133) (xy 144.024527 -140.435945)
			(xy 144.072133 -140.464999) (xy 144.115001 -140.500674) (xy 144.152218 -140.542211) (xy 144.182991 -140.588724)
			(xy 144.206663 -140.639221) (xy 144.222731 -140.692628) (xy 144.230851 -140.747804) (xy 144.23136 -140.77569)
			(xy 144.230851 -140.803576) (xy 144.222731 -140.858752) (xy 144.214871 -140.884876) (xy 145.677791 -140.884876)
			(xy 145.683735 -140.831296) (xy 145.697162 -140.779085) (xy 145.717805 -140.729285) (xy 145.745252 -140.682886)
			(xy 145.778958 -140.640813) (xy 145.798286 -140.62202) (xy 145.809427 -140.610896) (xy 145.826409 -140.584402)
			(xy 145.836371 -140.554549) (xy 145.838703 -140.523165) (xy 145.833263 -140.492169) (xy 145.820382 -140.463455)
			(xy 145.810986 -140.450824) (xy 145.794821 -140.429537) (xy 145.76789 -140.383367) (xy 145.747665 -140.333892)
			(xy 145.734542 -140.282079) (xy 145.728777 -140.228941) (xy 145.730484 -140.175519) (xy 145.739628 -140.122857)
			(xy 145.756032 -140.071987) (xy 145.779373 -140.023903) (xy 145.809196 -139.979547) (xy 145.844917 -139.939787)
			(xy 145.865088 -139.92225) (xy 145.881347 -139.908003) (xy 145.909259 -139.874996) (xy 145.931184 -139.837742)
			(xy 145.946491 -139.797316) (xy 145.954739 -139.754884) (xy 145.955689 -139.711667) (xy 145.949314 -139.668913)
			(xy 145.935799 -139.627854) (xy 145.926048 -139.60856) (xy 145.91353 -139.583907) (xy 145.894877 -139.531861)
			(xy 145.883936 -139.477667) (xy 145.880936 -139.422461) (xy 145.88594 -139.3674) (xy 145.898843 -139.31364)
			(xy 145.919376 -139.262306) (xy 145.947106 -139.214476) (xy 145.963894 -139.192508) (xy 145.97727 -139.174861)
			(xy 145.998352 -139.135926) (xy 146.012364 -139.093925) (xy 146.018884 -139.050132) (xy 146.017714 -139.005871)
			(xy 146.00889 -138.962483) (xy 145.992677 -138.921282) (xy 145.969568 -138.883514) (xy 145.940263 -138.850325)
			(xy 145.923254 -138.836146) (xy 145.902643 -138.81915) (xy 145.865931 -138.78034) (xy 145.834994 -138.736787)
			(xy 145.810435 -138.689345) (xy 145.792735 -138.638939) (xy 145.782241 -138.586558) (xy 145.779158 -138.533224)
			(xy 145.783546 -138.479982) (xy 145.795319 -138.427873) (xy 145.814247 -138.377916) (xy 145.83996 -138.331089)
			(xy 145.871955 -138.288307) (xy 145.909606 -138.250407) (xy 145.93062 -138.233912) (xy 145.9474 -138.220686)
			(xy 145.976642 -138.189538) (xy 146.000264 -138.153939) (xy 146.017598 -138.11489) (xy 146.028158 -138.073492)
			(xy 146.031645 -138.030911) (xy 146.027961 -137.988347) (xy 146.01721 -137.946998) (xy 146.008852 -137.927334)
			(xy 145.998009 -137.901926) (xy 145.982866 -137.848804) (xy 145.975541 -137.794053) (xy 145.976189 -137.738818)
			(xy 145.984794 -137.684253) (xy 146.001178 -137.6315) (xy 146.024998 -137.581661) (xy 146.055756 -137.535778)
			(xy 146.092808 -137.494809) (xy 146.135382 -137.459612) (xy 146.182586 -137.430922) (xy 146.233433 -137.409339)
			(xy 146.286862 -137.395314) (xy 146.341755 -137.38914) (xy 146.396964 -137.390946) (xy 146.451336 -137.400694)
			(xy 146.503733 -137.418181) (xy 146.553062 -137.443042) (xy 146.59829 -137.474756) (xy 146.638472 -137.51266)
			(xy 146.672768 -137.555962) (xy 146.700461 -137.603758) (xy 146.720972 -137.655047) (xy 146.733873 -137.708759)
			(xy 146.738894 -137.763769) (xy 146.73593 -137.818928) (xy 146.725043 -137.873083) (xy 146.70646 -137.925102)
			(xy 146.68057 -137.973898) (xy 146.647914 -138.018451) (xy 146.609175 -138.057828) (xy 146.587464 -138.074908)
			(xy 146.570682 -138.088133) (xy 146.541433 -138.119277) (xy 146.517807 -138.154876) (xy 146.50047 -138.193925)
			(xy 146.489909 -138.235325) (xy 146.486424 -138.277908) (xy 146.490113 -138.320474) (xy 146.500871 -138.361823)
			(xy 146.509232 -138.381486) (xy 146.519497 -138.405451) (xy 146.534191 -138.45547) (xy 146.541939 -138.507025)
			(xy 146.542597 -138.559154) (xy 146.536153 -138.610887) (xy 146.522726 -138.661262) (xy 146.502567 -138.70934)
			(xy 146.476051 -138.754227) (xy 146.46021 -138.774932) (xy 146.44679 -138.792547) (xy 146.425711 -138.831489)
			(xy 146.411701 -138.873496) (xy 146.405185 -138.917295) (xy 146.40636 -138.961561) (xy 146.415191 -139.004952)
			(xy 146.431409 -139.046157) (xy 146.454525 -139.083925) (xy 146.483838 -139.117116) (xy 146.50085 -139.131294)
			(xy 146.522485 -139.14929) (xy 146.560829 -139.190476) (xy 146.592708 -139.236847) (xy 146.617428 -139.287399)
			(xy 146.634455 -139.341033) (xy 146.643419 -139.396586) (xy 146.644125 -139.452854) (xy 146.636558 -139.508614)
			(xy 146.620882 -139.562659) (xy 146.597438 -139.613814) (xy 146.566733 -139.660971) (xy 146.529434 -139.703106)
			(xy 146.508216 -139.72159) (xy 146.491925 -139.735803) (xy 146.464014 -139.768816) (xy 146.44209 -139.806076)
			(xy 146.426786 -139.846507) (xy 146.418543 -139.888945) (xy 146.417598 -139.932166) (xy 146.423979 -139.974924)
			(xy 146.437502 -140.015986) (xy 146.447256 -140.03528) (xy 146.459824 -140.059944) (xy 146.478485 -140.112058)
			(xy 146.489422 -140.166322) (xy 146.492405 -140.221596) (xy 146.487372 -140.276721) (xy 146.474428 -140.330541)
			(xy 146.453844 -140.381927) (xy 146.426054 -140.4298) (xy 146.391639 -140.473156) (xy 146.371818 -140.49248)
			(xy 146.360677 -140.503604) (xy 146.343694 -140.530098) (xy 146.333732 -140.559951) (xy 146.3314 -140.591335)
			(xy 146.336841 -140.622331) (xy 146.349722 -140.651045) (xy 146.359118 -140.663676) (xy 146.377833 -140.688389)
			(xy 146.407823 -140.742638) (xy 146.418808 -140.771626) (xy 146.426628 -140.792139) (xy 146.448282 -140.830322)
			(xy 146.476172 -140.864218) (xy 146.50947 -140.892819) (xy 146.547186 -140.915276) (xy 146.588199 -140.930921)
			(xy 146.63129 -140.939289) (xy 146.675177 -140.940132) (xy 146.696938 -140.937234) (xy 146.724535 -140.933517)
			(xy 146.780213 -140.933046) (xy 146.835368 -140.940674) (xy 146.888828 -140.956241) (xy 146.939457 -140.979415)
			(xy 146.986178 -141.009704) (xy 147.028 -141.046463) (xy 147.064032 -141.088913) (xy 147.093509 -141.13615)
			(xy 147.115806 -141.187171) (xy 147.130447 -141.240892) (xy 147.137122 -141.296171) (xy 147.13569 -141.351833)
			(xy 147.12618 -141.406695) (xy 147.108794 -141.459591) (xy 147.083902 -141.509398) (xy 147.052033 -141.555056)
			(xy 147.013865 -141.595596) (xy 146.970208 -141.630155) (xy 146.92199 -141.658) (xy 146.870237 -141.678539)
			(xy 146.816047 -141.691335) (xy 146.760572 -141.696116) (xy 146.704992 -141.692781) (xy 146.650487 -141.6814)
			(xy 146.598216 -141.662215) (xy 146.54929 -141.635635) (xy 146.504748 -141.602224) (xy 146.465537 -141.562691)
			(xy 146.432491 -141.517878) (xy 146.406311 -141.468736) (xy 146.396456 -141.442694) (xy 146.388563 -141.422211)
			(xy 146.366919 -141.384032) (xy 146.339039 -141.350136) (xy 146.305752 -141.321533) (xy 146.268047 -141.299073)
			(xy 146.227045 -141.283422) (xy 146.183963 -141.275046) (xy 146.140084 -141.274194) (xy 146.118326 -141.277086)
			(xy 146.091618 -141.28076) (xy 146.037714 -141.281491) (xy 145.984244 -141.274626) (xy 145.932272 -141.260303)
			(xy 145.882834 -141.238807) (xy 145.836914 -141.210566) (xy 145.795427 -141.176142) (xy 145.759199 -141.13622)
			(xy 145.728951 -141.091597) (xy 145.705286 -141.04316) (xy 145.688675 -140.991873) (xy 145.679449 -140.93876)
			(xy 145.677791 -140.884876) (xy 144.214871 -140.884876) (xy 144.206663 -140.912159) (xy 144.182991 -140.962656)
			(xy 144.152218 -141.009169) (xy 144.115001 -141.050706) (xy 144.072133 -141.086381) (xy 144.024527 -141.115435)
			(xy 143.973198 -141.137247) (xy 143.919241 -141.151353) (xy 143.863804 -141.157453) (xy 143.80807 -141.155416)
			(xy 143.753227 -141.145286) (xy 143.700443 -141.127279) (xy 143.650843 -141.101778) (xy 143.605485 -141.069327)
			(xy 143.565336 -141.030618) (xy 143.53125 -140.986475) (xy 143.503954 -140.93784) (xy 143.484031 -140.885749)
			(xy 143.471905 -140.831312) (xy 143.467834 -140.77569) (xy 137.71626 -140.77569) (xy 135.9408 -142.55115)
			(xy 139.683234 -142.55115) (xy 139.687305 -142.495528) (xy 139.699431 -142.441091) (xy 139.719354 -142.389)
			(xy 139.74665 -142.340365) (xy 139.780736 -142.296222) (xy 139.820885 -142.257513) (xy 139.866243 -142.225062)
			(xy 139.915843 -142.199561) (xy 139.968627 -142.181554) (xy 140.02347 -142.171424) (xy 140.079204 -142.169387)
			(xy 140.134641 -142.175487) (xy 140.188598 -142.189593) (xy 140.202616 -142.19555) (xy 145.703034 -142.19555)
			(xy 145.707105 -142.139928) (xy 145.719231 -142.085491) (xy 145.739154 -142.0334) (xy 145.76645 -141.984765)
			(xy 145.800536 -141.940622) (xy 145.840685 -141.901913) (xy 145.886043 -141.869462) (xy 145.935643 -141.843961)
			(xy 145.988427 -141.825954) (xy 146.04327 -141.815824) (xy 146.099004 -141.813787) (xy 146.154441 -141.819887)
			(xy 146.208398 -141.833993) (xy 146.259727 -141.855805) (xy 146.307333 -141.884859) (xy 146.350201 -141.920534)
			(xy 146.387418 -141.962071) (xy 146.418191 -142.008584) (xy 146.441863 -142.059081) (xy 146.457931 -142.112488)
			(xy 146.466051 -142.167664) (xy 146.46656 -142.19555) (xy 146.466051 -142.223436) (xy 146.457931 -142.278612)
			(xy 146.441863 -142.332019) (xy 146.418191 -142.382516) (xy 146.387418 -142.429029) (xy 146.350201 -142.470566)
			(xy 146.307333 -142.506241) (xy 146.259727 -142.535295) (xy 146.208398 -142.557107) (xy 146.154441 -142.571213)
			(xy 146.099004 -142.577313) (xy 146.04327 -142.575276) (xy 145.988427 -142.565146) (xy 145.935643 -142.547139)
			(xy 145.886043 -142.521638) (xy 145.840685 -142.489187) (xy 145.800536 -142.450478) (xy 145.76645 -142.406335)
			(xy 145.739154 -142.3577) (xy 145.719231 -142.305609) (xy 145.707105 -142.251172) (xy 145.703034 -142.19555)
			(xy 140.202616 -142.19555) (xy 140.239927 -142.211405) (xy 140.287533 -142.240459) (xy 140.330401 -142.276134)
			(xy 140.367618 -142.317671) (xy 140.398391 -142.364184) (xy 140.422063 -142.414681) (xy 140.438131 -142.468088)
			(xy 140.446251 -142.523264) (xy 140.44676 -142.55115) (xy 140.446251 -142.579036) (xy 140.438131 -142.634212)
			(xy 140.422063 -142.687619) (xy 140.398391 -142.738116) (xy 140.367618 -142.784629) (xy 140.330401 -142.826166)
			(xy 140.287533 -142.861841) (xy 140.239927 -142.890895) (xy 140.188598 -142.912707) (xy 140.134641 -142.926813)
			(xy 140.079204 -142.932913) (xy 140.02347 -142.930876) (xy 139.968627 -142.920746) (xy 139.915843 -142.902739)
			(xy 139.866243 -142.877238) (xy 139.820885 -142.844787) (xy 139.780736 -142.806078) (xy 139.74665 -142.761935)
			(xy 139.719354 -142.7133) (xy 139.699431 -142.661209) (xy 139.687305 -142.606772) (xy 139.683234 -142.55115)
			(xy 135.9408 -142.55115) (xy 135.116316 -143.375634) (xy 142.156178 -143.375634) (xy 142.160249 -143.320012)
			(xy 142.172375 -143.265575) (xy 142.192298 -143.213484) (xy 142.219594 -143.164849) (xy 142.25368 -143.120706)
			(xy 142.293829 -143.081997) (xy 142.339187 -143.049546) (xy 142.388787 -143.024045) (xy 142.441571 -143.006038)
			(xy 142.496414 -142.995908) (xy 142.552148 -142.993871) (xy 142.607585 -142.999971) (xy 142.661542 -143.014077)
			(xy 142.712871 -143.035889) (xy 142.760477 -143.064943) (xy 142.803345 -143.100618) (xy 142.840562 -143.142155)
			(xy 142.871335 -143.188668) (xy 142.895007 -143.239165) (xy 142.911075 -143.292572) (xy 142.919195 -143.347748)
			(xy 142.919704 -143.375634) (xy 142.919195 -143.40352) (xy 142.911075 -143.458696) (xy 142.895007 -143.512103)
			(xy 142.871335 -143.5626) (xy 142.840562 -143.609113) (xy 142.803345 -143.65065) (xy 142.760477 -143.686325)
			(xy 142.712871 -143.715379) (xy 142.661542 -143.737191) (xy 142.607585 -143.751297) (xy 142.552148 -143.757397)
			(xy 142.496414 -143.75536) (xy 142.441571 -143.74523) (xy 142.388787 -143.727223) (xy 142.339187 -143.701722)
			(xy 142.293829 -143.669271) (xy 142.25368 -143.630562) (xy 142.219594 -143.586419) (xy 142.192298 -143.537784)
			(xy 142.172375 -143.485693) (xy 142.160249 -143.431256) (xy 142.156178 -143.375634) (xy 135.116316 -143.375634)
			(xy 133.268516 -145.223434) (xy 139.632414 -145.223434) (xy 139.635735 -145.167673) (xy 139.647151 -145.112992)
			(xy 139.66642 -145.060561) (xy 139.693128 -145.0115) (xy 139.726706 -144.966858) (xy 139.746228 -144.946878)
			(xy 139.761681 -144.930985) (xy 139.787316 -144.894825) (xy 139.806288 -144.854764) (xy 139.818019 -144.812019)
			(xy 139.822155 -144.767887) (xy 139.81857 -144.723707) (xy 139.807373 -144.680819) (xy 139.788902 -144.640525)
			(xy 139.776708 -144.622012) (xy 139.761267 -144.598733) (xy 139.73658 -144.548623) (xy 139.719465 -144.49545)
			(xy 139.710287 -144.440348) (xy 139.709243 -144.384498) (xy 139.716354 -144.329092) (xy 139.73147 -144.275316)
			(xy 139.754266 -144.224318) (xy 139.784255 -144.177191) (xy 139.820796 -144.13494) (xy 139.863108 -144.09847)
			(xy 139.910287 -144.068561) (xy 139.961322 -144.045851) (xy 140.015124 -144.030826) (xy 140.070542 -144.023808)
			(xy 140.126391 -144.024947) (xy 140.181476 -144.034218) (xy 140.234621 -144.051423) (xy 140.284689 -144.076194)
			(xy 140.330608 -144.108001) (xy 140.371399 -144.146166) (xy 140.406188 -144.189871) (xy 140.413316 -144.20215)
			(xy 143.477994 -144.20215) (xy 143.482065 -144.146528) (xy 143.494191 -144.092091) (xy 143.514114 -144.04)
			(xy 143.54141 -143.991365) (xy 143.575496 -143.947222) (xy 143.615645 -143.908513) (xy 143.661003 -143.876062)
			(xy 143.710603 -143.850561) (xy 143.763387 -143.832554) (xy 143.81823 -143.822424) (xy 143.873964 -143.820387)
			(xy 143.929401 -143.826487) (xy 143.983358 -143.840593) (xy 144.034687 -143.862405) (xy 144.082293 -143.891459)
			(xy 144.125161 -143.927134) (xy 144.162378 -143.968671) (xy 144.193151 -144.015184) (xy 144.216823 -144.065681)
			(xy 144.232891 -144.119088) (xy 144.241011 -144.174264) (xy 144.24152 -144.20215) (xy 145.677634 -144.20215)
			(xy 145.681705 -144.146528) (xy 145.693831 -144.092091) (xy 145.713754 -144.04) (xy 145.74105 -143.991365)
			(xy 145.775136 -143.947222) (xy 145.815285 -143.908513) (xy 145.860643 -143.876062) (xy 145.910243 -143.850561)
			(xy 145.963027 -143.832554) (xy 146.01787 -143.822424) (xy 146.073604 -143.820387) (xy 146.129041 -143.826487)
			(xy 146.182998 -143.840593) (xy 146.234327 -143.862405) (xy 146.281933 -143.891459) (xy 146.324801 -143.927134)
			(xy 146.362018 -143.968671) (xy 146.392791 -144.015184) (xy 146.416463 -144.065681) (xy 146.432531 -144.119088)
			(xy 146.440651 -144.174264) (xy 146.44116 -144.20215) (xy 146.440651 -144.230036) (xy 146.432531 -144.285212)
			(xy 146.416463 -144.338619) (xy 146.392791 -144.389116) (xy 146.362018 -144.435629) (xy 146.324801 -144.477166)
			(xy 146.281933 -144.512841) (xy 146.234327 -144.541895) (xy 146.182998 -144.563707) (xy 146.129041 -144.577813)
			(xy 146.073604 -144.583913) (xy 146.01787 -144.581876) (xy 145.963027 -144.571746) (xy 145.910243 -144.553739)
			(xy 145.860643 -144.528238) (xy 145.815285 -144.495787) (xy 145.775136 -144.457078) (xy 145.74105 -144.412935)
			(xy 145.713754 -144.3643) (xy 145.693831 -144.312209) (xy 145.681705 -144.257772) (xy 145.677634 -144.20215)
			(xy 144.24152 -144.20215) (xy 144.241011 -144.230036) (xy 144.232891 -144.285212) (xy 144.216823 -144.338619)
			(xy 144.193151 -144.389116) (xy 144.162378 -144.435629) (xy 144.125161 -144.477166) (xy 144.082293 -144.512841)
			(xy 144.034687 -144.541895) (xy 143.983358 -144.563707) (xy 143.929401 -144.577813) (xy 143.873964 -144.583913)
			(xy 143.81823 -144.581876) (xy 143.763387 -144.571746) (xy 143.710603 -144.553739) (xy 143.661003 -144.528238)
			(xy 143.615645 -144.495787) (xy 143.575496 -144.457078) (xy 143.54141 -144.412935) (xy 143.514114 -144.3643)
			(xy 143.494191 -144.312209) (xy 143.482065 -144.257772) (xy 143.477994 -144.20215) (xy 140.413316 -144.20215)
			(xy 140.434231 -144.238181) (xy 140.45493 -144.290065) (xy 140.467841 -144.344413) (xy 140.472688 -144.400063)
			(xy 140.469368 -144.455824) (xy 140.457952 -144.510506) (xy 140.438684 -144.562938) (xy 140.411975 -144.611999)
			(xy 140.378398 -144.656641) (xy 140.358876 -144.676622) (xy 140.343423 -144.692515) (xy 140.317787 -144.728675)
			(xy 140.298816 -144.768736) (xy 140.287084 -144.811481) (xy 140.282948 -144.855613) (xy 140.286533 -144.899793)
			(xy 140.297731 -144.942681) (xy 140.316201 -144.982975) (xy 140.328396 -145.001488) (xy 140.343832 -145.024771)
			(xy 140.368518 -145.07488) (xy 140.385633 -145.128053) (xy 140.39481 -145.183154) (xy 140.395702 -145.23085)
			(xy 142.266414 -145.23085) (xy 142.270485 -145.175228) (xy 142.282611 -145.120791) (xy 142.302534 -145.0687)
			(xy 142.32983 -145.020065) (xy 142.363916 -144.975922) (xy 142.404065 -144.937213) (xy 142.449423 -144.904762)
			(xy 142.499023 -144.879261) (xy 142.551807 -144.861254) (xy 142.60665 -144.851124) (xy 142.662384 -144.849087)
			(xy 142.717821 -144.855187) (xy 142.771778 -144.869293) (xy 142.823107 -144.891105) (xy 142.870713 -144.920159)
			(xy 142.913581 -144.955834) (xy 142.950798 -144.997371) (xy 142.981571 -145.043884) (xy 143.005243 -145.094381)
			(xy 143.021311 -145.147788) (xy 143.029431 -145.202964) (xy 143.02994 -145.23085) (xy 143.029431 -145.258736)
			(xy 143.021311 -145.313912) (xy 143.005243 -145.367319) (xy 142.981571 -145.417816) (xy 142.950798 -145.464329)
			(xy 142.913581 -145.505866) (xy 142.870713 -145.541541) (xy 142.823107 -145.570595) (xy 142.771778 -145.592407)
			(xy 142.717821 -145.606513) (xy 142.662384 -145.612613) (xy 142.60665 -145.610576) (xy 142.551807 -145.600446)
			(xy 142.499023 -145.582439) (xy 142.449423 -145.556938) (xy 142.404065 -145.524487) (xy 142.363916 -145.485778)
			(xy 142.32983 -145.441635) (xy 142.302534 -145.393) (xy 142.282611 -145.340909) (xy 142.270485 -145.286472)
			(xy 142.266414 -145.23085) (xy 140.395702 -145.23085) (xy 140.395854 -145.239004) (xy 140.388743 -145.29441)
			(xy 140.373627 -145.348186) (xy 140.350831 -145.399182) (xy 140.320841 -145.44631) (xy 140.2843 -145.48856)
			(xy 140.241988 -145.525029) (xy 140.19481 -145.554938) (xy 140.143774 -145.577648) (xy 140.089973 -145.592672)
			(xy 140.034556 -145.599689) (xy 139.978707 -145.59855) (xy 139.923622 -145.589279) (xy 139.870478 -145.572074)
			(xy 139.820411 -145.547303) (xy 139.774491 -145.515495) (xy 139.733701 -145.47733) (xy 139.698913 -145.433626)
			(xy 139.67087 -145.385315) (xy 139.650172 -145.333431) (xy 139.637261 -145.279084) (xy 139.632414 -145.223434)
			(xy 133.268516 -145.223434) (xy 132.13842 -146.35353) (xy 143.345914 -146.35353) (xy 143.349985 -146.297908)
			(xy 143.362111 -146.243471) (xy 143.382034 -146.19138) (xy 143.40933 -146.142745) (xy 143.443416 -146.098602)
			(xy 143.483565 -146.059893) (xy 143.528923 -146.027442) (xy 143.578523 -146.001941) (xy 143.631307 -145.983934)
			(xy 143.68615 -145.973804) (xy 143.741884 -145.971767) (xy 143.797321 -145.977867) (xy 143.851278 -145.991973)
			(xy 143.902607 -146.013785) (xy 143.950213 -146.042839) (xy 143.993081 -146.078514) (xy 144.030298 -146.120051)
			(xy 144.061071 -146.166564) (xy 144.084743 -146.217061) (xy 144.100811 -146.270468) (xy 144.108931 -146.325644)
			(xy 144.10944 -146.35353) (xy 144.108931 -146.381416) (xy 144.100811 -146.436592) (xy 144.084743 -146.489999)
			(xy 144.061071 -146.540496) (xy 144.030298 -146.587009) (xy 143.993081 -146.628546) (xy 143.950213 -146.664221)
			(xy 143.902607 -146.693275) (xy 143.851278 -146.715087) (xy 143.797321 -146.729193) (xy 143.741884 -146.735293)
			(xy 143.68615 -146.733256) (xy 143.631307 -146.723126) (xy 143.578523 -146.705119) (xy 143.528923 -146.679618)
			(xy 143.483565 -146.647167) (xy 143.443416 -146.608458) (xy 143.40933 -146.564315) (xy 143.382034 -146.51568)
			(xy 143.362111 -146.463589) (xy 143.349985 -146.409152) (xy 143.345914 -146.35353) (xy 132.13842 -146.35353)
			(xy 131.558792 -146.933158) (xy 130.883914 -146.933158) (xy 130.87477 -146.942556) (xy 126.322328 -146.942556)
			(xy 126.19736 -147.06727) (xy 126.19736 -147.775422) (xy 142.162274 -147.775422) (xy 142.166345 -147.7198)
			(xy 142.178471 -147.665363) (xy 142.198394 -147.613272) (xy 142.22569 -147.564637) (xy 142.259776 -147.520494)
			(xy 142.299925 -147.481785) (xy 142.345283 -147.449334) (xy 142.394883 -147.423833) (xy 142.447667 -147.405826)
			(xy 142.50251 -147.395696) (xy 142.558244 -147.393659) (xy 142.613681 -147.399759) (xy 142.667638 -147.413865)
			(xy 142.718967 -147.435677) (xy 142.766573 -147.464731) (xy 142.809441 -147.500406) (xy 142.846658 -147.541943)
			(xy 142.877431 -147.588456) (xy 142.901103 -147.638953) (xy 142.917171 -147.69236) (xy 142.925291 -147.747536)
			(xy 142.9258 -147.775422) (xy 142.925291 -147.803308) (xy 142.917171 -147.858484) (xy 142.901103 -147.911891)
			(xy 142.877431 -147.962388) (xy 142.846658 -148.008901) (xy 142.809441 -148.050438) (xy 142.766573 -148.086113)
			(xy 142.718967 -148.115167) (xy 142.667638 -148.136979) (xy 142.613681 -148.151085) (xy 142.558244 -148.157185)
			(xy 142.50251 -148.155148) (xy 142.447667 -148.145018) (xy 142.394883 -148.127011) (xy 142.345283 -148.10151)
			(xy 142.299925 -148.069059) (xy 142.259776 -148.03035) (xy 142.22569 -147.986207) (xy 142.198394 -147.937572)
			(xy 142.178471 -147.885481) (xy 142.166345 -147.831044) (xy 142.162274 -147.775422) (xy 126.19736 -147.775422)
			(xy 126.19736 -148.791997) (xy 126.584838 -148.791997) (xy 126.586279 -148.736437) (xy 126.595766 -148.681673)
			(xy 126.613097 -148.628866) (xy 126.637907 -148.579131) (xy 126.669669 -148.533522) (xy 126.707712 -148.493004)
			(xy 126.751231 -148.458433) (xy 126.799304 -148.430542) (xy 126.850916 -148.40992) (xy 126.904973 -148.397005)
			(xy 126.960333 -148.392068) (xy 127.015822 -148.395215) (xy 127.070269 -148.406379) (xy 127.122519 -148.425324)
			(xy 127.171468 -148.451649) (xy 127.21608 -148.484797) (xy 127.255411 -148.524066) (xy 127.260066 -148.53031)
			(xy 143.229074 -148.53031) (xy 143.233145 -148.474688) (xy 143.245271 -148.420251) (xy 143.265194 -148.36816)
			(xy 143.29249 -148.319525) (xy 143.326576 -148.275382) (xy 143.366725 -148.236673) (xy 143.412083 -148.204222)
			(xy 143.461683 -148.178721) (xy 143.514467 -148.160714) (xy 143.56931 -148.150584) (xy 143.625044 -148.148547)
			(xy 143.680481 -148.154647) (xy 143.734438 -148.168753) (xy 143.785767 -148.190565) (xy 143.833373 -148.219619)
			(xy 143.876241 -148.255294) (xy 143.913458 -148.296831) (xy 143.944231 -148.343344) (xy 143.967903 -148.393841)
			(xy 143.983971 -148.447248) (xy 143.992091 -148.502424) (xy 143.9926 -148.53031) (xy 143.992091 -148.558196)
			(xy 143.983971 -148.613372) (xy 143.967903 -148.666779) (xy 143.944231 -148.717276) (xy 143.913458 -148.763789)
			(xy 143.876241 -148.805326) (xy 143.833373 -148.841001) (xy 143.785767 -148.870055) (xy 143.734438 -148.891867)
			(xy 143.680481 -148.905973) (xy 143.625044 -148.912073) (xy 143.56931 -148.910036) (xy 143.514467 -148.899906)
			(xy 143.461683 -148.881899) (xy 143.412083 -148.856398) (xy 143.366725 -148.823947) (xy 143.326576 -148.785238)
			(xy 143.29249 -148.741095) (xy 143.265194 -148.69246) (xy 143.245271 -148.640369) (xy 143.233145 -148.585932)
			(xy 143.229074 -148.53031) (xy 127.260066 -148.53031) (xy 127.288629 -148.568627) (xy 127.315031 -148.617534)
			(xy 127.334058 -148.669755) (xy 127.345307 -148.724183) (xy 127.348541 -148.779668) (xy 127.343691 -148.835035)
			(xy 127.33086 -148.889113) (xy 127.321056 -148.91512) (xy 127.313289 -148.935987) (xy 127.30431 -148.979591)
			(xy 127.30307 -149.024094) (xy 127.309607 -149.068131) (xy 127.323722 -149.110354) (xy 127.344982 -149.149469)
			(xy 127.369761 -149.18055) (xy 139.556234 -149.18055) (xy 139.560305 -149.124928) (xy 139.572431 -149.070491)
			(xy 139.592354 -149.0184) (xy 139.61965 -148.969765) (xy 139.653736 -148.925622) (xy 139.693885 -148.886913)
			(xy 139.739243 -148.854462) (xy 139.788843 -148.828961) (xy 139.841627 -148.810954) (xy 139.89647 -148.800824)
			(xy 139.952204 -148.798787) (xy 140.007641 -148.804887) (xy 140.061598 -148.818993) (xy 140.112927 -148.840805)
			(xy 140.160533 -148.869859) (xy 140.203401 -148.905534) (xy 140.240618 -148.947071) (xy 140.271391 -148.993584)
			(xy 140.295063 -149.044081) (xy 140.311131 -149.097488) (xy 140.319251 -149.152664) (xy 140.31976 -149.18055)
			(xy 140.319251 -149.208436) (xy 140.311131 -149.263612) (xy 140.295063 -149.317019) (xy 140.271391 -149.367516)
			(xy 140.240618 -149.414029) (xy 140.203401 -149.455566) (xy 140.160533 -149.491241) (xy 140.112927 -149.520295)
			(xy 140.061598 -149.542107) (xy 140.007641 -149.556213) (xy 139.952204 -149.562313) (xy 139.89647 -149.560276)
			(xy 139.841627 -149.550146) (xy 139.788843 -149.532139) (xy 139.739243 -149.506638) (xy 139.693885 -149.474187)
			(xy 139.653736 -149.435478) (xy 139.61965 -149.391335) (xy 139.592354 -149.3427) (xy 139.572431 -149.290609)
			(xy 139.560305 -149.236172) (xy 139.556234 -149.18055) (xy 127.369761 -149.18055) (xy 127.372735 -149.18428)
			(xy 127.389128 -149.199346) (xy 127.409613 -149.218129) (xy 127.445499 -149.260565) (xy 127.474849 -149.307758)
			(xy 127.497043 -149.35871) (xy 127.511609 -149.412342) (xy 127.518241 -149.46752) (xy 127.516797 -149.523077)
			(xy 127.507309 -149.577836) (xy 127.489976 -149.63064) (xy 127.465167 -149.68037) (xy 127.433405 -149.725975)
			(xy 127.395363 -149.76649) (xy 127.351845 -149.801056) (xy 127.303773 -149.828944) (xy 127.252164 -149.849562)
			(xy 127.19811 -149.862476) (xy 127.142754 -149.86741) (xy 127.087268 -149.864261) (xy 127.032826 -149.853096)
			(xy 126.980579 -149.83415) (xy 126.931634 -149.807826) (xy 126.887026 -149.774679) (xy 126.847698 -149.73541)
			(xy 126.814484 -149.690852) (xy 126.788085 -149.641947) (xy 126.769061 -149.589729) (xy 126.757814 -149.535304)
			(xy 126.754581 -149.479822) (xy 126.759432 -149.424459) (xy 126.772264 -149.370385) (xy 126.782068 -149.34438)
			(xy 126.789857 -149.32352) (xy 126.798839 -149.279913) (xy 126.80008 -149.235407) (xy 126.79354 -149.191367)
			(xy 126.779421 -149.149142) (xy 126.758155 -149.110026) (xy 126.730393 -149.075218) (xy 126.713996 -149.060154)
			(xy 126.693484 -149.041399) (xy 126.657593 -148.998962) (xy 126.628239 -148.951768) (xy 126.606042 -148.900814)
			(xy 126.591472 -148.847178) (xy 126.584838 -148.791997) (xy 126.19736 -148.791997) (xy 126.19736 -150.053878)
			(xy 129.756095 -150.053878) (xy 129.762276 -149.999318) (xy 129.776212 -149.946207) (xy 129.797617 -149.895641)
			(xy 129.826048 -149.848666) (xy 129.860919 -149.80625) (xy 129.901508 -149.76927) (xy 129.946979 -149.738489)
			(xy 129.996391 -149.714543) (xy 130.048726 -149.697926) (xy 130.102902 -149.688982) (xy 130.1578 -149.687894)
			(xy 130.212288 -149.694686) (xy 130.26524 -149.709217) (xy 130.315562 -149.731187) (xy 130.362216 -149.760143)
			(xy 130.383534 -149.77745) (xy 130.40215 -149.792449) (xy 130.443833 -149.815847) (xy 130.48916 -149.831029)
			(xy 130.536527 -149.83746) (xy 130.58426 -149.834912) (xy 130.630673 -149.823475) (xy 130.674126 -149.803554)
			(xy 130.693922 -149.79015) (xy 130.71658 -149.774637) (xy 130.765445 -149.749586) (xy 130.817396 -149.731797)
			(xy 130.87136 -149.721637) (xy 130.926223 -149.719317) (xy 130.980852 -149.724883) (xy 131.03412 -149.738221)
			(xy 131.084926 -149.759056) (xy 131.132221 -149.786958) (xy 131.175029 -149.82135) (xy 131.212467 -149.861522)
			(xy 131.24376 -149.906645) (xy 131.261663 -149.94255) (xy 133.638034 -149.94255) (xy 133.642105 -149.886928)
			(xy 133.654231 -149.832491) (xy 133.674154 -149.7804) (xy 133.70145 -149.731765) (xy 133.735536 -149.687622)
			(xy 133.775685 -149.648913) (xy 133.821043 -149.616462) (xy 133.870643 -149.590961) (xy 133.923427 -149.572954)
			(xy 133.97827 -149.562824) (xy 134.034004 -149.560787) (xy 134.089441 -149.566887) (xy 134.143398 -149.580993)
			(xy 134.194727 -149.602805) (xy 134.242333 -149.631859) (xy 134.285201 -149.667534) (xy 134.322418 -149.709071)
			(xy 134.353191 -149.755584) (xy 134.376863 -149.806081) (xy 134.392931 -149.859488) (xy 134.401051 -149.914664)
			(xy 134.40156 -149.94255) (xy 135.009634 -149.94255) (xy 135.013705 -149.886928) (xy 135.025831 -149.832491)
			(xy 135.045754 -149.7804) (xy 135.07305 -149.731765) (xy 135.107136 -149.687622) (xy 135.147285 -149.648913)
			(xy 135.192643 -149.616462) (xy 135.242243 -149.590961) (xy 135.295027 -149.572954) (xy 135.34987 -149.562824)
			(xy 135.405604 -149.560787) (xy 135.461041 -149.566887) (xy 135.514998 -149.580993) (xy 135.566327 -149.602805)
			(xy 135.613933 -149.631859) (xy 135.656801 -149.667534) (xy 135.694018 -149.709071) (xy 135.724791 -149.755584)
			(xy 135.748463 -149.806081) (xy 135.764531 -149.859488) (xy 135.770662 -149.901148) (xy 136.956036 -149.901148)
			(xy 136.960107 -149.845526) (xy 136.972233 -149.791089) (xy 136.992156 -149.738998) (xy 137.019452 -149.690363)
			(xy 137.053538 -149.64622) (xy 137.093687 -149.607511) (xy 137.139045 -149.57506) (xy 137.188645 -149.549559)
			(xy 137.241429 -149.531552) (xy 137.296272 -149.521422) (xy 137.352006 -149.519385) (xy 137.407443 -149.525485)
			(xy 137.4614 -149.539591) (xy 137.512729 -149.561403) (xy 137.560335 -149.590457) (xy 137.603203 -149.626132)
			(xy 137.64042 -149.667669) (xy 137.671193 -149.714182) (xy 137.694865 -149.764679) (xy 137.710933 -149.818086)
			(xy 137.719053 -149.873262) (xy 137.719562 -149.901148) (xy 137.719557 -149.901402) (xy 138.555982 -149.901402)
			(xy 138.560053 -149.84578) (xy 138.572179 -149.791343) (xy 138.592102 -149.739252) (xy 138.619398 -149.690617)
			(xy 138.653484 -149.646474) (xy 138.693633 -149.607765) (xy 138.738991 -149.575314) (xy 138.788591 -149.549813)
			(xy 138.841375 -149.531806) (xy 138.896218 -149.521676) (xy 138.951952 -149.519639) (xy 139.007389 -149.525739)
			(xy 139.061346 -149.539845) (xy 139.112675 -149.561657) (xy 139.160281 -149.590711) (xy 139.203149 -149.626386)
			(xy 139.240366 -149.667923) (xy 139.259054 -149.69617) (xy 142.256254 -149.69617) (xy 142.260325 -149.640548)
			(xy 142.272451 -149.586111) (xy 142.292374 -149.53402) (xy 142.31967 -149.485385) (xy 142.353756 -149.441242)
			(xy 142.393905 -149.402533) (xy 142.439263 -149.370082) (xy 142.488863 -149.344581) (xy 142.541647 -149.326574)
			(xy 142.59649 -149.316444) (xy 142.652224 -149.314407) (xy 142.707661 -149.320507) (xy 142.761618 -149.334613)
			(xy 142.812947 -149.356425) (xy 142.860553 -149.385479) (xy 142.903421 -149.421154) (xy 142.940638 -149.462691)
			(xy 142.971411 -149.509204) (xy 142.995083 -149.559701) (xy 143.011151 -149.613108) (xy 143.019271 -149.668284)
			(xy 143.01978 -149.69617) (xy 143.019271 -149.724056) (xy 143.011151 -149.779232) (xy 142.995083 -149.832639)
			(xy 142.971411 -149.883136) (xy 142.940638 -149.929649) (xy 142.903421 -149.971186) (xy 142.860553 -150.006861)
			(xy 142.812947 -150.035915) (xy 142.761618 -150.057727) (xy 142.707661 -150.071833) (xy 142.652224 -150.077933)
			(xy 142.59649 -150.075896) (xy 142.541647 -150.065766) (xy 142.488863 -150.047759) (xy 142.439263 -150.022258)
			(xy 142.393905 -149.989807) (xy 142.353756 -149.951098) (xy 142.31967 -149.906955) (xy 142.292374 -149.85832)
			(xy 142.272451 -149.806229) (xy 142.260325 -149.751792) (xy 142.256254 -149.69617) (xy 139.259054 -149.69617)
			(xy 139.271139 -149.714436) (xy 139.294811 -149.764933) (xy 139.310879 -149.81834) (xy 139.318999 -149.873516)
			(xy 139.319508 -149.901402) (xy 139.318999 -149.929288) (xy 139.310879 -149.984464) (xy 139.294811 -150.037871)
			(xy 139.271139 -150.088368) (xy 139.240366 -150.134881) (xy 139.203149 -150.176418) (xy 139.160281 -150.212093)
			(xy 139.112675 -150.241147) (xy 139.061346 -150.262959) (xy 139.007389 -150.277065) (xy 138.951952 -150.283165)
			(xy 138.896218 -150.281128) (xy 138.841375 -150.270998) (xy 138.788591 -150.252991) (xy 138.738991 -150.22749)
			(xy 138.693633 -150.195039) (xy 138.653484 -150.15633) (xy 138.619398 -150.112187) (xy 138.592102 -150.063552)
			(xy 138.572179 -150.011461) (xy 138.560053 -149.957024) (xy 138.555982 -149.901402) (xy 137.719557 -149.901402)
			(xy 137.719053 -149.929034) (xy 137.710933 -149.98421) (xy 137.694865 -150.037617) (xy 137.671193 -150.088114)
			(xy 137.64042 -150.134627) (xy 137.603203 -150.176164) (xy 137.560335 -150.211839) (xy 137.512729 -150.240893)
			(xy 137.4614 -150.262705) (xy 137.407443 -150.276811) (xy 137.352006 -150.282911) (xy 137.296272 -150.280874)
			(xy 137.241429 -150.270744) (xy 137.188645 -150.252737) (xy 137.139045 -150.227236) (xy 137.093687 -150.194785)
			(xy 137.053538 -150.156076) (xy 137.019452 -150.111933) (xy 136.992156 -150.063298) (xy 136.972233 -150.011207)
			(xy 136.960107 -149.95677) (xy 136.956036 -149.901148) (xy 135.770662 -149.901148) (xy 135.772651 -149.914664)
			(xy 135.77316 -149.94255) (xy 135.772651 -149.970436) (xy 135.764531 -150.025612) (xy 135.748463 -150.079019)
			(xy 135.724791 -150.129516) (xy 135.694018 -150.176029) (xy 135.656801 -150.217566) (xy 135.613933 -150.253241)
			(xy 135.566327 -150.282295) (xy 135.514998 -150.304107) (xy 135.461041 -150.318213) (xy 135.405604 -150.324313)
			(xy 135.34987 -150.322276) (xy 135.295027 -150.312146) (xy 135.242243 -150.294139) (xy 135.192643 -150.268638)
			(xy 135.147285 -150.236187) (xy 135.107136 -150.197478) (xy 135.07305 -150.153335) (xy 135.045754 -150.1047)
			(xy 135.025831 -150.052609) (xy 135.013705 -149.998172) (xy 135.009634 -149.94255) (xy 134.40156 -149.94255)
			(xy 134.401051 -149.970436) (xy 134.392931 -150.025612) (xy 134.376863 -150.079019) (xy 134.353191 -150.129516)
			(xy 134.322418 -150.176029) (xy 134.285201 -150.217566) (xy 134.242333 -150.253241) (xy 134.194727 -150.282295)
			(xy 134.143398 -150.304107) (xy 134.089441 -150.318213) (xy 134.034004 -150.324313) (xy 133.97827 -150.322276)
			(xy 133.923427 -150.312146) (xy 133.870643 -150.294139) (xy 133.821043 -150.268638) (xy 133.775685 -150.236187)
			(xy 133.735536 -150.197478) (xy 133.70145 -150.153335) (xy 133.674154 -150.1047) (xy 133.654231 -150.052609)
			(xy 133.642105 -149.998172) (xy 133.638034 -149.94255) (xy 131.261663 -149.94255) (xy 131.268263 -149.955787)
			(xy 131.28547 -150.007933) (xy 131.295026 -150.062007) (xy 131.296733 -150.116893) (xy 131.290556 -150.171456)
			(xy 131.276623 -150.224571) (xy 131.255222 -150.275141) (xy 131.226793 -150.322122) (xy 131.191925 -150.364543)
			(xy 131.151337 -150.401529) (xy 131.105867 -150.432315) (xy 131.056454 -150.456268) (xy 131.004118 -150.472891)
			(xy 130.949941 -150.481841) (xy 130.89504 -150.482935) (xy 130.840548 -150.476148) (xy 130.787592 -150.461623)
			(xy 130.737265 -150.439657) (xy 130.690605 -150.410705) (xy 130.669284 -150.3934) (xy 130.650656 -150.378418)
			(xy 130.608974 -150.355024) (xy 130.563651 -150.339842) (xy 130.516287 -150.33341) (xy 130.468557 -150.335955)
			(xy 130.422145 -150.347386) (xy 130.378693 -150.3673) (xy 130.358896 -150.3807) (xy 130.336193 -150.396148)
			(xy 130.28733 -150.421196) (xy 130.235381 -150.438982) (xy 130.181419 -150.449138) (xy 130.126559 -150.451456)
			(xy 130.071932 -150.445887) (xy 130.018668 -150.432547) (xy 129.967866 -150.41171) (xy 129.920575 -150.383807)
			(xy 129.877771 -150.349415) (xy 129.840338 -150.309242) (xy 129.80905 -150.264119) (xy 129.784551 -150.214978)
			(xy 129.767349 -150.162833) (xy 129.757798 -150.108761) (xy 129.756095 -150.053878) (xy 126.19736 -150.053878)
			(xy 126.19736 -150.31212) (xy 127.016256 -151.131016) (xy 142.39748 -151.131016)
		)
		(stroke
			(width 0)
			(type solid)
		)
		(fill yes)
		(layer "In6.Cu")
		(net "P1V0_NODE1")
	)
	(gr_poly
		(pts
			(xy 32.929322 -166.49954) (xy 37.29228 -166.49954) (xy 39.812214 -163.97986) (xy 39.82841 -163.962899)
			(xy 39.854921 -163.92422) (xy 39.873889 -163.881336) (xy 39.884674 -163.835701) (xy 39.886908 -163.788862)
			(xy 39.880516 -163.742408) (xy 39.865715 -163.697913) (xy 39.843007 -163.656886) (xy 39.82847 -163.638484)
			(xy 39.810971 -163.616537) (xy 39.781932 -163.568504) (xy 39.760243 -163.516735) (xy 39.746375 -163.462346)
			(xy 39.740625 -163.406512) (xy 39.743118 -163.350438) (xy 39.753801 -163.295335) (xy 39.772442 -163.242392)
			(xy 39.798639 -163.192752) (xy 39.831828 -163.147486) (xy 39.87129 -163.107571) (xy 39.916175 -163.073869)
			(xy 39.965514 -163.047108) (xy 40.018241 -163.027865) (xy 40.04564 -163.021772) (xy 40.073158 -163.016606)
			(xy 40.129058 -163.013446) (xy 40.184819 -163.018494) (xy 40.239243 -163.03164) (xy 40.29116 -163.052603)
			(xy 40.339454 -163.08093) (xy 40.383087 -163.116015) (xy 40.421122 -163.157102) (xy 40.452741 -163.203308)
			(xy 40.477264 -163.253641) (xy 40.494165 -163.307018) (xy 40.503079 -163.362293) (xy 40.503817 -163.418277)
			(xy 40.49636 -163.473768) (xy 40.489124 -163.500816) (xy 40.484026 -163.523331) (xy 40.481123 -163.569398)
			(xy 40.48659 -163.615232) (xy 40.500246 -163.659324) (xy 40.521643 -163.700224) (xy 40.550076 -163.736587)
			(xy 40.584609 -163.767215) (xy 40.624107 -163.7911) (xy 40.66727 -163.807458) (xy 40.712678 -163.81575)
			(xy 40.735758 -163.816284) (xy 40.877744 -163.816284) (xy 40.894388 -163.815735) (xy 40.926539 -163.80711)
			(xy 40.955362 -163.790458) (xy 40.978895 -163.766915) (xy 40.995533 -163.738083) (xy 41.004143 -163.705928)
			(xy 41.004744 -163.689284) (xy 41.004744 -163.646612) (xy 40.978836 -163.612576) (xy 40.9628 -163.590695)
			(xy 40.936416 -163.543295) (xy 40.917013 -163.492635) (xy 40.904983 -163.439738) (xy 40.900569 -163.38567)
			(xy 40.903858 -163.331521) (xy 40.914786 -163.278385) (xy 40.933132 -163.227333) (xy 40.958525 -163.179395)
			(xy 40.990453 -163.135538) (xy 41.028273 -163.096646) (xy 41.07122 -163.063505) (xy 41.11843 -163.036782)
			(xy 41.16895 -163.017017) (xy 41.195244 -163.010342) (xy 41.223147 -163.004327) (xy 41.280036 -162.999682)
			(xy 41.336982 -163.003563) (xy 41.392715 -163.015883) (xy 41.445991 -163.036367) (xy 41.495621 -163.064558)
			(xy 41.540499 -163.099827) (xy 41.579623 -163.141387) (xy 41.612119 -163.188311) (xy 41.637264 -163.239553)
			(xy 41.654495 -163.293968) (xy 41.66343 -163.350342) (xy 41.663867 -163.407419) (xy 41.655798 -163.463924)
			(xy 41.648126 -163.491418) (xy 41.642047 -163.514185) (xy 41.637463 -163.561079) (xy 41.641597 -163.608015)
			(xy 41.654308 -163.653386) (xy 41.675161 -163.695638) (xy 41.703441 -163.733325) (xy 41.738181 -163.765156)
			(xy 41.778191 -163.790042) (xy 41.822101 -163.80713) (xy 41.868407 -163.815836) (xy 41.891966 -163.816284)
			(xy 51.103276 -163.816284) (xy 51.5493 -163.37026) (xy 51.5493 -162.672268) (xy 51.500786 -162.605466)
			(xy 51.461416 -162.592766) (xy 51.434684 -162.583605) (xy 51.384055 -162.558513) (xy 51.337682 -162.526225)
			(xy 51.296581 -162.487448) (xy 51.261651 -162.443031) (xy 51.233657 -162.393947) (xy 51.213212 -162.341269)
			(xy 51.200763 -162.286151) (xy 51.196583 -162.2298) (xy 51.200763 -162.173449) (xy 51.213212 -162.118331)
			(xy 51.233657 -162.065653) (xy 51.261651 -162.016569) (xy 51.296581 -161.972152) (xy 51.337682 -161.933375)
			(xy 51.384055 -161.901087) (xy 51.434684 -161.875995) (xy 51.461416 -161.866834) (xy 51.500786 -161.854134)
			(xy 51.5493 -161.787332) (xy 51.5493 -159.005524) (xy 51.54879 -158.989194) (xy 51.540482 -158.957606)
			(xy 51.524431 -158.929161) (xy 51.501687 -158.90572) (xy 51.473739 -158.888819) (xy 51.442416 -158.879563)
			(xy 51.42611 -158.878524) (xy 51.398137 -158.877195) (xy 51.343009 -158.867355) (xy 51.289912 -158.84956)
			(xy 51.239988 -158.824192) (xy 51.19431 -158.791796) (xy 51.15386 -158.753069) (xy 51.119508 -158.708843)
			(xy 51.091992 -158.660069) (xy 51.071905 -158.607797) (xy 51.059677 -158.553148) (xy 51.055571 -158.497299)
			(xy 51.059677 -158.44145) (xy 51.071905 -158.386802) (xy 51.091993 -158.334529) (xy 51.119509 -158.285755)
			(xy 51.153861 -158.24153) (xy 51.194311 -158.202803) (xy 51.239989 -158.170407) (xy 51.289913 -158.145039)
			(xy 51.343011 -158.127244) (xy 51.398139 -158.117405) (xy 51.42611 -158.116016) (xy 51.442423 -158.115023)
			(xy 51.473759 -158.105778) (xy 51.501717 -158.088873) (xy 51.524462 -158.065419) (xy 51.540501 -158.036956)
			(xy 51.548781 -158.005352) (xy 51.5493 -157.989016) (xy 51.5493 -154.990546) (xy 51.522122 -154.956002)
			(xy 51.505073 -154.933477) (xy 51.477104 -154.884398) (xy 51.456677 -154.831731) (xy 51.44424 -154.776627)
			(xy 51.440065 -154.720292) (xy 51.444243 -154.663957) (xy 51.456682 -154.608854) (xy 51.47711 -154.556188)
			(xy 51.505082 -154.50711) (xy 51.522122 -154.484578) (xy 51.5493 -154.450034) (xy 51.5493 -153.720546)
			(xy 51.522122 -153.686002) (xy 51.505073 -153.663477) (xy 51.477104 -153.614398) (xy 51.456677 -153.561731)
			(xy 51.44424 -153.506627) (xy 51.440065 -153.450292) (xy 51.444243 -153.393957) (xy 51.456682 -153.338854)
			(xy 51.47711 -153.286188) (xy 51.505082 -153.23711) (xy 51.522122 -153.214578) (xy 51.5493 -153.180034)
			(xy 51.5493 -152.132792) (xy 51.081432 -151.664924) (xy 37.391848 -151.664924) (xy 37.369497 -151.665398)
			(xy 37.325486 -151.673226) (xy 37.283523 -151.68863) (xy 37.2449 -151.711137) (xy 37.21081 -151.740053)
			(xy 37.182302 -151.774485) (xy 37.160257 -151.813372) (xy 37.145353 -151.855516) (xy 37.138049 -151.899617)
			(xy 37.137848 -151.921972) (xy 37.137617 -151.951172) (xy 37.129364 -152.008978) (xy 37.112406 -152.064852)
			(xy 37.087137 -152.117493) (xy 37.054147 -152.165672) (xy 37.014204 -152.208265) (xy 36.968242 -152.244279)
			(xy 36.917331 -152.272874) (xy 36.890198 -152.283668) (xy 36.864596 -152.292751) (xy 36.811537 -152.304403)
			(xy 36.757362 -152.308405) (xy 36.703167 -152.304676) (xy 36.65005 -152.293291) (xy 36.599087 -152.274482)
			(xy 36.551311 -152.248629) (xy 36.507688 -152.216255) (xy 36.469103 -152.178016) (xy 36.452302 -152.156668)
			(xy 36.438251 -152.139573) (xy 36.405293 -152.110053) (xy 36.367722 -152.086683) (xy 36.326674 -152.070168)
			(xy 36.283387 -152.061007) (xy 36.239168 -152.059476) (xy 36.195351 -152.065622) (xy 36.153259 -152.079259)
			(xy 36.114162 -152.099975) (xy 36.096448 -152.113234) (xy 36.073939 -152.13009) (xy 36.024953 -152.157704)
			(xy 35.972445 -152.177829) (xy 35.917552 -152.190031) (xy 35.861462 -152.194046) (xy 35.805391 -152.189785)
			(xy 35.750552 -152.177343) (xy 35.698132 -152.156987) (xy 35.649268 -152.129159) (xy 35.605016 -152.094461)
			(xy 35.566335 -152.053645) (xy 35.534063 -152.007595) (xy 35.508898 -151.957307) (xy 35.491386 -151.90387)
			(xy 35.486086 -151.876252) (xy 35.481893 -151.854384) (xy 35.466882 -151.812467) (xy 35.444797 -151.773808)
			(xy 35.416312 -151.739589) (xy 35.382299 -151.710857) (xy 35.343801 -151.688493) (xy 35.301993 -151.67318)
			(xy 35.258157 -151.665387) (xy 35.235896 -151.664924) (xy 35.20186 -151.664924) (xy 35.179944 -151.665387)
			(xy 35.136761 -151.67291) (xy 35.095509 -151.687727) (xy 35.057408 -151.709399) (xy 35.023588 -151.737283)
			(xy 34.995051 -151.770554) (xy 34.972642 -151.808226) (xy 34.957025 -151.849182) (xy 34.948662 -151.89221)
			(xy 34.947802 -151.936035) (xy 34.95447 -151.979358) (xy 34.968469 -152.020895) (xy 34.978594 -152.040336)
			(xy 34.992349 -152.064431) (xy 35.013509 -152.115718) (xy 35.027018 -152.169528) (xy 35.032592 -152.224728)
			(xy 35.030112 -152.280153) (xy 35.019631 -152.334634) (xy 35.00137 -152.387023) (xy 34.975714 -152.436215)
			(xy 34.943204 -152.481173) (xy 34.938901 -152.485598) (xy 41.73931 -152.485598) (xy 41.743381 -152.429976)
			(xy 41.755507 -152.375539) (xy 41.77543 -152.323448) (xy 41.802726 -152.274813) (xy 41.836812 -152.23067)
			(xy 41.876961 -152.191961) (xy 41.922319 -152.15951) (xy 41.971919 -152.134009) (xy 42.024703 -152.116002)
			(xy 42.079546 -152.105872) (xy 42.13528 -152.103835) (xy 42.190717 -152.109935) (xy 42.244674 -152.124041)
			(xy 42.296003 -152.145853) (xy 42.343609 -152.174907) (xy 42.386477 -152.210582) (xy 42.423694 -152.252119)
			(xy 42.454467 -152.298632) (xy 42.478139 -152.349129) (xy 42.494207 -152.402536) (xy 42.502327 -152.457712)
			(xy 42.502836 -152.485598) (xy 42.502372 -152.510998) (xy 43.66971 -152.510998) (xy 43.673781 -152.455376)
			(xy 43.685907 -152.400939) (xy 43.70583 -152.348848) (xy 43.733126 -152.300213) (xy 43.767212 -152.25607)
			(xy 43.807361 -152.217361) (xy 43.852719 -152.18491) (xy 43.902319 -152.159409) (xy 43.955103 -152.141402)
			(xy 44.009946 -152.131272) (xy 44.06568 -152.129235) (xy 44.121117 -152.135335) (xy 44.175074 -152.149441)
			(xy 44.226403 -152.171253) (xy 44.274009 -152.200307) (xy 44.316877 -152.235982) (xy 44.354094 -152.277519)
			(xy 44.384867 -152.324032) (xy 44.408539 -152.374529) (xy 44.424607 -152.427936) (xy 44.432727 -152.483112)
			(xy 44.433236 -152.510998) (xy 45.21911 -152.510998) (xy 45.223181 -152.455376) (xy 45.235307 -152.400939)
			(xy 45.25523 -152.348848) (xy 45.282526 -152.300213) (xy 45.316612 -152.25607) (xy 45.356761 -152.217361)
			(xy 45.402119 -152.18491) (xy 45.451719 -152.159409) (xy 45.504503 -152.141402) (xy 45.559346 -152.131272)
			(xy 45.61508 -152.129235) (xy 45.670517 -152.135335) (xy 45.724474 -152.149441) (xy 45.775803 -152.171253)
			(xy 45.823409 -152.200307) (xy 45.866277 -152.235982) (xy 45.903494 -152.277519) (xy 45.934267 -152.324032)
			(xy 45.957939 -152.374529) (xy 45.974007 -152.427936) (xy 45.982127 -152.483112) (xy 45.982636 -152.510998)
			(xy 45.982172 -152.536398) (xy 46.59071 -152.536398) (xy 46.594781 -152.480776) (xy 46.606907 -152.426339)
			(xy 46.62683 -152.374248) (xy 46.654126 -152.325613) (xy 46.688212 -152.28147) (xy 46.728361 -152.242761)
			(xy 46.773719 -152.21031) (xy 46.823319 -152.184809) (xy 46.876103 -152.166802) (xy 46.930946 -152.156672)
			(xy 46.98668 -152.154635) (xy 47.042117 -152.160735) (xy 47.096074 -152.174841) (xy 47.147403 -152.196653)
			(xy 47.195009 -152.225707) (xy 47.237877 -152.261382) (xy 47.275094 -152.302919) (xy 47.305867 -152.349432)
			(xy 47.329539 -152.399929) (xy 47.345607 -152.453336) (xy 47.353727 -152.508512) (xy 47.354236 -152.536398)
			(xy 47.353727 -152.564284) (xy 47.345607 -152.61946) (xy 47.329539 -152.672867) (xy 47.305867 -152.723364)
			(xy 47.275094 -152.769877) (xy 47.237877 -152.811414) (xy 47.195009 -152.847089) (xy 47.147403 -152.876143)
			(xy 47.096074 -152.897955) (xy 47.042117 -152.912061) (xy 46.98668 -152.918161) (xy 46.930946 -152.916124)
			(xy 46.876103 -152.905994) (xy 46.823319 -152.887987) (xy 46.773719 -152.862486) (xy 46.728361 -152.830035)
			(xy 46.688212 -152.791326) (xy 46.654126 -152.747183) (xy 46.62683 -152.698548) (xy 46.606907 -152.646457)
			(xy 46.594781 -152.59202) (xy 46.59071 -152.536398) (xy 45.982172 -152.536398) (xy 45.982127 -152.538884)
			(xy 45.974007 -152.59406) (xy 45.957939 -152.647467) (xy 45.934267 -152.697964) (xy 45.903494 -152.744477)
			(xy 45.866277 -152.786014) (xy 45.823409 -152.821689) (xy 45.775803 -152.850743) (xy 45.724474 -152.872555)
			(xy 45.670517 -152.886661) (xy 45.61508 -152.892761) (xy 45.559346 -152.890724) (xy 45.504503 -152.880594)
			(xy 45.451719 -152.862587) (xy 45.402119 -152.837086) (xy 45.356761 -152.804635) (xy 45.316612 -152.765926)
			(xy 45.282526 -152.721783) (xy 45.25523 -152.673148) (xy 45.235307 -152.621057) (xy 45.223181 -152.56662)
			(xy 45.21911 -152.510998) (xy 44.433236 -152.510998) (xy 44.432727 -152.538884) (xy 44.424607 -152.59406)
			(xy 44.408539 -152.647467) (xy 44.384867 -152.697964) (xy 44.354094 -152.744477) (xy 44.316877 -152.786014)
			(xy 44.274009 -152.821689) (xy 44.226403 -152.850743) (xy 44.175074 -152.872555) (xy 44.121117 -152.886661)
			(xy 44.06568 -152.892761) (xy 44.009946 -152.890724) (xy 43.955103 -152.880594) (xy 43.902319 -152.862587)
			(xy 43.852719 -152.837086) (xy 43.807361 -152.804635) (xy 43.767212 -152.765926) (xy 43.733126 -152.721783)
			(xy 43.70583 -152.673148) (xy 43.685907 -152.621057) (xy 43.673781 -152.56662) (xy 43.66971 -152.510998)
			(xy 42.502372 -152.510998) (xy 42.502327 -152.513484) (xy 42.494207 -152.56866) (xy 42.478139 -152.622067)
			(xy 42.454467 -152.672564) (xy 42.423694 -152.719077) (xy 42.386477 -152.760614) (xy 42.343609 -152.796289)
			(xy 42.296003 -152.825343) (xy 42.244674 -152.847155) (xy 42.190717 -152.861261) (xy 42.13528 -152.867361)
			(xy 42.079546 -152.865324) (xy 42.024703 -152.855194) (xy 41.971919 -152.837187) (xy 41.922319 -152.811686)
			(xy 41.876961 -152.779235) (xy 41.836812 -152.740526) (xy 41.802726 -152.696383) (xy 41.77543 -152.647748)
			(xy 41.755507 -152.595657) (xy 41.743381 -152.54122) (xy 41.73931 -152.485598) (xy 34.938901 -152.485598)
			(xy 34.904526 -152.520948) (xy 34.860495 -152.554702) (xy 34.812039 -152.581723) (xy 34.760181 -152.601441)
			(xy 34.706014 -152.613441) (xy 34.65068 -152.617469) (xy 34.595346 -152.613441) (xy 34.541179 -152.601441)
			(xy 34.489321 -152.581723) (xy 34.440865 -152.554702) (xy 34.396834 -152.520948) (xy 34.358156 -152.481173)
			(xy 34.325646 -152.436215) (xy 34.29999 -152.387023) (xy 34.281729 -152.334634) (xy 34.271248 -152.280153)
			(xy 34.268768 -152.224728) (xy 34.274342 -152.169528) (xy 34.287851 -152.115718) (xy 34.309011 -152.064431)
			(xy 34.322766 -152.040336) (xy 34.332843 -152.020862) (xy 34.346884 -151.979329) (xy 34.353588 -151.936001)
			(xy 34.352755 -151.892166) (xy 34.34441 -151.849125) (xy 34.328801 -151.808155) (xy 34.30639 -151.770472)
			(xy 34.277844 -151.737196) (xy 34.244009 -151.709313) (xy 34.205891 -151.687653) (xy 34.16462 -151.672857)
			(xy 34.121422 -151.665365) (xy 34.0995 -151.664924) (xy 33.262824 -151.664924) (xy 33.256728 -151.665432)
			(xy 33.238724 -151.66693) (xy 33.202596 -151.66693) (xy 33.184592 -151.665432) (xy 33.178496 -151.664924)
			(xy 24.664416 -151.664924) (xy 23.216641 -153.112699) (xy 37.815207 -153.112699) (xy 37.821977 -153.058341)
			(xy 37.836454 -153.005511) (xy 37.85834 -152.955296) (xy 37.887184 -152.908728) (xy 37.922394 -152.866766)
			(xy 37.963245 -152.830272) (xy 38.008897 -152.799998) (xy 38.058409 -152.776566) (xy 38.110765 -152.760459)
			(xy 38.164887 -152.752007) (xy 38.219661 -152.751385) (xy 38.27396 -152.758605) (xy 38.326669 -152.773519)
			(xy 38.376701 -152.79582) (xy 38.423028 -152.82505) (xy 38.44417 -152.842468) (xy 38.462591 -152.857499)
			(xy 38.503851 -152.881114) (xy 38.54878 -152.896651) (xy 38.595814 -152.903569) (xy 38.643314 -152.901626)
			(xy 38.689625 -152.890891) (xy 38.733135 -152.871737) (xy 38.753034 -152.858724) (xy 38.775908 -152.843651)
			(xy 38.825026 -152.819402) (xy 38.877108 -152.802429) (xy 38.931082 -152.793081) (xy 38.985838 -152.791551)
			(xy 39.04025 -152.79787) (xy 39.093199 -152.811908) (xy 39.143594 -152.833377) (xy 39.1904 -152.861834)
			(xy 39.232653 -152.896695) (xy 39.269484 -152.937242) (xy 39.300136 -152.982641) (xy 39.323978 -153.031957)
			(xy 39.34052 -153.084178) (xy 39.34942 -153.138227) (xy 39.350497 -153.192994) (xy 39.343728 -153.247352)
			(xy 39.329252 -153.300183) (xy 39.307368 -153.350399) (xy 39.278524 -153.396967) (xy 39.243315 -153.438931)
			(xy 39.202465 -153.475425) (xy 39.156814 -153.505701) (xy 39.107302 -153.529134) (xy 39.054946 -153.545243)
			(xy 39.000825 -153.553696) (xy 38.946051 -153.55432) (xy 38.891751 -153.547101) (xy 38.839042 -153.532189)
			(xy 38.789009 -153.509889) (xy 38.742681 -153.480661) (xy 38.721538 -153.463244) (xy 38.703111 -153.44822)
			(xy 38.661853 -153.424603) (xy 38.616925 -153.409065) (xy 38.569892 -153.402146) (xy 38.522393 -153.404088)
			(xy 38.476082 -153.414822) (xy 38.432572 -153.433975) (xy 38.412674 -153.446988) (xy 38.389789 -153.462046)
			(xy 38.340672 -153.486295) (xy 38.28859 -153.503268) (xy 38.234616 -153.512615) (xy 38.17986 -153.514145)
			(xy 38.125448 -153.507825) (xy 38.0725 -153.493787) (xy 38.022105 -153.472318) (xy 37.975299 -153.44386)
			(xy 37.933047 -153.408999) (xy 37.896216 -153.368452) (xy 37.865565 -153.323053) (xy 37.841723 -153.273736)
			(xy 37.825183 -153.221515) (xy 37.816283 -153.167466) (xy 37.815207 -153.112699) (xy 23.216641 -153.112699)
			(xy 22.395942 -153.933398) (xy 41.73931 -153.933398) (xy 41.743381 -153.877776) (xy 41.755507 -153.823339)
			(xy 41.77543 -153.771248) (xy 41.802726 -153.722613) (xy 41.836812 -153.67847) (xy 41.876961 -153.639761)
			(xy 41.922319 -153.60731) (xy 41.971919 -153.581809) (xy 42.024703 -153.563802) (xy 42.079546 -153.553672)
			(xy 42.13528 -153.551635) (xy 42.190717 -153.557735) (xy 42.244674 -153.571841) (xy 42.296003 -153.593653)
			(xy 42.343609 -153.622707) (xy 42.386477 -153.658382) (xy 42.423694 -153.699919) (xy 42.454467 -153.746432)
			(xy 42.478139 -153.796929) (xy 42.494207 -153.850336) (xy 42.502327 -153.905512) (xy 42.502836 -153.933398)
			(xy 42.502327 -153.961284) (xy 42.494207 -154.01646) (xy 42.478139 -154.069867) (xy 42.458764 -154.111198)
			(xy 46.61611 -154.111198) (xy 46.620181 -154.055576) (xy 46.632307 -154.001139) (xy 46.65223 -153.949048)
			(xy 46.679526 -153.900413) (xy 46.713612 -153.85627) (xy 46.753761 -153.817561) (xy 46.799119 -153.78511)
			(xy 46.848719 -153.759609) (xy 46.901503 -153.741602) (xy 46.956346 -153.731472) (xy 47.01208 -153.729435)
			(xy 47.067517 -153.735535) (xy 47.121474 -153.749641) (xy 47.172803 -153.771453) (xy 47.220409 -153.800507)
			(xy 47.263277 -153.836182) (xy 47.300494 -153.877719) (xy 47.331267 -153.924232) (xy 47.354939 -153.974729)
			(xy 47.371007 -154.028136) (xy 47.379127 -154.083312) (xy 47.379636 -154.111198) (xy 47.379127 -154.139084)
			(xy 47.371007 -154.19426) (xy 47.354939 -154.247667) (xy 47.331267 -154.298164) (xy 47.300494 -154.344677)
			(xy 47.263277 -154.386214) (xy 47.220409 -154.421889) (xy 47.172803 -154.450943) (xy 47.121474 -154.472755)
			(xy 47.067517 -154.486861) (xy 47.01208 -154.492961) (xy 46.956346 -154.490924) (xy 46.901503 -154.480794)
			(xy 46.848719 -154.462787) (xy 46.799119 -154.437286) (xy 46.753761 -154.404835) (xy 46.713612 -154.366126)
			(xy 46.679526 -154.321983) (xy 46.65223 -154.273348) (xy 46.632307 -154.221257) (xy 46.620181 -154.16682)
			(xy 46.61611 -154.111198) (xy 42.458764 -154.111198) (xy 42.454467 -154.120364) (xy 42.423694 -154.166877)
			(xy 42.386477 -154.208414) (xy 42.343609 -154.244089) (xy 42.296003 -154.273143) (xy 42.244674 -154.294955)
			(xy 42.190717 -154.309061) (xy 42.13528 -154.315161) (xy 42.079546 -154.313124) (xy 42.024703 -154.302994)
			(xy 41.971919 -154.284987) (xy 41.922319 -154.259486) (xy 41.876961 -154.227035) (xy 41.836812 -154.188326)
			(xy 41.802726 -154.144183) (xy 41.77543 -154.095548) (xy 41.755507 -154.043457) (xy 41.743381 -153.98902)
			(xy 41.73931 -153.933398) (xy 22.395942 -153.933398) (xy 21.99386 -154.33548) (xy 21.99386 -155.42006)
			(xy 27.466542 -155.42006) (xy 27.470613 -155.364438) (xy 27.482739 -155.310001) (xy 27.502662 -155.25791)
			(xy 27.529958 -155.209275) (xy 27.564044 -155.165132) (xy 27.604193 -155.126423) (xy 27.649551 -155.093972)
			(xy 27.699151 -155.068471) (xy 27.751935 -155.050464) (xy 27.806778 -155.040334) (xy 27.862512 -155.038297)
			(xy 27.917949 -155.044397) (xy 27.971906 -155.058503) (xy 28.023235 -155.080315) (xy 28.070841 -155.109369)
			(xy 28.113709 -155.145044) (xy 28.150926 -155.186581) (xy 28.181699 -155.233094) (xy 28.205371 -155.283591)
			(xy 28.221439 -155.336998) (xy 28.229559 -155.392174) (xy 28.230068 -155.42006) (xy 28.229559 -155.447946)
			(xy 28.221439 -155.503122) (xy 28.205371 -155.556529) (xy 28.181699 -155.607026) (xy 28.150926 -155.653539)
			(xy 28.113709 -155.695076) (xy 28.070841 -155.730751) (xy 28.060933 -155.736798) (xy 41.73931 -155.736798)
			(xy 41.743381 -155.681176) (xy 41.755507 -155.626739) (xy 41.77543 -155.574648) (xy 41.802726 -155.526013)
			(xy 41.836812 -155.48187) (xy 41.876961 -155.443161) (xy 41.922319 -155.41071) (xy 41.971919 -155.385209)
			(xy 42.024703 -155.367202) (xy 42.079546 -155.357072) (xy 42.13528 -155.355035) (xy 42.190717 -155.361135)
			(xy 42.244674 -155.375241) (xy 42.296003 -155.397053) (xy 42.343609 -155.426107) (xy 42.386477 -155.461782)
			(xy 42.423694 -155.503319) (xy 42.454467 -155.549832) (xy 42.478139 -155.600329) (xy 42.494207 -155.653736)
			(xy 42.498955 -155.685998) (xy 46.61611 -155.685998) (xy 46.620181 -155.630376) (xy 46.632307 -155.575939)
			(xy 46.65223 -155.523848) (xy 46.679526 -155.475213) (xy 46.713612 -155.43107) (xy 46.753761 -155.392361)
			(xy 46.799119 -155.35991) (xy 46.848719 -155.334409) (xy 46.901503 -155.316402) (xy 46.956346 -155.306272)
			(xy 47.01208 -155.304235) (xy 47.067517 -155.310335) (xy 47.121474 -155.324441) (xy 47.172803 -155.346253)
			(xy 47.220409 -155.375307) (xy 47.263277 -155.410982) (xy 47.300494 -155.452519) (xy 47.331267 -155.499032)
			(xy 47.354939 -155.549529) (xy 47.371007 -155.602936) (xy 47.379127 -155.658112) (xy 47.379636 -155.685998)
			(xy 47.379127 -155.713884) (xy 47.371007 -155.76906) (xy 47.354939 -155.822467) (xy 47.331267 -155.872964)
			(xy 47.300494 -155.919477) (xy 47.263277 -155.961014) (xy 47.220409 -155.996689) (xy 47.172803 -156.025743)
			(xy 47.121474 -156.047555) (xy 47.067517 -156.061661) (xy 47.01208 -156.067761) (xy 46.956346 -156.065724)
			(xy 46.901503 -156.055594) (xy 46.848719 -156.037587) (xy 46.799119 -156.012086) (xy 46.753761 -155.979635)
			(xy 46.713612 -155.940926) (xy 46.679526 -155.896783) (xy 46.65223 -155.848148) (xy 46.632307 -155.796057)
			(xy 46.620181 -155.74162) (xy 46.61611 -155.685998) (xy 42.498955 -155.685998) (xy 42.502327 -155.708912)
			(xy 42.502836 -155.736798) (xy 42.502327 -155.764684) (xy 42.494207 -155.81986) (xy 42.478139 -155.873267)
			(xy 42.454467 -155.923764) (xy 42.423694 -155.970277) (xy 42.386477 -156.011814) (xy 42.343609 -156.047489)
			(xy 42.296003 -156.076543) (xy 42.244674 -156.098355) (xy 42.190717 -156.112461) (xy 42.13528 -156.118561)
			(xy 42.079546 -156.116524) (xy 42.024703 -156.106394) (xy 41.971919 -156.088387) (xy 41.922319 -156.062886)
			(xy 41.876961 -156.030435) (xy 41.836812 -155.991726) (xy 41.802726 -155.947583) (xy 41.77543 -155.898948)
			(xy 41.755507 -155.846857) (xy 41.743381 -155.79242) (xy 41.73931 -155.736798) (xy 28.060933 -155.736798)
			(xy 28.023235 -155.759805) (xy 27.971906 -155.781617) (xy 27.917949 -155.795723) (xy 27.862512 -155.801823)
			(xy 27.806778 -155.799786) (xy 27.751935 -155.789656) (xy 27.699151 -155.771649) (xy 27.649551 -155.746148)
			(xy 27.604193 -155.713697) (xy 27.564044 -155.674988) (xy 27.529958 -155.630845) (xy 27.502662 -155.58221)
			(xy 27.482739 -155.530119) (xy 27.470613 -155.475682) (xy 27.466542 -155.42006) (xy 21.99386 -155.42006)
			(xy 21.99386 -156.647896) (xy 27.430982 -156.647896) (xy 27.435053 -156.592274) (xy 27.447179 -156.537837)
			(xy 27.467102 -156.485746) (xy 27.494398 -156.437111) (xy 27.528484 -156.392968) (xy 27.568633 -156.354259)
			(xy 27.613991 -156.321808) (xy 27.663591 -156.296307) (xy 27.716375 -156.2783) (xy 27.771218 -156.26817)
			(xy 27.826952 -156.266133) (xy 27.882389 -156.272233) (xy 27.936346 -156.286339) (xy 27.987675 -156.308151)
			(xy 28.007893 -156.32049) (xy 49.714402 -156.32049) (xy 49.718473 -156.264868) (xy 49.730599 -156.210431)
			(xy 49.750522 -156.15834) (xy 49.777818 -156.109705) (xy 49.811904 -156.065562) (xy 49.852053 -156.026853)
			(xy 49.897411 -155.994402) (xy 49.947011 -155.968901) (xy 49.999795 -155.950894) (xy 50.054638 -155.940764)
			(xy 50.110372 -155.938727) (xy 50.165809 -155.944827) (xy 50.219766 -155.958933) (xy 50.271095 -155.980745)
			(xy 50.318701 -156.009799) (xy 50.361569 -156.045474) (xy 50.398786 -156.087011) (xy 50.429559 -156.133524)
			(xy 50.453231 -156.184021) (xy 50.469299 -156.237428) (xy 50.477419 -156.292604) (xy 50.477928 -156.32049)
			(xy 50.477419 -156.348376) (xy 50.469299 -156.403552) (xy 50.453231 -156.456959) (xy 50.429559 -156.507456)
			(xy 50.398786 -156.553969) (xy 50.361569 -156.595506) (xy 50.318701 -156.631181) (xy 50.271095 -156.660235)
			(xy 50.219766 -156.682047) (xy 50.165809 -156.696153) (xy 50.110372 -156.702253) (xy 50.054638 -156.700216)
			(xy 49.999795 -156.690086) (xy 49.947011 -156.672079) (xy 49.897411 -156.646578) (xy 49.852053 -156.614127)
			(xy 49.811904 -156.575418) (xy 49.777818 -156.531275) (xy 49.750522 -156.48264) (xy 49.730599 -156.430549)
			(xy 49.718473 -156.376112) (xy 49.714402 -156.32049) (xy 28.007893 -156.32049) (xy 28.035281 -156.337205)
			(xy 28.078149 -156.37288) (xy 28.115366 -156.414417) (xy 28.146139 -156.46093) (xy 28.169811 -156.511427)
			(xy 28.185879 -156.564834) (xy 28.193999 -156.62001) (xy 28.194508 -156.647896) (xy 28.193999 -156.675782)
			(xy 28.185879 -156.730958) (xy 28.169811 -156.784365) (xy 28.146139 -156.834862) (xy 28.115366 -156.881375)
			(xy 28.078149 -156.922912) (xy 28.035281 -156.958587) (xy 27.987675 -156.987641) (xy 27.936346 -157.009453)
			(xy 27.882389 -157.023559) (xy 27.826952 -157.029659) (xy 27.771218 -157.027622) (xy 27.716375 -157.017492)
			(xy 27.663591 -156.999485) (xy 27.613991 -156.973984) (xy 27.568633 -156.941533) (xy 27.528484 -156.902824)
			(xy 27.494398 -156.858681) (xy 27.467102 -156.810046) (xy 27.447179 -156.757955) (xy 27.435053 -156.703518)
			(xy 27.430982 -156.647896) (xy 21.99386 -156.647896) (xy 21.99386 -157.336998) (xy 41.73931 -157.336998)
			(xy 41.743381 -157.281376) (xy 41.755507 -157.226939) (xy 41.77543 -157.174848) (xy 41.802726 -157.126213)
			(xy 41.836812 -157.08207) (xy 41.876961 -157.043361) (xy 41.922319 -157.01091) (xy 41.971919 -156.985409)
			(xy 42.024703 -156.967402) (xy 42.079546 -156.957272) (xy 42.13528 -156.955235) (xy 42.190717 -156.961335)
			(xy 42.244674 -156.975441) (xy 42.296003 -156.997253) (xy 42.343609 -157.026307) (xy 42.386477 -157.061982)
			(xy 42.423694 -157.103519) (xy 42.454467 -157.150032) (xy 42.478139 -157.200529) (xy 42.494207 -157.253936)
			(xy 42.502327 -157.309112) (xy 42.502836 -157.336998) (xy 42.502372 -157.362398) (xy 43.44111 -157.362398)
			(xy 43.445181 -157.306776) (xy 43.457307 -157.252339) (xy 43.47723 -157.200248) (xy 43.504526 -157.151613)
			(xy 43.538612 -157.10747) (xy 43.578761 -157.068761) (xy 43.624119 -157.03631) (xy 43.673719 -157.010809)
			(xy 43.726503 -156.992802) (xy 43.781346 -156.982672) (xy 43.83708 -156.980635) (xy 43.892517 -156.986735)
			(xy 43.946474 -157.000841) (xy 43.997803 -157.022653) (xy 44.045409 -157.051707) (xy 44.088277 -157.087382)
			(xy 44.125494 -157.128919) (xy 44.156267 -157.175432) (xy 44.179939 -157.225929) (xy 44.196007 -157.279336)
			(xy 44.204127 -157.334512) (xy 44.204172 -157.336998) (xy 44.99051 -157.336998) (xy 44.994581 -157.281376)
			(xy 45.006707 -157.226939) (xy 45.02663 -157.174848) (xy 45.053926 -157.126213) (xy 45.088012 -157.08207)
			(xy 45.128161 -157.043361) (xy 45.173519 -157.01091) (xy 45.223119 -156.985409) (xy 45.275903 -156.967402)
			(xy 45.330746 -156.957272) (xy 45.38648 -156.955235) (xy 45.441917 -156.961335) (xy 45.495874 -156.975441)
			(xy 45.547203 -156.997253) (xy 45.594809 -157.026307) (xy 45.637677 -157.061982) (xy 45.674894 -157.103519)
			(xy 45.705667 -157.150032) (xy 45.729339 -157.200529) (xy 45.745407 -157.253936) (xy 45.753527 -157.309112)
			(xy 45.754036 -157.336998) (xy 46.59071 -157.336998) (xy 46.594781 -157.281376) (xy 46.606907 -157.226939)
			(xy 46.62683 -157.174848) (xy 46.654126 -157.126213) (xy 46.688212 -157.08207) (xy 46.728361 -157.043361)
			(xy 46.773719 -157.01091) (xy 46.823319 -156.985409) (xy 46.876103 -156.967402) (xy 46.930946 -156.957272)
			(xy 46.98668 -156.955235) (xy 47.042117 -156.961335) (xy 47.096074 -156.975441) (xy 47.147403 -156.997253)
			(xy 47.195009 -157.026307) (xy 47.237877 -157.061982) (xy 47.275094 -157.103519) (xy 47.305867 -157.150032)
			(xy 47.328739 -157.198822) (xy 50.363626 -157.198822) (xy 50.367697 -157.1432) (xy 50.379823 -157.088763)
			(xy 50.399746 -157.036672) (xy 50.427042 -156.988037) (xy 50.461128 -156.943894) (xy 50.501277 -156.905185)
			(xy 50.546635 -156.872734) (xy 50.596235 -156.847233) (xy 50.649019 -156.829226) (xy 50.703862 -156.819096)
			(xy 50.759596 -156.817059) (xy 50.815033 -156.823159) (xy 50.86899 -156.837265) (xy 50.920319 -156.859077)
			(xy 50.967925 -156.888131) (xy 51.010793 -156.923806) (xy 51.04801 -156.965343) (xy 51.078783 -157.011856)
			(xy 51.102455 -157.062353) (xy 51.118523 -157.11576) (xy 51.126643 -157.170936) (xy 51.127152 -157.198822)
			(xy 51.126643 -157.226708) (xy 51.118523 -157.281884) (xy 51.102455 -157.335291) (xy 51.078783 -157.385788)
			(xy 51.04801 -157.432301) (xy 51.010793 -157.473838) (xy 50.967925 -157.509513) (xy 50.920319 -157.538567)
			(xy 50.86899 -157.560379) (xy 50.815033 -157.574485) (xy 50.759596 -157.580585) (xy 50.703862 -157.578548)
			(xy 50.649019 -157.568418) (xy 50.596235 -157.550411) (xy 50.546635 -157.52491) (xy 50.501277 -157.492459)
			(xy 50.461128 -157.45375) (xy 50.427042 -157.409607) (xy 50.399746 -157.360972) (xy 50.379823 -157.308881)
			(xy 50.367697 -157.254444) (xy 50.363626 -157.198822) (xy 47.328739 -157.198822) (xy 47.329539 -157.200529)
			(xy 47.345607 -157.253936) (xy 47.353727 -157.309112) (xy 47.354236 -157.336998) (xy 47.353727 -157.364884)
			(xy 47.345607 -157.42006) (xy 47.329539 -157.473467) (xy 47.305867 -157.523964) (xy 47.275094 -157.570477)
			(xy 47.237877 -157.612014) (xy 47.195009 -157.647689) (xy 47.147403 -157.676743) (xy 47.096074 -157.698555)
			(xy 47.042117 -157.712661) (xy 46.98668 -157.718761) (xy 46.930946 -157.716724) (xy 46.876103 -157.706594)
			(xy 46.823319 -157.688587) (xy 46.773719 -157.663086) (xy 46.728361 -157.630635) (xy 46.688212 -157.591926)
			(xy 46.654126 -157.547783) (xy 46.62683 -157.499148) (xy 46.606907 -157.447057) (xy 46.594781 -157.39262)
			(xy 46.59071 -157.336998) (xy 45.754036 -157.336998) (xy 45.753527 -157.364884) (xy 45.745407 -157.42006)
			(xy 45.729339 -157.473467) (xy 45.705667 -157.523964) (xy 45.674894 -157.570477) (xy 45.637677 -157.612014)
			(xy 45.594809 -157.647689) (xy 45.547203 -157.676743) (xy 45.495874 -157.698555) (xy 45.441917 -157.712661)
			(xy 45.38648 -157.718761) (xy 45.330746 -157.716724) (xy 45.275903 -157.706594) (xy 45.223119 -157.688587)
			(xy 45.173519 -157.663086) (xy 45.128161 -157.630635) (xy 45.088012 -157.591926) (xy 45.053926 -157.547783)
			(xy 45.02663 -157.499148) (xy 45.006707 -157.447057) (xy 44.994581 -157.39262) (xy 44.99051 -157.336998)
			(xy 44.204172 -157.336998) (xy 44.204636 -157.362398) (xy 44.204127 -157.390284) (xy 44.196007 -157.44546)
			(xy 44.179939 -157.498867) (xy 44.156267 -157.549364) (xy 44.125494 -157.595877) (xy 44.088277 -157.637414)
			(xy 44.045409 -157.673089) (xy 43.997803 -157.702143) (xy 43.946474 -157.723955) (xy 43.892517 -157.738061)
			(xy 43.83708 -157.744161) (xy 43.781346 -157.742124) (xy 43.726503 -157.731994) (xy 43.673719 -157.713987)
			(xy 43.624119 -157.688486) (xy 43.578761 -157.656035) (xy 43.538612 -157.617326) (xy 43.504526 -157.573183)
			(xy 43.47723 -157.524548) (xy 43.457307 -157.472457) (xy 43.445181 -157.41802) (xy 43.44111 -157.362398)
			(xy 42.502372 -157.362398) (xy 42.502327 -157.364884) (xy 42.494207 -157.42006) (xy 42.478139 -157.473467)
			(xy 42.454467 -157.523964) (xy 42.423694 -157.570477) (xy 42.386477 -157.612014) (xy 42.343609 -157.647689)
			(xy 42.296003 -157.676743) (xy 42.244674 -157.698555) (xy 42.190717 -157.712661) (xy 42.13528 -157.718761)
			(xy 42.079546 -157.716724) (xy 42.024703 -157.706594) (xy 41.971919 -157.688587) (xy 41.922319 -157.663086)
			(xy 41.876961 -157.630635) (xy 41.836812 -157.591926) (xy 41.802726 -157.547783) (xy 41.77543 -157.499148)
			(xy 41.755507 -157.447057) (xy 41.743381 -157.39262) (xy 41.73931 -157.336998) (xy 21.99386 -157.336998)
			(xy 21.99386 -157.84195) (xy 27.408122 -157.84195) (xy 27.412193 -157.786328) (xy 27.424319 -157.731891)
			(xy 27.444242 -157.6798) (xy 27.471538 -157.631165) (xy 27.505624 -157.587022) (xy 27.545773 -157.548313)
			(xy 27.591131 -157.515862) (xy 27.640731 -157.490361) (xy 27.693515 -157.472354) (xy 27.748358 -157.462224)
			(xy 27.804092 -157.460187) (xy 27.859529 -157.466287) (xy 27.913486 -157.480393) (xy 27.964815 -157.502205)
			(xy 28.012421 -157.531259) (xy 28.055289 -157.566934) (xy 28.092506 -157.608471) (xy 28.123279 -157.654984)
			(xy 28.146951 -157.705481) (xy 28.163019 -157.758888) (xy 28.171139 -157.814064) (xy 28.171648 -157.84195)
			(xy 28.171139 -157.869836) (xy 28.163019 -157.925012) (xy 28.146951 -157.978419) (xy 28.123279 -158.028916)
			(xy 28.092506 -158.075429) (xy 28.055289 -158.116966) (xy 28.012421 -158.152641) (xy 27.964815 -158.181695)
			(xy 27.913486 -158.203507) (xy 27.859529 -158.217613) (xy 27.804092 -158.223713) (xy 27.748358 -158.221676)
			(xy 27.693515 -158.211546) (xy 27.640731 -158.193539) (xy 27.591131 -158.168038) (xy 27.545773 -158.135587)
			(xy 27.505624 -158.096878) (xy 27.471538 -158.052735) (xy 27.444242 -158.0041) (xy 27.424319 -157.952009)
			(xy 27.412193 -157.897572) (xy 27.408122 -157.84195) (xy 21.99386 -157.84195) (xy 21.99386 -160.082543)
			(xy 36.638669 -160.082543) (xy 36.642913 -160.027687) (xy 36.654995 -159.97401) (xy 36.674663 -159.922626)
			(xy 36.701511 -159.874601) (xy 36.73498 -159.830932) (xy 36.774377 -159.792525) (xy 36.818883 -159.760177)
			(xy 36.867575 -159.734559) (xy 36.919442 -159.716203) (xy 36.946332 -159.710374) (xy 36.969137 -159.705215)
			(xy 37.012537 -159.687843) (xy 37.05203 -159.662831) (xy 37.086285 -159.631021) (xy 37.114149 -159.593486)
			(xy 37.134683 -159.55149) (xy 37.147194 -159.506448) (xy 37.151261 -159.459878) (xy 37.149532 -159.436562)
			(xy 37.147398 -159.40913) (xy 37.149976 -159.354172) (xy 37.160424 -159.300154) (xy 37.178525 -159.248198)
			(xy 37.203903 -159.199382) (xy 37.236032 -159.154719) (xy 37.274245 -159.115135) (xy 37.317749 -159.081453)
			(xy 37.365641 -159.054372) (xy 37.416927 -159.034452) (xy 37.470544 -159.022108) (xy 37.525377 -159.017596)
			(xy 37.58029 -159.02101) (xy 37.634142 -159.032278) (xy 37.65059 -159.03829) (xy 49.689002 -159.03829)
			(xy 49.693073 -158.982668) (xy 49.705199 -158.928231) (xy 49.725122 -158.87614) (xy 49.752418 -158.827505)
			(xy 49.786504 -158.783362) (xy 49.826653 -158.744653) (xy 49.872011 -158.712202) (xy 49.921611 -158.686701)
			(xy 49.974395 -158.668694) (xy 50.029238 -158.658564) (xy 50.084972 -158.656527) (xy 50.140409 -158.662627)
			(xy 50.194366 -158.676733) (xy 50.245695 -158.698545) (xy 50.293301 -158.727599) (xy 50.336169 -158.763274)
			(xy 50.373386 -158.804811) (xy 50.404159 -158.851324) (xy 50.427831 -158.901821) (xy 50.443899 -158.955228)
			(xy 50.452019 -159.010404) (xy 50.452528 -159.03829) (xy 50.452019 -159.066176) (xy 50.443899 -159.121352)
			(xy 50.427831 -159.174759) (xy 50.404159 -159.225256) (xy 50.373386 -159.271769) (xy 50.336169 -159.313306)
			(xy 50.293301 -159.348981) (xy 50.245695 -159.378035) (xy 50.194366 -159.399847) (xy 50.140409 -159.413953)
			(xy 50.084972 -159.420053) (xy 50.029238 -159.418016) (xy 49.974395 -159.407886) (xy 49.921611 -159.389879)
			(xy 49.872011 -159.364378) (xy 49.826653 -159.331927) (xy 49.786504 -159.293218) (xy 49.752418 -159.249075)
			(xy 49.725122 -159.20044) (xy 49.705199 -159.148349) (xy 49.693073 -159.093912) (xy 49.689002 -159.03829)
			(xy 37.65059 -159.03829) (xy 37.685817 -159.051166) (xy 37.734242 -159.077284) (xy 37.778411 -159.110089)
			(xy 37.817409 -159.148899) (xy 37.850425 -159.19291) (xy 37.876776 -159.241208) (xy 37.895913 -159.292792)
			(xy 37.90744 -159.346589) (xy 37.911118 -159.401485) (xy 37.90687 -159.45634) (xy 37.894784 -159.510015)
			(xy 37.875112 -159.561396) (xy 37.848261 -159.609418) (xy 37.814788 -159.653083) (xy 37.775389 -159.691486)
			(xy 37.730881 -159.72383) (xy 37.682188 -159.749443) (xy 37.63032 -159.767793) (xy 37.60343 -159.77362)
			(xy 37.58062 -159.778759) (xy 37.558565 -159.78759) (xy 50.514502 -159.78759) (xy 50.518573 -159.731968)
			(xy 50.530699 -159.677531) (xy 50.550622 -159.62544) (xy 50.577918 -159.576805) (xy 50.612004 -159.532662)
			(xy 50.652153 -159.493953) (xy 50.697511 -159.461502) (xy 50.747111 -159.436001) (xy 50.799895 -159.417994)
			(xy 50.854738 -159.407864) (xy 50.910472 -159.405827) (xy 50.965909 -159.411927) (xy 51.019866 -159.426033)
			(xy 51.071195 -159.447845) (xy 51.118801 -159.476899) (xy 51.161669 -159.512574) (xy 51.198886 -159.554111)
			(xy 51.229659 -159.600624) (xy 51.253331 -159.651121) (xy 51.269399 -159.704528) (xy 51.277519 -159.759704)
			(xy 51.278028 -159.78759) (xy 51.277519 -159.815476) (xy 51.269399 -159.870652) (xy 51.253331 -159.924059)
			(xy 51.229659 -159.974556) (xy 51.198886 -160.021069) (xy 51.161669 -160.062606) (xy 51.118801 -160.098281)
			(xy 51.071195 -160.127335) (xy 51.019866 -160.149147) (xy 50.965909 -160.163253) (xy 50.910472 -160.169353)
			(xy 50.854738 -160.167316) (xy 50.799895 -160.157186) (xy 50.747111 -160.139179) (xy 50.697511 -160.113678)
			(xy 50.652153 -160.081227) (xy 50.612004 -160.042518) (xy 50.577918 -159.998375) (xy 50.550622 -159.94974)
			(xy 50.530699 -159.897649) (xy 50.518573 -159.843212) (xy 50.514502 -159.78759) (xy 37.558565 -159.78759)
			(xy 37.537222 -159.796136) (xy 37.49773 -159.821153) (xy 37.463476 -159.852966) (xy 37.435613 -159.890504)
			(xy 37.415081 -159.932501) (xy 37.40257 -159.977545) (xy 37.398502 -160.024116) (xy 37.40023 -160.047432)
			(xy 37.402415 -160.074859) (xy 37.399838 -160.129819) (xy 37.389392 -160.183838) (xy 37.371292 -160.235796)
			(xy 37.345915 -160.284614) (xy 37.313787 -160.329279) (xy 37.275575 -160.368864) (xy 37.232072 -160.402549)
			(xy 37.18418 -160.429633) (xy 37.132893 -160.449556) (xy 37.079277 -160.461902) (xy 37.024442 -160.466417)
			(xy 36.969528 -160.463006) (xy 36.915674 -160.451741) (xy 36.863997 -160.432855) (xy 36.81557 -160.406739)
			(xy 36.771398 -160.373937) (xy 36.732397 -160.335128) (xy 36.699377 -160.291118) (xy 36.673023 -160.242821)
			(xy 36.653882 -160.191238) (xy 36.64235 -160.13744) (xy 36.638669 -160.082543) (xy 21.99386 -160.082543)
			(xy 21.99386 -160.524444) (xy 43.935648 -160.524444) (xy 43.939719 -160.468822) (xy 43.951845 -160.414385)
			(xy 43.971768 -160.362294) (xy 43.999064 -160.313659) (xy 44.03315 -160.269516) (xy 44.073299 -160.230807)
			(xy 44.118657 -160.198356) (xy 44.168257 -160.172855) (xy 44.221041 -160.154848) (xy 44.275884 -160.144718)
			(xy 44.331618 -160.142681) (xy 44.387055 -160.148781) (xy 44.441012 -160.162887) (xy 44.492341 -160.184699)
			(xy 44.539947 -160.213753) (xy 44.582815 -160.249428) (xy 44.620032 -160.290965) (xy 44.650805 -160.337478)
			(xy 44.674477 -160.387975) (xy 44.688924 -160.435995) (xy 45.935791 -160.435995) (xy 45.938954 -160.3799)
			(xy 45.95031 -160.324876) (xy 45.969613 -160.272111) (xy 45.996445 -160.222748) (xy 46.030226 -160.177854)
			(xy 46.070226 -160.1384) (xy 46.11558 -160.105238) (xy 46.165306 -160.079086) (xy 46.218331 -160.06051)
			(xy 46.273506 -160.049911) (xy 46.329639 -160.047518) (xy 46.385516 -160.053383) (xy 46.439929 -160.06738)
			(xy 46.491701 -160.089205) (xy 46.539712 -160.118387) (xy 46.582925 -160.154295) (xy 46.620404 -160.196151)
			(xy 46.651339 -160.243052) (xy 46.675062 -160.293982) (xy 46.691059 -160.347841) (xy 46.698984 -160.403463)
			(xy 46.698666 -160.459646) (xy 46.690113 -160.515176) (xy 46.673508 -160.56885) (xy 46.664472 -160.58769)
			(xy 48.419002 -160.58769) (xy 48.423073 -160.532068) (xy 48.435199 -160.477631) (xy 48.455122 -160.42554)
			(xy 48.482418 -160.376905) (xy 48.516504 -160.332762) (xy 48.556653 -160.294053) (xy 48.602011 -160.261602)
			(xy 48.651611 -160.236101) (xy 48.704395 -160.218094) (xy 48.759238 -160.207964) (xy 48.814972 -160.205927)
			(xy 48.870409 -160.212027) (xy 48.924366 -160.226133) (xy 48.975695 -160.247945) (xy 49.023301 -160.276999)
			(xy 49.066169 -160.312674) (xy 49.103386 -160.354211) (xy 49.134159 -160.400724) (xy 49.157831 -160.451221)
			(xy 49.173899 -160.504628) (xy 49.182019 -160.559804) (xy 49.182528 -160.58769) (xy 49.182019 -160.615576)
			(xy 49.173899 -160.670752) (xy 49.157831 -160.724159) (xy 49.134159 -160.774656) (xy 49.103386 -160.821169)
			(xy 49.066169 -160.862706) (xy 49.023301 -160.898381) (xy 48.975695 -160.927435) (xy 48.924366 -160.949247)
			(xy 48.870409 -160.963353) (xy 48.814972 -160.969453) (xy 48.759238 -160.967416) (xy 48.704395 -160.957286)
			(xy 48.651611 -160.939279) (xy 48.602011 -160.913778) (xy 48.556653 -160.881327) (xy 48.516504 -160.842618)
			(xy 48.482418 -160.798475) (xy 48.455122 -160.74984) (xy 48.435199 -160.697749) (xy 48.423073 -160.643312)
			(xy 48.419002 -160.58769) (xy 46.664472 -160.58769) (xy 46.64921 -160.619509) (xy 46.633892 -160.643062)
			(xy 46.621392 -160.662519) (xy 46.602826 -160.704868) (xy 46.592234 -160.749878) (xy 46.589965 -160.796062)
			(xy 46.596094 -160.841894) (xy 46.61042 -160.885858) (xy 46.632468 -160.926503) (xy 46.646592 -160.944814)
			(xy 46.663835 -160.966996) (xy 46.692351 -161.015402) (xy 46.713461 -161.067467) (xy 46.726707 -161.122064)
			(xy 46.731802 -161.178014) (xy 46.728638 -161.234106) (xy 46.717282 -161.289128) (xy 46.69798 -161.341889)
			(xy 46.671149 -161.391249) (xy 46.63737 -161.436141) (xy 46.597372 -161.475594) (xy 46.552021 -161.508754)
			(xy 46.502297 -161.534905) (xy 46.449276 -161.553482) (xy 46.394104 -161.564082) (xy 46.337974 -161.566476)
			(xy 46.282099 -161.560613) (xy 46.227689 -161.546619) (xy 46.175918 -161.524798) (xy 46.127908 -161.49562)
			(xy 46.084696 -161.459717) (xy 46.047216 -161.417865) (xy 46.016279 -161.370968) (xy 45.992554 -161.320043)
			(xy 45.976554 -161.266188) (xy 45.968624 -161.210569) (xy 45.968937 -161.154389) (xy 45.977485 -161.098862)
			(xy 45.994084 -161.045188) (xy 46.018375 -160.99453) (xy 46.03369 -160.970976) (xy 46.04625 -160.951555)
			(xy 46.064812 -160.909197) (xy 46.075398 -160.864178) (xy 46.077658 -160.817986) (xy 46.071518 -160.772149)
			(xy 46.057181 -160.72818) (xy 46.035121 -160.687534) (xy 46.02099 -160.669224) (xy 46.00377 -160.647022)
			(xy 45.97525 -160.598614) (xy 45.954137 -160.546548) (xy 45.940889 -160.491948) (xy 45.935791 -160.435995)
			(xy 44.688924 -160.435995) (xy 44.690545 -160.441382) (xy 44.698665 -160.496558) (xy 44.699174 -160.524444)
			(xy 44.698665 -160.55233) (xy 44.690545 -160.607506) (xy 44.674477 -160.660913) (xy 44.650805 -160.71141)
			(xy 44.620032 -160.757923) (xy 44.582815 -160.79946) (xy 44.539947 -160.835135) (xy 44.492341 -160.864189)
			(xy 44.441012 -160.886001) (xy 44.387055 -160.900107) (xy 44.331618 -160.906207) (xy 44.275884 -160.90417)
			(xy 44.221041 -160.89404) (xy 44.168257 -160.876033) (xy 44.118657 -160.850532) (xy 44.073299 -160.818081)
			(xy 44.03315 -160.779372) (xy 43.999064 -160.735229) (xy 43.971768 -160.686594) (xy 43.951845 -160.634503)
			(xy 43.939719 -160.580066) (xy 43.935648 -160.524444) (xy 21.99386 -160.524444) (xy 21.99386 -160.96869)
			(xy 39.740584 -160.96869) (xy 39.744655 -160.913068) (xy 39.756781 -160.858631) (xy 39.776704 -160.80654)
			(xy 39.804 -160.757905) (xy 39.838086 -160.713762) (xy 39.878235 -160.675053) (xy 39.923593 -160.642602)
			(xy 39.973193 -160.617101) (xy 40.025977 -160.599094) (xy 40.08082 -160.588964) (xy 40.136554 -160.586927)
			(xy 40.191991 -160.593027) (xy 40.245948 -160.607133) (xy 40.297277 -160.628945) (xy 40.344883 -160.657999)
			(xy 40.387751 -160.693674) (xy 40.424968 -160.735211) (xy 40.455741 -160.781724) (xy 40.479413 -160.832221)
			(xy 40.495481 -160.885628) (xy 40.503601 -160.940804) (xy 40.50411 -160.96869) (xy 40.503601 -160.996576)
			(xy 40.495481 -161.051752) (xy 40.479413 -161.105159) (xy 40.455741 -161.155656) (xy 40.424968 -161.202169)
			(xy 40.387751 -161.243706) (xy 40.344883 -161.279381) (xy 40.297277 -161.308435) (xy 40.245948 -161.330247)
			(xy 40.191991 -161.344353) (xy 40.136554 -161.350453) (xy 40.08082 -161.348416) (xy 40.025977 -161.338286)
			(xy 39.973193 -161.320279) (xy 39.923593 -161.294778) (xy 39.878235 -161.262327) (xy 39.838086 -161.223618)
			(xy 39.804 -161.179475) (xy 39.776704 -161.13084) (xy 39.756781 -161.078749) (xy 39.744655 -161.024312)
			(xy 39.740584 -160.96869) (xy 21.99386 -160.96869) (xy 21.99386 -161.65449) (xy 40.900602 -161.65449)
			(xy 40.904673 -161.598868) (xy 40.916799 -161.544431) (xy 40.936722 -161.49234) (xy 40.964018 -161.443705)
			(xy 40.998104 -161.399562) (xy 41.038253 -161.360853) (xy 41.083611 -161.328402) (xy 41.133211 -161.302901)
			(xy 41.185995 -161.284894) (xy 41.240838 -161.274764) (xy 41.296572 -161.272727) (xy 41.352009 -161.278827)
			(xy 41.405966 -161.292933) (xy 41.457295 -161.314745) (xy 41.504901 -161.343799) (xy 41.54067 -161.373566)
			(xy 42.780202 -161.373566) (xy 42.784273 -161.317944) (xy 42.796399 -161.263507) (xy 42.816322 -161.211416)
			(xy 42.843618 -161.162781) (xy 42.877704 -161.118638) (xy 42.917853 -161.079929) (xy 42.963211 -161.047478)
			(xy 43.012811 -161.021977) (xy 43.065595 -161.00397) (xy 43.120438 -160.99384) (xy 43.176172 -160.991803)
			(xy 43.231609 -160.997903) (xy 43.285566 -161.012009) (xy 43.336895 -161.033821) (xy 43.384501 -161.062875)
			(xy 43.427369 -161.09855) (xy 43.464586 -161.140087) (xy 43.495359 -161.1866) (xy 43.519031 -161.237097)
			(xy 43.535099 -161.290504) (xy 43.543219 -161.34568) (xy 43.543728 -161.373566) (xy 43.543219 -161.401452)
			(xy 43.535099 -161.456628) (xy 43.519031 -161.510035) (xy 43.495359 -161.560532) (xy 43.464586 -161.607045)
			(xy 43.427369 -161.648582) (xy 43.384501 -161.684257) (xy 43.336895 -161.713311) (xy 43.285566 -161.735123)
			(xy 43.231609 -161.749229) (xy 43.176172 -161.755329) (xy 43.120438 -161.753292) (xy 43.065595 -161.743162)
			(xy 43.012811 -161.725155) (xy 42.963211 -161.699654) (xy 42.917853 -161.667203) (xy 42.877704 -161.628494)
			(xy 42.843618 -161.584351) (xy 42.816322 -161.535716) (xy 42.796399 -161.483625) (xy 42.784273 -161.429188)
			(xy 42.780202 -161.373566) (xy 41.54067 -161.373566) (xy 41.547769 -161.379474) (xy 41.584986 -161.421011)
			(xy 41.615759 -161.467524) (xy 41.639431 -161.518021) (xy 41.655499 -161.571428) (xy 41.663619 -161.626604)
			(xy 41.664128 -161.65449) (xy 41.663619 -161.682376) (xy 41.655499 -161.737552) (xy 41.639431 -161.790959)
			(xy 41.615759 -161.841456) (xy 41.584986 -161.887969) (xy 41.547769 -161.929506) (xy 41.504901 -161.965181)
			(xy 41.457295 -161.994235) (xy 41.405966 -162.016047) (xy 41.352009 -162.030153) (xy 41.296572 -162.036253)
			(xy 41.240838 -162.034216) (xy 41.185995 -162.024086) (xy 41.133211 -162.006079) (xy 41.083611 -161.980578)
			(xy 41.038253 -161.948127) (xy 40.998104 -161.909418) (xy 40.964018 -161.865275) (xy 40.936722 -161.81664)
			(xy 40.916799 -161.764549) (xy 40.904673 -161.710112) (xy 40.900602 -161.65449) (xy 21.99386 -161.65449)
			(xy 21.99386 -162.501834) (xy 43.435522 -162.501834) (xy 43.439593 -162.446212) (xy 43.451719 -162.391775)
			(xy 43.471642 -162.339684) (xy 43.498938 -162.291049) (xy 43.533024 -162.246906) (xy 43.573173 -162.208197)
			(xy 43.618531 -162.175746) (xy 43.668131 -162.150245) (xy 43.720915 -162.132238) (xy 43.775758 -162.122108)
			(xy 43.831492 -162.120071) (xy 43.886929 -162.126171) (xy 43.940886 -162.140277) (xy 43.992215 -162.162089)
			(xy 44.039821 -162.191143) (xy 44.082689 -162.226818) (xy 44.119906 -162.268355) (xy 44.150679 -162.314868)
			(xy 44.174351 -162.365365) (xy 44.190419 -162.418772) (xy 44.196812 -162.46221) (xy 45.114462 -162.46221)
			(xy 45.118533 -162.406588) (xy 45.130659 -162.352151) (xy 45.150582 -162.30006) (xy 45.177878 -162.251425)
			(xy 45.211964 -162.207282) (xy 45.252113 -162.168573) (xy 45.297471 -162.136122) (xy 45.347071 -162.110621)
			(xy 45.399855 -162.092614) (xy 45.454698 -162.082484) (xy 45.510432 -162.080447) (xy 45.565869 -162.086547)
			(xy 45.619826 -162.100653) (xy 45.671155 -162.122465) (xy 45.718761 -162.151519) (xy 45.761629 -162.187194)
			(xy 45.798846 -162.228731) (xy 45.829619 -162.275244) (xy 45.853291 -162.325741) (xy 45.869359 -162.379148)
			(xy 45.877479 -162.434324) (xy 45.877988 -162.46221) (xy 45.877654 -162.480498) (xy 46.543974 -162.480498)
			(xy 46.548045 -162.424876) (xy 46.560171 -162.370439) (xy 46.580094 -162.318348) (xy 46.60739 -162.269713)
			(xy 46.641476 -162.22557) (xy 46.681625 -162.186861) (xy 46.726983 -162.15441) (xy 46.776583 -162.128909)
			(xy 46.829367 -162.110902) (xy 46.88421 -162.100772) (xy 46.939944 -162.098735) (xy 46.995381 -162.104835)
			(xy 47.049338 -162.118941) (xy 47.100667 -162.140753) (xy 47.148273 -162.169807) (xy 47.191141 -162.205482)
			(xy 47.228358 -162.247019) (xy 47.259131 -162.293532) (xy 47.28105 -162.34029) (xy 48.253902 -162.34029)
			(xy 48.257973 -162.284668) (xy 48.270099 -162.230231) (xy 48.290022 -162.17814) (xy 48.317318 -162.129505)
			(xy 48.351404 -162.085362) (xy 48.391553 -162.046653) (xy 48.436911 -162.014202) (xy 48.486511 -161.988701)
			(xy 48.539295 -161.970694) (xy 48.594138 -161.960564) (xy 48.649872 -161.958527) (xy 48.705309 -161.964627)
			(xy 48.759266 -161.978733) (xy 48.810595 -162.000545) (xy 48.858201 -162.029599) (xy 48.901069 -162.065274)
			(xy 48.938286 -162.106811) (xy 48.969059 -162.153324) (xy 48.992731 -162.203821) (xy 49.008799 -162.257228)
			(xy 49.016919 -162.312404) (xy 49.017428 -162.34029) (xy 49.016919 -162.368176) (xy 49.008799 -162.423352)
			(xy 48.992731 -162.476759) (xy 48.975737 -162.51301) (xy 49.777902 -162.51301) (xy 49.781973 -162.457388)
			(xy 49.794099 -162.402951) (xy 49.814022 -162.35086) (xy 49.841318 -162.302225) (xy 49.875404 -162.258082)
			(xy 49.915553 -162.219373) (xy 49.960911 -162.186922) (xy 50.010511 -162.161421) (xy 50.063295 -162.143414)
			(xy 50.118138 -162.133284) (xy 50.173872 -162.131247) (xy 50.229309 -162.137347) (xy 50.283266 -162.151453)
			(xy 50.334595 -162.173265) (xy 50.382201 -162.202319) (xy 50.425069 -162.237994) (xy 50.462286 -162.279531)
			(xy 50.493059 -162.326044) (xy 50.516731 -162.376541) (xy 50.532799 -162.429948) (xy 50.540919 -162.485124)
			(xy 50.541428 -162.51301) (xy 50.540919 -162.540896) (xy 50.532799 -162.596072) (xy 50.516731 -162.649479)
			(xy 50.493059 -162.699976) (xy 50.462286 -162.746489) (xy 50.425069 -162.788026) (xy 50.382201 -162.823701)
			(xy 50.334595 -162.852755) (xy 50.283266 -162.874567) (xy 50.229309 -162.888673) (xy 50.173872 -162.894773)
			(xy 50.118138 -162.892736) (xy 50.063295 -162.882606) (xy 50.010511 -162.864599) (xy 49.960911 -162.839098)
			(xy 49.915553 -162.806647) (xy 49.875404 -162.767938) (xy 49.841318 -162.723795) (xy 49.814022 -162.67516)
			(xy 49.794099 -162.623069) (xy 49.781973 -162.568632) (xy 49.777902 -162.51301) (xy 48.975737 -162.51301)
			(xy 48.969059 -162.527256) (xy 48.938286 -162.573769) (xy 48.901069 -162.615306) (xy 48.858201 -162.650981)
			(xy 48.810595 -162.680035) (xy 48.759266 -162.701847) (xy 48.705309 -162.715953) (xy 48.649872 -162.722053)
			(xy 48.594138 -162.720016) (xy 48.539295 -162.709886) (xy 48.486511 -162.691879) (xy 48.436911 -162.666378)
			(xy 48.391553 -162.633927) (xy 48.351404 -162.595218) (xy 48.317318 -162.551075) (xy 48.290022 -162.50244)
			(xy 48.270099 -162.450349) (xy 48.257973 -162.395912) (xy 48.253902 -162.34029) (xy 47.28105 -162.34029)
			(xy 47.282803 -162.344029) (xy 47.298871 -162.397436) (xy 47.306991 -162.452612) (xy 47.3075 -162.480498)
			(xy 47.306991 -162.508384) (xy 47.298871 -162.56356) (xy 47.282803 -162.616967) (xy 47.259131 -162.667464)
			(xy 47.228358 -162.713977) (xy 47.191141 -162.755514) (xy 47.148273 -162.791189) (xy 47.100667 -162.820243)
			(xy 47.049338 -162.842055) (xy 46.995381 -162.856161) (xy 46.939944 -162.862261) (xy 46.88421 -162.860224)
			(xy 46.829367 -162.850094) (xy 46.776583 -162.832087) (xy 46.726983 -162.806586) (xy 46.681625 -162.774135)
			(xy 46.641476 -162.735426) (xy 46.60739 -162.691283) (xy 46.580094 -162.642648) (xy 46.560171 -162.590557)
			(xy 46.548045 -162.53612) (xy 46.543974 -162.480498) (xy 45.877654 -162.480498) (xy 45.877479 -162.490096)
			(xy 45.869359 -162.545272) (xy 45.853291 -162.598679) (xy 45.829619 -162.649176) (xy 45.798846 -162.695689)
			(xy 45.761629 -162.737226) (xy 45.718761 -162.772901) (xy 45.671155 -162.801955) (xy 45.619826 -162.823767)
			(xy 45.565869 -162.837873) (xy 45.510432 -162.843973) (xy 45.454698 -162.841936) (xy 45.399855 -162.831806)
			(xy 45.347071 -162.813799) (xy 45.297471 -162.788298) (xy 45.252113 -162.755847) (xy 45.211964 -162.717138)
			(xy 45.177878 -162.672995) (xy 45.150582 -162.62436) (xy 45.130659 -162.572269) (xy 45.118533 -162.517832)
			(xy 45.114462 -162.46221) (xy 44.196812 -162.46221) (xy 44.198539 -162.473948) (xy 44.199048 -162.501834)
			(xy 44.198539 -162.52972) (xy 44.190419 -162.584896) (xy 44.174351 -162.638303) (xy 44.150679 -162.6888)
			(xy 44.119906 -162.735313) (xy 44.082689 -162.77685) (xy 44.039821 -162.812525) (xy 43.992215 -162.841579)
			(xy 43.940886 -162.863391) (xy 43.886929 -162.877497) (xy 43.831492 -162.883597) (xy 43.775758 -162.88156)
			(xy 43.720915 -162.87143) (xy 43.668131 -162.853423) (xy 43.618531 -162.827922) (xy 43.573173 -162.795471)
			(xy 43.533024 -162.756762) (xy 43.498938 -162.712619) (xy 43.471642 -162.663984) (xy 43.451719 -162.611893)
			(xy 43.439593 -162.557456) (xy 43.435522 -162.501834) (xy 21.99386 -162.501834) (xy 21.99386 -163.750498)
			(xy 27.370022 -163.750498) (xy 27.374093 -163.694876) (xy 27.386219 -163.640439) (xy 27.406142 -163.588348)
			(xy 27.433438 -163.539713) (xy 27.467524 -163.49557) (xy 27.507673 -163.456861) (xy 27.553031 -163.42441)
			(xy 27.602631 -163.398909) (xy 27.655415 -163.380902) (xy 27.710258 -163.370772) (xy 27.765992 -163.368735)
			(xy 27.821429 -163.374835) (xy 27.875386 -163.388941) (xy 27.926715 -163.410753) (xy 27.974321 -163.439807)
			(xy 28.017189 -163.475482) (xy 28.054406 -163.517019) (xy 28.085179 -163.563532) (xy 28.108851 -163.614029)
			(xy 28.124919 -163.667436) (xy 28.133039 -163.722612) (xy 28.133548 -163.750498) (xy 28.133039 -163.778384)
			(xy 28.124919 -163.83356) (xy 28.108851 -163.886967) (xy 28.085179 -163.937464) (xy 28.054406 -163.983977)
			(xy 28.017189 -164.025514) (xy 27.974321 -164.061189) (xy 27.926715 -164.090243) (xy 27.875386 -164.112055)
			(xy 27.821429 -164.126161) (xy 27.765992 -164.132261) (xy 27.710258 -164.130224) (xy 27.655415 -164.120094)
			(xy 27.602631 -164.102087) (xy 27.553031 -164.076586) (xy 27.507673 -164.044135) (xy 27.467524 -164.005426)
			(xy 27.433438 -163.961283) (xy 27.406142 -163.912648) (xy 27.386219 -163.860557) (xy 27.374093 -163.80612)
			(xy 27.370022 -163.750498) (xy 21.99386 -163.750498) (xy 21.99386 -164.843206) (xy 27.370022 -164.843206)
			(xy 27.374093 -164.787584) (xy 27.386219 -164.733147) (xy 27.406142 -164.681056) (xy 27.433438 -164.632421)
			(xy 27.467524 -164.588278) (xy 27.507673 -164.549569) (xy 27.553031 -164.517118) (xy 27.602631 -164.491617)
			(xy 27.655415 -164.47361) (xy 27.710258 -164.46348) (xy 27.765992 -164.461443) (xy 27.821429 -164.467543)
			(xy 27.875386 -164.481649) (xy 27.926715 -164.503461) (xy 27.974321 -164.532515) (xy 28.017189 -164.56819)
			(xy 28.054406 -164.609727) (xy 28.085179 -164.65624) (xy 28.108851 -164.706737) (xy 28.124919 -164.760144)
			(xy 28.133039 -164.81532) (xy 28.133548 -164.843206) (xy 28.133039 -164.871092) (xy 28.124919 -164.926268)
			(xy 28.108851 -164.979675) (xy 28.085179 -165.030172) (xy 28.054406 -165.076685) (xy 28.017189 -165.118222)
			(xy 27.974321 -165.153897) (xy 27.926715 -165.182951) (xy 27.875386 -165.204763) (xy 27.821429 -165.218869)
			(xy 27.765992 -165.224969) (xy 27.710258 -165.222932) (xy 27.655415 -165.212802) (xy 27.602631 -165.194795)
			(xy 27.553031 -165.169294) (xy 27.507673 -165.136843) (xy 27.467524 -165.098134) (xy 27.433438 -165.053991)
			(xy 27.406142 -165.005356) (xy 27.386219 -164.953265) (xy 27.374093 -164.898828) (xy 27.370022 -164.843206)
			(xy 21.99386 -164.843206) (xy 21.99386 -166.614856) (xy 23.10638 -167.727376) (xy 31.701486 -167.727376)
		)
		(stroke
			(width 0)
			(type solid)
		)
		(fill yes)
		(layer "In6.Cu")
		(net "P1V9_LAN1")
	)
	(gr_poly
		(pts
			(xy 47.10557 -101.327712) (xy 50.68824 -101.327712) (xy 50.74031 -101.379782) (xy 54.203092 -101.379782)
			(xy 54.21951 -101.379277) (xy 54.251257 -101.370895) (xy 54.279798 -101.35466) (xy 54.30323 -101.331658)
			(xy 54.312058 -101.317806) (xy 54.312312 -101.317552) (xy 54.326621 -101.294324) (xy 54.360841 -101.251836)
			(xy 54.400765 -101.214656) (xy 54.445577 -101.183541) (xy 54.494364 -101.159127) (xy 54.546131 -101.14191)
			(xy 54.599822 -101.132243) (xy 54.654343 -101.130322) (xy 54.708582 -101.136187) (xy 54.761433 -101.149717)
			(xy 54.811817 -101.170638) (xy 54.858708 -101.198522) (xy 54.901149 -101.2328) (xy 54.938274 -101.272774)
			(xy 54.95417 -101.294946) (xy 54.97068 -101.318568) (xy 55.077868 -101.379782) (xy 65.303146 -101.379782)
			(xy 66.400172 -100.282756) (xy 66.400172 -99.9363) (xy 66.400673 -99.904457) (xy 66.408641 -99.841272)
			(xy 66.424439 -99.779577) (xy 66.44782 -99.720338) (xy 66.478418 -99.664484) (xy 66.515753 -99.61289)
			(xy 66.559241 -99.566364) (xy 66.6082 -99.525634) (xy 66.661863 -99.491339) (xy 66.71939 -99.464017)
			(xy 66.77988 -99.444094) (xy 66.842384 -99.431883) (xy 66.905924 -99.427576) (xy 66.969504 -99.43124)
			(xy 67.032129 -99.442817) (xy 67.092817 -99.462126) (xy 67.150618 -99.488865) (xy 67.17792 -99.505262)
			(xy 67.243198 -99.43973) (xy 67.578478 -99.10445) (xy 67.587876 -99.075494) (xy 67.5894 -99.071176)
			(xy 67.59194 -99.064064) (xy 67.592956 -99.061778) (xy 67.602608 -99.036632) (xy 67.600068 -98.9838)
			(xy 67.558666 -98.899726) (xy 67.539108 -98.882962) (xy 67.51783 -98.863953) (xy 67.480604 -98.820714)
			(xy 67.450234 -98.772413) (xy 67.427397 -98.720127) (xy 67.419474 -98.692716) (xy 67.412681 -98.665465)
			(xy 67.406243 -98.609674) (xy 67.408055 -98.553543) (xy 67.418078 -98.498283) (xy 67.436095 -98.445091)
			(xy 67.461717 -98.395115) (xy 67.49439 -98.349436) (xy 67.533407 -98.309042) (xy 67.577925 -98.274805)
			(xy 67.626983 -98.247466) (xy 67.679518 -98.227616) (xy 67.734397 -98.215683) (xy 67.790432 -98.211926)
			(xy 67.846412 -98.216425) (xy 67.901128 -98.229085) (xy 67.927474 -98.238818) (xy 67.955434 -98.250415)
			(xy 68.007576 -98.281153) (xy 68.054207 -98.319744) (xy 68.094153 -98.365218) (xy 68.126413 -98.416433)
			(xy 68.138802 -98.44405) (xy 68.145006 -98.457537) (xy 68.162678 -98.481384) (xy 68.185392 -98.500489)
			(xy 68.211914 -98.513813) (xy 68.240801 -98.520633) (xy 68.255642 -98.521012) (xy 68.309236 -98.521012)
			(xy 68.325882 -98.520465) (xy 68.358037 -98.511841) (xy 68.386866 -98.49519) (xy 68.410405 -98.471647)
			(xy 68.42705 -98.442815) (xy 68.435668 -98.410658) (xy 68.436236 -98.394012) (xy 68.436236 -98.369882)
			(xy 68.427346 -98.347276) (xy 68.418039 -98.322534) (xy 68.405554 -98.271167) (xy 68.402454 -98.244914)
			(xy 68.400762 -98.225004) (xy 68.40102 -98.185045) (xy 68.402962 -98.165158) (xy 68.404255 -98.154276)
			(xy 68.407938 -98.132672) (xy 68.410328 -98.121978) (xy 68.417181 -98.094367) (xy 68.437973 -98.041415)
			(xy 68.466419 -97.992151) (xy 68.483734 -97.969578) (xy 68.500373 -97.949388) (xy 68.538261 -97.913307)
			(xy 68.580722 -97.882737) (xy 68.626959 -97.858253) (xy 68.676106 -97.840312) (xy 68.727243 -97.82925)
			(xy 68.779411 -97.825275) (xy 68.831634 -97.828461) (xy 68.857368 -97.83318) (xy 68.885051 -97.83927)
			(xy 68.938358 -97.858532) (xy 68.98823 -97.885467) (xy 69.033568 -97.919483) (xy 69.073376 -97.959831)
			(xy 69.106779 -98.005624) (xy 69.13304 -98.055853) (xy 69.151582 -98.109415) (xy 69.161998 -98.16513)
			(xy 69.164057 -98.221773) (xy 69.161406 -98.249994) (xy 69.160365 -98.273107) (xy 69.165674 -98.319064)
			(xy 69.179214 -98.3633) (xy 69.200538 -98.404354) (xy 69.228941 -98.44087) (xy 69.263486 -98.471642)
			(xy 69.303029 -98.495652) (xy 69.346266 -98.512107) (xy 69.391767 -98.520464) (xy 69.414898 -98.521012)
			(xy 74.654664 -98.521012) (xy 74.734928 -98.440748) (xy 74.734928 -97.494598) (xy 74.73188 -97.491296)
			(xy 74.73188 -96.941386) (xy 74.731384 -96.924733) (xy 74.72276 -96.892564) (xy 74.706104 -96.863723)
			(xy 74.68255 -96.840176) (xy 74.653704 -96.823527) (xy 74.621533 -96.814912) (xy 74.60488 -96.814386)
			(xy 72.414384 -96.814386) (xy 71.155052 -95.555054) (xy 71.139322 -95.53996) (xy 71.103692 -95.514847)
			(xy 71.064299 -95.496181) (xy 71.022299 -95.484511) (xy 70.978924 -95.480177) (xy 70.935446 -95.483308)
			(xy 70.893139 -95.493811) (xy 70.853244 -95.511379) (xy 70.816932 -95.535496) (xy 70.785268 -95.565455)
			(xy 70.759179 -95.600377) (xy 70.739431 -95.639239) (xy 70.73265 -95.659956) (xy 70.723924 -95.686602)
			(xy 70.699751 -95.737192) (xy 70.668431 -95.783697) (xy 70.630639 -95.825115) (xy 70.587189 -95.860553)
			(xy 70.539019 -95.889246) (xy 70.487167 -95.910577) (xy 70.43275 -95.924086) (xy 70.376942 -95.929481)
			(xy 70.320945 -95.926646) (xy 70.265967 -95.915642) (xy 70.213193 -95.896707) (xy 70.16376 -95.870248)
			(xy 70.118734 -95.836837) (xy 70.079086 -95.797192) (xy 70.04567 -95.752169) (xy 70.019207 -95.702739)
			(xy 70.000267 -95.649966) (xy 69.989258 -95.594989) (xy 69.986418 -95.538992) (xy 69.991808 -95.483184)
			(xy 70.005312 -95.428766) (xy 70.026638 -95.376911) (xy 70.055328 -95.328739) (xy 70.090761 -95.285286)
			(xy 70.132176 -95.247491) (xy 70.178678 -95.216166) (xy 70.229266 -95.191989) (xy 70.255892 -95.183198)
			(xy 70.276598 -95.176365) (xy 70.315478 -95.156635) (xy 70.350419 -95.130558) (xy 70.380397 -95.098899)
			(xy 70.40453 -95.062588) (xy 70.422111 -95.02269) (xy 70.432623 -94.980377) (xy 70.435759 -94.93689)
			(xy 70.431425 -94.893507) (xy 70.41975 -94.8515) (xy 70.401075 -94.812102) (xy 70.37595 -94.77647)
			(xy 70.360794 -94.760796) (xy 65.989454 -90.389456) (xy 65.940178 -90.370152) (xy 65.913508 -90.371168)
			(xy 65.884914 -90.371761) (xy 65.828076 -90.365411) (xy 65.772822 -90.350649) (xy 65.72039 -90.327806)
			(xy 65.671955 -90.297393) (xy 65.628602 -90.260091) (xy 65.591302 -90.216737) (xy 65.56089 -90.168301)
			(xy 65.538048 -90.115869) (xy 65.523287 -90.060615) (xy 65.516939 -90.003777) (xy 65.517522 -89.975182)
			(xy 65.51768 -89.957688) (xy 65.509535 -89.923679) (xy 65.492429 -89.893178) (xy 65.480438 -89.88044)
			(xy 63.173864 -87.573866) (xy 63.173864 -86.661498) (xy 63.067184 -86.538308) (xy 63.028322 -86.528656)
			(xy 63.014385 -86.52506) (xy 62.98705 -86.516032) (xy 62.973712 -86.510622) (xy 62.96279 -86.50605)
			(xy 62.938152 -86.500716) (xy 62.921744 -86.497888) (xy 62.888518 -86.499825) (xy 62.856919 -86.510279)
			(xy 62.829094 -86.52854) (xy 62.80693 -86.553369) (xy 62.791932 -86.583081) (xy 62.788038 -86.599268)
			(xy 62.784228 -86.617556) (xy 62.785752 -86.636098) (xy 62.787646 -86.664038) (xy 62.78421 -86.719933)
			(xy 62.772643 -86.774726) (xy 62.753193 -86.827239) (xy 62.726277 -86.876347) (xy 62.692474 -86.920994)
			(xy 62.652509 -86.960222) (xy 62.60724 -86.993188) (xy 62.55764 -87.019185) (xy 62.504773 -87.037655)
			(xy 62.449775 -87.0482) (xy 62.393826 -87.050595) (xy 62.338127 -87.044788) (xy 62.283876 -87.030904)
			(xy 62.232235 -87.00924) (xy 62.184315 -86.980263) (xy 62.141144 -86.944594) (xy 62.103649 -86.902999)
			(xy 62.072636 -86.856371) (xy 62.048769 -86.805711) (xy 62.032562 -86.752107) (xy 62.024362 -86.696711)
			(xy 62.024345 -86.640711) (xy 62.032513 -86.585309) (xy 62.048689 -86.531696) (xy 62.072527 -86.481023)
			(xy 62.103513 -86.434377) (xy 62.140984 -86.39276) (xy 62.184134 -86.357065) (xy 62.232037 -86.32806)
			(xy 62.257686 -86.31682) (xy 62.278784 -86.307418) (xy 62.317442 -86.282146) (xy 62.350897 -86.250304)
			(xy 62.378048 -86.212941) (xy 62.398001 -86.171287) (xy 62.410099 -86.126714) (xy 62.413943 -86.080688)
			(xy 62.409408 -86.034726) (xy 62.396642 -85.990339) (xy 62.376066 -85.94899) (xy 62.362588 -85.930232)
			(xy 62.344671 -85.907476) (xy 62.315201 -85.857618) (xy 62.293607 -85.803878) (xy 62.280383 -85.747492)
			(xy 62.275834 -85.689755) (xy 62.280064 -85.631994) (xy 62.292976 -85.575535) (xy 62.314274 -85.521677)
			(xy 62.343467 -85.471657) (xy 62.379886 -85.426624) (xy 62.400942 -85.406738) (xy 62.421801 -85.388403)
			(xy 62.467833 -85.357337) (xy 62.517881 -85.333268) (xy 62.570888 -85.316704) (xy 62.625736 -85.307995)
			(xy 62.681267 -85.307326) (xy 62.736308 -85.314709) (xy 62.789699 -85.329989) (xy 62.815216 -85.340952)
			(xy 62.836431 -85.349996) (xy 62.881186 -85.361108) (xy 62.927211 -85.363964) (xy 62.972997 -85.35847)
			(xy 63.01704 -85.344807) (xy 63.057896 -85.323422) (xy 63.094223 -85.295018) (xy 63.124831 -85.260526)
			(xy 63.148713 -85.221079) (xy 63.165088 -85.17797) (xy 63.173418 -85.132615) (xy 63.173864 -85.109558)
			(xy 63.173864 -85.03539) (xy 63.173368 -85.018738) (xy 63.164745 -84.986569) (xy 63.148088 -84.957729)
			(xy 63.124534 -84.934184) (xy 63.095688 -84.917538) (xy 63.063516 -84.908926) (xy 63.046864 -84.90839)
			(xy 63.012828 -84.90839) (xy 62.983364 -84.925154) (xy 62.958619 -84.938803) (xy 62.906018 -84.959453)
			(xy 62.850946 -84.972117) (xy 62.794608 -84.976519) (xy 62.738238 -84.972562) (xy 62.683067 -84.960333)
			(xy 62.630305 -84.940099) (xy 62.581104 -84.912303) (xy 62.536542 -84.877553) (xy 62.497594 -84.83661)
			(xy 62.465112 -84.790369) (xy 62.439806 -84.739842) (xy 62.422231 -84.686135) (xy 62.412771 -84.630424)
			(xy 62.411632 -84.573926) (xy 62.418841 -84.517878) (xy 62.434238 -84.463507) (xy 62.457488 -84.412002)
			(xy 62.472316 -84.387944) (xy 62.48146 -84.37372) (xy 62.50432 -84.302092) (xy 62.469522 -84.215478)
			(xy 62.455552 -84.199476) (xy 62.438147 -84.178589) (xy 62.408808 -84.132817) (xy 62.386262 -84.083344)
			(xy 62.370964 -84.031173) (xy 62.363224 -83.977359) (xy 62.363199 -83.922991) (xy 62.370889 -83.86917)
			(xy 62.386139 -83.816985) (xy 62.40864 -83.767492) (xy 62.437937 -83.721693) (xy 62.473436 -83.680514)
			(xy 62.51442 -83.64479) (xy 62.560058 -83.615243) (xy 62.609428 -83.592472) (xy 62.661529 -83.576937)
			(xy 62.715307 -83.568952) (xy 62.769674 -83.56868) (xy 62.82353 -83.576125) (xy 62.84976 -83.583272)
			(xy 62.872509 -83.589275) (xy 62.919342 -83.593724) (xy 62.966194 -83.589481) (xy 63.011466 -83.576691)
			(xy 63.053612 -83.555791) (xy 63.091194 -83.527493) (xy 63.122928 -83.492766) (xy 63.147733 -83.452792)
			(xy 63.16476 -83.408938) (xy 63.173428 -83.3627) (xy 63.173864 -83.339178) (xy 63.173864 -82.781394)
			(xy 63.17341 -82.759547) (xy 63.16594 -82.716498) (xy 63.15122 -82.675359) (xy 63.129685 -82.637342)
			(xy 63.101967 -82.603565) (xy 63.068883 -82.575025) (xy 63.031408 -82.55256) (xy 62.990644 -82.536832)
			(xy 62.947791 -82.528305) (xy 62.92596 -82.527394) (xy 62.89205 -82.526018) (xy 62.825023 -82.515373)
			(xy 62.760011 -82.495896) (xy 62.728856 -82.482436) (xy 62.699566 -82.468623) (xy 62.644438 -82.434646)
			(xy 62.594072 -82.393941) (xy 62.549284 -82.347168) (xy 62.510801 -82.295084) (xy 62.479245 -82.238534)
			(xy 62.455129 -82.178434) (xy 62.438842 -82.115757) (xy 62.430649 -82.051519) (xy 62.430152 -82.01914)
			(xy 62.430152 -81.806796) (xy 62.63894 -81.598008) (xy 62.652621 -81.580653) (xy 62.674395 -81.542203)
			(xy 62.68919 -81.500565) (xy 62.696559 -81.456996) (xy 62.696281 -81.41281) (xy 62.688363 -81.369337)
			(xy 62.673045 -81.327889) (xy 62.650789 -81.289716) (xy 62.622264 -81.255968) (xy 62.588332 -81.227664)
			(xy 62.550015 -81.205655) (xy 62.508469 -81.190606) (xy 62.464946 -81.182971) (xy 62.442852 -81.182464)
			(xy 61.720984 -81.182464) (xy 61.704257 -81.182959) (xy 61.671951 -81.191644) (xy 61.643018 -81.208437)
			(xy 61.619453 -81.232181) (xy 61.610748 -81.246472) (xy 61.597082 -81.269482) (xy 61.5643 -81.311783)
			(xy 61.525926 -81.349087) (xy 61.482716 -81.380661) (xy 61.435517 -81.405886) (xy 61.385255 -81.424265)
			(xy 61.332917 -81.43544) (xy 61.279532 -81.439189) (xy 61.226147 -81.43544) (xy 61.173809 -81.424265)
			(xy 61.123547 -81.405886) (xy 61.076348 -81.380661) (xy 61.033138 -81.349087) (xy 60.994764 -81.311783)
			(xy 60.961982 -81.269482) (xy 60.948316 -81.246472) (xy 60.939577 -81.23221) (xy 60.916005 -81.208495)
			(xy 60.887084 -81.191711) (xy 60.854798 -81.183011) (xy 60.83808 -81.182464) (xy 58.460894 -81.182464)
			(xy 58.398156 -81.245202) (xy 58.398156 -82.081116) (xy 58.39869 -82.104861) (xy 58.407516 -82.151525)
			(xy 58.424856 -82.195736) (xy 58.450108 -82.235957) (xy 58.482393 -82.270786) (xy 58.520586 -82.299011)
			(xy 58.563357 -82.31965) (xy 58.609218 -82.331983) (xy 58.632852 -82.334354) (xy 58.659918 -82.336882)
			(xy 58.712993 -82.34863) (xy 58.763863 -82.367793) (xy 58.811499 -82.393983) (xy 58.854934 -82.426668)
			(xy 58.893291 -82.465187) (xy 58.925792 -82.508761) (xy 58.95178 -82.556506) (xy 58.970727 -82.607457)
			(xy 58.982251 -82.660581) (xy 58.986118 -82.714803) (xy 58.98225 -82.769025) (xy 58.970725 -82.82215)
			(xy 58.951777 -82.8731) (xy 58.925789 -82.920845) (xy 58.893287 -82.964418) (xy 58.854929 -83.002937)
			(xy 58.811493 -83.035621) (xy 58.763857 -83.06181) (xy 58.71459 -83.080368) (xy 60.208643 -83.080368)
			(xy 60.214941 -83.025118) (xy 60.229192 -82.971367) (xy 60.251095 -82.920255) (xy 60.280184 -82.872863)
			(xy 60.315845 -82.830195) (xy 60.357322 -82.793156) (xy 60.403736 -82.76253) (xy 60.454103 -82.738965)
			(xy 60.507358 -82.722961) (xy 60.562372 -82.714857) (xy 60.590176 -82.714338) (xy 60.604847 -82.713936)
			(xy 60.633401 -82.707171) (xy 60.659655 -82.694062) (xy 60.682221 -82.675304) (xy 60.699905 -82.651887)
			(xy 60.711772 -82.625049) (xy 60.71489 -82.610706) (xy 60.720438 -82.583702) (xy 60.73833 -82.531559)
			(xy 60.763541 -82.482533) (xy 60.795544 -82.437646) (xy 60.833675 -82.397833) (xy 60.877139 -82.363922)
			(xy 60.925032 -82.336619) (xy 60.976355 -82.316494) (xy 61.03004 -82.303964) (xy 61.084969 -82.299292)
			(xy 61.139999 -82.302574) (xy 61.193984 -82.313742) (xy 61.2458 -82.332563) (xy 61.294367 -82.358646)
			(xy 61.338674 -82.391447) (xy 61.3778 -82.430283) (xy 61.410929 -82.474346) (xy 61.437371 -82.522719)
			(xy 61.456576 -82.574393) (xy 61.468143 -82.628294) (xy 61.471833 -82.683298) (xy 61.467568 -82.738261)
			(xy 61.455437 -82.792037) (xy 61.435693 -82.843508) (xy 61.408746 -82.891601) (xy 61.375159 -82.935316)
			(xy 61.355732 -82.954876) (xy 61.340681 -82.970161) (xy 61.315386 -83.004803) (xy 61.29627 -83.043201)
			(xy 61.283874 -83.084264) (xy 61.278553 -83.126826) (xy 61.280457 -83.169678) (xy 61.289531 -83.2116)
			(xy 61.305518 -83.251403) (xy 61.327964 -83.287955) (xy 61.341762 -83.30438) (xy 61.359619 -83.32552)
			(xy 61.389707 -83.371962) (xy 61.412769 -83.422264) (xy 61.428321 -83.47537) (xy 61.436038 -83.530165)
			(xy 61.435758 -83.585501) (xy 61.427485 -83.640215) (xy 61.411394 -83.693161) (xy 61.387823 -83.743226)
			(xy 61.357266 -83.78936) (xy 61.320364 -83.830595) (xy 61.277892 -83.866067) (xy 61.23074 -83.89503)
			(xy 61.179899 -83.916876) (xy 61.126435 -83.931149) (xy 61.07147 -83.937547) (xy 61.016157 -83.935936)
			(xy 60.961657 -83.926352) (xy 60.909114 -83.908994) (xy 60.859629 -83.884226) (xy 60.814243 -83.852569)
			(xy 60.773906 -83.814687) (xy 60.739465 -83.771375) (xy 60.711643 -83.723541) (xy 60.691025 -83.67219)
			(xy 60.678041 -83.618398) (xy 60.675012 -83.590892) (xy 60.67321 -83.576226) (xy 60.663755 -83.548239)
			(xy 60.648119 -83.523177) (xy 60.627138 -83.502381) (xy 60.601938 -83.486967) (xy 60.573869 -83.47776)
			(xy 60.559188 -83.476084) (xy 60.53151 -83.473407) (xy 60.477337 -83.46086) (xy 60.425558 -83.440583)
			(xy 60.377271 -83.413005) (xy 60.333498 -83.378709) (xy 60.295168 -83.338423) (xy 60.263091 -83.292999)
			(xy 60.237947 -83.243401) (xy 60.220269 -83.190678) (xy 60.210432 -83.135947) (xy 60.208643 -83.080368)
			(xy 58.71459 -83.080368) (xy 58.712987 -83.080972) (xy 58.659912 -83.092719) (xy 58.632852 -83.095338)
			(xy 58.609218 -83.097677) (xy 58.563364 -83.110026) (xy 58.520601 -83.130675) (xy 58.482417 -83.158907)
			(xy 58.45014 -83.19374) (xy 58.424895 -83.233961) (xy 58.407558 -83.278172) (xy 58.398734 -83.324832)
			(xy 58.398156 -83.348576) (xy 58.398156 -83.605116) (xy 58.39869 -83.628861) (xy 58.407516 -83.675525)
			(xy 58.424856 -83.719736) (xy 58.450108 -83.759957) (xy 58.482393 -83.794786) (xy 58.520586 -83.823011)
			(xy 58.563357 -83.84365) (xy 58.609218 -83.855983) (xy 58.632852 -83.858354) (xy 58.659732 -83.860847)
			(xy 58.712453 -83.872448) (xy 58.763012 -83.891365) (xy 58.8104 -83.91722) (xy 58.85367 -83.949496)
			(xy 58.891959 -83.987549) (xy 58.924502 -84.03062) (xy 58.950648 -84.077847) (xy 58.969877 -84.128289)
			(xy 58.97626 -84.154518) (xy 58.979933 -84.168854) (xy 58.992914 -84.195441) (xy 59.011664 -84.218326)
			(xy 59.035178 -84.236283) (xy 59.062193 -84.248346) (xy 59.091259 -84.253868) (xy 59.106054 -84.253578)
			(xy 59.132116 -84.252804) (xy 59.184041 -84.257522) (xy 59.23484 -84.269269) (xy 59.283566 -84.287826)
			(xy 59.329309 -84.312847) (xy 59.371218 -84.343866) (xy 59.408512 -84.380304) (xy 59.424824 -84.400644)
			(xy 59.441394 -84.42281) (xy 59.468642 -84.470977) (xy 59.488649 -84.522574) (xy 59.500995 -84.57652)
			(xy 59.503909 -84.612836) (xy 60.209164 -84.612836) (xy 60.214296 -84.556921) (xy 60.22757 -84.502363)
			(xy 60.248698 -84.450339) (xy 60.277224 -84.401975) (xy 60.312532 -84.358315) (xy 60.353858 -84.320303)
			(xy 60.400311 -84.28876) (xy 60.450885 -84.264366) (xy 60.504489 -84.247651) (xy 60.559965 -84.238973)
			(xy 60.616113 -84.238522) (xy 60.671721 -84.246307) (xy 60.725587 -84.262159) (xy 60.776547 -84.285736)
			(xy 60.8235 -84.316529) (xy 60.865432 -84.353873) (xy 60.901437 -84.39696) (xy 60.930736 -84.444859)
			(xy 60.952698 -84.496536) (xy 60.960254 -84.52358) (xy 60.965261 -84.540287) (xy 60.982953 -84.570327)
			(xy 61.008099 -84.594475) (xy 61.038832 -84.610937) (xy 61.072867 -84.618489) (xy 61.090302 -84.618068)
			(xy 61.118174 -84.617058) (xy 61.173719 -84.622055) (xy 61.227944 -84.635085) (xy 61.279696 -84.655869)
			(xy 61.32787 -84.683965) (xy 61.371442 -84.718774) (xy 61.409482 -84.759555) (xy 61.441181 -84.805439)
			(xy 61.465864 -84.855449) (xy 61.483003 -84.908519) (xy 61.492235 -84.963519) (xy 61.493362 -85.019276)
			(xy 61.486361 -85.074604) (xy 61.47138 -85.128323) (xy 61.448739 -85.17929) (xy 61.418921 -85.226418)
			(xy 61.38256 -85.268703) (xy 61.361828 -85.287358) (xy 61.344319 -85.303249) (xy 61.314963 -85.340308)
			(xy 61.29296 -85.382154) (xy 61.279066 -85.427344) (xy 61.273761 -85.474324) (xy 61.277227 -85.521474)
			(xy 61.289345 -85.567173) (xy 61.309698 -85.609846) (xy 61.32322 -85.629242) (xy 61.338831 -85.651342)
			(xy 61.364271 -85.699098) (xy 61.38271 -85.749968) (xy 61.393777 -85.802932) (xy 61.397251 -85.85693)
			(xy 61.393062 -85.910876) (xy 61.381294 -85.963689) (xy 61.362184 -86.014311) (xy 61.336114 -86.061725)
			(xy 61.303607 -86.104981) (xy 61.265316 -86.143211) (xy 61.222007 -86.175648) (xy 61.198506 -86.189058)
			(xy 61.185623 -86.196571) (xy 61.163527 -86.216594) (xy 61.146693 -86.241205) (xy 61.136044 -86.269056)
			(xy 61.132163 -86.29862) (xy 61.135263 -86.328277) (xy 61.139832 -86.342474) (xy 61.148678 -86.369042)
			(xy 61.159285 -86.424025) (xy 61.16174 -86.479967) (xy 61.15599 -86.535668) (xy 61.14216 -86.58993)
			(xy 61.120545 -86.641586) (xy 61.091611 -86.689528) (xy 61.055979 -86.732725) (xy 61.014415 -86.770249)
			(xy 60.967811 -86.801293) (xy 60.91717 -86.825191) (xy 60.86358 -86.841428) (xy 60.808191 -86.849657)
			(xy 60.752194 -86.8497) (xy 60.696793 -86.841557) (xy 60.643178 -86.825401) (xy 60.5925 -86.801581)
			(xy 60.545849 -86.770609) (xy 60.504227 -86.733149) (xy 60.468529 -86.690007) (xy 60.439521 -86.64211)
			(xy 60.417827 -86.590486) (xy 60.403913 -86.536246) (xy 60.398078 -86.480554) (xy 60.400447 -86.424608)
			(xy 60.41097 -86.369609) (xy 60.429419 -86.316739) (xy 60.4554 -86.267134) (xy 60.488354 -86.221861)
			(xy 60.527572 -86.181891) (xy 60.572211 -86.148085) (xy 60.596526 -86.134194) (xy 60.609383 -86.126641)
			(xy 60.631474 -86.106624) (xy 60.648307 -86.082022) (xy 60.65896 -86.05418) (xy 60.662849 -86.024624)
			(xy 60.659762 -85.994974) (xy 60.6552 -85.980778) (xy 60.646612 -85.954682) (xy 60.636151 -85.900751)
			(xy 60.634372 -85.873336) (xy 60.632943 -85.856209) (xy 60.622207 -85.823579) (xy 60.603136 -85.795009)
			(xy 60.577117 -85.772581) (xy 60.546048 -85.757929) (xy 60.529216 -85.754464) (xy 60.501964 -85.749215)
			(xy 60.449223 -85.731953) (xy 60.399538 -85.707231) (xy 60.353961 -85.675571) (xy 60.313451 -85.637642)
			(xy 60.278865 -85.594243) (xy 60.250932 -85.546291) (xy 60.230241 -85.494798) (xy 60.21723 -85.44085)
			(xy 60.212173 -85.385586) (xy 60.215177 -85.330172) (xy 60.226178 -85.275779) (xy 60.244944 -85.223554)
			(xy 60.271079 -85.174598) (xy 60.287154 -85.151976) (xy 60.300541 -85.132978) (xy 60.320929 -85.091221)
			(xy 60.333379 -85.046452) (xy 60.337473 -85.000164) (xy 60.333074 -84.953904) (xy 60.320331 -84.909217)
			(xy 60.299668 -84.867595) (xy 60.286138 -84.8487) (xy 60.269604 -84.826007) (xy 60.242834 -84.776649)
			(xy 60.223589 -84.7239) (xy 60.212284 -84.6689) (xy 60.209164 -84.612836) (xy 59.503909 -84.612836)
			(xy 59.505422 -84.631683) (xy 59.501838 -84.686907) (xy 59.490316 -84.741035) (xy 59.471099 -84.792931)
			(xy 59.444589 -84.841509) (xy 59.42838 -84.86394) (xy 59.416348 -84.882553) (xy 59.39823 -84.922996)
			(xy 59.387404 -84.96597) (xy 59.384199 -85.01017) (xy 59.388713 -85.054256) (xy 59.400807 -85.09689)
			(xy 59.420116 -85.136778) (xy 59.432698 -85.155024) (xy 59.449439 -85.177258) (xy 59.47698 -85.225621)
			(xy 59.497203 -85.277472) (xy 59.509678 -85.33171) (xy 59.51414 -85.387186) (xy 59.510496 -85.442721)
			(xy 59.498821 -85.497137) (xy 59.479364 -85.54928) (xy 59.452538 -85.598043) (xy 59.418912 -85.642391)
			(xy 59.399424 -85.662262) (xy 59.383511 -85.679453) (xy 59.357631 -85.718492) (xy 59.339343 -85.761613)
			(xy 59.329268 -85.807355) (xy 59.327745 -85.854169) (xy 59.334827 -85.900469) (xy 59.350274 -85.944687)
			(xy 59.373562 -85.985325) (xy 59.403904 -86.021008) (xy 59.421776 -86.03615) (xy 59.445338 -86.054148)
			(xy 59.487129 -86.096204) (xy 59.521919 -86.144213) (xy 59.548872 -86.197021) (xy 59.567342 -86.25336)
			(xy 59.572652 -86.28253) (xy 59.576285 -86.307561) (xy 59.577699 -86.358122) (xy 59.572425 -86.408427)
			(xy 59.560555 -86.457595) (xy 59.542298 -86.504765) (xy 59.530488 -86.527132) (xy 59.530234 -86.52764)
			(xy 59.516174 -86.552133) (xy 59.481955 -86.597058) (xy 59.44149 -86.636452) (xy 59.395662 -86.669454)
			(xy 59.345473 -86.695344) (xy 59.292016 -86.713557) (xy 59.23646 -86.723695) (xy 59.180017 -86.725538)
			(xy 59.123918 -86.719044) (xy 59.069387 -86.704357) (xy 59.043316 -86.693502) (xy 59.018876 -86.682306)
			(xy 58.973135 -86.654064) (xy 58.931802 -86.619692) (xy 58.895692 -86.579869) (xy 58.880248 -86.557866)
			(xy 58.864576 -86.533835) (xy 58.839858 -86.482064) (xy 58.823186 -86.427171) (xy 58.818526 -86.398862)
			(xy 58.815963 -86.384359) (xy 58.805102 -86.356993) (xy 58.788254 -86.332847) (xy 58.766318 -86.313208)
			(xy 58.740462 -86.299124) (xy 58.712065 -86.291346) (xy 58.697368 -86.290404) (xy 58.679334 -86.289388)
			(xy 58.675524 -86.289134) (xy 58.652101 -86.287507) (xy 58.605353 -86.291838) (xy 58.560197 -86.304681)
			(xy 58.518168 -86.325601) (xy 58.480697 -86.353884) (xy 58.449059 -86.38857) (xy 58.424331 -86.428477)
			(xy 58.407353 -86.472247) (xy 58.398705 -86.518391) (xy 58.398156 -86.541864) (xy 58.398156 -87.427816)
			(xy 60.75375 -87.427816) (xy 60.757821 -87.372194) (xy 60.769947 -87.317757) (xy 60.78987 -87.265666)
			(xy 60.817166 -87.217031) (xy 60.851252 -87.172888) (xy 60.891401 -87.134179) (xy 60.936759 -87.101728)
			(xy 60.986359 -87.076227) (xy 61.039143 -87.05822) (xy 61.093986 -87.04809) (xy 61.14972 -87.046053)
			(xy 61.205157 -87.052153) (xy 61.259114 -87.066259) (xy 61.310443 -87.088071) (xy 61.358049 -87.117125)
			(xy 61.400917 -87.1528) (xy 61.438134 -87.194337) (xy 61.468907 -87.24085) (xy 61.492579 -87.291347)
			(xy 61.508647 -87.344754) (xy 61.516767 -87.39993) (xy 61.517276 -87.427816) (xy 61.516767 -87.455702)
			(xy 61.508647 -87.510878) (xy 61.492579 -87.564285) (xy 61.468907 -87.614782) (xy 61.438134 -87.661295)
			(xy 61.400917 -87.702832) (xy 61.358049 -87.738507) (xy 61.310443 -87.767561) (xy 61.259114 -87.789373)
			(xy 61.205157 -87.803479) (xy 61.14972 -87.809579) (xy 61.093986 -87.807542) (xy 61.039143 -87.797412)
			(xy 60.986359 -87.779405) (xy 60.936759 -87.753904) (xy 60.891401 -87.721453) (xy 60.851252 -87.682744)
			(xy 60.817166 -87.638601) (xy 60.78987 -87.589966) (xy 60.769947 -87.537875) (xy 60.757821 -87.483438)
			(xy 60.75375 -87.427816) (xy 58.398156 -87.427816) (xy 58.398156 -90.603324) (xy 58.398664 -90.608912)
			(xy 58.399862 -90.625019) (xy 58.399864 -90.657321) (xy 58.398664 -90.673428) (xy 58.398156 -90.679016)
			(xy 58.398156 -90.682813) (xy 58.961576 -90.682813) (xy 58.967892 -90.627913) (xy 58.982063 -90.574499)
			(xy 59.003794 -90.523689) (xy 59.032629 -90.476546) (xy 59.04992 -90.454988) (xy 59.06325 -90.43823)
			(xy 59.084705 -90.401177) (xy 59.099652 -90.361055) (xy 59.107668 -90.318995) (xy 59.108527 -90.276188)
			(xy 59.102204 -90.233841) (xy 59.088879 -90.193151) (xy 59.068927 -90.155268) (xy 59.05627 -90.137996)
			(xy 59.03986 -90.115765) (xy 59.012948 -90.067508) (xy 58.993281 -90.015873) (xy 58.98127 -89.96194)
			(xy 58.977166 -89.906839) (xy 58.981056 -89.851722) (xy 58.992859 -89.797743) (xy 59.012326 -89.746032)
			(xy 59.039051 -89.697671) (xy 59.072475 -89.653672) (xy 59.111897 -89.614957) (xy 59.156493 -89.582334)
			(xy 59.205329 -89.556488) (xy 59.257384 -89.537959) (xy 59.311567 -89.527135) (xy 59.366745 -89.524242)
			(xy 59.421764 -89.529341) (xy 59.47547 -89.542326) (xy 59.526742 -89.562923) (xy 59.574504 -89.590704)
			(xy 59.617759 -89.625085) (xy 59.618316 -89.625678) (xy 63.456818 -89.625678) (xy 63.460889 -89.570056)
			(xy 63.473015 -89.515619) (xy 63.492938 -89.463528) (xy 63.520234 -89.414893) (xy 63.55432 -89.37075)
			(xy 63.594469 -89.332041) (xy 63.639827 -89.29959) (xy 63.689427 -89.274089) (xy 63.742211 -89.256082)
			(xy 63.797054 -89.245952) (xy 63.852788 -89.243915) (xy 63.908225 -89.250015) (xy 63.962182 -89.264121)
			(xy 64.013511 -89.285933) (xy 64.061117 -89.314987) (xy 64.103985 -89.350662) (xy 64.141202 -89.392199)
			(xy 64.171975 -89.438712) (xy 64.195647 -89.489209) (xy 64.211715 -89.542616) (xy 64.219835 -89.597792)
			(xy 64.220344 -89.625678) (xy 64.219835 -89.653564) (xy 64.211715 -89.70874) (xy 64.195647 -89.762147)
			(xy 64.171975 -89.812644) (xy 64.141202 -89.859157) (xy 64.103985 -89.900694) (xy 64.061117 -89.936369)
			(xy 64.013511 -89.965423) (xy 63.962182 -89.987235) (xy 63.908225 -90.001341) (xy 63.852788 -90.007441)
			(xy 63.797054 -90.005404) (xy 63.742211 -89.995274) (xy 63.689427 -89.977267) (xy 63.639827 -89.951766)
			(xy 63.594469 -89.919315) (xy 63.55432 -89.880606) (xy 63.520234 -89.836463) (xy 63.492938 -89.787828)
			(xy 63.473015 -89.735737) (xy 63.460889 -89.6813) (xy 63.456818 -89.625678) (xy 59.618316 -89.625678)
			(xy 59.6556 -89.665347) (xy 59.687235 -89.710649) (xy 59.712003 -89.760041) (xy 59.729385 -89.812489)
			(xy 59.739017 -89.866897) (xy 59.740698 -89.922126) (xy 59.734392 -89.977019) (xy 59.720232 -90.030428)
			(xy 59.698514 -90.081234) (xy 59.669692 -90.128376) (xy 59.652408 -90.149934) (xy 59.639057 -90.166676)
			(xy 59.6176 -90.203732) (xy 59.602654 -90.243857) (xy 59.594639 -90.28592) (xy 59.593783 -90.328731)
			(xy 59.60011 -90.37108) (xy 59.613441 -90.411771) (xy 59.618813 -90.421968) (xy 60.091318 -90.421968)
			(xy 60.095389 -90.366346) (xy 60.107515 -90.311909) (xy 60.127438 -90.259818) (xy 60.154734 -90.211183)
			(xy 60.18882 -90.16704) (xy 60.228969 -90.128331) (xy 60.274327 -90.09588) (xy 60.323927 -90.070379)
			(xy 60.376711 -90.052372) (xy 60.431554 -90.042242) (xy 60.487288 -90.040205) (xy 60.542725 -90.046305)
			(xy 60.596682 -90.060411) (xy 60.648011 -90.082223) (xy 60.695617 -90.111277) (xy 60.738485 -90.146952)
			(xy 60.775702 -90.188489) (xy 60.806475 -90.235002) (xy 60.830147 -90.285499) (xy 60.846215 -90.338906)
			(xy 60.853318 -90.38717) (xy 62.169292 -90.38717) (xy 62.173363 -90.331548) (xy 62.185489 -90.277111)
			(xy 62.205412 -90.22502) (xy 62.232708 -90.176385) (xy 62.266794 -90.132242) (xy 62.306943 -90.093533)
			(xy 62.352301 -90.061082) (xy 62.401901 -90.035581) (xy 62.454685 -90.017574) (xy 62.509528 -90.007444)
			(xy 62.565262 -90.005407) (xy 62.620699 -90.011507) (xy 62.674656 -90.025613) (xy 62.725985 -90.047425)
			(xy 62.773591 -90.076479) (xy 62.816459 -90.112154) (xy 62.853676 -90.153691) (xy 62.884449 -90.200204)
			(xy 62.908121 -90.250701) (xy 62.924189 -90.304108) (xy 62.932309 -90.359284) (xy 62.932818 -90.38717)
			(xy 62.932309 -90.415056) (xy 62.924189 -90.470232) (xy 62.908121 -90.523639) (xy 62.884449 -90.574136)
			(xy 62.853676 -90.620649) (xy 62.816459 -90.662186) (xy 62.773591 -90.697861) (xy 62.750365 -90.712036)
			(xy 63.496696 -90.712036) (xy 63.500767 -90.656414) (xy 63.512893 -90.601977) (xy 63.532816 -90.549886)
			(xy 63.560112 -90.501251) (xy 63.594198 -90.457108) (xy 63.634347 -90.418399) (xy 63.679705 -90.385948)
			(xy 63.729305 -90.360447) (xy 63.782089 -90.34244) (xy 63.836932 -90.33231) (xy 63.892666 -90.330273)
			(xy 63.948103 -90.336373) (xy 64.00206 -90.350479) (xy 64.053389 -90.372291) (xy 64.100995 -90.401345)
			(xy 64.143863 -90.43702) (xy 64.18108 -90.478557) (xy 64.211853 -90.52507) (xy 64.235525 -90.575567)
			(xy 64.251593 -90.628974) (xy 64.259713 -90.68415) (xy 64.260222 -90.712036) (xy 64.259713 -90.739922)
			(xy 64.251593 -90.795098) (xy 64.235525 -90.848505) (xy 64.211853 -90.899002) (xy 64.18108 -90.945515)
			(xy 64.143863 -90.987052) (xy 64.100995 -91.022727) (xy 64.053389 -91.051781) (xy 64.00206 -91.073593)
			(xy 63.948103 -91.087699) (xy 63.892666 -91.093799) (xy 63.836932 -91.091762) (xy 63.782089 -91.081632)
			(xy 63.729305 -91.063625) (xy 63.679705 -91.038124) (xy 63.634347 -91.005673) (xy 63.594198 -90.966964)
			(xy 63.560112 -90.922821) (xy 63.532816 -90.874186) (xy 63.512893 -90.822095) (xy 63.500767 -90.767658)
			(xy 63.496696 -90.712036) (xy 62.750365 -90.712036) (xy 62.725985 -90.726915) (xy 62.674656 -90.748727)
			(xy 62.620699 -90.762833) (xy 62.565262 -90.768933) (xy 62.509528 -90.766896) (xy 62.454685 -90.756766)
			(xy 62.401901 -90.738759) (xy 62.352301 -90.713258) (xy 62.306943 -90.680807) (xy 62.266794 -90.642098)
			(xy 62.232708 -90.597955) (xy 62.205412 -90.54932) (xy 62.185489 -90.497229) (xy 62.173363 -90.442792)
			(xy 62.169292 -90.38717) (xy 60.853318 -90.38717) (xy 60.854335 -90.394082) (xy 60.854844 -90.421968)
			(xy 60.854335 -90.449854) (xy 60.846215 -90.50503) (xy 60.830147 -90.558437) (xy 60.806475 -90.608934)
			(xy 60.775702 -90.655447) (xy 60.738485 -90.696984) (xy 60.695617 -90.732659) (xy 60.648011 -90.761713)
			(xy 60.596682 -90.783525) (xy 60.542725 -90.797631) (xy 60.487288 -90.803731) (xy 60.431554 -90.801694)
			(xy 60.376711 -90.791564) (xy 60.323927 -90.773557) (xy 60.274327 -90.748056) (xy 60.228969 -90.715605)
			(xy 60.18882 -90.676896) (xy 60.154734 -90.632753) (xy 60.127438 -90.584118) (xy 60.107515 -90.532027)
			(xy 60.095389 -90.47759) (xy 60.091318 -90.421968) (xy 59.618813 -90.421968) (xy 59.633398 -90.449655)
			(xy 59.646058 -90.466926) (xy 59.66244 -90.489183) (xy 59.689361 -90.537444) (xy 59.709036 -90.589085)
			(xy 59.721054 -90.643025) (xy 59.725162 -90.698134) (xy 59.721275 -90.753259) (xy 59.709474 -90.807247)
			(xy 59.690006 -90.858966) (xy 59.663279 -90.907335) (xy 59.629851 -90.951341) (xy 59.590424 -90.990063)
			(xy 59.545822 -91.02269) (xy 59.496978 -91.04854) (xy 59.444916 -91.06707) (xy 59.390724 -91.077895)
			(xy 59.335537 -91.080786) (xy 59.280511 -91.075683) (xy 59.226798 -91.062694) (xy 59.17552 -91.04209)
			(xy 59.127753 -91.014302) (xy 59.084495 -90.979911) (xy 59.046653 -90.939639) (xy 59.015018 -90.894328)
			(xy 58.990252 -90.844926) (xy 58.972875 -90.792467) (xy 58.963249 -90.73805) (xy 58.961576 -90.682813)
			(xy 58.398156 -90.682813) (xy 58.398156 -91.18727) (xy 64.791334 -91.18727) (xy 64.795405 -91.131648)
			(xy 64.807531 -91.077211) (xy 64.827454 -91.02512) (xy 64.85475 -90.976485) (xy 64.888836 -90.932342)
			(xy 64.928985 -90.893633) (xy 64.974343 -90.861182) (xy 65.023943 -90.835681) (xy 65.076727 -90.817674)
			(xy 65.13157 -90.807544) (xy 65.187304 -90.805507) (xy 65.242741 -90.811607) (xy 65.296698 -90.825713)
			(xy 65.348027 -90.847525) (xy 65.395633 -90.876579) (xy 65.438501 -90.912254) (xy 65.475718 -90.953791)
			(xy 65.506491 -91.000304) (xy 65.530163 -91.050801) (xy 65.546231 -91.104208) (xy 65.554351 -91.159384)
			(xy 65.55486 -91.18727) (xy 65.554351 -91.215156) (xy 65.546231 -91.270332) (xy 65.530163 -91.323739)
			(xy 65.506491 -91.374236) (xy 65.475718 -91.420749) (xy 65.438501 -91.462286) (xy 65.395633 -91.497961)
			(xy 65.348027 -91.527015) (xy 65.296698 -91.548827) (xy 65.242741 -91.562933) (xy 65.187304 -91.569033)
			(xy 65.13157 -91.566996) (xy 65.076727 -91.556866) (xy 65.023943 -91.538859) (xy 64.974343 -91.513358)
			(xy 64.928985 -91.480907) (xy 64.888836 -91.442198) (xy 64.85475 -91.398055) (xy 64.827454 -91.34942)
			(xy 64.807531 -91.297329) (xy 64.795405 -91.242892) (xy 64.791334 -91.18727) (xy 58.398156 -91.18727)
			(xy 58.398156 -91.37396) (xy 58.398588 -91.395669) (xy 58.405953 -91.438459) (xy 58.420491 -91.479371)
			(xy 58.441779 -91.517213) (xy 58.469195 -91.55088) (xy 58.501941 -91.579391) (xy 58.53906 -91.601914)
			(xy 58.579471 -91.617793) (xy 58.621995 -91.626564) (xy 58.66539 -91.62797) (xy 58.686954 -91.62542)
			(xy 58.713938 -91.622168) (xy 58.768287 -91.622426) (xy 58.822049 -91.630393) (xy 58.874137 -91.645908)
			(xy 58.923496 -91.668657) (xy 58.969129 -91.698179) (xy 59.010111 -91.733877) (xy 59.045613 -91.775028)
			(xy 59.074917 -91.820801) (xy 59.09743 -91.870268) (xy 59.112697 -91.922429) (xy 59.120408 -91.976229)
			(xy 59.120407 -92.030579) (xy 59.112695 -92.084378) (xy 59.097427 -92.136539) (xy 59.074913 -92.186006)
			(xy 59.045608 -92.231778) (xy 59.010105 -92.272929) (xy 58.969123 -92.308626) (xy 58.923887 -92.33789)
			(xy 61.745112 -92.33789) (xy 61.749183 -92.282268) (xy 61.761309 -92.227831) (xy 61.781232 -92.17574)
			(xy 61.808528 -92.127105) (xy 61.842614 -92.082962) (xy 61.882763 -92.044253) (xy 61.928121 -92.011802)
			(xy 61.977721 -91.986301) (xy 62.030505 -91.968294) (xy 62.085348 -91.958164) (xy 62.141082 -91.956127)
			(xy 62.196519 -91.962227) (xy 62.250476 -91.976333) (xy 62.301805 -91.998145) (xy 62.349411 -92.027199)
			(xy 62.392279 -92.062874) (xy 62.429496 -92.104411) (xy 62.460269 -92.150924) (xy 62.483941 -92.201421)
			(xy 62.500009 -92.254828) (xy 62.508129 -92.310004) (xy 62.508638 -92.33789) (xy 62.508129 -92.365776)
			(xy 62.500009 -92.420952) (xy 62.483941 -92.474359) (xy 62.460269 -92.524856) (xy 62.429496 -92.571369)
			(xy 62.392279 -92.612906) (xy 62.349411 -92.648581) (xy 62.301805 -92.677635) (xy 62.250476 -92.699447)
			(xy 62.196519 -92.713553) (xy 62.141082 -92.719653) (xy 62.085348 -92.717616) (xy 62.030505 -92.707486)
			(xy 61.977721 -92.689479) (xy 61.928121 -92.663978) (xy 61.882763 -92.631527) (xy 61.842614 -92.592818)
			(xy 61.808528 -92.548675) (xy 61.781232 -92.50004) (xy 61.761309 -92.447949) (xy 61.749183 -92.393512)
			(xy 61.745112 -92.33789) (xy 58.923887 -92.33789) (xy 58.92349 -92.338147) (xy 58.87413 -92.360894)
			(xy 58.822041 -92.376408) (xy 58.768279 -92.384374) (xy 58.71393 -92.384632) (xy 58.686954 -92.381324)
			(xy 58.665396 -92.378793) (xy 58.622017 -92.380247) (xy 58.579516 -92.389048) (xy 58.539128 -92.404943)
			(xy 58.502027 -92.427468) (xy 58.469293 -92.455968) (xy 58.441876 -92.489616) (xy 58.420574 -92.527432)
			(xy 58.406006 -92.568317) (xy 58.398596 -92.611083) (xy 58.398156 -92.632784) (xy 58.398156 -92.760292)
			(xy 58.398541 -92.780781) (xy 58.405113 -92.821228) (xy 58.418105 -92.860091) (xy 58.437177 -92.896359)
			(xy 58.44921 -92.912946) (xy 58.44921 -93.23578) (xy 58.834526 -93.23578) (xy 58.838597 -93.180158)
			(xy 58.850723 -93.125721) (xy 58.870646 -93.07363) (xy 58.897942 -93.024995) (xy 58.932028 -92.980852)
			(xy 58.972177 -92.942143) (xy 59.017535 -92.909692) (xy 59.067135 -92.884191) (xy 59.119919 -92.866184)
			(xy 59.174762 -92.856054) (xy 59.230496 -92.854017) (xy 59.285933 -92.860117) (xy 59.33989 -92.874223)
			(xy 59.391219 -92.896035) (xy 59.438825 -92.925089) (xy 59.481693 -92.960764) (xy 59.51891 -93.002301)
			(xy 59.549683 -93.048814) (xy 59.573355 -93.099311) (xy 59.589423 -93.152718) (xy 59.597543 -93.207894)
			(xy 59.598052 -93.23578) (xy 59.597543 -93.263666) (xy 59.589423 -93.318842) (xy 59.573355 -93.372249)
			(xy 59.549683 -93.422746) (xy 59.51891 -93.469259) (xy 59.481693 -93.510796) (xy 59.438825 -93.546471)
			(xy 59.391219 -93.575525) (xy 59.33989 -93.597337) (xy 59.285933 -93.611443) (xy 59.230496 -93.617543)
			(xy 59.174762 -93.615506) (xy 59.119919 -93.605376) (xy 59.067135 -93.587369) (xy 59.017535 -93.561868)
			(xy 58.972177 -93.529417) (xy 58.932028 -93.490708) (xy 58.897942 -93.446565) (xy 58.870646 -93.39793)
			(xy 58.850723 -93.345839) (xy 58.838597 -93.291402) (xy 58.834526 -93.23578) (xy 58.44921 -93.23578)
			(xy 58.44921 -93.343222) (xy 58.215784 -93.576648) (xy 58.206132 -93.603318) (xy 58.196192 -93.629428)
			(xy 58.169769 -93.678653) (xy 58.136451 -93.723499) (xy 58.09695 -93.763007) (xy 58.052109 -93.796333)
			(xy 58.002889 -93.822765) (xy 57.97677 -93.83268) (xy 57.9501 -93.842332) (xy 57.918096 -93.874336)
			(xy 59.962794 -93.874336) (xy 59.966865 -93.818714) (xy 59.978991 -93.764277) (xy 59.998914 -93.712186)
			(xy 60.02621 -93.663551) (xy 60.060296 -93.619408) (xy 60.100445 -93.580699) (xy 60.145803 -93.548248)
			(xy 60.195403 -93.522747) (xy 60.248187 -93.50474) (xy 60.30303 -93.49461) (xy 60.358764 -93.492573)
			(xy 60.414201 -93.498673) (xy 60.468158 -93.512779) (xy 60.519487 -93.534591) (xy 60.567093 -93.563645)
			(xy 60.574172 -93.569536) (xy 61.359794 -93.569536) (xy 61.363865 -93.513914) (xy 61.375991 -93.459477)
			(xy 61.395914 -93.407386) (xy 61.42321 -93.358751) (xy 61.457296 -93.314608) (xy 61.497445 -93.275899)
			(xy 61.542803 -93.243448) (xy 61.592403 -93.217947) (xy 61.645187 -93.19994) (xy 61.70003 -93.18981)
			(xy 61.755764 -93.187773) (xy 61.811201 -93.193873) (xy 61.865158 -93.207979) (xy 61.916487 -93.229791)
			(xy 61.964093 -93.258845) (xy 62.006961 -93.29452) (xy 62.044178 -93.336057) (xy 62.074951 -93.38257)
			(xy 62.098623 -93.433067) (xy 62.114691 -93.486474) (xy 62.122811 -93.54165) (xy 62.12332 -93.569536)
			(xy 62.122811 -93.597422) (xy 62.114691 -93.652598) (xy 62.098623 -93.706005) (xy 62.074951 -93.756502)
			(xy 62.044178 -93.803015) (xy 62.006961 -93.844552) (xy 61.964093 -93.880227) (xy 61.916487 -93.909281)
			(xy 61.865158 -93.931093) (xy 61.811201 -93.945199) (xy 61.755764 -93.951299) (xy 61.70003 -93.949262)
			(xy 61.645187 -93.939132) (xy 61.592403 -93.921125) (xy 61.542803 -93.895624) (xy 61.497445 -93.863173)
			(xy 61.457296 -93.824464) (xy 61.42321 -93.780321) (xy 61.395914 -93.731686) (xy 61.375991 -93.679595)
			(xy 61.363865 -93.625158) (xy 61.359794 -93.569536) (xy 60.574172 -93.569536) (xy 60.609961 -93.59932)
			(xy 60.647178 -93.640857) (xy 60.677951 -93.68737) (xy 60.701623 -93.737867) (xy 60.717691 -93.791274)
			(xy 60.725811 -93.84645) (xy 60.72632 -93.874336) (xy 60.725811 -93.902222) (xy 60.717691 -93.957398)
			(xy 60.701623 -94.010805) (xy 60.677951 -94.061302) (xy 60.647178 -94.107815) (xy 60.609961 -94.149352)
			(xy 60.567093 -94.185027) (xy 60.519487 -94.214081) (xy 60.468158 -94.235893) (xy 60.414201 -94.249999)
			(xy 60.358764 -94.256099) (xy 60.30303 -94.254062) (xy 60.248187 -94.243932) (xy 60.195403 -94.225925)
			(xy 60.145803 -94.200424) (xy 60.100445 -94.167973) (xy 60.060296 -94.129264) (xy 60.02621 -94.085121)
			(xy 59.998914 -94.036486) (xy 59.978991 -93.984395) (xy 59.966865 -93.929958) (xy 59.962794 -93.874336)
			(xy 57.918096 -93.874336) (xy 57.050686 -94.741746) (xy 50.062638 -94.741746) (xy 50.046849 -94.74223)
			(xy 50.016243 -94.750001) (xy 49.988484 -94.765054) (xy 49.965273 -94.786463) (xy 49.956212 -94.799404)
			(xy 49.943486 -94.8182) (xy 58.040522 -94.8182) (xy 58.044593 -94.762578) (xy 58.056719 -94.708141)
			(xy 58.076642 -94.65605) (xy 58.103938 -94.607415) (xy 58.138024 -94.563272) (xy 58.178173 -94.524563)
			(xy 58.223531 -94.492112) (xy 58.273131 -94.466611) (xy 58.325915 -94.448604) (xy 58.380758 -94.438474)
			(xy 58.436492 -94.436437) (xy 58.491929 -94.442537) (xy 58.545886 -94.456643) (xy 58.597215 -94.478455)
			(xy 58.644821 -94.507509) (xy 58.687689 -94.543184) (xy 58.724906 -94.584721) (xy 58.755679 -94.631234)
			(xy 58.779351 -94.681731) (xy 58.795419 -94.735138) (xy 58.803539 -94.790314) (xy 58.804048 -94.8182)
			(xy 58.803539 -94.846086) (xy 58.795419 -94.901262) (xy 58.779351 -94.954669) (xy 58.755679 -95.005166)
			(xy 58.725445 -95.050864) (xy 65.794126 -95.050864) (xy 65.798197 -94.995242) (xy 65.810323 -94.940805)
			(xy 65.830246 -94.888714) (xy 65.857542 -94.840079) (xy 65.891628 -94.795936) (xy 65.931777 -94.757227)
			(xy 65.977135 -94.724776) (xy 66.026735 -94.699275) (xy 66.079519 -94.681268) (xy 66.134362 -94.671138)
			(xy 66.190096 -94.669101) (xy 66.245533 -94.675201) (xy 66.29949 -94.689307) (xy 66.350819 -94.711119)
			(xy 66.398425 -94.740173) (xy 66.441293 -94.775848) (xy 66.47851 -94.817385) (xy 66.509283 -94.863898)
			(xy 66.532955 -94.914395) (xy 66.549023 -94.967802) (xy 66.557143 -95.022978) (xy 66.557652 -95.050864)
			(xy 66.557143 -95.07875) (xy 66.549023 -95.133926) (xy 66.532955 -95.187333) (xy 66.509283 -95.23783)
			(xy 66.47851 -95.284343) (xy 66.441293 -95.32588) (xy 66.398425 -95.361555) (xy 66.350819 -95.390609)
			(xy 66.29949 -95.412421) (xy 66.245533 -95.426527) (xy 66.190096 -95.432627) (xy 66.134362 -95.43059)
			(xy 66.079519 -95.42046) (xy 66.026735 -95.402453) (xy 65.977135 -95.376952) (xy 65.931777 -95.344501)
			(xy 65.891628 -95.305792) (xy 65.857542 -95.261649) (xy 65.830246 -95.213014) (xy 65.810323 -95.160923)
			(xy 65.798197 -95.106486) (xy 65.794126 -95.050864) (xy 58.725445 -95.050864) (xy 58.724906 -95.051679)
			(xy 58.687689 -95.093216) (xy 58.644821 -95.128891) (xy 58.597215 -95.157945) (xy 58.545886 -95.179757)
			(xy 58.491929 -95.193863) (xy 58.436492 -95.199963) (xy 58.380758 -95.197926) (xy 58.325915 -95.187796)
			(xy 58.273131 -95.169789) (xy 58.223531 -95.144288) (xy 58.178173 -95.111837) (xy 58.138024 -95.073128)
			(xy 58.103938 -95.028985) (xy 58.076642 -94.98035) (xy 58.056719 -94.928259) (xy 58.044593 -94.873822)
			(xy 58.040522 -94.8182) (xy 49.943486 -94.8182) (xy 49.941034 -94.821822) (xy 49.905355 -94.86254)
			(xy 49.864277 -94.897804) (xy 49.818625 -94.926905) (xy 49.769317 -94.949259) (xy 49.717343 -94.964415)
			(xy 49.663749 -94.972071) (xy 49.609611 -94.972071) (xy 49.556017 -94.964415) (xy 49.504043 -94.949259)
			(xy 49.454735 -94.926905) (xy 49.409083 -94.897804) (xy 49.368005 -94.86254) (xy 49.332326 -94.821822)
			(xy 49.317148 -94.799404) (xy 49.308126 -94.786434) (xy 49.284906 -94.765025) (xy 49.257133 -94.749984)
			(xy 49.226514 -94.742236) (xy 49.210722 -94.741746) (xy 46.052232 -94.741746) (xy 45.168312 -95.625666)
			(xy 46.368714 -95.625666) (xy 46.372785 -95.570044) (xy 46.384911 -95.515607) (xy 46.404834 -95.463516)
			(xy 46.43213 -95.414881) (xy 46.466216 -95.370738) (xy 46.506365 -95.332029) (xy 46.551723 -95.299578)
			(xy 46.601323 -95.274077) (xy 46.654107 -95.25607) (xy 46.70895 -95.24594) (xy 46.764684 -95.243903)
			(xy 46.820121 -95.250003) (xy 46.874078 -95.264109) (xy 46.925407 -95.285921) (xy 46.973013 -95.314975)
			(xy 47.015881 -95.35065) (xy 47.053098 -95.392187) (xy 47.083871 -95.4387) (xy 47.107543 -95.489197)
			(xy 47.123611 -95.542604) (xy 47.131731 -95.59778) (xy 47.13224 -95.625666) (xy 47.131731 -95.653552)
			(xy 47.123611 -95.708728) (xy 47.107543 -95.762135) (xy 47.083871 -95.812632) (xy 47.053098 -95.859145)
			(xy 47.017643 -95.898716) (xy 48.558956 -95.898716) (xy 48.563027 -95.843094) (xy 48.575153 -95.788657)
			(xy 48.595076 -95.736566) (xy 48.622372 -95.687931) (xy 48.656458 -95.643788) (xy 48.696607 -95.605079)
			(xy 48.741965 -95.572628) (xy 48.791565 -95.547127) (xy 48.844349 -95.52912) (xy 48.899192 -95.51899)
			(xy 48.954926 -95.516953) (xy 49.010363 -95.523053) (xy 49.06432 -95.537159) (xy 49.115649 -95.558971)
			(xy 49.163255 -95.588025) (xy 49.206123 -95.6237) (xy 49.24334 -95.665237) (xy 49.274113 -95.71175)
			(xy 49.286507 -95.738188) (xy 51.135024 -95.738188) (xy 51.139095 -95.682566) (xy 51.151221 -95.628129)
			(xy 51.171144 -95.576038) (xy 51.19844 -95.527403) (xy 51.232526 -95.48326) (xy 51.272675 -95.444551)
			(xy 51.318033 -95.4121) (xy 51.367633 -95.386599) (xy 51.420417 -95.368592) (xy 51.47526 -95.358462)
			(xy 51.530994 -95.356425) (xy 51.586431 -95.362525) (xy 51.640388 -95.376631) (xy 51.691717 -95.398443)
			(xy 51.739323 -95.427497) (xy 51.782191 -95.463172) (xy 51.819408 -95.504709) (xy 51.850181 -95.551222)
			(xy 51.873853 -95.601719) (xy 51.889921 -95.655126) (xy 51.898041 -95.710302) (xy 51.89855 -95.738188)
			(xy 51.898041 -95.766074) (xy 51.889921 -95.82125) (xy 51.873853 -95.874657) (xy 51.850181 -95.925154)
			(xy 51.819408 -95.971667) (xy 51.782191 -96.013204) (xy 51.739323 -96.048879) (xy 51.691717 -96.077933)
			(xy 51.640388 -96.099745) (xy 51.586431 -96.113851) (xy 51.530994 -96.119951) (xy 51.47526 -96.117914)
			(xy 51.420417 -96.107784) (xy 51.367633 -96.089777) (xy 51.318033 -96.064276) (xy 51.272675 -96.031825)
			(xy 51.232526 -95.993116) (xy 51.19844 -95.948973) (xy 51.171144 -95.900338) (xy 51.151221 -95.848247)
			(xy 51.139095 -95.79381) (xy 51.135024 -95.738188) (xy 49.286507 -95.738188) (xy 49.297785 -95.762247)
			(xy 49.313853 -95.815654) (xy 49.321973 -95.87083) (xy 49.322482 -95.898716) (xy 49.321973 -95.926602)
			(xy 49.313853 -95.981778) (xy 49.297785 -96.035185) (xy 49.274113 -96.085682) (xy 49.24334 -96.132195)
			(xy 49.206123 -96.173732) (xy 49.163255 -96.209407) (xy 49.115649 -96.238461) (xy 49.06432 -96.260273)
			(xy 49.010363 -96.274379) (xy 48.954926 -96.280479) (xy 48.899192 -96.278442) (xy 48.844349 -96.268312)
			(xy 48.791565 -96.250305) (xy 48.741965 -96.224804) (xy 48.696607 -96.192353) (xy 48.656458 -96.153644)
			(xy 48.622372 -96.109501) (xy 48.595076 -96.060866) (xy 48.575153 -96.008775) (xy 48.563027 -95.954338)
			(xy 48.558956 -95.898716) (xy 47.017643 -95.898716) (xy 47.015881 -95.900682) (xy 46.973013 -95.936357)
			(xy 46.925407 -95.965411) (xy 46.874078 -95.987223) (xy 46.820121 -96.001329) (xy 46.764684 -96.007429)
			(xy 46.70895 -96.005392) (xy 46.654107 -95.995262) (xy 46.601323 -95.977255) (xy 46.551723 -95.951754)
			(xy 46.506365 -95.919303) (xy 46.466216 -95.880594) (xy 46.43213 -95.836451) (xy 46.404834 -95.787816)
			(xy 46.384911 -95.735725) (xy 46.372785 -95.681288) (xy 46.368714 -95.625666) (xy 45.168312 -95.625666)
			(xy 45.09897 -95.695008) (xy 45.091096 -95.731076) (xy 45.084772 -95.75736) (xy 45.065709 -95.807946)
			(xy 45.039696 -95.855336) (xy 45.007254 -95.898578) (xy 44.969032 -95.936807) (xy 44.925796 -95.969258)
			(xy 44.878412 -95.995279) (xy 44.827828 -96.014351) (xy 44.801536 -96.020636) (xy 44.765468 -96.02851)
			(xy 44.73829 -96.055688) (xy 44.722492 -96.072175) (xy 44.696502 -96.109714) (xy 44.677635 -96.151292)
			(xy 44.666496 -96.19557) (xy 44.663444 -96.241126) (xy 44.668577 -96.286495) (xy 44.68173 -96.330217)
			(xy 44.70248 -96.370888) (xy 44.73016 -96.407199) (xy 44.746672 -96.422972) (xy 44.766982 -96.442181)
			(xy 44.802319 -96.485497) (xy 44.830956 -96.533506) (xy 44.852281 -96.58518) (xy 44.865838 -96.639412)
			(xy 44.871336 -96.695042) (xy 44.870887 -96.704404) (xy 46.626778 -96.704404) (xy 46.630849 -96.648782)
			(xy 46.642975 -96.594345) (xy 46.662898 -96.542254) (xy 46.690194 -96.493619) (xy 46.72428 -96.449476)
			(xy 46.764429 -96.410767) (xy 46.809787 -96.378316) (xy 46.859387 -96.352815) (xy 46.912171 -96.334808)
			(xy 46.967014 -96.324678) (xy 47.022748 -96.322641) (xy 47.078185 -96.328741) (xy 47.132142 -96.342847)
			(xy 47.183471 -96.364659) (xy 47.231077 -96.393713) (xy 47.273945 -96.429388) (xy 47.311162 -96.470925)
			(xy 47.341935 -96.517438) (xy 47.365607 -96.567935) (xy 47.381675 -96.621342) (xy 47.389795 -96.676518)
			(xy 47.390304 -96.704404) (xy 47.389795 -96.73229) (xy 47.381675 -96.787466) (xy 47.365607 -96.840873)
			(xy 47.341935 -96.89137) (xy 47.311162 -96.937883) (xy 47.273945 -96.97942) (xy 47.231077 -97.015095)
			(xy 47.183471 -97.044149) (xy 47.132142 -97.065961) (xy 47.078185 -97.080067) (xy 47.022748 -97.086167)
			(xy 46.967014 -97.08413) (xy 46.912171 -97.074) (xy 46.859387 -97.055993) (xy 46.809787 -97.030492)
			(xy 46.764429 -96.998041) (xy 46.72428 -96.959332) (xy 46.690194 -96.915189) (xy 46.662898 -96.866554)
			(xy 46.642975 -96.814463) (xy 46.630849 -96.760026) (xy 46.626778 -96.704404) (xy 44.870887 -96.704404)
			(xy 44.868657 -96.750879) (xy 44.857858 -96.805728) (xy 44.839172 -96.858413) (xy 44.812997 -96.907808)
			(xy 44.779895 -96.952855) (xy 44.740574 -96.992589) (xy 44.718478 -97.009712) (xy 44.69638 -97.026222)
			(xy 44.648628 -97.11436) (xy 44.64812 -97.176844) (xy 44.662344 -97.204784) (xy 44.673832 -97.228127)
			(xy 44.691082 -97.277211) (xy 44.701501 -97.328183) (xy 44.704843 -97.379282) (xy 48.789842 -97.379282)
			(xy 48.793913 -97.32366) (xy 48.806039 -97.269223) (xy 48.825962 -97.217132) (xy 48.853258 -97.168497)
			(xy 48.887344 -97.124354) (xy 48.927493 -97.085645) (xy 48.972851 -97.053194) (xy 49.022451 -97.027693)
			(xy 49.075235 -97.009686) (xy 49.130078 -96.999556) (xy 49.185812 -96.997519) (xy 49.241249 -97.003619)
			(xy 49.295206 -97.017725) (xy 49.346535 -97.039537) (xy 49.394141 -97.068591) (xy 49.437009 -97.104266)
			(xy 49.474226 -97.145803) (xy 49.504999 -97.192316) (xy 49.528671 -97.242813) (xy 49.544739 -97.29622)
			(xy 49.552859 -97.351396) (xy 49.553368 -97.379282) (xy 49.552859 -97.407168) (xy 49.544739 -97.462344)
			(xy 49.528671 -97.515751) (xy 49.504999 -97.566248) (xy 49.474226 -97.612761) (xy 49.437009 -97.654298)
			(xy 49.394141 -97.689973) (xy 49.346535 -97.719027) (xy 49.295206 -97.740839) (xy 49.241249 -97.754945)
			(xy 49.185812 -97.761045) (xy 49.130078 -97.759008) (xy 49.075235 -97.748878) (xy 49.022451 -97.730871)
			(xy 48.972851 -97.70537) (xy 48.927493 -97.672919) (xy 48.887344 -97.63421) (xy 48.853258 -97.590067)
			(xy 48.825962 -97.541432) (xy 48.806039 -97.489341) (xy 48.793913 -97.434904) (xy 48.789842 -97.379282)
			(xy 44.704843 -97.379282) (xy 44.704896 -97.380099) (xy 44.701203 -97.431994) (xy 44.69049 -97.482906)
			(xy 44.682156 -97.507552) (xy 44.675016 -97.528921) (xy 44.667538 -97.573347) (xy 44.668013 -97.618395)
			(xy 44.676425 -97.662653) (xy 44.692511 -97.704734) (xy 44.715766 -97.743318) (xy 44.745462 -97.777196)
			(xy 44.780667 -97.805306) (xy 44.800266 -97.816416) (xy 44.824288 -97.830004) (xy 44.8685 -97.863037)
			(xy 44.88338 -97.877943) (xy 51.403908 -97.877943) (xy 51.405158 -97.822943) (xy 51.414293 -97.768694)
			(xy 51.431126 -97.716318) (xy 51.455306 -97.666903) (xy 51.486332 -97.621473) (xy 51.523562 -97.58097)
			(xy 51.566222 -97.546234) (xy 51.613429 -97.517985) (xy 51.664204 -97.496809) (xy 51.717494 -97.483144)
			(xy 51.772193 -97.477275) (xy 51.827169 -97.479322) (xy 51.881281 -97.489244) (xy 51.933406 -97.506834)
			(xy 51.982465 -97.531728) (xy 52.00523 -97.547176) (xy 52.023664 -97.559607) (xy 52.063895 -97.578527)
			(xy 52.106806 -97.590152) (xy 52.151086 -97.594127) (xy 52.195382 -97.590331) (xy 52.238339 -97.578879)
			(xy 52.278647 -97.560122) (xy 52.315072 -97.534632) (xy 52.331112 -97.519236) (xy 53.370226 -96.480376)
			(xy 54.812692 -96.480376) (xy 55.122826 -96.79051) (xy 55.134998 -96.801912) (xy 55.16387 -96.818581)
			(xy 55.196073 -96.82721) (xy 55.229411 -96.82721) (xy 55.261614 -96.818581) (xy 55.290486 -96.801912)
			(xy 55.302658 -96.79051) (xy 55.449216 -96.643952) (xy 57.61228 -96.643952) (xy 58.456576 -97.488248)
			(xy 58.478811 -97.511192) (xy 58.517972 -97.561678) (xy 58.550497 -97.616674) (xy 58.575872 -97.675313)
			(xy 58.593698 -97.73667) (xy 58.603693 -97.799777) (xy 58.6057 -97.863639) (xy 58.599687 -97.92725)
			(xy 58.585749 -97.989604) (xy 58.564106 -98.049721) (xy 58.535099 -98.106651) (xy 58.499185 -98.159496)
			(xy 58.456931 -98.207423) (xy 58.409004 -98.249677) (xy 58.356159 -98.285591) (xy 58.299229 -98.314598)
			(xy 58.239112 -98.336241) (xy 58.176758 -98.350179) (xy 58.113147 -98.356192) (xy 58.049285 -98.354185)
			(xy 57.986178 -98.34419) (xy 57.924821 -98.326364) (xy 57.866182 -98.300989) (xy 57.811186 -98.268464)
			(xy 57.7607 -98.229303) (xy 57.737756 -98.207068) (xy 57.503822 -97.973388) (xy 57.487347 -97.957514)
			(xy 57.449725 -97.931488) (xy 57.408052 -97.912615) (xy 57.363673 -97.901507) (xy 57.318023 -97.898521)
			(xy 57.272576 -97.903754) (xy 57.228799 -97.917037) (xy 57.188107 -97.937941) (xy 57.151813 -97.96579)
			(xy 57.12109 -97.999687) (xy 57.108598 -98.018854) (xy 57.093774 -98.041778) (xy 57.058627 -98.083548)
			(xy 57.017885 -98.119884) (xy 56.972381 -98.150042) (xy 56.923044 -98.173407) (xy 56.87088 -98.189502)
			(xy 56.816955 -98.197999) (xy 56.76237 -98.198724) (xy 56.708238 -98.191663) (xy 56.655665 -98.176959)
			(xy 56.605724 -98.154913) (xy 56.559435 -98.125974) (xy 56.517743 -98.090734) (xy 56.481498 -98.049912)
			(xy 56.451442 -98.004341) (xy 56.428186 -97.954952) (xy 56.412207 -97.902752) (xy 56.407558 -97.875852)
			(xy 56.403612 -97.853662) (xy 56.388975 -97.81104) (xy 56.36706 -97.771662) (xy 56.338552 -97.73676)
			(xy 56.304342 -97.707425) (xy 56.2655 -97.684574) (xy 56.22324 -97.668922) (xy 56.178884 -97.660958)
			(xy 56.156352 -97.66046) (xy 55.870348 -97.66046) (xy 55.384192 -98.146616) (xy 55.362453 -98.167734)
			(xy 55.314824 -98.205219) (xy 55.263078 -98.236776) (xy 55.207948 -98.261959) (xy 55.150215 -98.28041)
			(xy 55.12054 -98.28657) (xy 55.097746 -98.291487) (xy 55.054317 -98.308445) (xy 55.01471 -98.333043)
			(xy 54.980257 -98.364454) (xy 54.952113 -98.401624) (xy 54.931223 -98.443305) (xy 54.918288 -98.488098)
			(xy 54.913743 -98.534499) (xy 54.91774 -98.580951) (xy 54.923436 -98.603562) (xy 54.930429 -98.630744)
			(xy 54.93728 -98.686449) (xy 54.935894 -98.742557) (xy 54.926304 -98.797856) (xy 54.908714 -98.851154)
			(xy 54.883506 -98.901299) (xy 54.851223 -98.94721) (xy 54.812561 -98.987895) (xy 54.768356 -99.022477)
			(xy 54.719561 -99.050209) (xy 54.66723 -99.070493) (xy 54.612491 -99.08289) (xy 54.556527 -99.087134)
			(xy 54.500545 -99.083133) (xy 54.445753 -99.070972) (xy 54.393334 -99.050915) (xy 54.34442 -99.023395)
			(xy 54.300065 -98.989005) (xy 54.261228 -98.948487) (xy 54.228747 -98.902716) (xy 54.203321 -98.852681)
			(xy 54.185501 -98.79946) (xy 54.175671 -98.744203) (xy 54.174043 -98.688101) (xy 54.180652 -98.632367)
			(xy 54.195356 -98.578202) (xy 54.217837 -98.526776) (xy 54.232302 -98.502724) (xy 54.243586 -98.483749)
			(xy 54.260181 -98.442845) (xy 54.269457 -98.399689) (xy 54.271135 -98.355579) (xy 54.265164 -98.311842)
			(xy 54.251723 -98.269796) (xy 54.231218 -98.230706) (xy 54.204265 -98.195748) (xy 54.171676 -98.165974)
			(xy 54.153308 -98.153728) (xy 54.130601 -98.138743) (xy 54.089288 -98.103344) (xy 54.053428 -98.062432)
			(xy 54.023747 -98.016837) (xy 54.000849 -97.967486) (xy 53.985199 -97.915382) (xy 53.977114 -97.861582)
			(xy 53.97676 -97.807179) (xy 53.984143 -97.753278) (xy 53.999113 -97.700974) (xy 54.009798 -97.675954)
			(xy 54.020974 -97.651062) (xy 54.020974 -97.623884) (xy 54.020519 -97.607226) (xy 54.011892 -97.575047)
			(xy 53.99523 -97.546198) (xy 53.971668 -97.522644) (xy 53.942814 -97.505992) (xy 53.910632 -97.497375)
			(xy 53.893974 -97.496884) (xy 53.791358 -97.496884) (xy 52.63007 -98.658172) (xy 52.606917 -98.680619)
			(xy 52.555921 -98.720092) (xy 52.500341 -98.752798) (xy 52.441071 -98.778211) (xy 52.379062 -98.795923)
			(xy 52.315312 -98.805649) (xy 52.250843 -98.807234) (xy 52.186691 -98.800651) (xy 52.123887 -98.786007)
			(xy 52.06344 -98.763537) (xy 52.006321 -98.733601) (xy 51.953447 -98.696681) (xy 51.905668 -98.653369)
			(xy 51.86375 -98.604362) (xy 51.828368 -98.550447) (xy 51.80009 -98.492489) (xy 51.77937 -98.43142)
			(xy 51.766541 -98.368221) (xy 51.763676 -98.3361) (xy 51.762063 -98.32091) (xy 51.752633 -98.291868)
			(xy 51.736556 -98.265908) (xy 51.714757 -98.244526) (xy 51.688492 -98.228954) (xy 51.674014 -98.224086)
			(xy 51.647873 -98.215508) (xy 51.598112 -98.192047) (xy 51.552237 -98.161683) (xy 51.511199 -98.125044)
			(xy 51.475847 -98.082892) (xy 51.446917 -98.0361) (xy 51.425006 -97.985638) (xy 51.41057 -97.932552)
			(xy 51.403908 -97.877943) (xy 44.88338 -97.877943) (xy 44.907491 -97.902095) (xy 44.940448 -97.946363)
			(xy 44.966684 -97.994917) (xy 44.985652 -98.046744) (xy 44.996954 -98.100763) (xy 45.000357 -98.155847)
			(xy 44.995788 -98.210847) (xy 44.983343 -98.264615) (xy 44.963282 -98.316029) (xy 44.936024 -98.364016)
			(xy 44.902136 -98.407576) (xy 44.882562 -98.427032) (xy 44.867072 -98.442496) (xy 44.841117 -98.477734)
			(xy 44.821592 -98.516903) (xy 44.809075 -98.55884) (xy 44.803937 -98.602303) (xy 44.806331 -98.646002)
			(xy 44.816186 -98.688644) (xy 44.833209 -98.728963) (xy 44.844716 -98.74758) (xy 44.859328 -98.771259)
			(xy 44.882283 -98.821943) (xy 44.897632 -98.875424) (xy 44.90505 -98.930566) (xy 44.904381 -98.986202)
			(xy 44.895638 -99.041151) (xy 44.879006 -99.094247) (xy 44.862818 -99.127818) (xy 48.952656 -99.127818)
			(xy 48.956727 -99.072196) (xy 48.968853 -99.017759) (xy 48.988776 -98.965668) (xy 49.016072 -98.917033)
			(xy 49.050158 -98.87289) (xy 49.090307 -98.834181) (xy 49.135665 -98.80173) (xy 49.185265 -98.776229)
			(xy 49.238049 -98.758222) (xy 49.292892 -98.748092) (xy 49.348626 -98.746055) (xy 49.404063 -98.752155)
			(xy 49.45802 -98.766261) (xy 49.509349 -98.788073) (xy 49.556955 -98.817127) (xy 49.599823 -98.852802)
			(xy 49.63704 -98.894339) (xy 49.667813 -98.940852) (xy 49.691485 -98.991349) (xy 49.707553 -99.044756)
			(xy 49.715673 -99.099932) (xy 49.715723 -99.102672) (xy 50.529488 -99.102672) (xy 50.533559 -99.04705)
			(xy 50.545685 -98.992613) (xy 50.565608 -98.940522) (xy 50.592904 -98.891887) (xy 50.62699 -98.847744)
			(xy 50.667139 -98.809035) (xy 50.712497 -98.776584) (xy 50.762097 -98.751083) (xy 50.814881 -98.733076)
			(xy 50.869724 -98.722946) (xy 50.925458 -98.720909) (xy 50.980895 -98.727009) (xy 51.034852 -98.741115)
			(xy 51.086181 -98.762927) (xy 51.133787 -98.791981) (xy 51.176655 -98.827656) (xy 51.213872 -98.869193)
			(xy 51.244645 -98.915706) (xy 51.268317 -98.966203) (xy 51.284385 -99.01961) (xy 51.292505 -99.074786)
			(xy 51.293014 -99.102672) (xy 51.292505 -99.130558) (xy 51.284385 -99.185734) (xy 51.268317 -99.239141)
			(xy 51.246613 -99.28544) (xy 55.012797 -99.28544) (xy 55.016868 -99.230576) (xy 55.028777 -99.176866)
			(xy 55.048278 -99.125423) (xy 55.074966 -99.077315) (xy 55.108288 -99.03354) (xy 55.147551 -98.995005)
			(xy 55.191944 -98.962509) (xy 55.240543 -98.936727) (xy 55.292342 -98.918193) (xy 55.346266 -98.907292)
			(xy 55.401196 -98.90425) (xy 55.455994 -98.90913) (xy 55.509523 -98.92183) (xy 55.560672 -98.942088)
			(xy 55.608381 -98.969483) (xy 55.630318 -98.986086) (xy 55.648996 -99.000121) (xy 55.690411 -99.021738)
			(xy 55.735078 -99.035422) (xy 55.781494 -99.040714) (xy 55.828096 -99.037434) (xy 55.873313 -99.025694)
			(xy 55.915624 -99.005889) (xy 55.953604 -98.978686) (xy 55.97017 -98.96221) (xy 55.989595 -98.942729)
			(xy 56.033007 -98.908942) (xy 56.080823 -98.881741) (xy 56.13205 -98.861691) (xy 56.185626 -98.849207)
			(xy 56.24044 -98.844548) (xy 56.295354 -98.84781) (xy 56.349231 -98.858927) (xy 56.400951 -98.877668)
			(xy 56.449444 -98.903643) (xy 56.493702 -98.936315) (xy 56.532809 -98.975005) (xy 56.565952 -99.018911)
			(xy 56.592445 -99.067122) (xy 56.611739 -99.118639) (xy 56.623432 -99.172393) (xy 56.627283 -99.22727)
			(xy 56.623211 -99.28213) (xy 56.611301 -99.335837) (xy 56.5918 -99.387275) (xy 56.576887 -99.414157)
			(xy 58.34861 -99.414157) (xy 58.353776 -99.358637) (xy 58.366968 -99.304461) (xy 58.387905 -99.252781)
			(xy 58.416142 -99.2047) (xy 58.451076 -99.16124) (xy 58.491964 -99.123328) (xy 58.537934 -99.091771)
			(xy 58.562748 -99.07905) (xy 58.577126 -99.071455) (xy 58.601758 -99.050242) (xy 58.620228 -99.023491)
			(xy 58.631334 -98.99294) (xy 58.634355 -98.960574) (xy 58.629096 -98.928495) (xy 58.622946 -98.913442)
			(xy 58.61209 -98.887762) (xy 58.59715 -98.834048) (xy 58.590186 -98.778732) (xy 58.591347 -98.722991)
			(xy 58.60061 -98.668013) (xy 58.617775 -98.614969) (xy 58.642478 -98.564988) (xy 58.674193 -98.519134)
			(xy 58.712244 -98.478385) (xy 58.75582 -98.443608) (xy 58.803994 -98.415543) (xy 58.85574 -98.394789)
			(xy 58.909956 -98.381788) (xy 58.965487 -98.376816) (xy 59.021149 -98.379979) (xy 59.075759 -98.391211)
			(xy 59.128153 -98.410271) (xy 59.177214 -98.436753) (xy 59.221899 -98.470095) (xy 59.237644 -98.485894)
			(xy 59.666689 -98.485894) (xy 59.670045 -98.430677) (xy 59.68134 -98.376525) (xy 59.700337 -98.324571)
			(xy 59.726638 -98.275905) (xy 59.759691 -98.231547) (xy 59.7789 -98.21164) (xy 59.790638 -98.199104)
			(xy 59.807524 -98.169214) (xy 59.815854 -98.13591) (xy 59.815028 -98.10159) (xy 59.805106 -98.068725)
			(xy 59.796426 -98.053906) (xy 59.782025 -98.030287) (xy 59.759428 -97.979796) (xy 59.744361 -97.926572)
			(xy 59.737138 -97.871729) (xy 59.737911 -97.816417) (xy 59.746665 -97.761798) (xy 59.763215 -97.709015)
			(xy 59.787214 -97.659176) (xy 59.81816 -97.613325) (xy 59.855403 -97.572424) (xy 59.898163 -97.537331)
			(xy 59.945542 -97.508781) (xy 59.996548 -97.487373) (xy 60.050112 -97.473556) (xy 60.105109 -97.467619)
			(xy 60.160387 -97.469688) (xy 60.214786 -97.479718) (xy 60.267167 -97.4975) (xy 60.316431 -97.52266)
			(xy 60.361544 -97.554671) (xy 60.401561 -97.592862) (xy 60.435644 -97.636431) (xy 60.463076 -97.684467)
			(xy 60.483284 -97.73596) (xy 60.495843 -97.789832) (xy 60.500489 -97.844953) (xy 60.499709 -97.857767)
			(xy 61.732877 -97.857767) (xy 61.738699 -97.802626) (xy 61.752441 -97.748909) (xy 61.773814 -97.697747)
			(xy 61.802368 -97.650218) (xy 61.837502 -97.607323) (xy 61.878475 -97.569965) (xy 61.924424 -97.538932)
			(xy 61.974381 -97.514878) (xy 62.027295 -97.498308) (xy 62.082049 -97.489573) (xy 62.137491 -97.488855)
			(xy 62.192454 -97.496171) (xy 62.245778 -97.511366) (xy 62.296341 -97.53412) (xy 62.343078 -97.563954)
			(xy 62.364366 -97.58172) (xy 62.377862 -97.592585) (xy 62.409191 -97.607343) (xy 62.443334 -97.613133)
			(xy 62.477777 -97.609529) (xy 62.509982 -97.596797) (xy 62.524132 -97.5868) (xy 62.546305 -97.570599)
			(xy 62.594402 -97.544099) (xy 62.6458 -97.524763) (xy 62.699437 -97.512987) (xy 62.754208 -97.509017)
			(xy 62.808983 -97.512933) (xy 62.862632 -97.524654) (xy 62.914049 -97.543939) (xy 62.962173 -97.57039)
			(xy 62.98438 -97.586546) (xy 63.003115 -97.600054) (xy 63.044379 -97.620793) (xy 63.08871 -97.633736)
			(xy 63.13465 -97.638458) (xy 63.180687 -97.634802) (xy 63.225306 -97.62289) (xy 63.267039 -97.603112)
			(xy 63.304513 -97.57612) (xy 63.336493 -97.542803) (xy 63.349632 -97.523808) (xy 63.364695 -97.501799)
			(xy 63.400006 -97.461832) (xy 63.44054 -97.427172) (xy 63.485506 -97.398496) (xy 63.534029 -97.376363)
			(xy 63.585161 -97.361204) (xy 63.637906 -97.353315) (xy 63.691236 -97.352849) (xy 63.744111 -97.359815)
			(xy 63.7955 -97.374079) (xy 63.844401 -97.395361) (xy 63.889862 -97.423246) (xy 63.930996 -97.457192)
			(xy 63.949326 -97.476564) (xy 63.964181 -97.492137) (xy 63.998187 -97.51851) (xy 64.036149 -97.538781)
			(xy 64.076981 -97.552371) (xy 64.119519 -97.558892) (xy 64.162547 -97.558157) (xy 64.204838 -97.550188)
			(xy 64.245183 -97.535211) (xy 64.264032 -97.524824) (xy 64.288252 -97.511414) (xy 64.339648 -97.490844)
			(xy 64.393477 -97.477919) (xy 64.448609 -97.472912) (xy 64.503885 -97.475927) (xy 64.558146 -97.486901)
			(xy 64.61025 -97.505603) (xy 64.659103 -97.531641) (xy 64.703679 -97.564467) (xy 64.743042 -97.603393)
			(xy 64.776364 -97.647599) (xy 64.802946 -97.696159) (xy 64.820073 -97.742248) (xy 66.780916 -97.742248)
			(xy 66.784987 -97.686626) (xy 66.797113 -97.632189) (xy 66.817036 -97.580098) (xy 66.844332 -97.531463)
			(xy 66.878418 -97.48732) (xy 66.918567 -97.448611) (xy 66.963925 -97.41616) (xy 67.013525 -97.390659)
			(xy 67.066309 -97.372652) (xy 67.121152 -97.362522) (xy 67.176886 -97.360485) (xy 67.232323 -97.366585)
			(xy 67.28628 -97.380691) (xy 67.337609 -97.402503) (xy 67.385215 -97.431557) (xy 67.428083 -97.467232)
			(xy 67.4653 -97.508769) (xy 67.496073 -97.555282) (xy 67.519745 -97.605779) (xy 67.535813 -97.659186)
			(xy 67.543933 -97.714362) (xy 67.544442 -97.742248) (xy 67.543933 -97.770134) (xy 67.537271 -97.8154)
			(xy 69.89648 -97.8154) (xy 69.900551 -97.759778) (xy 69.912677 -97.705341) (xy 69.9326 -97.65325)
			(xy 69.959896 -97.604615) (xy 69.993982 -97.560472) (xy 70.034131 -97.521763) (xy 70.079489 -97.489312)
			(xy 70.129089 -97.463811) (xy 70.181873 -97.445804) (xy 70.236716 -97.435674) (xy 70.29245 -97.433637)
			(xy 70.347887 -97.439737) (xy 70.401844 -97.453843) (xy 70.453173 -97.475655) (xy 70.500779 -97.504709)
			(xy 70.543647 -97.540384) (xy 70.580864 -97.581921) (xy 70.611637 -97.628434) (xy 70.635309 -97.678931)
			(xy 70.651377 -97.732338) (xy 70.659497 -97.787514) (xy 70.660006 -97.8154) (xy 70.659497 -97.843286)
			(xy 70.651377 -97.898462) (xy 70.635309 -97.951869) (xy 70.611637 -98.002366) (xy 70.580864 -98.048879)
			(xy 70.543647 -98.090416) (xy 70.500779 -98.126091) (xy 70.453173 -98.155145) (xy 70.401844 -98.176957)
			(xy 70.347887 -98.191063) (xy 70.29245 -98.197163) (xy 70.236716 -98.195126) (xy 70.181873 -98.184996)
			(xy 70.129089 -98.166989) (xy 70.079489 -98.141488) (xy 70.034131 -98.109037) (xy 69.993982 -98.070328)
			(xy 69.959896 -98.026185) (xy 69.9326 -97.97755) (xy 69.912677 -97.925459) (xy 69.900551 -97.871022)
			(xy 69.89648 -97.8154) (xy 67.537271 -97.8154) (xy 67.535813 -97.82531) (xy 67.519745 -97.878717)
			(xy 67.496073 -97.929214) (xy 67.4653 -97.975727) (xy 67.428083 -98.017264) (xy 67.385215 -98.052939)
			(xy 67.337609 -98.081993) (xy 67.28628 -98.103805) (xy 67.232323 -98.117911) (xy 67.176886 -98.124011)
			(xy 67.121152 -98.121974) (xy 67.066309 -98.111844) (xy 67.013525 -98.093837) (xy 66.963925 -98.068336)
			(xy 66.918567 -98.035885) (xy 66.878418 -97.997176) (xy 66.844332 -97.953033) (xy 66.817036 -97.904398)
			(xy 66.797113 -97.852307) (xy 66.784987 -97.79787) (xy 66.780916 -97.742248) (xy 64.820073 -97.742248)
			(xy 64.822229 -97.74805) (xy 64.833809 -97.802185) (xy 64.837441 -97.857424) (xy 64.83305 -97.912609)
			(xy 64.820728 -97.966579) (xy 64.800733 -98.018201) (xy 64.773487 -98.06639) (xy 64.73956 -98.110135)
			(xy 64.699666 -98.148515) (xy 64.654643 -98.180726) (xy 64.605437 -98.20609) (xy 64.553081 -98.224075)
			(xy 64.498675 -98.234302) (xy 64.443362 -98.236557) (xy 64.388304 -98.230793) (xy 64.334658 -98.21713)
			(xy 64.28355 -98.195856) (xy 64.236054 -98.167417) (xy 64.193168 -98.132411) (xy 64.174116 -98.112326)
			(xy 64.159227 -98.096788) (xy 64.125227 -98.070414) (xy 64.087272 -98.050141) (xy 64.046445 -98.036548)
			(xy 64.003913 -98.030023) (xy 63.960889 -98.030752) (xy 63.918602 -98.038714) (xy 63.878259 -98.053683)
			(xy 63.85941 -98.064066) (xy 63.834961 -98.077667) (xy 63.783 -98.098405) (xy 63.728567 -98.111329)
			(xy 63.67283 -98.116162) (xy 63.616985 -98.112799) (xy 63.562231 -98.101313) (xy 63.509742 -98.081951)
			(xy 63.460646 -98.055128) (xy 63.438024 -98.038666) (xy 63.419287 -98.02516) (xy 63.378024 -98.004419)
			(xy 63.333693 -97.991474) (xy 63.287753 -97.986752) (xy 63.241716 -97.990407) (xy 63.197096 -98.00232)
			(xy 63.155363 -98.022098) (xy 63.11789 -98.04909) (xy 63.085911 -98.082408) (xy 63.072772 -98.101404)
			(xy 63.057515 -98.123733) (xy 63.021614 -98.164178) (xy 62.98036 -98.199147) (xy 62.934582 -98.227941)
			(xy 62.885196 -98.249981) (xy 62.833193 -98.264826) (xy 62.779614 -98.272178) (xy 62.725534 -98.271891)
			(xy 62.672037 -98.263969) (xy 62.620194 -98.248572) (xy 62.571046 -98.226008) (xy 62.525576 -98.196729)
			(xy 62.504828 -98.179382) (xy 62.491336 -98.168512) (xy 62.460006 -98.153754) (xy 62.425861 -98.147965)
			(xy 62.391418 -98.15157) (xy 62.359212 -98.164304) (xy 62.345062 -98.174302) (xy 62.32267 -98.190655)
			(xy 62.274092 -98.217385) (xy 62.222155 -98.236801) (xy 62.167955 -98.248495) (xy 62.112634 -98.25222)
			(xy 62.057356 -98.247897) (xy 62.003285 -98.235618) (xy 61.951562 -98.215641) (xy 61.903276 -98.188387)
			(xy 61.859443 -98.15443) (xy 61.820987 -98.114486) (xy 61.788718 -98.069396) (xy 61.763317 -98.02011)
			(xy 61.745317 -97.967666) (xy 61.735099 -97.913169) (xy 61.732877 -97.857767) (xy 60.499709 -97.857767)
			(xy 60.497127 -97.900168) (xy 60.485825 -97.954318) (xy 60.466822 -98.006267) (xy 60.440515 -98.054928)
			(xy 60.407456 -98.09928) (xy 60.388246 -98.119184) (xy 60.376489 -98.131704) (xy 60.359599 -98.161598)
			(xy 60.35127 -98.194907) (xy 60.352102 -98.229232) (xy 60.362034 -98.262099) (xy 60.37072 -98.276918)
			(xy 60.38519 -98.300494) (xy 60.407788 -98.350986) (xy 60.422858 -98.404212) (xy 60.430083 -98.459056)
			(xy 60.429655 -98.48977) (xy 66.048888 -98.48977) (xy 66.052959 -98.434148) (xy 66.065085 -98.379711)
			(xy 66.085008 -98.32762) (xy 66.112304 -98.278985) (xy 66.14639 -98.234842) (xy 66.186539 -98.196133)
			(xy 66.231897 -98.163682) (xy 66.281497 -98.138181) (xy 66.334281 -98.120174) (xy 66.389124 -98.110044)
			(xy 66.444858 -98.108007) (xy 66.500295 -98.114107) (xy 66.554252 -98.128213) (xy 66.605581 -98.150025)
			(xy 66.653187 -98.179079) (xy 66.696055 -98.214754) (xy 66.733272 -98.256291) (xy 66.764045 -98.302804)
			(xy 66.787717 -98.353301) (xy 66.803785 -98.406708) (xy 66.811905 -98.461884) (xy 66.812414 -98.48977)
			(xy 66.811905 -98.517656) (xy 66.803785 -98.572832) (xy 66.787717 -98.626239) (xy 66.764045 -98.676736)
			(xy 66.733272 -98.723249) (xy 66.696055 -98.764786) (xy 66.653187 -98.800461) (xy 66.605581 -98.829515)
			(xy 66.554252 -98.851327) (xy 66.500295 -98.865433) (xy 66.444858 -98.871533) (xy 66.389124 -98.869496)
			(xy 66.334281 -98.859366) (xy 66.281497 -98.841359) (xy 66.231897 -98.815858) (xy 66.186539 -98.783407)
			(xy 66.14639 -98.744698) (xy 66.112304 -98.700555) (xy 66.085008 -98.65192) (xy 66.065085 -98.599829)
			(xy 66.052959 -98.545392) (xy 66.048888 -98.48977) (xy 60.429655 -98.48977) (xy 60.429312 -98.514369)
			(xy 60.42056 -98.568991) (xy 60.404012 -98.621776) (xy 60.380015 -98.671618) (xy 60.349071 -98.717472)
			(xy 60.311829 -98.758376) (xy 60.26907 -98.793473) (xy 60.221691 -98.822027) (xy 60.170685 -98.843439)
			(xy 60.117121 -98.85726) (xy 60.062122 -98.863201) (xy 60.006843 -98.861137) (xy 59.952441 -98.851111)
			(xy 59.900057 -98.833334) (xy 59.850789 -98.808178) (xy 59.805671 -98.77617) (xy 59.765649 -98.737982)
			(xy 59.731561 -98.694415) (xy 59.704123 -98.646381) (xy 59.683909 -98.594888) (xy 59.671343 -98.541016)
			(xy 59.666689 -98.485894) (xy 59.237644 -98.485894) (xy 59.261255 -98.509585) (xy 59.294444 -98.554383)
			(xy 59.32076 -98.603534) (xy 59.339641 -98.655992) (xy 59.350687 -98.71064) (xy 59.353661 -98.766313)
			(xy 59.3485 -98.821827) (xy 59.335314 -98.875998) (xy 59.314384 -98.927673) (xy 59.286156 -98.975751)
			(xy 59.251231 -99.019209) (xy 59.210352 -99.057121) (xy 59.164391 -99.088679) (xy 59.139582 -99.101402)
			(xy 59.125176 -99.108951) (xy 59.100538 -99.130171) (xy 59.082068 -99.156931) (xy 59.070965 -99.187493)
			(xy 59.069642 -99.201717) (xy 60.462857 -99.201717) (xy 60.465756 -99.146523) (xy 60.476591 -99.092326)
			(xy 60.495135 -99.040261) (xy 60.521 -98.991417) (xy 60.553644 -98.946818) (xy 60.592384 -98.907397)
			(xy 60.636407 -98.873981) (xy 60.684793 -98.847269) (xy 60.736528 -98.82782) (xy 60.790528 -98.816043)
			(xy 60.845662 -98.812182) (xy 60.900777 -98.81632) (xy 60.954717 -98.82837) (xy 61.006353 -98.848079)
			(xy 61.054603 -98.875035) (xy 61.098458 -98.908672) (xy 61.136998 -98.948287) (xy 61.169417 -98.99305)
			(xy 61.195035 -99.042024) (xy 61.213317 -99.094182) (xy 61.21908 -99.121214) (xy 61.22295 -99.137956)
			(xy 61.238206 -99.168725) (xy 61.26112 -99.194308) (xy 61.290029 -99.212848) (xy 61.322837 -99.223003)
			(xy 61.339984 -99.224084) (xy 61.365932 -99.225257) (xy 61.417168 -99.23379) (xy 61.442092 -99.241102)
			(xy 61.457844 -99.24546) (xy 61.490481 -99.246945) (xy 61.522421 -99.240073) (xy 61.551559 -99.225298)
			(xy 61.575976 -99.203592) (xy 61.594064 -99.176386) (xy 61.599826 -99.161092) (xy 61.609341 -99.134822)
			(xy 61.634974 -99.085178) (xy 61.667574 -99.039803) (xy 61.706444 -98.999668) (xy 61.750752 -98.965632)
			(xy 61.79955 -98.938423) (xy 61.851796 -98.918622) (xy 61.90637 -98.906654) (xy 61.962107 -98.902773)
			(xy 62.017814 -98.907064) (xy 62.072299 -98.919434) (xy 62.124397 -98.939619) (xy 62.172994 -98.967187)
			(xy 62.21705 -99.001549) (xy 62.255623 -99.041969) (xy 62.287887 -99.087583) (xy 62.313154 -99.137415)
			(xy 62.330882 -99.190399) (xy 62.340692 -99.245403) (xy 62.342375 -99.301249) (xy 62.335894 -99.356743)
			(xy 62.321388 -99.410699) (xy 62.299167 -99.461962) (xy 62.269707 -99.509435) (xy 62.233637 -99.552104)
			(xy 62.19173 -99.589056) (xy 62.144881 -99.619499) (xy 62.094093 -99.642784) (xy 62.040451 -99.658412)
			(xy 61.985104 -99.666049) (xy 61.929235 -99.665531) (xy 61.874038 -99.65687) (xy 61.847222 -99.649026)
			(xy 61.83147 -99.644666) (xy 61.798832 -99.643177) (xy 61.76689 -99.650047) (xy 61.737751 -99.664823)
			(xy 61.713334 -99.686531) (xy 61.695248 -99.713741) (xy 61.689488 -99.729036) (xy 61.67998 -99.755127)
			(xy 61.654545 -99.804488) (xy 61.622222 -99.849639) (xy 61.583695 -99.889628) (xy 61.539777 -99.923608)
			(xy 61.491397 -99.950862) (xy 61.439577 -99.970813) (xy 61.385411 -99.983041) (xy 61.330045 -99.987287)
			(xy 61.274649 -99.98346) (xy 61.220392 -99.971643) (xy 61.168422 -99.952084) (xy 61.119837 -99.925197)
			(xy 61.075664 -99.89155) (xy 61.036835 -99.851854) (xy 61.004172 -99.806948) (xy 60.978364 -99.757782)
			(xy 60.959957 -99.705392) (xy 60.954158 -99.678236) (xy 60.950377 -99.66147) (xy 60.935099 -99.630696)
			(xy 60.912164 -99.605115) (xy 60.883235 -99.586581) (xy 60.850408 -99.576438) (xy 60.833254 -99.575366)
			(xy 60.805647 -99.574017) (xy 60.751221 -99.564402) (xy 60.698751 -99.547032) (xy 60.649339 -99.522271)
			(xy 60.604018 -99.490637) (xy 60.563737 -99.452793) (xy 60.52934 -99.409531) (xy 60.501548 -99.361757)
			(xy 60.480943 -99.310473) (xy 60.467955 -99.256751) (xy 60.462857 -99.201717) (xy 59.069642 -99.201717)
			(xy 59.067953 -99.21987) (xy 59.073226 -99.251955) (xy 59.079384 -99.26701) (xy 59.090228 -99.2927)
			(xy 59.105174 -99.346419) (xy 59.112143 -99.401741) (xy 59.110984 -99.457489) (xy 59.101724 -99.512474)
			(xy 59.084559 -99.565526) (xy 59.059856 -99.615514) (xy 59.028139 -99.661375) (xy 58.990084 -99.70213)
			(xy 58.946503 -99.736912) (xy 58.898324 -99.764981) (xy 58.846572 -99.785738) (xy 58.792349 -99.798741)
			(xy 58.736812 -99.803714) (xy 58.681142 -99.80055) (xy 58.626526 -99.789316) (xy 58.574126 -99.770253)
			(xy 58.525059 -99.743766) (xy 58.480371 -99.710418) (xy 58.441011 -99.670922) (xy 58.40782 -99.626117)
			(xy 58.381504 -99.576958) (xy 58.362623 -99.524492) (xy 58.35158 -99.469837) (xy 58.34861 -99.414157)
			(xy 56.576887 -99.414157) (xy 56.565113 -99.43538) (xy 56.531793 -99.479152) (xy 56.492531 -99.517684)
			(xy 56.448141 -99.550177) (xy 56.399544 -99.575957) (xy 56.347749 -99.594489) (xy 56.293828 -99.605388)
			(xy 56.238901 -99.60843) (xy 56.184106 -99.60355) (xy 56.130581 -99.59085) (xy 56.079435 -99.570593)
			(xy 56.031729 -99.5432) (xy 56.009794 -99.526598) (xy 55.991106 -99.512577) (xy 55.949694 -99.490962)
			(xy 55.905028 -99.477277) (xy 55.858614 -99.471984) (xy 55.812015 -99.475262) (xy 55.766799 -99.486999)
			(xy 55.724488 -99.506801) (xy 55.686509 -99.534) (xy 55.669942 -99.550474) (xy 55.650533 -99.569973)
			(xy 55.607119 -99.603764) (xy 55.559302 -99.630969) (xy 55.508073 -99.651023) (xy 55.454494 -99.66351)
			(xy 55.399677 -99.668172) (xy 55.344759 -99.664912) (xy 55.290879 -99.653796) (xy 55.239154 -99.635056)
			(xy 55.190658 -99.609081) (xy 55.146395 -99.576409) (xy 55.107285 -99.537718) (xy 55.074138 -99.493811)
			(xy 55.047641 -99.445597) (xy 55.028345 -99.394077) (xy 55.01665 -99.34032) (xy 55.012797 -99.28544)
			(xy 51.246613 -99.28544) (xy 51.244645 -99.289638) (xy 51.213872 -99.336151) (xy 51.176655 -99.377688)
			(xy 51.133787 -99.413363) (xy 51.086181 -99.442417) (xy 51.034852 -99.464229) (xy 50.980895 -99.478335)
			(xy 50.925458 -99.484435) (xy 50.869724 -99.482398) (xy 50.814881 -99.472268) (xy 50.762097 -99.454261)
			(xy 50.712497 -99.42876) (xy 50.667139 -99.396309) (xy 50.62699 -99.3576) (xy 50.592904 -99.313457)
			(xy 50.565608 -99.264822) (xy 50.545685 -99.212731) (xy 50.533559 -99.158294) (xy 50.529488 -99.102672)
			(xy 49.715723 -99.102672) (xy 49.716182 -99.127818) (xy 49.715673 -99.155704) (xy 49.707553 -99.21088)
			(xy 49.691485 -99.264287) (xy 49.667813 -99.314784) (xy 49.63704 -99.361297) (xy 49.599823 -99.402834)
			(xy 49.556955 -99.438509) (xy 49.509349 -99.467563) (xy 49.45802 -99.489375) (xy 49.404063 -99.503481)
			(xy 49.348626 -99.509581) (xy 49.292892 -99.507544) (xy 49.238049 -99.497414) (xy 49.185265 -99.479407)
			(xy 49.135665 -99.453906) (xy 49.090307 -99.421455) (xy 49.050158 -99.382746) (xy 49.016072 -99.338603)
			(xy 48.988776 -99.289968) (xy 48.968853 -99.237877) (xy 48.956727 -99.18344) (xy 48.952656 -99.127818)
			(xy 44.862818 -99.127818) (xy 44.854839 -99.144364) (xy 44.823649 -99.19044) (xy 44.786098 -99.231496)
			(xy 44.742981 -99.266664) (xy 44.695214 -99.295195) (xy 44.643809 -99.316487) (xy 44.589857 -99.330086)
			(xy 44.534501 -99.335705) (xy 44.478917 -99.333224) (xy 44.424282 -99.322695) (xy 44.371756 -99.304344)
			(xy 44.322453 -99.278557) (xy 44.277417 -99.245883) (xy 44.237605 -99.207014) (xy 44.203861 -99.162775)
			(xy 44.1769 -99.114104) (xy 44.157294 -99.062033) (xy 44.145459 -99.007666) (xy 44.141646 -98.952157)
			(xy 44.145936 -98.896683) (xy 44.158238 -98.842421) (xy 44.178291 -98.79052) (xy 44.205669 -98.742082)
			(xy 44.239793 -98.698135) (xy 44.2595 -98.678492) (xy 44.274986 -98.663029) (xy 44.300932 -98.627792)
			(xy 44.320448 -98.588627) (xy 44.332956 -98.546694) (xy 44.338083 -98.503236) (xy 44.335679 -98.459544)
			(xy 44.325814 -98.416911) (xy 44.308781 -98.376604) (xy 44.297346 -98.357944) (xy 44.282103 -98.33318)
			(xy 44.258486 -98.280044) (xy 44.243208 -98.223938) (xy 44.236621 -98.166164) (xy 44.238879 -98.10806)
			(xy 44.249928 -98.050971) (xy 44.259246 -98.023426) (xy 44.266384 -98.002057) (xy 44.273858 -97.957634)
			(xy 44.27338 -97.912588) (xy 44.264965 -97.868333) (xy 44.248878 -97.826256) (xy 44.225622 -97.787675)
			(xy 44.195926 -97.7538) (xy 44.160722 -97.725694) (xy 44.141136 -97.714562) (xy 44.115851 -97.700243)
			(xy 44.069551 -97.665135) (xy 44.02911 -97.623413) (xy 43.995462 -97.576041) (xy 43.969386 -97.524116)
			(xy 43.951485 -97.468836) (xy 43.946318 -97.440242) (xy 43.942099 -97.417368) (xy 43.926459 -97.373568)
			(xy 43.903109 -97.333346) (xy 43.872829 -97.298045) (xy 43.836631 -97.268843) (xy 43.795723 -97.246716)
			(xy 43.751472 -97.232403) (xy 43.705355 -97.226382) (xy 43.658912 -97.228853) (xy 43.613695 -97.239734)
			(xy 43.571212 -97.258662) (xy 43.532884 -97.285005) (xy 43.516042 -97.30105) (xy 43.299888 -97.517458)
			(xy 43.299888 -99.814126) (xy 45.447202 -99.814126) (xy 45.451273 -99.758504) (xy 45.463399 -99.704067)
			(xy 45.483322 -99.651976) (xy 45.510618 -99.603341) (xy 45.544704 -99.559198) (xy 45.584853 -99.520489)
			(xy 45.630211 -99.488038) (xy 45.679811 -99.462537) (xy 45.732595 -99.44453) (xy 45.787438 -99.4344)
			(xy 45.843172 -99.432363) (xy 45.898609 -99.438463) (xy 45.952566 -99.452569) (xy 46.003895 -99.474381)
			(xy 46.051501 -99.503435) (xy 46.094369 -99.53911) (xy 46.131586 -99.580647) (xy 46.162359 -99.62716)
			(xy 46.186031 -99.677657) (xy 46.202099 -99.731064) (xy 46.210219 -99.78624) (xy 46.210728 -99.814126)
			(xy 46.210219 -99.842012) (xy 46.202099 -99.897188) (xy 46.188803 -99.94138) (xy 59.671202 -99.94138)
			(xy 59.675273 -99.885758) (xy 59.687399 -99.831321) (xy 59.707322 -99.77923) (xy 59.734618 -99.730595)
			(xy 59.768704 -99.686452) (xy 59.808853 -99.647743) (xy 59.854211 -99.615292) (xy 59.903811 -99.589791)
			(xy 59.956595 -99.571784) (xy 60.011438 -99.561654) (xy 60.067172 -99.559617) (xy 60.122609 -99.565717)
			(xy 60.176566 -99.579823) (xy 60.227895 -99.601635) (xy 60.275501 -99.630689) (xy 60.318369 -99.666364)
			(xy 60.355586 -99.707901) (xy 60.386359 -99.754414) (xy 60.410031 -99.804911) (xy 60.426099 -99.858318)
			(xy 60.434219 -99.913494) (xy 60.434728 -99.94138) (xy 60.434219 -99.969266) (xy 60.426099 -100.024442)
			(xy 60.410031 -100.077849) (xy 60.386359 -100.128346) (xy 60.355586 -100.174859) (xy 60.318369 -100.216396)
			(xy 60.275501 -100.252071) (xy 60.227895 -100.281125) (xy 60.176566 -100.302937) (xy 60.122609 -100.317043)
			(xy 60.067172 -100.323143) (xy 60.011438 -100.321106) (xy 59.956595 -100.310976) (xy 59.903811 -100.292969)
			(xy 59.854211 -100.267468) (xy 59.808853 -100.235017) (xy 59.768704 -100.196308) (xy 59.734618 -100.152165)
			(xy 59.707322 -100.10353) (xy 59.687399 -100.051439) (xy 59.675273 -99.997002) (xy 59.671202 -99.94138)
			(xy 46.188803 -99.94138) (xy 46.186031 -99.950595) (xy 46.162359 -100.001092) (xy 46.131586 -100.047605)
			(xy 46.094369 -100.089142) (xy 46.051501 -100.124817) (xy 46.003895 -100.153871) (xy 45.952566 -100.175683)
			(xy 45.898609 -100.189789) (xy 45.843172 -100.195889) (xy 45.787438 -100.193852) (xy 45.732595 -100.183722)
			(xy 45.679811 -100.165715) (xy 45.630211 -100.140214) (xy 45.584853 -100.107763) (xy 45.544704 -100.069054)
			(xy 45.510618 -100.024911) (xy 45.483322 -99.976276) (xy 45.463399 -99.924185) (xy 45.451273 -99.869748)
			(xy 45.447202 -99.814126) (xy 43.299888 -99.814126) (xy 43.299888 -100.69195) (xy 48.977802 -100.69195)
			(xy 48.981873 -100.636328) (xy 48.993999 -100.581891) (xy 49.013922 -100.5298) (xy 49.041218 -100.481165)
			(xy 49.075304 -100.437022) (xy 49.115453 -100.398313) (xy 49.160811 -100.365862) (xy 49.210411 -100.340361)
			(xy 49.263195 -100.322354) (xy 49.318038 -100.312224) (xy 49.373772 -100.310187) (xy 49.429209 -100.316287)
			(xy 49.483166 -100.330393) (xy 49.534495 -100.352205) (xy 49.582101 -100.381259) (xy 49.624969 -100.416934)
			(xy 49.662186 -100.458471) (xy 49.692959 -100.504984) (xy 49.716631 -100.555481) (xy 49.732699 -100.608888)
			(xy 49.740819 -100.664064) (xy 49.741328 -100.69195) (xy 50.541934 -100.69195) (xy 50.546005 -100.636328)
			(xy 50.558131 -100.581891) (xy 50.578054 -100.5298) (xy 50.60535 -100.481165) (xy 50.639436 -100.437022)
			(xy 50.679585 -100.398313) (xy 50.724943 -100.365862) (xy 50.774543 -100.340361) (xy 50.827327 -100.322354)
			(xy 50.88217 -100.312224) (xy 50.937904 -100.310187) (xy 50.993341 -100.316287) (xy 51.047298 -100.330393)
			(xy 51.098627 -100.352205) (xy 51.146233 -100.381259) (xy 51.189101 -100.416934) (xy 51.226318 -100.458471)
			(xy 51.231899 -100.466906) (xy 54.077106 -100.466906) (xy 54.081177 -100.411284) (xy 54.093303 -100.356847)
			(xy 54.113226 -100.304756) (xy 54.140522 -100.256121) (xy 54.174608 -100.211978) (xy 54.214757 -100.173269)
			(xy 54.260115 -100.140818) (xy 54.309715 -100.115317) (xy 54.362499 -100.09731) (xy 54.417342 -100.08718)
			(xy 54.473076 -100.085143) (xy 54.528513 -100.091243) (xy 54.58247 -100.105349) (xy 54.633799 -100.127161)
			(xy 54.681405 -100.156215) (xy 54.724273 -100.19189) (xy 54.76149 -100.233427) (xy 54.792263 -100.27994)
			(xy 54.815935 -100.330437) (xy 54.832003 -100.383844) (xy 54.840123 -100.43902) (xy 54.840632 -100.466906)
			(xy 54.840123 -100.494792) (xy 54.832003 -100.549968) (xy 54.820924 -100.586794) (xy 58.71032 -100.586794)
			(xy 58.714391 -100.531172) (xy 58.726517 -100.476735) (xy 58.74644 -100.424644) (xy 58.773736 -100.376009)
			(xy 58.807822 -100.331866) (xy 58.847971 -100.293157) (xy 58.893329 -100.260706) (xy 58.942929 -100.235205)
			(xy 58.995713 -100.217198) (xy 59.050556 -100.207068) (xy 59.10629 -100.205031) (xy 59.161727 -100.211131)
			(xy 59.215684 -100.225237) (xy 59.267013 -100.247049) (xy 59.314619 -100.276103) (xy 59.357487 -100.311778)
			(xy 59.394704 -100.353315) (xy 59.425477 -100.399828) (xy 59.449149 -100.450325) (xy 59.465217 -100.503732)
			(xy 59.473337 -100.558908) (xy 59.473846 -100.586794) (xy 59.473337 -100.61468) (xy 59.465217 -100.669856)
			(xy 59.449149 -100.723263) (xy 59.425477 -100.77376) (xy 59.394704 -100.820273) (xy 59.357487 -100.86181)
			(xy 59.314619 -100.897485) (xy 59.267013 -100.926539) (xy 59.215684 -100.948351) (xy 59.161727 -100.962457)
			(xy 59.10629 -100.968557) (xy 59.050556 -100.96652) (xy 58.995713 -100.95639) (xy 58.942929 -100.938383)
			(xy 58.893329 -100.912882) (xy 58.847971 -100.880431) (xy 58.807822 -100.841722) (xy 58.773736 -100.797579)
			(xy 58.74644 -100.748944) (xy 58.726517 -100.696853) (xy 58.714391 -100.642416) (xy 58.71032 -100.586794)
			(xy 54.820924 -100.586794) (xy 54.815935 -100.603375) (xy 54.792263 -100.653872) (xy 54.76149 -100.700385)
			(xy 54.724273 -100.741922) (xy 54.681405 -100.777597) (xy 54.633799 -100.806651) (xy 54.58247 -100.828463)
			(xy 54.528513 -100.842569) (xy 54.473076 -100.848669) (xy 54.417342 -100.846632) (xy 54.362499 -100.836502)
			(xy 54.309715 -100.818495) (xy 54.260115 -100.792994) (xy 54.214757 -100.760543) (xy 54.174608 -100.721834)
			(xy 54.140522 -100.677691) (xy 54.113226 -100.629056) (xy 54.093303 -100.576965) (xy 54.081177 -100.522528)
			(xy 54.077106 -100.466906) (xy 51.231899 -100.466906) (xy 51.257091 -100.504984) (xy 51.280763 -100.555481)
			(xy 51.296831 -100.608888) (xy 51.304951 -100.664064) (xy 51.30546 -100.69195) (xy 51.304951 -100.719836)
			(xy 51.296831 -100.775012) (xy 51.280763 -100.828419) (xy 51.257091 -100.878916) (xy 51.226318 -100.925429)
			(xy 51.189101 -100.966966) (xy 51.146233 -101.002641) (xy 51.098627 -101.031695) (xy 51.047298 -101.053507)
			(xy 50.993341 -101.067613) (xy 50.937904 -101.073713) (xy 50.88217 -101.071676) (xy 50.827327 -101.061546)
			(xy 50.774543 -101.043539) (xy 50.724943 -101.018038) (xy 50.679585 -100.985587) (xy 50.639436 -100.946878)
			(xy 50.60535 -100.902735) (xy 50.578054 -100.8541) (xy 50.558131 -100.802009) (xy 50.546005 -100.747572)
			(xy 50.541934 -100.69195) (xy 49.741328 -100.69195) (xy 49.740819 -100.719836) (xy 49.732699 -100.775012)
			(xy 49.716631 -100.828419) (xy 49.692959 -100.878916) (xy 49.662186 -100.925429) (xy 49.624969 -100.966966)
			(xy 49.582101 -101.002641) (xy 49.534495 -101.031695) (xy 49.483166 -101.053507) (xy 49.429209 -101.067613)
			(xy 49.373772 -101.073713) (xy 49.318038 -101.071676) (xy 49.263195 -101.061546) (xy 49.210411 -101.043539)
			(xy 49.160811 -101.018038) (xy 49.115453 -100.985587) (xy 49.075304 -100.946878) (xy 49.041218 -100.902735)
			(xy 49.013922 -100.8541) (xy 48.993999 -100.802009) (xy 48.981873 -100.747572) (xy 48.977802 -100.69195)
			(xy 43.299888 -100.69195) (xy 43.299888 -101.106224) (xy 45.449742 -101.106224) (xy 45.453813 -101.050602)
			(xy 45.465939 -100.996165) (xy 45.485862 -100.944074) (xy 45.513158 -100.895439) (xy 45.547244 -100.851296)
			(xy 45.587393 -100.812587) (xy 45.632751 -100.780136) (xy 45.682351 -100.754635) (xy 45.735135 -100.736628)
			(xy 45.789978 -100.726498) (xy 45.845712 -100.724461) (xy 45.901149 -100.730561) (xy 45.955106 -100.744667)
			(xy 46.006435 -100.766479) (xy 46.054041 -100.795533) (xy 46.096909 -100.831208) (xy 46.134126 -100.872745)
			(xy 46.164899 -100.919258) (xy 46.188571 -100.969755) (xy 46.204639 -101.023162) (xy 46.212759 -101.078338)
			(xy 46.213268 -101.106224) (xy 46.212759 -101.13411) (xy 46.204639 -101.189286) (xy 46.188571 -101.242693)
			(xy 46.164899 -101.29319) (xy 46.134126 -101.339703) (xy 46.096909 -101.38124) (xy 46.054041 -101.416915)
			(xy 46.006435 -101.445969) (xy 45.955106 -101.467781) (xy 45.901149 -101.481887) (xy 45.845712 -101.487987)
			(xy 45.789978 -101.48595) (xy 45.735135 -101.47582) (xy 45.682351 -101.457813) (xy 45.632751 -101.432312)
			(xy 45.587393 -101.399861) (xy 45.547244 -101.361152) (xy 45.513158 -101.317009) (xy 45.485862 -101.268374)
			(xy 45.465939 -101.216283) (xy 45.453813 -101.161846) (xy 45.449742 -101.106224) (xy 43.299888 -101.106224)
			(xy 43.299888 -102.1334) (xy 44.166282 -103.000048) (xy 44.20108 -103.053388) (xy 44.201842 -103.054658)
			(xy 44.20997 -103.06812) (xy 44.292012 -103.150162) (xy 45.28312 -103.150162)
		)
		(stroke
			(width 0)
			(type solid)
		)
		(fill yes)
		(layer "In6.Cu")
		(net "P3V3_NODE1")
	)
	(gr_poly
		(pts
			(xy 70.243446 -140.234416) (xy 70.261734 -140.213588) (xy 70.280486 -140.192963) (xy 70.323043 -140.156966)
			(xy 70.370488 -140.127709) (xy 70.421761 -140.105845) (xy 70.475718 -140.091861) (xy 70.531157 -140.08607)
			(xy 70.586839 -140.088601) (xy 70.641524 -140.099398) (xy 70.69399 -140.118218) (xy 70.743068 -140.144644)
			(xy 70.787663 -140.178084) (xy 70.80758 -140.197586) (xy 70.82409 -140.21435) (xy 70.91807 -140.257022)
			(xy 70.965822 -140.257022) (xy 70.983855 -140.256384) (xy 71.018483 -140.246295) (xy 71.048925 -140.226951)
			(xy 71.061326 -140.213842) (xy 71.06158 -140.213588) (xy 71.074506 -140.199172) (xy 71.102882 -140.172825)
			(xy 71.118222 -140.16101) (xy 71.131406 -140.150481) (xy 71.152152 -140.123887) (xy 71.165194 -140.092781)
			(xy 71.169617 -140.059344) (xy 71.165112 -140.025917) (xy 71.151994 -139.994844) (xy 71.131182 -139.968301)
			(xy 71.117968 -139.95781) (xy 71.096291 -139.94095) (xy 71.057659 -139.901922) (xy 71.025173 -139.857648)
			(xy 70.999536 -139.809085) (xy 70.981302 -139.757286) (xy 70.970866 -139.703373) (xy 70.968455 -139.648511)
			(xy 70.974121 -139.59389) (xy 70.98774 -139.540691) (xy 71.009018 -139.490067) (xy 71.037495 -139.443113)
			(xy 71.072554 -139.400846) (xy 71.113436 -139.364181) (xy 71.159255 -139.333913) (xy 71.20902 -139.310695)
			(xy 71.261653 -139.295032) (xy 71.316015 -139.287261) (xy 71.370928 -139.287552) (xy 71.39813 -139.291314)
			(xy 71.42432 -139.295812) (xy 71.475164 -139.311259) (xy 71.523298 -139.333774) (xy 71.567743 -139.362901)
			(xy 71.607597 -139.398048) (xy 71.642053 -139.438503) (xy 71.670409 -139.483443) (xy 71.692092 -139.531957)
			(xy 71.706659 -139.58306) (xy 71.713817 -139.635715) (xy 71.71342 -139.688852) (xy 71.705475 -139.741394)
			(xy 71.690144 -139.792273) (xy 71.667738 -139.840457) (xy 71.638712 -139.884968) (xy 71.603655 -139.924903)
			(xy 71.583804 -139.94257) (xy 71.5645 -139.959334) (xy 71.54291 -140.00226) (xy 71.536649 -140.015607)
			(xy 71.529855 -140.044288) (xy 71.529861 -140.073763) (xy 71.536666 -140.102442) (xy 71.54291 -140.115798)
			(xy 71.564754 -140.158978) (xy 71.584058 -140.175742) (xy 71.607172 -140.197332) (xy 71.623936 -140.21435)
			(xy 71.717916 -140.257022) (xy 71.793608 -140.257022) (xy 71.843392 -140.234416) (xy 71.86168 -140.213588)
			(xy 71.880432 -140.192966) (xy 71.922988 -140.156976) (xy 71.970431 -140.127725) (xy 72.021701 -140.105867)
			(xy 72.075655 -140.09189) (xy 72.131089 -140.086104) (xy 72.186767 -140.088639) (xy 72.241445 -140.099439)
			(xy 72.293905 -140.118263) (xy 72.342977 -140.14469) (xy 72.387565 -140.178132) (xy 72.407526 -140.197586)
			(xy 72.424036 -140.21435) (xy 72.518016 -140.257022) (xy 72.566022 -140.257022) (xy 72.584055 -140.256384)
			(xy 72.618683 -140.246295) (xy 72.649125 -140.226951) (xy 72.661526 -140.213842) (xy 72.66178 -140.213588)
			(xy 72.680532 -140.192966) (xy 72.723088 -140.156976) (xy 72.770531 -140.127725) (xy 72.821801 -140.105867)
			(xy 72.875755 -140.09189) (xy 72.931189 -140.086104) (xy 72.986867 -140.088639) (xy 73.041545 -140.099439)
			(xy 73.094005 -140.118263) (xy 73.143077 -140.14469) (xy 73.187665 -140.178132) (xy 73.207626 -140.197586)
			(xy 73.224136 -140.21435) (xy 73.318116 -140.257022) (xy 73.573386 -140.257022) (xy 73.589581 -140.256565)
			(xy 73.620939 -140.248462) (xy 73.649246 -140.232722) (xy 73.672677 -140.210362) (xy 73.689721 -140.182821)
			(xy 73.699281 -140.151876) (xy 73.700739 -140.11952) (xy 73.694002 -140.08784) (xy 73.679505 -140.058878)
			(xy 73.658181 -140.0345) (xy 73.631405 -140.016278) (xy 73.616312 -140.010388) (xy 73.590241 -140.000501)
			(xy 73.541134 -139.974095) (xy 73.496511 -139.940666) (xy 73.457367 -139.900961) (xy 73.424577 -139.855866)
			(xy 73.398873 -139.806388) (xy 73.380829 -139.753632) (xy 73.370848 -139.698777) (xy 73.369153 -139.643047)
			(xy 73.375782 -139.587686) (xy 73.390586 -139.533931) (xy 73.413235 -139.482983) (xy 73.443224 -139.435978)
			(xy 73.479882 -139.393967) (xy 73.522391 -139.357888) (xy 73.569802 -139.328546) (xy 73.621056 -139.306597)
			(xy 73.675009 -139.292531) (xy 73.702672 -139.289028) (xy 73.729307 -139.286679) (xy 73.782738 -139.288722)
			(xy 73.835328 -139.298381) (xy 73.885997 -139.315458) (xy 73.933706 -139.339602) (xy 73.977473 -139.370317)
			(xy 74.016401 -139.406972) (xy 74.04969 -139.448816) (xy 74.076657 -139.494987) (xy 74.096747 -139.544539)
			(xy 74.109548 -139.596453) (xy 74.114798 -139.649665) (xy 74.112389 -139.70308) (xy 74.102369 -139.755603)
			(xy 74.094086 -139.781026) (xy 74.086045 -139.803201) (xy 74.065158 -139.845495) (xy 74.05243 -139.865354)
			(xy 74.040546 -139.88471) (xy 74.023111 -139.926643) (xy 74.013405 -139.971008) (xy 74.011739 -140.016392)
			(xy 74.018166 -140.061349) (xy 74.032479 -140.104449) (xy 74.054225 -140.144318) (xy 74.082711 -140.179688)
			(xy 74.117029 -140.209432) (xy 74.156087 -140.232604) (xy 74.198641 -140.248465) (xy 74.243337 -140.256511)
			(xy 74.266044 -140.257022) (xy 78.909418 -140.257022) (xy 78.931281 -140.256565) (xy 78.97436 -140.249077)
			(xy 79.015522 -140.234326) (xy 79.053552 -140.212747) (xy 79.087327 -140.184978) (xy 79.11585 -140.151836)
			(xy 79.138279 -140.114302) (xy 79.153953 -140.073482) (xy 79.162408 -140.030582) (xy 79.163395 -139.986868)
			(xy 79.160624 -139.965176) (xy 79.157028 -139.938064) (xy 79.156714 -139.883373) (xy 79.164216 -139.829198)
			(xy 79.179378 -139.77665) (xy 79.20189 -139.726807) (xy 79.23129 -139.68069) (xy 79.266976 -139.639245)
			(xy 79.308216 -139.603322) (xy 79.354164 -139.573657) (xy 79.403877 -139.55086) (xy 79.456337 -139.535397)
			(xy 79.510468 -139.527585) (xy 79.56516 -139.527585) (xy 79.619291 -139.535397) (xy 79.671751 -139.55086)
			(xy 79.721464 -139.573657) (xy 79.767412 -139.603322) (xy 79.808652 -139.639245) (xy 79.844338 -139.68069)
			(xy 79.873738 -139.726807) (xy 79.89625 -139.77665) (xy 79.911412 -139.829198) (xy 79.918914 -139.883373)
			(xy 79.9186 -139.938064) (xy 79.915004 -139.965176) (xy 79.912199 -139.986862) (xy 79.913185 -140.030575)
			(xy 79.921642 -140.073473) (xy 79.937319 -140.11429) (xy 79.959753 -140.15182) (xy 79.988283 -140.184954)
			(xy 80.022064 -140.212714) (xy 80.0601 -140.23428) (xy 80.101266 -140.249014) (xy 80.144348 -140.256482)
			(xy 80.16621 -140.257022) (xy 82.89671 -140.257022) (xy 83.79714 -139.356592) (xy 83.79714 -136.109964)
			(xy 83.796632 -136.087819) (xy 83.788902 -136.044208) (xy 83.773735 -136.002595) (xy 83.751589 -135.964238)
			(xy 83.723134 -135.930298) (xy 83.68923 -135.901799) (xy 83.650902 -135.879604) (xy 83.609308 -135.864383)
			(xy 83.58759 -135.860028) (xy 83.560088 -135.854635) (xy 83.50694 -135.836854) (xy 83.456964 -135.81149)
			(xy 83.411237 -135.779087) (xy 83.370743 -135.740344) (xy 83.336352 -135.696093) (xy 83.308804 -135.647287)
			(xy 83.288693 -135.594976) (xy 83.276451 -135.540286) (xy 83.272342 -135.484393) (xy 83.276453 -135.428501)
			(xy 83.288697 -135.373811) (xy 83.30881 -135.321501) (xy 83.336359 -135.272696) (xy 83.370752 -135.228447)
			(xy 83.411248 -135.189704) (xy 83.456976 -135.157303) (xy 83.506952 -135.131941) (xy 83.560101 -135.114162)
			(xy 83.58759 -135.108696) (xy 83.60932 -135.104357) (xy 83.650945 -135.089175) (xy 83.689304 -135.067)
			(xy 83.723233 -135.038506) (xy 83.751703 -135.004557) (xy 83.773851 -134.966182) (xy 83.789004 -134.924547)
			(xy 83.796702 -134.880913) (xy 83.79714 -134.85876) (xy 83.79714 -133.129528) (xy 82.68208 -132.014468)
			(xy 82.665824 -132.005578) (xy 82.641731 -131.991996) (xy 82.597383 -131.958948) (xy 82.558274 -131.919841)
			(xy 82.525221 -131.875497) (xy 82.511646 -131.8514) (xy 82.502756 -131.835144) (xy 81.286096 -130.618484)
			(xy 81.24444 -130.612388) (xy 81.217721 -130.607956) (xy 81.165805 -130.592532) (xy 81.116591 -130.569923)
			(xy 81.071068 -130.540583) (xy 81.03015 -130.505101) (xy 80.99466 -130.464191) (xy 80.965312 -130.418673)
			(xy 80.942693 -130.369463) (xy 80.92726 -130.31755) (xy 80.922876 -130.290824) (xy 80.91678 -130.249168)
			(xy 80.01 -129.342388) (xy 80.01 -127.536702) (xy 77.44714 -124.973842) (xy 68.42252 -124.973842)
			(xy 68.361814 -125.010926) (xy 68.345558 -125.042676) (xy 68.332596 -125.066882) (xy 68.300775 -125.111629)
			(xy 68.262863 -125.151348) (xy 68.219644 -125.185217) (xy 68.172014 -125.212535) (xy 68.120958 -125.232738)
			(xy 68.094352 -125.239526) (xy 68.065774 -125.245788) (xy 68.007461 -125.250495) (xy 67.949114 -125.246235)
			(xy 67.892103 -125.233108) (xy 67.837767 -125.211423) (xy 67.787384 -125.18169) (xy 67.764406 -125.16358)
			(xy 67.753851 -125.154755) (xy 67.733893 -125.135813) (xy 67.724528 -125.125734) (xy 67.709291 -125.109762)
			(xy 67.67433 -125.082818) (xy 67.635236 -125.062327) (xy 67.593188 -125.048906) (xy 67.549452 -125.04296)
			(xy 67.505346 -125.044668) (xy 67.462201 -125.053979) (xy 67.421316 -125.070611) (xy 67.383924 -125.094064)
			(xy 67.351152 -125.123631) (xy 67.337178 -125.14072) (xy 67.319348 -125.162675) (xy 67.278301 -125.201583)
			(xy 67.231958 -125.234003) (xy 67.181336 -125.259223) (xy 67.127545 -125.276692) (xy 67.071763 -125.286025)
			(xy 67.015215 -125.287018) (xy 66.959141 -125.27965) (xy 66.904769 -125.264081) (xy 66.853292 -125.240654)
			(xy 66.80584 -125.209882) (xy 66.763452 -125.17244) (xy 66.74485 -125.151134) (xy 66.728063 -125.130489)
			(xy 66.699775 -125.085421) (xy 66.678031 -125.036857) (xy 66.670174 -125.011434) (xy 66.662604 -124.983229)
			(xy 66.655133 -124.925313) (xy 66.656569 -124.866934) (xy 66.666881 -124.809455) (xy 66.685826 -124.754218)
			(xy 66.712964 -124.702511) (xy 66.729864 -124.678694) (xy 66.742538 -124.65945) (xy 66.761446 -124.617435)
			(xy 66.772471 -124.5727) (xy 66.775252 -124.52671) (xy 66.769699 -124.480973) (xy 66.755992 -124.436985)
			(xy 66.734582 -124.396188) (xy 66.706169 -124.359919) (xy 66.671683 -124.329365) (xy 66.632256 -124.305527)
			(xy 66.589177 -124.289186) (xy 66.543859 -124.280878) (xy 66.520822 -124.280422) (xy 57.38368 -124.280422)
			(xy 57.367028 -124.280919) (xy 57.33486 -124.289544) (xy 57.306021 -124.306201) (xy 57.282475 -124.329754)
			(xy 57.265828 -124.358599) (xy 57.257214 -124.39077) (xy 57.25668 -124.407422) (xy 57.25668 -124.702316)
			(xy 57.275222 -124.732542) (xy 57.289103 -124.756365) (xy 57.310613 -124.807132) (xy 57.324597 -124.860464)
			(xy 57.330764 -124.915254) (xy 57.328984 -124.970361) (xy 57.319295 -125.024638) (xy 57.301899 -125.076957)
			(xy 57.277157 -125.12623) (xy 57.26176 -125.149102) (xy 57.250076 -125.165104) (xy 57.235731 -125.184399)
			(xy 57.213816 -125.227186) (xy 57.200345 -125.273332) (xy 57.1958 -125.32119) (xy 57.200341 -125.369047)
			(xy 57.213809 -125.415195) (xy 57.23572 -125.457984) (xy 57.250076 -125.47727) (xy 57.266589 -125.499252)
			(xy 57.293798 -125.547025) (xy 57.313867 -125.59821) (xy 57.326381 -125.651745) (xy 57.331082 -125.706521)
			(xy 57.327871 -125.761406) (xy 57.316816 -125.815261) (xy 57.298145 -125.866972) (xy 57.272245 -125.915467)
			(xy 57.239652 -125.959743) (xy 57.201042 -125.998881) (xy 57.157213 -126.032073) (xy 57.109074 -126.058629)
			(xy 57.057622 -126.078001) (xy 57.003922 -126.089787) (xy 56.949086 -126.093743) (xy 56.89425 -126.089787)
			(xy 56.84055 -126.078001) (xy 56.789098 -126.058629) (xy 56.740959 -126.032073) (xy 56.69713 -125.998881)
			(xy 56.65852 -125.959743) (xy 56.625927 -125.915467) (xy 56.600027 -125.866972) (xy 56.581356 -125.815261)
			(xy 56.570301 -125.761406) (xy 56.56709 -125.706521) (xy 56.571791 -125.651745) (xy 56.584305 -125.59821)
			(xy 56.604374 -125.547025) (xy 56.631583 -125.499252) (xy 56.648096 -125.47727) (xy 56.6624 -125.45796)
			(xy 56.684244 -125.415162) (xy 56.697668 -125.369026) (xy 56.702195 -125.32119) (xy 56.697664 -125.273354)
			(xy 56.684237 -125.227219) (xy 56.662389 -125.184423) (xy 56.648096 -125.165104) (xy 56.63247 -125.144325)
			(xy 56.606386 -125.099351) (xy 56.586642 -125.051256) (xy 56.573604 -125.000927) (xy 56.567512 -124.949294)
			(xy 56.567578 -124.923296) (xy 56.567556 -124.901237) (xy 56.56082 -124.857647) (xy 56.546649 -124.815878)
			(xy 56.525469 -124.777189) (xy 56.497917 -124.742745) (xy 56.464825 -124.713584) (xy 56.427189 -124.690585)
			(xy 56.386143 -124.67444) (xy 56.364632 -124.66955) (xy 56.346474 -124.665555) (xy 56.310978 -124.654484)
			(xy 56.293766 -124.647452) (xy 56.280863 -124.641981) (xy 56.255817 -124.629397) (xy 56.243728 -124.622306)
			(xy 56.216042 -124.603764) (xy 56.197822 -124.591864) (xy 56.15823 -124.573806) (xy 56.116142 -124.562756)
			(xy 56.072786 -124.559036) (xy 56.02943 -124.562756) (xy 55.987342 -124.573806) (xy 55.94775 -124.591864)
			(xy 55.92953 -124.603764) (xy 55.908301 -124.61871) (xy 55.862596 -124.643339) (xy 55.813974 -124.661541)
			(xy 55.763331 -124.67298) (xy 55.737506 -124.675646) (xy 55.707752 -124.677653) (xy 55.648266 -124.673504)
			(xy 55.590149 -124.660148) (xy 55.53482 -124.637909) (xy 55.483626 -124.60733) (xy 55.437816 -124.569155)
			(xy 55.41772 -124.547122) (xy 55.402875 -124.531894) (xy 55.369052 -124.506117) (xy 55.331413 -124.486327)
			(xy 55.291006 -124.473074) (xy 55.248957 -124.466728) (xy 55.206438 -124.467466) (xy 55.164635 -124.475266)
			(xy 55.124711 -124.489913) (xy 55.106062 -124.500132) (xy 55.085635 -124.511372) (xy 55.042619 -124.529356)
			(xy 54.997734 -124.541971) (xy 54.974744 -124.545852) (xy 54.949236 -124.549324) (xy 54.897765 -124.550189)
			(xy 54.846645 -124.544123) (xy 54.796805 -124.531236) (xy 54.749151 -124.511764) (xy 54.704549 -124.486059)
			(xy 54.683914 -124.470668) (xy 54.665288 -124.457935) (xy 54.624545 -124.438565) (xy 54.581022 -124.426694)
			(xy 54.536086 -124.422695) (xy 54.49115 -124.426694) (xy 54.447627 -124.438565) (xy 54.406884 -124.457935)
			(xy 54.388258 -124.470668) (xy 54.367322 -124.486274) (xy 54.322009 -124.512225) (xy 54.273581 -124.531752)
			(xy 54.222941 -124.544492) (xy 54.171037 -124.550205) (xy 54.144926 -124.549916) (xy 54.118981 -124.548805)
			(xy 54.067731 -124.540426) (xy 54.018092 -124.525167) (xy 53.970984 -124.503312) (xy 53.927279 -124.475265)
			(xy 53.887785 -124.441545) (xy 53.853234 -124.402776) (xy 53.824266 -124.359676) (xy 53.81244 -124.336556)
			(xy 53.800473 -124.310975) (xy 53.783372 -124.257153) (xy 53.774392 -124.201398) (xy 53.773731 -124.144929)
			(xy 53.781401 -124.088978) (xy 53.788818 -124.061728) (xy 53.791104 -124.0536) (xy 53.794152 -124.033788)
			(xy 53.796012 -124.018969) (xy 53.79356 -123.989211) (xy 53.784258 -123.960838) (xy 53.768616 -123.935404)
			(xy 53.758338 -123.924568) (xy 53.42636 -123.59259) (xy 53.426106 -123.59259) (xy 53.263292 -123.429522)
			(xy 53.162708 -123.328938) (xy 50.183288 -123.328938) (xy 49.479708 -124.032264) (xy 49.469613 -124.042908)
			(xy 49.454127 -124.067812) (xy 49.444754 -124.095601) (xy 49.441993 -124.124798) (xy 49.44599 -124.153851)
			(xy 49.456532 -124.181217) (xy 49.464468 -124.193554) (xy 49.4795 -124.216477) (xy 49.503545 -124.265737)
			(xy 49.52029 -124.317933) (xy 49.52939 -124.371988) (xy 49.530658 -124.426789) (xy 49.524068 -124.481207)
			(xy 49.509755 -124.534122) (xy 49.488014 -124.584442) (xy 49.459293 -124.631131) (xy 49.424184 -124.673228)
			(xy 49.383411 -124.709865) (xy 49.337812 -124.740287) (xy 49.288327 -124.763868) (xy 49.262284 -124.77242)
			(xy 49.222406 -124.784866) (xy 49.17313 -124.851922) (xy 49.17313 -126.688596) (xy 49.697825 -127.213291)
			(xy 52.630321 -127.213291) (xy 52.634948 -127.157988) (xy 52.647538 -127.103938) (xy 52.667828 -127.052284)
			(xy 52.695387 -127.004114) (xy 52.729635 -126.960446) (xy 52.769849 -126.922201) (xy 52.81518 -126.890187)
			(xy 52.864672 -126.865078) (xy 52.917279 -126.847406) (xy 52.971892 -126.837543) (xy 53.027357 -126.835696)
			(xy 53.082443 -126.841899) (xy 68.563362 -126.841899) (xy 68.569667 -126.787861) (xy 68.583763 -126.735314)
			(xy 68.605352 -126.685376) (xy 68.633975 -126.639109) (xy 68.65112 -126.617984) (xy 68.664943 -126.600908)
			(xy 68.687042 -126.562941) (xy 68.702281 -126.521739) (xy 68.710206 -126.478529) (xy 68.710581 -126.434601)
			(xy 68.703395 -126.391262) (xy 68.688862 -126.349806) (xy 68.667414 -126.311467) (xy 68.653914 -126.294134)
			(xy 68.637082 -126.27275) (xy 68.609231 -126.225998) (xy 68.588476 -126.175692) (xy 68.575259 -126.122902)
			(xy 68.569859 -126.068751) (xy 68.572393 -126.014391) (xy 68.582806 -125.960977) (xy 68.600877 -125.909646)
			(xy 68.626222 -125.861489) (xy 68.658301 -125.81753) (xy 68.696432 -125.778704) (xy 68.739805 -125.745836)
			(xy 68.787497 -125.719627) (xy 68.838494 -125.700632) (xy 68.891711 -125.689257) (xy 68.946017 -125.685742)
			(xy 69.000256 -125.690163) (xy 69.053276 -125.702426) (xy 69.103948 -125.72227) (xy 69.151196 -125.749272)
			(xy 69.194014 -125.78286) (xy 69.231491 -125.822317) (xy 69.262832 -125.866806) (xy 69.287368 -125.91538)
			(xy 69.304579 -125.967006) (xy 69.314099 -126.020586) (xy 69.315724 -126.074981) (xy 69.309421 -126.129034)
			(xy 69.295323 -126.181596) (xy 69.273731 -126.231548) (xy 69.245103 -126.277829) (xy 69.227954 -126.29896)
			(xy 69.214186 -126.316078) (xy 69.192086 -126.354036) (xy 69.176843 -126.39523) (xy 69.168913 -126.438431)
			(xy 69.16853 -126.482353) (xy 69.175707 -126.525686) (xy 69.19023 -126.567139) (xy 69.211666 -126.605477)
			(xy 69.22516 -126.62281) (xy 69.241894 -126.644264) (xy 69.269727 -126.69101) (xy 69.290467 -126.741306)
			(xy 69.30367 -126.794085) (xy 69.309058 -126.848222) (xy 69.308067 -126.869396) (xy 71.769167 -126.869396)
			(xy 71.771716 -126.814375) (xy 71.782337 -126.760329) (xy 71.800801 -126.708436) (xy 71.826704 -126.659826)
			(xy 71.859481 -126.615561) (xy 71.898419 -126.576603) (xy 71.942668 -126.543804) (xy 71.991265 -126.517877)
			(xy 72.043149 -126.499387) (xy 72.09719 -126.488738) (xy 72.152209 -126.486162) (xy 72.207009 -126.491715)
			(xy 72.260394 -126.505276) (xy 72.3112 -126.526549) (xy 72.35832 -126.555071) (xy 72.37984 -126.572264)
			(xy 72.397082 -126.585932) (xy 72.435292 -126.607737) (xy 72.476683 -126.622645) (xy 72.520022 -126.630212)
			(xy 72.564016 -126.630212) (xy 72.607355 -126.622645) (xy 72.648746 -126.607737) (xy 72.686956 -126.585932)
			(xy 72.704198 -126.572264) (xy 72.720883 -126.558804) (xy 72.756784 -126.535374) (xy 72.775826 -126.525528)
			(xy 72.795943 -126.514816) (xy 72.83241 -126.487491) (xy 72.863422 -126.454104) (xy 72.887987 -126.415723)
			(xy 72.905317 -126.373579) (xy 72.914858 -126.329021) (xy 72.916304 -126.283475) (xy 72.909609 -126.238401)
			(xy 72.894987 -126.195242) (xy 72.872907 -126.155381) (xy 72.858884 -126.137416) (xy 72.841719 -126.115582)
			(xy 72.813173 -126.067945) (xy 72.791835 -126.016673) (xy 72.778155 -125.962848) (xy 72.772423 -125.90761)
			(xy 72.77476 -125.852123) (xy 72.785116 -125.797562) (xy 72.803273 -125.745078) (xy 72.828847 -125.695782)
			(xy 72.861297 -125.650713) (xy 72.899939 -125.610825) (xy 72.943955 -125.576961) (xy 72.992415 -125.549836)
			(xy 73.044296 -125.530023) (xy 73.098501 -125.51794) (xy 73.153885 -125.513844) (xy 73.209278 -125.51782)
			(xy 73.26351 -125.529785) (xy 73.315434 -125.549485) (xy 73.363953 -125.576506) (xy 73.408042 -125.610274)
			(xy 73.44677 -125.650078) (xy 73.479318 -125.695076) (xy 73.504999 -125.744317) (xy 73.52327 -125.796761)
			(xy 73.533744 -125.8513) (xy 73.536201 -125.906781) (xy 73.530589 -125.962032) (xy 73.517026 -126.015886)
			(xy 73.495799 -126.067205) (xy 73.467357 -126.114904) (xy 73.432299 -126.157975) (xy 73.391368 -126.19551)
			(xy 73.345427 -126.226713) (xy 73.320656 -126.23927) (xy 73.30035 -126.249635) (xy 73.26354 -126.276527)
			(xy 73.232116 -126.309553) (xy 73.207087 -126.347654) (xy 73.189255 -126.389609) (xy 73.179193 -126.434072)
			(xy 73.177223 -126.479616) (xy 73.183409 -126.524782) (xy 73.197551 -126.56812) (xy 73.219196 -126.60824)
			(xy 73.228721 -126.620724) (xy 75.15037 -126.620724) (xy 75.156483 -126.565556) (xy 75.170526 -126.511856)
			(xy 75.192203 -126.460759) (xy 75.221056 -126.413342) (xy 75.256476 -126.370608) (xy 75.297716 -126.333457)
			(xy 75.343903 -126.302675) (xy 75.394064 -126.278911) (xy 75.44714 -126.262667) (xy 75.502008 -126.254286)
			(xy 75.557513 -126.253945) (xy 75.585066 -126.257304) (xy 75.607833 -126.260075) (xy 75.653656 -126.258202)
			(xy 75.698399 -126.248133) (xy 75.740607 -126.230193) (xy 75.778907 -126.204966) (xy 75.812056 -126.173273)
			(xy 75.838975 -126.136142) (xy 75.85879 -126.094782) (xy 75.870857 -126.050536) (xy 75.874783 -126.004843)
			(xy 75.873102 -125.981968) (xy 75.871022 -125.954294) (xy 75.873937 -125.898874) (xy 75.884854 -125.844462)
			(xy 75.903539 -125.792206) (xy 75.9296 -125.74321) (xy 75.962486 -125.698507) (xy 76.001503 -125.659042)
			(xy 76.045827 -125.625647) (xy 76.094522 -125.599027) (xy 76.146561 -125.579745) (xy 76.200844 -125.568208)
			(xy 76.256227 -125.564659) (xy 76.311539 -125.569172) (xy 76.365614 -125.581653) (xy 76.417309 -125.601839)
			(xy 76.465533 -125.629303) (xy 76.509268 -125.663465) (xy 76.547592 -125.703604) (xy 76.579694 -125.748873)
			(xy 76.604897 -125.798316) (xy 76.62267 -125.850889) (xy 76.632636 -125.905483) (xy 76.634587 -125.960945)
			(xy 76.628479 -126.016104) (xy 76.614443 -126.069796) (xy 76.592774 -126.120887) (xy 76.563931 -126.168299)
			(xy 76.528521 -126.21103) (xy 76.487293 -126.24818) (xy 76.441117 -126.278962) (xy 76.390967 -126.302729)
			(xy 76.337903 -126.318977) (xy 76.283044 -126.327365) (xy 76.227549 -126.327714) (xy 76.2 -126.32436)
			(xy 76.177234 -126.321592) (xy 76.131413 -126.32347) (xy 76.086673 -126.333544) (xy 76.044469 -126.351485)
			(xy 76.006171 -126.376712) (xy 75.973024 -126.408404) (xy 75.946104 -126.445532) (xy 75.926288 -126.486889)
			(xy 75.914218 -126.531132) (xy 75.910286 -126.576822) (xy 75.911964 -126.599696) (xy 75.914023 -126.627377)
			(xy 75.91111 -126.682806) (xy 75.900196 -126.737228) (xy 75.88151 -126.789493) (xy 75.855447 -126.838499)
			(xy 75.822558 -126.883211) (xy 75.783536 -126.922684) (xy 75.739206 -126.956086) (xy 75.690503 -126.982711)
			(xy 75.638456 -127.001996) (xy 75.584164 -127.013536) (xy 75.528772 -127.017086) (xy 75.47345 -127.012572)
			(xy 75.419367 -127.000088) (xy 75.367664 -126.979898) (xy 75.319433 -126.952428) (xy 75.275691 -126.918259)
			(xy 75.237363 -126.878112) (xy 75.205258 -126.832834) (xy 75.180053 -126.783381) (xy 75.162281 -126.730798)
			(xy 75.152316 -126.676195) (xy 75.15037 -126.620724) (xy 73.228721 -126.620724) (xy 73.233026 -126.626366)
			(xy 73.249537 -126.647585) (xy 73.276715 -126.693979) (xy 73.296943 -126.743797) (xy 73.3098 -126.796005)
			(xy 73.315021 -126.849518) (xy 73.312497 -126.903227) (xy 73.30228 -126.956015) (xy 73.284582 -127.006787)
			(xy 73.259771 -127.054488) (xy 73.228361 -127.098128) (xy 73.191006 -127.136801) (xy 73.148481 -127.169703)
			(xy 73.101668 -127.196152) (xy 73.05154 -127.215599) (xy 72.999137 -127.227639) (xy 72.945548 -127.232023)
			(xy 72.891886 -127.228659) (xy 72.839264 -127.217617) (xy 72.788775 -127.199128) (xy 72.741467 -127.173574)
			(xy 72.698324 -127.141486) (xy 72.66024 -127.103531) (xy 72.643746 -127.082296) (xy 72.633222 -127.069079)
			(xy 72.606623 -127.048268) (xy 72.575495 -127.035167) (xy 72.542019 -127.030696) (xy 72.508543 -127.035167)
			(xy 72.477415 -127.048268) (xy 72.450816 -127.069079) (xy 72.440292 -127.082296) (xy 72.428862 -127.097028)
			(xy 72.415213 -127.114266) (xy 72.393403 -127.152439) (xy 72.378491 -127.193796) (xy 72.37092 -127.237103)
			(xy 72.370917 -127.281066) (xy 72.378483 -127.324374) (xy 72.393391 -127.365733) (xy 72.415196 -127.403909)
			(xy 72.428862 -127.421132) (xy 72.445866 -127.442397) (xy 72.474171 -127.488907) (xy 72.495406 -127.539041)
			(xy 72.509121 -127.591731) (xy 72.515021 -127.645856) (xy 72.514524 -127.65913) (xy 73.368926 -127.65913)
			(xy 73.372902 -127.604804) (xy 73.384745 -127.551635) (xy 73.404204 -127.500758) (xy 73.430864 -127.453256)
			(xy 73.464155 -127.410142) (xy 73.503369 -127.372335) (xy 73.547671 -127.34064) (xy 73.596114 -127.315734)
			(xy 73.647668 -127.298146) (xy 73.701234 -127.288252) (xy 73.755669 -127.286262) (xy 73.809814 -127.29222)
			(xy 73.862514 -127.305998) (xy 73.912647 -127.327302) (xy 73.959143 -127.355678) (xy 74.001013 -127.390522)
			(xy 74.037362 -127.431091) (xy 74.067418 -127.47652) (xy 74.090539 -127.525841) (xy 74.106232 -127.578003)
			(xy 74.114163 -127.631894) (xy 74.11466 -127.65913) (xy 74.114163 -127.686366) (xy 74.106232 -127.740257)
			(xy 74.096405 -127.772922) (xy 77.267814 -127.772922) (xy 77.271885 -127.7173) (xy 77.284011 -127.662863)
			(xy 77.303934 -127.610772) (xy 77.33123 -127.562137) (xy 77.365316 -127.517994) (xy 77.405465 -127.479285)
			(xy 77.450823 -127.446834) (xy 77.500423 -127.421333) (xy 77.553207 -127.403326) (xy 77.60805 -127.393196)
			(xy 77.663784 -127.391159) (xy 77.719221 -127.397259) (xy 77.773178 -127.411365) (xy 77.824507 -127.433177)
			(xy 77.872113 -127.462231) (xy 77.914981 -127.497906) (xy 77.952198 -127.539443) (xy 77.982971 -127.585956)
			(xy 78.006643 -127.636453) (xy 78.022711 -127.68986) (xy 78.030831 -127.745036) (xy 78.03134 -127.772922)
			(xy 78.030831 -127.800808) (xy 78.022711 -127.855984) (xy 78.006643 -127.909391) (xy 77.982971 -127.959888)
			(xy 77.952198 -128.006401) (xy 77.914981 -128.047938) (xy 77.872113 -128.083613) (xy 77.824507 -128.112667)
			(xy 77.773178 -128.134479) (xy 77.719221 -128.148585) (xy 77.663784 -128.154685) (xy 77.60805 -128.152648)
			(xy 77.553207 -128.142518) (xy 77.500423 -128.124511) (xy 77.450823 -128.09901) (xy 77.405465 -128.066559)
			(xy 77.365316 -128.02785) (xy 77.33123 -127.983707) (xy 77.303934 -127.935072) (xy 77.284011 -127.882981)
			(xy 77.271885 -127.828544) (xy 77.267814 -127.772922) (xy 74.096405 -127.772922) (xy 74.090539 -127.792419)
			(xy 74.067418 -127.84174) (xy 74.037362 -127.887169) (xy 74.001013 -127.927738) (xy 73.959143 -127.962582)
			(xy 73.912647 -127.990958) (xy 73.862514 -128.012262) (xy 73.809814 -128.02604) (xy 73.755669 -128.031998)
			(xy 73.701234 -128.030008) (xy 73.647668 -128.020114) (xy 73.596114 -128.002526) (xy 73.547671 -127.97762)
			(xy 73.503369 -127.945925) (xy 73.464155 -127.908118) (xy 73.430864 -127.865004) (xy 73.404204 -127.817502)
			(xy 73.384745 -127.766625) (xy 73.372902 -127.713456) (xy 73.368926 -127.65913) (xy 72.514524 -127.65913)
			(xy 72.512984 -127.700264) (xy 72.50305 -127.753796) (xy 72.485433 -127.805313) (xy 72.460506 -127.853718)
			(xy 72.428802 -127.89798) (xy 72.390993 -127.937158) (xy 72.347887 -127.970417) (xy 72.300399 -127.99705)
			(xy 72.249542 -128.016488) (xy 72.196397 -128.02832) (xy 72.142096 -128.032292) (xy 72.087795 -128.02832)
			(xy 72.03465 -128.016488) (xy 71.983793 -127.99705) (xy 71.936305 -127.970417) (xy 71.893199 -127.937158)
			(xy 71.85539 -127.89798) (xy 71.823686 -127.853718) (xy 71.798759 -127.805313) (xy 71.781142 -127.753796)
			(xy 71.771208 -127.700264) (xy 71.769171 -127.645856) (xy 71.775071 -127.591731) (xy 71.788786 -127.539041)
			(xy 71.810021 -127.488907) (xy 71.838326 -127.442397) (xy 71.85533 -127.421132) (xy 71.869018 -127.403923)
			(xy 71.890826 -127.365744) (xy 71.905735 -127.324381) (xy 71.913302 -127.281069) (xy 71.913299 -127.2371)
			(xy 71.905728 -127.193789) (xy 71.890813 -127.152428) (xy 71.869 -127.114251) (xy 71.85533 -127.097028)
			(xy 71.838179 -127.075473) (xy 71.809634 -127.028367) (xy 71.788335 -126.977571) (xy 71.774748 -126.924193)
			(xy 71.769167 -126.869396) (xy 69.308067 -126.869396) (xy 69.306514 -126.902567) (xy 69.296094 -126.955965)
			(xy 69.278019 -127.007279) (xy 69.252673 -127.05542) (xy 69.220595 -127.099362) (xy 69.182468 -127.138171)
			(xy 69.139102 -127.171023) (xy 69.091418 -127.197218) (xy 69.040433 -127.216201) (xy 68.987228 -127.227566)
			(xy 68.932936 -127.231072) (xy 68.878712 -127.226646) (xy 68.825708 -127.21438) (xy 68.775051 -127.194536)
			(xy 68.727819 -127.167535) (xy 68.685016 -127.133953) (xy 68.647553 -127.094502) (xy 68.616225 -127.050023)
			(xy 68.591699 -127.00146) (xy 68.574496 -126.949846) (xy 68.564983 -126.896279) (xy 68.563362 -126.841899)
			(xy 53.082443 -126.841899) (xy 53.082505 -126.841906) (xy 53.136171 -126.856041) (xy 53.187223 -126.877802)
			(xy 53.234583 -126.906731) (xy 53.277251 -126.942217) (xy 53.314327 -126.983511) (xy 53.330094 -127.00635)
			(xy 53.342764 -127.024538) (xy 53.373319 -127.056644) (xy 53.408981 -127.082962) (xy 53.448668 -127.102694)
			(xy 53.491176 -127.115241) (xy 53.535216 -127.120224) (xy 53.579453 -127.117491) (xy 53.601112 -127.112776)
			(xy 53.628216 -127.106817) (xy 53.68348 -127.101798) (xy 53.738888 -127.10484) (xy 53.793271 -127.115879)
			(xy 53.84548 -127.134681) (xy 53.894414 -127.160849) (xy 53.93904 -127.193832) (xy 53.978416 -127.232932)
			(xy 54.011711 -127.277325) (xy 54.038222 -127.326075) (xy 54.057389 -127.378151) (xy 54.068809 -127.432455)
			(xy 54.07224 -127.48784) (xy 54.067609 -127.543138) (xy 54.055015 -127.597182) (xy 54.034723 -127.64883)
			(xy 54.007162 -127.696993) (xy 53.972912 -127.740654) (xy 53.932698 -127.778892) (xy 53.887368 -127.8109)
			(xy 53.837878 -127.836001) (xy 53.785274 -127.853667) (xy 53.730664 -127.863524) (xy 53.675203 -127.865364)
			(xy 53.620061 -127.859149) (xy 53.566401 -127.845009) (xy 53.515356 -127.823244) (xy 53.468004 -127.794312)
			(xy 53.425343 -127.758824) (xy 53.388275 -127.717529) (xy 53.372512 -127.69469) (xy 53.359826 -127.676513)
			(xy 53.329275 -127.644405) (xy 53.293617 -127.618084) (xy 53.253933 -127.59835) (xy 53.211427 -127.585801)
			(xy 53.167388 -127.580816) (xy 53.123152 -127.583549) (xy 53.101494 -127.588264) (xy 53.074411 -127.594317)
			(xy 53.019142 -127.599339) (xy 52.963729 -127.5963) (xy 52.909341 -127.585264) (xy 52.857126 -127.566464)
			(xy 52.808186 -127.540297) (xy 52.763555 -127.507314) (xy 52.724173 -127.468213) (xy 52.690872 -127.423818)
			(xy 52.664355 -127.375067) (xy 52.645182 -127.322988) (xy 52.633757 -127.26868) (xy 52.630321 -127.213291)
			(xy 49.697825 -127.213291) (xy 50.848932 -128.364398) (xy 56.449024 -128.364398) (xy 56.452381 -128.309646)
			(xy 56.463731 -128.255978) (xy 56.482827 -128.204554) (xy 56.509257 -128.156486) (xy 56.542449 -128.112813)
			(xy 56.581686 -128.074478) (xy 56.62612 -128.042311) (xy 56.67479 -128.017007) (xy 56.726644 -127.999113)
			(xy 56.780562 -127.989015) (xy 56.835377 -127.986932) (xy 56.889906 -127.992908) (xy 56.942968 -128.006816)
			(xy 56.993419 -128.028353) (xy 57.040165 -128.057055) (xy 57.082199 -128.092301) (xy 57.11861 -128.133329)
			(xy 57.148612 -128.179253) (xy 57.171555 -128.229079) (xy 57.179718 -128.255268) (xy 57.18484 -128.271186)
			(xy 57.202129 -128.299797) (xy 57.226259 -128.322933) (xy 57.255571 -128.339004) (xy 57.288053 -128.346906)
			(xy 57.321472 -128.346096) (xy 57.353533 -128.336631) (xy 57.382033 -128.319159) (xy 57.405013 -128.294882)
			(xy 57.413398 -128.280414) (xy 57.421648 -128.265584) (xy 57.440476 -128.237347) (xy 57.45099 -128.224026)
			(xy 57.464443 -128.206632) (xy 57.485734 -128.168161) (xy 57.500086 -128.1266) (xy 57.507073 -128.083189)
			(xy 57.506484 -128.039224) (xy 57.498339 -127.996015) (xy 57.482879 -127.954853) (xy 57.460567 -127.916966)
			(xy 57.446672 -127.899922) (xy 57.428939 -127.878529) (xy 57.399548 -127.831369) (xy 57.377485 -127.780368)
			(xy 57.363239 -127.726656) (xy 57.357127 -127.671425) (xy 57.359282 -127.615898) (xy 57.369659 -127.561307)
			(xy 57.388026 -127.508861) (xy 57.413977 -127.459725) (xy 57.446936 -127.414985) (xy 57.486172 -127.375636)
			(xy 57.530816 -127.342549) (xy 57.579878 -127.316457) (xy 57.632271 -127.297939) (xy 57.686832 -127.287405)
			(xy 57.742352 -127.28509) (xy 57.797601 -127.291044) (xy 57.851353 -127.305135) (xy 57.902418 -127.327051)
			(xy 57.949662 -127.356306) (xy 57.971182 -127.373888) (xy 57.988531 -127.388) (xy 58.027159 -127.410528)
			(xy 58.069135 -127.425945) (xy 58.113161 -127.433774) (xy 58.157879 -127.433774) (xy 58.201905 -127.425945)
			(xy 58.243881 -127.410528) (xy 58.282509 -127.388) (xy 58.299858 -127.373888) (xy 58.320005 -127.357407)
			(xy 58.363999 -127.329593) (xy 58.411436 -127.308171) (xy 58.461393 -127.29356) (xy 58.512897 -127.286042)
			(xy 58.564946 -127.285766) (xy 58.616527 -127.292735) (xy 58.666636 -127.306815) (xy 58.714299 -127.327731)
			(xy 58.758587 -127.355076) (xy 58.778902 -127.371348) (xy 58.796126 -127.385014) (xy 58.834303 -127.406819)
			(xy 58.875663 -127.421727) (xy 58.918972 -127.429295) (xy 58.962936 -127.429295) (xy 59.006245 -127.421727)
			(xy 59.047605 -127.406819) (xy 59.085782 -127.385014) (xy 59.103006 -127.371348) (xy 59.124054 -127.354579)
			(xy 59.169979 -127.326533) (xy 59.219461 -127.305384) (xy 59.271469 -127.291571) (xy 59.324924 -127.285383)
			(xy 59.378713 -127.286947) (xy 59.431718 -127.296231) (xy 59.482836 -127.313043) (xy 59.531005 -127.337031)
			(xy 59.575223 -127.367699) (xy 59.61457 -127.404407) (xy 59.648228 -127.446393) (xy 59.675498 -127.492784)
			(xy 59.695811 -127.542614) (xy 59.708747 -127.594848) (xy 59.714035 -127.648399) (xy 59.71359 -127.658091)
			(xy 61.36798 -127.658091) (xy 61.37195 -127.603821) (xy 61.383774 -127.550706) (xy 61.403199 -127.499876)
			(xy 61.429813 -127.452414) (xy 61.463049 -127.409328) (xy 61.5022 -127.371536) (xy 61.546433 -127.339843)
			(xy 61.594806 -127.314922) (xy 61.64629 -127.297304) (xy 61.69979 -127.287363) (xy 61.754166 -127.285312)
			(xy 61.808262 -127.291194) (xy 61.860927 -127.304884) (xy 61.91104 -127.32609) (xy 61.957534 -127.354362)
			(xy 61.978794 -127.371348) (xy 61.996036 -127.385016) (xy 62.034246 -127.406821) (xy 62.075637 -127.421729)
			(xy 62.118976 -127.429296) (xy 62.16297 -127.429296) (xy 62.206309 -127.421729) (xy 62.2477 -127.406821)
			(xy 62.28591 -127.385016) (xy 62.303152 -127.371348) (xy 62.325572 -127.353457) (xy 62.374824 -127.32406)
			(xy 62.427996 -127.302552) (xy 62.483835 -127.289441) (xy 62.541023 -127.285037) (xy 62.598211 -127.289441)
			(xy 62.65405 -127.302552) (xy 62.707222 -127.32406) (xy 62.756474 -127.353457) (xy 62.778894 -127.371348)
			(xy 62.796118 -127.385014) (xy 62.834295 -127.406819) (xy 62.875655 -127.421727) (xy 62.918964 -127.429295)
			(xy 62.962928 -127.429295) (xy 63.006237 -127.421727) (xy 63.047597 -127.406819) (xy 63.085774 -127.385014)
			(xy 63.102998 -127.371348) (xy 63.125421 -127.353426) (xy 63.174689 -127.323974) (xy 63.22789 -127.302425)
			(xy 63.283766 -127.289289) (xy 63.340996 -127.284875) (xy 63.398226 -127.289289) (xy 63.454102 -127.302425)
			(xy 63.507303 -127.323974) (xy 63.556571 -127.353426) (xy 63.578994 -127.371348) (xy 63.596218 -127.385014)
			(xy 63.634395 -127.406819) (xy 63.675755 -127.421727) (xy 63.719064 -127.429295) (xy 63.763028 -127.429295)
			(xy 63.806337 -127.421727) (xy 63.847697 -127.406819) (xy 63.885874 -127.385014) (xy 63.903098 -127.371348)
			(xy 63.925518 -127.353457) (xy 63.97477 -127.32406) (xy 64.027942 -127.302552) (xy 64.083781 -127.289441)
			(xy 64.140969 -127.285037) (xy 64.198157 -127.289441) (xy 64.253996 -127.302552) (xy 64.307168 -127.32406)
			(xy 64.35642 -127.353457) (xy 64.37884 -127.371348) (xy 64.396082 -127.385016) (xy 64.434292 -127.406821)
			(xy 64.475683 -127.421729) (xy 64.519022 -127.429296) (xy 64.563016 -127.429296) (xy 64.606355 -127.421729)
			(xy 64.647746 -127.406821) (xy 64.685956 -127.385016) (xy 64.703198 -127.371348) (xy 64.724747 -127.354206)
			(xy 64.771868 -127.325722) (xy 64.822667 -127.304483) (xy 64.876039 -127.290951) (xy 64.930822 -127.285421)
			(xy 64.985821 -127.288014) (xy 65.039841 -127.298673) (xy 65.091703 -127.317165) (xy 65.140279 -127.343089)
			(xy 65.184511 -127.37588) (xy 65.223436 -127.414823) (xy 65.256205 -127.45907) (xy 65.282106 -127.507659)
			(xy 65.300574 -127.55953) (xy 65.311207 -127.613554) (xy 65.313774 -127.668555) (xy 65.308218 -127.723335)
			(xy 65.294661 -127.776701) (xy 65.273398 -127.82749) (xy 65.244892 -127.874597) (xy 65.227708 -127.896112)
			(xy 65.214077 -127.913363) (xy 65.192271 -127.951534) (xy 65.17736 -127.992888) (xy 65.169789 -128.036192)
			(xy 65.169785 -128.080153) (xy 65.177346 -128.123458) (xy 65.192248 -128.164816) (xy 65.214045 -128.202991)
			(xy 65.227708 -128.220216) (xy 65.245642 -128.242629) (xy 65.275089 -128.2919) (xy 65.296635 -128.345103)
			(xy 65.309769 -128.40098) (xy 65.31418 -128.458211) (xy 66.167661 -128.458211) (xy 66.172072 -128.400982)
			(xy 66.185207 -128.345107) (xy 66.206753 -128.291907) (xy 66.236202 -128.242639) (xy 66.254122 -128.220216)
			(xy 66.267821 -128.203017) (xy 66.28962 -128.164834) (xy 66.304523 -128.123469) (xy 66.312084 -128.080156)
			(xy 66.31208 -128.036188) (xy 66.304508 -127.992878) (xy 66.289597 -127.951516) (xy 66.267789 -127.913337)
			(xy 66.254122 -127.896112) (xy 66.236934 -127.874569) (xy 66.208368 -127.827441) (xy 66.187055 -127.776621)
			(xy 66.173458 -127.723216) (xy 66.167875 -127.66839) (xy 66.170427 -127.613341) (xy 66.181059 -127.559267)
			(xy 66.199538 -127.507349) (xy 66.225463 -127.458719) (xy 66.258266 -127.414437) (xy 66.297234 -127.375468)
			(xy 66.341516 -127.342664) (xy 66.390146 -127.31674) (xy 66.442064 -127.29826) (xy 66.496137 -127.287627)
			(xy 66.551187 -127.285075) (xy 66.606012 -127.290657) (xy 66.659418 -127.304254) (xy 66.710238 -127.325567)
			(xy 66.757366 -127.354132) (xy 66.778886 -127.371348) (xy 66.79611 -127.385014) (xy 66.834287 -127.406819)
			(xy 66.875647 -127.421727) (xy 66.918956 -127.429295) (xy 66.96292 -127.429295) (xy 67.006229 -127.421727)
			(xy 67.047589 -127.406819) (xy 67.085766 -127.385014) (xy 67.10299 -127.371348) (xy 67.124074 -127.354392)
			(xy 67.170267 -127.326219) (xy 67.220047 -127.30502) (xy 67.27237 -127.291242) (xy 67.326134 -127.285174)
			(xy 67.380212 -127.286943) (xy 67.433465 -127.296513) (xy 67.484775 -127.313682) (xy 67.533063 -127.338089)
			(xy 67.577315 -127.369222) (xy 67.6166 -127.406426) (xy 67.650093 -127.44892) (xy 67.67709 -127.495809)
			(xy 67.697024 -127.54611) (xy 67.709475 -127.598764) (xy 67.714183 -127.652665) (xy 67.713894 -127.657635)
			(xy 69.370657 -127.657635) (xy 69.374677 -127.603473) (xy 69.386517 -127.550469) (xy 69.405925 -127.499745)
			(xy 69.432491 -127.452376) (xy 69.465652 -127.409364) (xy 69.504706 -127.371622) (xy 69.548824 -127.339949)
			(xy 69.597073 -127.315016) (xy 69.64843 -127.297351) (xy 69.701808 -127.287328) (xy 69.756075 -127.285159)
			(xy 69.810082 -127.290891) (xy 69.862685 -127.304402) (xy 69.912769 -127.325406) (xy 69.959274 -127.353458)
			(xy 69.980556 -127.370332) (xy 69.997687 -127.38388) (xy 70.035663 -127.405449) (xy 70.076765 -127.420212)
			(xy 70.119786 -127.427737) (xy 70.163459 -127.427802) (xy 70.206502 -127.420405) (xy 70.247648 -127.405764)
			(xy 70.285688 -127.384309) (xy 70.302882 -127.37084) (xy 70.324217 -127.354035) (xy 70.37079 -127.326103)
			(xy 70.420925 -127.305227) (xy 70.47356 -127.291851) (xy 70.527578 -127.286257) (xy 70.581837 -127.288564)
			(xy 70.635186 -127.298723) (xy 70.686495 -127.316519) (xy 70.734677 -127.341574) (xy 70.778712 -127.373359)
			(xy 70.817666 -127.411199) (xy 70.850714 -127.454294) (xy 70.877157 -127.501729) (xy 70.896433 -127.5525)
			(xy 70.908135 -127.605532) (xy 70.912015 -127.659701) (xy 70.90799 -127.713859) (xy 70.896145 -127.766859)
			(xy 70.876733 -127.817579) (xy 70.850163 -127.864943) (xy 70.816999 -127.907948) (xy 70.777944 -127.945684)
			(xy 70.733824 -127.97735) (xy 70.685575 -128.002276) (xy 70.634218 -128.019934) (xy 70.580842 -128.02995)
			(xy 70.526578 -128.032111) (xy 70.472574 -128.026372) (xy 70.419976 -128.012855) (xy 70.369897 -127.991845)
			(xy 70.323398 -127.963788) (xy 70.30212 -127.946912) (xy 70.284935 -127.933435) (xy 70.246972 -127.911858)
			(xy 70.205881 -127.897085) (xy 70.162869 -127.88955) (xy 70.119203 -127.889475) (xy 70.076166 -127.896862)
			(xy 70.035024 -127.911493) (xy 69.996987 -127.932939) (xy 69.979794 -127.946404) (xy 69.958514 -127.963278)
			(xy 69.911939 -127.991214) (xy 69.861802 -128.012093) (xy 69.809166 -128.025473) (xy 69.755145 -128.03107)
			(xy 69.700883 -128.028767) (xy 69.647531 -128.018611) (xy 69.596218 -128.000817) (xy 69.548031 -127.975764)
			(xy 69.503992 -127.943981) (xy 69.465033 -127.906141) (xy 69.431979 -127.863048) (xy 69.405532 -127.815612)
			(xy 69.38625 -127.76484) (xy 69.374542 -127.711806) (xy 69.370657 -127.657635) (xy 67.713894 -127.657635)
			(xy 67.711047 -127.70668) (xy 67.700135 -127.759674) (xy 67.681674 -127.810534) (xy 67.656054 -127.85819)
			(xy 67.623813 -127.90164) (xy 67.585628 -127.939973) (xy 67.564254 -127.956564) (xy 67.551098 -127.967121)
			(xy 67.530328 -127.993681) (xy 67.517252 -128.024759) (xy 67.512785 -128.058178) (xy 67.51724 -128.091599)
			(xy 67.530306 -128.122682) (xy 67.551067 -128.149249) (xy 67.564254 -128.159764) (xy 67.578986 -128.171448)
			(xy 67.59621 -128.185114) (xy 67.634387 -128.206919) (xy 67.675747 -128.221827) (xy 67.719056 -128.229395)
			(xy 67.76302 -128.229395) (xy 67.806329 -128.221827) (xy 67.847689 -128.206919) (xy 67.885866 -128.185114)
			(xy 67.90309 -128.171448) (xy 67.924609 -128.154228) (xy 67.971739 -128.125658) (xy 68.022563 -128.104341)
			(xy 68.075972 -128.090742) (xy 68.130802 -128.085157) (xy 68.185856 -128.087708) (xy 68.239934 -128.09834)
			(xy 68.291856 -128.116821) (xy 68.34049 -128.142747) (xy 68.384776 -128.175553) (xy 68.423747 -128.214524)
			(xy 68.456553 -128.25881) (xy 68.482479 -128.307444) (xy 68.50096 -128.359367) (xy 68.511592 -128.413445)
			(xy 68.514143 -128.468499) (xy 68.508558 -128.523328) (xy 68.494959 -128.576737) (xy 68.473642 -128.627561)
			(xy 68.445072 -128.674691) (xy 68.427854 -128.696212) (xy 68.414221 -128.713462) (xy 68.392411 -128.751632)
			(xy 68.377497 -128.792987) (xy 68.369925 -128.836291) (xy 68.36992 -128.880253) (xy 68.377483 -128.92356)
			(xy 68.392388 -128.964918) (xy 68.414189 -129.003092) (xy 68.427854 -129.020316) (xy 68.444992 -129.041778)
			(xy 68.473459 -129.088746) (xy 68.494726 -129.139382) (xy 68.508331 -129.192591) (xy 68.513981 -129.247221)
			(xy 68.511554 -129.302089) (xy 68.5011 -129.356006) (xy 68.482848 -129.407805) (xy 68.457192 -129.456365)
			(xy 68.424688 -129.500635) (xy 68.386039 -129.539655) (xy 68.364354 -129.55651) (xy 68.351143 -129.567017)
			(xy 68.330413 -129.593646) (xy 68.31737 -129.62477) (xy 68.312923 -129.658222) (xy 68.317381 -129.691673)
			(xy 68.330435 -129.722793) (xy 68.351175 -129.749414) (xy 68.364354 -129.759964) (xy 68.379086 -129.771394)
			(xy 68.39631 -129.78506) (xy 68.434487 -129.806865) (xy 68.475847 -129.821773) (xy 68.519156 -129.829341)
			(xy 68.56312 -129.829341) (xy 68.606429 -129.821773) (xy 68.647789 -129.806865) (xy 68.685966 -129.78506)
			(xy 68.70319 -129.771394) (xy 68.724494 -129.754439) (xy 68.771003 -129.726138) (xy 68.821135 -129.704906)
			(xy 68.873824 -129.691195) (xy 68.927946 -129.685297) (xy 68.982351 -129.687338) (xy 69.03588 -129.697273)
			(xy 69.087393 -129.714893) (xy 69.135794 -129.739821) (xy 69.180052 -129.771526) (xy 69.219226 -129.809335)
			(xy 69.252481 -129.852441) (xy 69.279109 -129.899928) (xy 69.298543 -129.950784) (xy 69.31037 -130.003927)
			(xy 69.314338 -130.058226) (xy 69.310363 -130.112523) (xy 69.298529 -130.165665) (xy 69.279087 -130.216518)
			(xy 69.252453 -130.264001) (xy 69.219192 -130.307103) (xy 69.180013 -130.344906) (xy 69.13575 -130.376606)
			(xy 69.087346 -130.401527) (xy 69.03583 -130.41914) (xy 68.9823 -130.429068) (xy 68.927895 -130.431101)
			(xy 68.873773 -130.425196) (xy 68.821087 -130.411478) (xy 68.770957 -130.390239) (xy 68.724452 -130.361931)
			(xy 68.70319 -130.344926) (xy 68.685966 -130.33126) (xy 68.647789 -130.309455) (xy 68.606429 -130.294547)
			(xy 68.56312 -130.286979) (xy 68.519156 -130.286979) (xy 68.475847 -130.294547) (xy 68.434487 -130.309455)
			(xy 68.39631 -130.33126) (xy 68.379086 -130.344926) (xy 68.358004 -130.361861) (xy 68.311833 -130.390011)
			(xy 68.262077 -130.411191) (xy 68.209782 -130.424957) (xy 68.156047 -130.431019) (xy 68.102 -130.429249)
			(xy 68.048776 -130.419686) (xy 67.997493 -130.402529) (xy 67.949229 -130.37814) (xy 67.904998 -130.34703)
			(xy 67.865728 -130.309853) (xy 67.832245 -130.267391) (xy 67.805251 -130.220534) (xy 67.785314 -130.170267)
			(xy 67.772852 -130.117646) (xy 67.768128 -130.063777) (xy 67.77124 -130.00979) (xy 67.782123 -129.956821)
			(xy 67.800549 -129.90598) (xy 67.82613 -129.858338) (xy 67.858329 -129.814893) (xy 67.89647 -129.776559)
			(xy 67.917822 -129.759964) (xy 67.931004 -129.749399) (xy 67.951819 -129.722811) (xy 67.964925 -129.691691)
			(xy 67.969402 -129.658222) (xy 67.964937 -129.624752) (xy 67.951842 -129.593628) (xy 67.931036 -129.567032)
			(xy 67.917822 -129.55651) (xy 67.90309 -129.54508) (xy 67.885868 -129.531367) (xy 67.847676 -129.50948)
			(xy 67.806279 -129.494514) (xy 67.762921 -129.486917) (xy 67.718901 -129.486917) (xy 67.675543 -129.494514)
			(xy 67.634146 -129.50948) (xy 67.595954 -129.531367) (xy 67.578732 -129.54508) (xy 67.556325 -129.563001)
			(xy 67.507087 -129.592452) (xy 67.453914 -129.614001) (xy 67.398065 -129.627139) (xy 67.340861 -129.631552)
			(xy 67.283657 -129.627139) (xy 67.227808 -129.614001) (xy 67.174635 -129.592452) (xy 67.125397 -129.563001)
			(xy 67.10299 -129.54508) (xy 67.085763 -129.531379) (xy 67.047565 -129.509514) (xy 67.00617 -129.494564)
			(xy 66.962817 -129.486974) (xy 66.918805 -129.486974) (xy 66.875452 -129.494564) (xy 66.834057 -129.509514)
			(xy 66.795859 -129.531379) (xy 66.778632 -129.54508) (xy 66.75712 -129.562275) (xy 66.709995 -129.590772)
			(xy 66.659189 -129.612023) (xy 66.605808 -129.625564) (xy 66.551016 -129.631101) (xy 66.496005 -129.628512)
			(xy 66.441975 -129.617855) (xy 66.390102 -129.599362) (xy 66.341515 -129.573434) (xy 66.297275 -129.540638)
			(xy 66.258343 -129.501687) (xy 66.225568 -129.45743) (xy 66.199665 -129.408831) (xy 66.181196 -129.356949)
			(xy 66.170566 -129.302914) (xy 66.168004 -129.247902) (xy 66.173568 -129.193112) (xy 66.187135 -129.139738)
			(xy 66.208411 -129.088943) (xy 66.236931 -129.041832) (xy 66.254122 -129.020316) (xy 66.267821 -129.003117)
			(xy 66.28962 -128.964934) (xy 66.304523 -128.923569) (xy 66.312084 -128.880256) (xy 66.31208 -128.836288)
			(xy 66.304508 -128.792978) (xy 66.289597 -128.751616) (xy 66.267789 -128.713437) (xy 66.254122 -128.696212)
			(xy 66.236214 -128.673779) (xy 66.206763 -128.624513) (xy 66.185213 -128.571313) (xy 66.172076 -128.515439)
			(xy 66.167661 -128.458211) (xy 65.31418 -128.458211) (xy 65.309765 -128.515441) (xy 65.296628 -128.571318)
			(xy 65.27508 -128.624519) (xy 65.245629 -128.673789) (xy 65.227708 -128.696212) (xy 65.214077 -128.713463)
			(xy 65.192271 -128.751634) (xy 65.17736 -128.792988) (xy 65.169789 -128.836292) (xy 65.169785 -128.880253)
			(xy 65.177346 -128.923558) (xy 65.192248 -128.964916) (xy 65.214045 -129.003091) (xy 65.227708 -129.020316)
			(xy 65.245587 -129.042745) (xy 65.274985 -129.091995) (xy 65.296494 -129.145166) (xy 65.309607 -129.201003)
			(xy 65.314014 -129.25819) (xy 65.30961 -129.315377) (xy 65.296501 -129.371215) (xy 65.274994 -129.424387)
			(xy 65.245598 -129.473638) (xy 65.227708 -129.496058) (xy 65.214003 -129.513272) (xy 65.192196 -129.551488)
			(xy 65.177289 -129.592885) (xy 65.169725 -129.636229) (xy 65.16973 -129.680228) (xy 65.177304 -129.723571)
			(xy 65.19222 -129.764964) (xy 65.214035 -129.803175) (xy 65.227708 -129.820416) (xy 65.244808 -129.841999)
			(xy 65.273327 -129.889097) (xy 65.2946 -129.939881) (xy 65.308165 -129.993243) (xy 65.313726 -130.048021)
			(xy 65.311162 -130.10302) (xy 65.300529 -130.157043) (xy 65.282059 -130.208911) (xy 65.256153 -130.257496)
			(xy 65.223377 -130.301736) (xy 65.184445 -130.34067) (xy 65.140205 -130.373447) (xy 65.091621 -130.399354)
			(xy 65.039753 -130.417826) (xy 64.985731 -130.428461) (xy 64.930731 -130.431027) (xy 64.875953 -130.425467)
			(xy 64.822591 -130.411903) (xy 64.771807 -130.390631) (xy 64.724708 -130.362115) (xy 64.703198 -130.344926)
			(xy 64.685971 -130.331225) (xy 64.647773 -130.30936) (xy 64.606378 -130.29441) (xy 64.563025 -130.28682)
			(xy 64.519013 -130.28682) (xy 64.47566 -130.29441) (xy 64.434265 -130.30936) (xy 64.396067 -130.331225)
			(xy 64.37884 -130.344926) (xy 64.357775 -130.361874) (xy 64.311605 -130.390004) (xy 64.261852 -130.411166)
			(xy 64.209564 -130.424913) (xy 64.155837 -130.430958) (xy 64.101801 -130.429174) (xy 64.04859 -130.419597)
			(xy 63.997323 -130.402429) (xy 63.949075 -130.378032) (xy 63.904861 -130.346916) (xy 63.865608 -130.309736)
			(xy 63.832143 -130.267272) (xy 63.805166 -130.220418) (xy 63.785246 -130.170155) (xy 63.772801 -130.117542)
			(xy 63.768091 -130.063682) (xy 63.771216 -130.009706) (xy 63.78211 -129.95675) (xy 63.800545 -129.905924)
			(xy 63.826132 -129.858297) (xy 63.858336 -129.814868) (xy 63.896479 -129.776551) (xy 63.91783 -129.759964)
			(xy 63.931011 -129.749398) (xy 63.951825 -129.72281) (xy 63.96493 -129.69169) (xy 63.969407 -129.658222)
			(xy 63.964942 -129.624753) (xy 63.951848 -129.593628) (xy 63.931043 -129.567033) (xy 63.91783 -129.55651)
			(xy 63.903098 -129.54508) (xy 63.885874 -129.531414) (xy 63.847697 -129.509609) (xy 63.806337 -129.494701)
			(xy 63.763028 -129.487133) (xy 63.719064 -129.487133) (xy 63.675755 -129.494701) (xy 63.634395 -129.509609)
			(xy 63.596218 -129.531414) (xy 63.578994 -129.54508) (xy 63.557464 -129.562284) (xy 63.510335 -129.590849)
			(xy 63.459514 -129.612161) (xy 63.406108 -129.625756) (xy 63.351282 -129.631338) (xy 63.296232 -129.628785)
			(xy 63.242158 -129.618152) (xy 63.19024 -129.599671) (xy 63.141609 -129.573746) (xy 63.097327 -129.540942)
			(xy 63.058359 -129.501974) (xy 63.025554 -129.457692) (xy 62.999629 -129.409061) (xy 62.981148 -129.357143)
			(xy 62.970515 -129.303069) (xy 62.967962 -129.248019) (xy 62.973544 -129.193193) (xy 62.987139 -129.139787)
			(xy 63.008451 -129.088966) (xy 63.037015 -129.041837) (xy 63.05423 -129.020316) (xy 63.067933 -129.003119)
			(xy 63.08974 -128.964937) (xy 63.104649 -128.923572) (xy 63.112213 -128.880257) (xy 63.112208 -128.836287)
			(xy 63.104634 -128.792974) (xy 63.089717 -128.751612) (xy 63.067902 -128.713435) (xy 63.05423 -128.696212)
			(xy 63.037012 -128.674788) (xy 63.008494 -128.627802) (xy 62.987187 -128.577136) (xy 62.973553 -128.52389)
			(xy 62.967889 -128.469218) (xy 62.970317 -128.414308) (xy 62.980783 -128.36035) (xy 62.999062 -128.308515)
			(xy 63.024757 -128.259927) (xy 63.05731 -128.21564) (xy 63.096015 -128.176615) (xy 63.11773 -128.159764)
			(xy 63.130959 -128.149291) (xy 63.151732 -128.122713) (xy 63.164805 -128.091616) (xy 63.169264 -128.058178)
			(xy 63.164794 -128.024743) (xy 63.15171 -127.99365) (xy 63.130928 -127.967079) (xy 63.11773 -127.956564)
			(xy 63.102998 -127.94488) (xy 63.085774 -127.931214) (xy 63.047597 -127.909409) (xy 63.006237 -127.894501)
			(xy 62.962928 -127.886933) (xy 62.918964 -127.886933) (xy 62.875655 -127.894501) (xy 62.834295 -127.909409)
			(xy 62.796118 -127.931214) (xy 62.778894 -127.94488) (xy 62.756487 -127.962801) (xy 62.707249 -127.992252)
			(xy 62.654076 -128.013801) (xy 62.598227 -128.026939) (xy 62.541023 -128.031352) (xy 62.483819 -128.026939)
			(xy 62.42797 -128.013801) (xy 62.374797 -127.992252) (xy 62.325559 -127.962801) (xy 62.303152 -127.94488)
			(xy 62.285925 -127.931179) (xy 62.247727 -127.909314) (xy 62.206332 -127.894364) (xy 62.162979 -127.886774)
			(xy 62.118967 -127.886774) (xy 62.075614 -127.894364) (xy 62.034219 -127.909314) (xy 61.996021 -127.931179)
			(xy 61.978794 -127.94488) (xy 61.95752 -127.961848) (xy 61.911024 -127.990118) (xy 61.86091 -128.011322)
			(xy 61.808245 -128.025009) (xy 61.754148 -128.030888) (xy 61.699772 -128.028835) (xy 61.646273 -128.018892)
			(xy 61.59479 -128.001271) (xy 61.546418 -127.976348) (xy 61.502187 -127.944652) (xy 61.463038 -127.906859)
			(xy 61.429804 -127.863771) (xy 61.403192 -127.816308) (xy 61.383769 -127.765477) (xy 61.371948 -127.712361)
			(xy 61.36798 -127.658091) (xy 59.71359 -127.658091) (xy 59.711566 -127.702154) (xy 59.701391 -127.754995)
			(xy 59.683722 -127.805824) (xy 59.658926 -127.853582) (xy 59.627519 -127.897277) (xy 59.590154 -127.936001)
			(xy 59.547607 -127.968948) (xy 59.500765 -127.995433) (xy 59.4506 -128.014906) (xy 59.398155 -128.026961)
			(xy 59.344523 -128.031347) (xy 59.290817 -128.027974) (xy 59.238155 -128.016911) (xy 59.187631 -127.99839)
			(xy 59.140296 -127.972794) (xy 59.097136 -127.940656) (xy 59.059046 -127.902644) (xy 59.042554 -127.88138)
			(xy 59.032039 -127.868188) (xy 59.005469 -127.847417) (xy 58.974382 -127.834343) (xy 58.940954 -127.829881)
			(xy 58.907526 -127.834343) (xy 58.876439 -127.847417) (xy 58.849869 -127.868188) (xy 58.839354 -127.88138)
			(xy 58.82767 -127.896112) (xy 58.814036 -127.913362) (xy 58.792225 -127.951531) (xy 58.77731 -127.992886)
			(xy 58.769737 -128.036191) (xy 58.769733 -128.080153) (xy 58.777296 -128.12346) (xy 58.792202 -128.164818)
			(xy 58.814004 -128.202993) (xy 58.82767 -128.220216) (xy 58.844535 -128.241373) (xy 58.872711 -128.287559)
			(xy 58.893913 -128.337333) (xy 58.907695 -128.38965) (xy 58.913766 -128.443411) (xy 58.912001 -128.497484)
			(xy 58.902435 -128.550733) (xy 58.885269 -128.60204) (xy 58.860865 -128.650325) (xy 58.829735 -128.694574)
			(xy 58.792534 -128.733856) (xy 58.750044 -128.767347) (xy 58.703158 -128.794341) (xy 58.652861 -128.814272)
			(xy 58.600211 -128.82672) (xy 58.546314 -128.831424) (xy 58.492303 -128.828286) (xy 58.439314 -128.81737)
			(xy 58.38846 -128.798907) (xy 58.34081 -128.773284) (xy 58.297366 -128.741041) (xy 58.259041 -128.702854)
			(xy 58.242454 -128.68148) (xy 58.231939 -128.668288) (xy 58.205369 -128.647517) (xy 58.174282 -128.634443)
			(xy 58.140854 -128.629981) (xy 58.107426 -128.634443) (xy 58.076339 -128.647517) (xy 58.049769 -128.668288)
			(xy 58.039254 -128.68148) (xy 58.02757 -128.695958) (xy 58.013852 -128.713197) (xy 57.991986 -128.75144)
			(xy 57.977046 -128.792882) (xy 57.96948 -128.836281) (xy 57.969516 -128.880333) (xy 57.977153 -128.923719)
			(xy 57.99216 -128.965137) (xy 58.014089 -129.003344) (xy 58.027824 -129.02057) (xy 58.044828 -129.041827)
			(xy 58.073209 -129.088274) (xy 58.094526 -129.138358) (xy 58.108328 -129.191011) (xy 58.114318 -129.245113)
			(xy 58.11237 -129.29951) (xy 58.102526 -129.353044) (xy 58.084994 -129.404575) (xy 58.060149 -129.453006)
			(xy 58.028519 -129.497305) (xy 57.990778 -129.536528) (xy 57.94773 -129.56984) (xy 57.900293 -129.596533)
			(xy 57.849475 -129.616036) (xy 57.796359 -129.627935) (xy 57.742078 -129.631976) (xy 57.687786 -129.628074)
			(xy 57.63464 -129.616311) (xy 57.583773 -129.596938) (xy 57.536266 -129.570367) (xy 57.493134 -129.537165)
			(xy 57.455293 -129.498039) (xy 57.423549 -129.453821) (xy 57.39858 -129.405454) (xy 57.380916 -129.353968)
			(xy 57.370935 -129.300459) (xy 57.368848 -129.246067) (xy 57.374699 -129.191951) (xy 57.388366 -129.139263)
			(xy 57.409555 -129.089124) (xy 57.437816 -129.042604) (xy 57.4548 -129.021332) (xy 57.468529 -129.004101)
			(xy 57.490397 -128.965857) (xy 57.505338 -128.924413) (xy 57.512904 -128.881013) (xy 57.512866 -128.836958)
			(xy 57.505227 -128.793571) (xy 57.490216 -128.752152) (xy 57.468283 -128.713946) (xy 57.454546 -128.69672)
			(xy 57.44083 -128.679194) (xy 57.426539 -128.660643) (xy 57.39232 -128.62868) (xy 57.352826 -128.603525)
			(xy 57.309392 -128.586029) (xy 57.263489 -128.576785) (xy 57.216669 -128.576106) (xy 57.170516 -128.584014)
			(xy 57.126593 -128.600241) (xy 57.086386 -128.624239) (xy 57.068466 -128.639316) (xy 57.047561 -128.657078)
			(xy 57.001536 -128.686924) (xy 56.951632 -128.709698) (xy 56.898928 -128.724909) (xy 56.844563 -128.732228)
			(xy 56.789713 -128.731497) (xy 56.735563 -128.722731) (xy 56.683284 -128.70612) (xy 56.634005 -128.682023)
			(xy 56.588792 -128.65096) (xy 56.548622 -128.613605) (xy 56.514363 -128.570763) (xy 56.486757 -128.523361)
			(xy 56.466399 -128.472423) (xy 56.45373 -128.419051) (xy 56.449024 -128.364398) (xy 50.848932 -128.364398)
			(xy 52.859432 -130.374898) (xy 53.873908 -130.374898) (xy 53.904388 -130.405378) (xy 57.921144 -130.405378)
			(xy 57.944785 -130.404852) (xy 57.991251 -130.396103) (xy 58.035298 -130.378915) (xy 58.075409 -130.35388)
			(xy 58.1102 -130.321861) (xy 58.138472 -130.283962) (xy 58.15925 -130.24149) (xy 58.171818 -130.195909)
			(xy 58.175744 -130.14879) (xy 58.173874 -130.125216) (xy 58.172604 -130.11404) (xy 58.17235 -130.112516)
			(xy 58.168835 -130.085446) (xy 58.168827 -130.030861) (xy 58.176787 -129.97686) (xy 58.192543 -129.924598)
			(xy 58.215759 -129.875196) (xy 58.245937 -129.829712) (xy 58.28243 -129.789119) (xy 58.324458 -129.754288)
			(xy 58.37112 -129.725964) (xy 58.421416 -129.704755) (xy 58.474269 -129.691113) (xy 58.528547 -129.685333)
			(xy 58.583087 -129.687536) (xy 58.609992 -129.692146) (xy 58.640781 -129.698596) (xy 58.699774 -129.720419)
			(xy 58.75427 -129.751829) (xy 58.778902 -129.771394) (xy 58.796126 -129.78506) (xy 58.834303 -129.806865)
			(xy 58.875663 -129.821773) (xy 58.918972 -129.829341) (xy 58.962936 -129.829341) (xy 59.006245 -129.821773)
			(xy 59.047605 -129.806865) (xy 59.085782 -129.78506) (xy 59.103006 -129.771394) (xy 59.10453 -129.770124)
			(xy 59.117738 -129.759964) (xy 59.130917 -129.749415) (xy 59.151659 -129.722794) (xy 59.164714 -129.691674)
			(xy 59.169173 -129.658222) (xy 59.164725 -129.624769) (xy 59.151681 -129.593645) (xy 59.130949 -129.567017)
			(xy 59.117738 -129.55651) (xy 59.097337 -129.540707) (xy 59.060671 -129.504396) (xy 59.029369 -129.463371)
			(xy 59.004029 -129.418418) (xy 58.985136 -129.370397) (xy 58.973054 -129.320228) (xy 58.968012 -129.268871)
			(xy 58.96864 -129.243074) (xy 58.970252 -129.215907) (xy 58.98037 -129.162435) (xy 58.998152 -129.111002)
			(xy 59.023223 -129.062701) (xy 59.055048 -129.018556) (xy 59.092953 -128.979507) (xy 59.136131 -128.946383)
			(xy 59.159648 -128.932686) (xy 59.184343 -128.9195) (xy 59.236771 -128.899871) (xy 59.291545 -128.888309)
			(xy 59.347433 -128.885072) (xy 59.403176 -128.890234) (xy 59.457519 -128.903678) (xy 59.509238 -128.925103)
			(xy 59.55717 -128.954025) (xy 59.579002 -128.971548) (xy 59.596226 -128.985214) (xy 59.634403 -129.007019)
			(xy 59.675763 -129.021927) (xy 59.719072 -129.029495) (xy 59.763036 -129.029495) (xy 59.806345 -129.021927)
			(xy 59.847705 -129.007019) (xy 59.885882 -128.985214) (xy 59.903106 -128.971548) (xy 59.925027 -128.954016)
			(xy 59.973114 -128.925064) (xy 59.998864 -128.91389) (xy 60.024671 -128.903782) (xy 60.078466 -128.890447)
			(xy 60.133643 -128.885227) (xy 60.188984 -128.888238) (xy 60.243269 -128.899412) (xy 60.295299 -128.918504)
			(xy 60.343929 -128.945092) (xy 60.388083 -128.978589) (xy 60.426789 -129.018257) (xy 60.459193 -129.06322)
			(xy 60.484579 -129.112488) (xy 60.502388 -129.164971) (xy 60.512226 -129.219514) (xy 60.513382 -129.258314)
			(xy 61.367934 -129.258314) (xy 61.37191 -129.203988) (xy 61.383753 -129.150819) (xy 61.403212 -129.099942)
			(xy 61.429872 -129.05244) (xy 61.463163 -129.009326) (xy 61.502377 -128.971519) (xy 61.546679 -128.939824)
			(xy 61.595122 -128.914918) (xy 61.646676 -128.89733) (xy 61.700242 -128.887436) (xy 61.754677 -128.885446)
			(xy 61.808822 -128.891404) (xy 61.861522 -128.905182) (xy 61.911655 -128.926486) (xy 61.958151 -128.954862)
			(xy 62.000021 -128.989706) (xy 62.03637 -129.030275) (xy 62.066426 -129.075704) (xy 62.089547 -129.125025)
			(xy 62.10524 -129.177187) (xy 62.113171 -129.231078) (xy 62.113668 -129.258314) (xy 62.113171 -129.28555)
			(xy 62.10524 -129.339441) (xy 62.089547 -129.391603) (xy 62.066426 -129.440924) (xy 62.03637 -129.486353)
			(xy 62.000021 -129.526922) (xy 61.958151 -129.561766) (xy 61.911655 -129.590142) (xy 61.861522 -129.611446)
			(xy 61.808822 -129.625224) (xy 61.754677 -129.631182) (xy 61.700242 -129.629192) (xy 61.646676 -129.619298)
			(xy 61.595122 -129.60171) (xy 61.546679 -129.576804) (xy 61.502377 -129.545109) (xy 61.463163 -129.507302)
			(xy 61.429872 -129.464188) (xy 61.403212 -129.416686) (xy 61.383753 -129.365809) (xy 61.37191 -129.31264)
			(xy 61.367934 -129.258314) (xy 60.513382 -129.258314) (xy 60.513877 -129.274913) (xy 60.507305 -129.329944)
			(xy 60.492654 -129.383396) (xy 60.470247 -129.434087) (xy 60.440579 -129.480901) (xy 60.42279 -129.502154)
			(xy 60.408464 -129.521454) (xy 60.386583 -129.564244) (xy 60.373137 -129.610384) (xy 60.368604 -129.658229)
			(xy 60.373148 -129.706074) (xy 60.386605 -129.752211) (xy 60.408495 -129.794995) (xy 60.42279 -129.81432)
			(xy 60.441377 -129.836649) (xy 60.47212 -129.885945) (xy 60.494849 -129.939411) (xy 60.509015 -129.995753)
			(xy 60.512198 -130.024632) (xy 60.514206 -130.052375) (xy 60.510952 -130.1079) (xy 60.499467 -130.162323)
			(xy 60.480008 -130.214429) (xy 60.466986 -130.239008) (xy 60.458391 -130.254072) (xy 60.438799 -130.282692)
			(xy 60.42787 -130.296158) (xy 60.414202 -130.313381) (xy 60.392395 -130.351557) (xy 60.377485 -130.392916)
			(xy 60.369918 -130.436225) (xy 60.369919 -130.48019) (xy 60.377489 -130.523499) (xy 60.392401 -130.564857)
			(xy 60.414211 -130.603031) (xy 60.42787 -130.620262) (xy 60.447278 -130.644634) (xy 60.463653 -130.67284)
			(xy 75.033884 -130.67284) (xy 75.037955 -130.617218) (xy 75.050081 -130.562781) (xy 75.070004 -130.51069)
			(xy 75.0973 -130.462055) (xy 75.131386 -130.417912) (xy 75.171535 -130.379203) (xy 75.216893 -130.346752)
			(xy 75.266493 -130.321251) (xy 75.319277 -130.303244) (xy 75.37412 -130.293114) (xy 75.429854 -130.291077)
			(xy 75.485291 -130.297177) (xy 75.539248 -130.311283) (xy 75.590577 -130.333095) (xy 75.638183 -130.362149)
			(xy 75.681051 -130.397824) (xy 75.718268 -130.439361) (xy 75.749041 -130.485874) (xy 75.762506 -130.514598)
			(xy 76.18806 -130.514598) (xy 76.192131 -130.458976) (xy 76.204257 -130.404539) (xy 76.22418 -130.352448)
			(xy 76.251476 -130.303813) (xy 76.285562 -130.25967) (xy 76.325711 -130.220961) (xy 76.371069 -130.18851)
			(xy 76.420669 -130.163009) (xy 76.473453 -130.145002) (xy 76.528296 -130.134872) (xy 76.58403 -130.132835)
			(xy 76.639467 -130.138935) (xy 76.693424 -130.153041) (xy 76.744753 -130.174853) (xy 76.792359 -130.203907)
			(xy 76.835227 -130.239582) (xy 76.872444 -130.281119) (xy 76.903217 -130.327632) (xy 76.926889 -130.378129)
			(xy 76.942957 -130.431536) (xy 76.951077 -130.486712) (xy 76.951586 -130.514598) (xy 76.951077 -130.542484)
			(xy 76.942957 -130.59766) (xy 76.926889 -130.651067) (xy 76.903217 -130.701564) (xy 76.872444 -130.748077)
			(xy 76.835227 -130.789614) (xy 76.792359 -130.825289) (xy 76.744753 -130.854343) (xy 76.693424 -130.876155)
			(xy 76.639467 -130.890261) (xy 76.58403 -130.896361) (xy 76.528296 -130.894324) (xy 76.473453 -130.884194)
			(xy 76.420669 -130.866187) (xy 76.371069 -130.840686) (xy 76.325711 -130.808235) (xy 76.285562 -130.769526)
			(xy 76.251476 -130.725383) (xy 76.22418 -130.676748) (xy 76.204257 -130.624657) (xy 76.192131 -130.57022)
			(xy 76.18806 -130.514598) (xy 75.762506 -130.514598) (xy 75.772713 -130.536371) (xy 75.788781 -130.589778)
			(xy 75.796901 -130.644954) (xy 75.79741 -130.67284) (xy 75.796901 -130.700726) (xy 75.788781 -130.755902)
			(xy 75.772713 -130.809309) (xy 75.749041 -130.859806) (xy 75.718268 -130.906319) (xy 75.681051 -130.947856)
			(xy 75.638183 -130.983531) (xy 75.590577 -131.012585) (xy 75.539248 -131.034397) (xy 75.485291 -131.048503)
			(xy 75.429854 -131.054603) (xy 75.37412 -131.052566) (xy 75.319277 -131.042436) (xy 75.266493 -131.024429)
			(xy 75.216893 -130.998928) (xy 75.171535 -130.966477) (xy 75.131386 -130.927768) (xy 75.0973 -130.883625)
			(xy 75.070004 -130.83499) (xy 75.050081 -130.782899) (xy 75.037955 -130.728462) (xy 75.033884 -130.67284)
			(xy 60.463653 -130.67284) (xy 60.478557 -130.698512) (xy 60.4901 -130.72745) (xy 60.495914 -130.741736)
			(xy 60.513344 -130.767174) (xy 60.536364 -130.787691) (xy 60.563631 -130.802093) (xy 60.593555 -130.809538)
			(xy 60.608972 -130.81) (xy 61.723016 -130.81) (xy 62.008004 -131.094988) (xy 62.105286 -131.099814)
			(xy 62.143386 -131.068826) (xy 62.163336 -131.053052) (xy 62.206633 -131.026368) (xy 62.253092 -131.005675)
			(xy 62.301888 -130.991339) (xy 62.352157 -130.983614) (xy 62.377574 -130.98272) (xy 62.389004 -130.98272)
			(xy 62.416499 -130.983516) (xy 62.47084 -130.992035) (xy 62.523397 -131.008261) (xy 62.573082 -131.031859)
			(xy 62.618868 -131.062341) (xy 62.659808 -131.099076) (xy 62.677802 -131.11988) (xy 62.694459 -131.140575)
			(xy 62.722487 -131.185703) (xy 62.74398 -131.234285) (xy 62.758522 -131.285379) (xy 62.765832 -131.337997)
			(xy 62.765768 -131.391121) (xy 62.758331 -131.443721) (xy 62.751462 -131.469384) (xy 62.744334 -131.492814)
			(xy 62.724929 -131.53778) (xy 62.699944 -131.579901) (xy 62.685168 -131.599432) (xy 62.668228 -131.62029)
			(xy 62.629478 -131.657517) (xy 62.607952 -131.6736) (xy 62.592602 -131.684381) (xy 62.560157 -131.70321)
			(xy 62.543182 -131.711192) (xy 62.522354 -131.720844) (xy 62.348872 -131.894326) (xy 62.348872 -134.048116)
			(xy 62.967957 -134.048116) (xy 62.973539 -133.993288) (xy 62.987135 -133.939881) (xy 63.008449 -133.889059)
			(xy 63.037014 -133.841929) (xy 63.05423 -133.820408) (xy 63.067941 -133.803217) (xy 63.089747 -133.765034)
			(xy 63.104655 -133.723667) (xy 63.112219 -133.680352) (xy 63.112213 -133.636381) (xy 63.104638 -133.593067)
			(xy 63.089719 -133.551704) (xy 63.067902 -133.513527) (xy 63.05423 -133.496304) (xy 63.037025 -133.474774)
			(xy 63.008458 -133.427646) (xy 62.987144 -133.376824) (xy 62.973547 -133.323417) (xy 62.967963 -133.26859)
			(xy 62.970516 -133.213538) (xy 62.981148 -133.159463) (xy 62.999628 -133.107544) (xy 63.025554 -133.058912)
			(xy 63.058358 -133.014628) (xy 63.097327 -132.975659) (xy 63.141611 -132.942854) (xy 63.190242 -132.916929)
			(xy 63.242162 -132.898448) (xy 63.296237 -132.887816) (xy 63.351288 -132.885263) (xy 63.406115 -132.890846)
			(xy 63.459522 -132.904443) (xy 63.510344 -132.925757) (xy 63.557473 -132.954324) (xy 63.578994 -132.97154)
			(xy 63.596218 -132.985206) (xy 63.634395 -133.007011) (xy 63.675755 -133.021919) (xy 63.719064 -133.029487)
			(xy 63.763028 -133.029487) (xy 63.806337 -133.021919) (xy 63.847697 -133.007011) (xy 63.885874 -132.985206)
			(xy 63.903098 -132.97154) (xy 63.925518 -132.953649) (xy 63.97477 -132.924252) (xy 64.027942 -132.902744)
			(xy 64.083781 -132.889633) (xy 64.140969 -132.885229) (xy 64.198157 -132.889633) (xy 64.253996 -132.902744)
			(xy 64.307168 -132.924252) (xy 64.35642 -132.953649) (xy 64.37884 -132.97154) (xy 64.396082 -132.985208)
			(xy 64.434292 -133.007013) (xy 64.475683 -133.021921) (xy 64.519022 -133.029488) (xy 64.563016 -133.029488)
			(xy 64.606355 -133.021921) (xy 64.647746 -133.007013) (xy 64.685956 -132.985208) (xy 64.703198 -132.97154)
			(xy 64.724754 -132.954407) (xy 64.771874 -132.925925) (xy 64.822672 -132.904686) (xy 64.876043 -132.891155)
			(xy 64.930824 -132.885626) (xy 64.985823 -132.888219) (xy 65.039841 -132.898878) (xy 65.091702 -132.91737)
			(xy 65.140277 -132.943294) (xy 65.184508 -132.976083) (xy 65.223431 -133.015026) (xy 65.2562 -133.059272)
			(xy 65.282101 -133.107859) (xy 65.300569 -133.159729) (xy 65.311202 -133.213752) (xy 65.313281 -133.258305)
			(xy 66.167655 -133.258305) (xy 66.172068 -133.201076) (xy 66.185204 -133.1452) (xy 66.206751 -133.091999)
			(xy 66.236201 -133.042731) (xy 66.254122 -133.020308) (xy 66.267829 -133.003115) (xy 66.289627 -132.96493)
			(xy 66.304529 -132.923564) (xy 66.31209 -132.88025) (xy 66.312084 -132.836282) (xy 66.304512 -132.79297)
			(xy 66.289599 -132.751608) (xy 66.26779 -132.713429) (xy 66.254122 -132.696204) (xy 66.236926 -132.674667)
			(xy 66.208361 -132.627539) (xy 66.187047 -132.576718) (xy 66.173451 -132.523313) (xy 66.167868 -132.468487)
			(xy 66.170421 -132.413437) (xy 66.181053 -132.359363) (xy 66.199533 -132.307445) (xy 66.225458 -132.258814)
			(xy 66.258262 -132.214532) (xy 66.29723 -132.175564) (xy 66.341512 -132.142759) (xy 66.390143 -132.116834)
			(xy 66.442061 -132.098354) (xy 66.496135 -132.087721) (xy 66.551185 -132.085168) (xy 66.60601 -132.090751)
			(xy 66.659416 -132.104347) (xy 66.710237 -132.125659) (xy 66.757365 -132.154225) (xy 66.778886 -132.17144)
			(xy 66.79611 -132.185106) (xy 66.834287 -132.206911) (xy 66.875647 -132.221819) (xy 66.918956 -132.229387)
			(xy 66.96292 -132.229387) (xy 67.006229 -132.221819) (xy 67.047589 -132.206911) (xy 67.085766 -132.185106)
			(xy 67.10299 -132.17144) (xy 67.125413 -132.153518) (xy 67.174681 -132.124066) (xy 67.227882 -132.102517)
			(xy 67.283758 -132.089381) (xy 67.340988 -132.084967) (xy 67.398218 -132.089381) (xy 67.454094 -132.102517)
			(xy 67.507295 -132.124066) (xy 67.556563 -132.153518) (xy 67.578986 -132.17144) (xy 67.59621 -132.185106)
			(xy 67.634387 -132.206911) (xy 67.675747 -132.221819) (xy 67.719056 -132.229387) (xy 67.76302 -132.229387)
			(xy 67.806329 -132.221819) (xy 67.847689 -132.206911) (xy 67.885866 -132.185106) (xy 67.90309 -132.17144)
			(xy 67.924616 -132.154229) (xy 67.971745 -132.125661) (xy 68.022568 -132.104345) (xy 68.075976 -132.090746)
			(xy 68.130804 -132.085162) (xy 68.185857 -132.087713) (xy 68.239934 -132.098345) (xy 68.291855 -132.116826)
			(xy 68.340488 -132.142751) (xy 68.384773 -132.175557) (xy 68.423743 -132.214527) (xy 68.456548 -132.258811)
			(xy 68.482474 -132.307444) (xy 68.500954 -132.359365) (xy 68.511586 -132.413442) (xy 68.514138 -132.468495)
			(xy 68.508554 -132.523323) (xy 68.494956 -132.576731) (xy 68.47364 -132.627554) (xy 68.445071 -132.674683)
			(xy 68.427854 -132.696204) (xy 68.414229 -132.71346) (xy 68.392418 -132.751629) (xy 68.377504 -132.792982)
			(xy 68.369931 -132.836286) (xy 68.369925 -132.880247) (xy 68.377486 -132.923552) (xy 68.39239 -132.96491)
			(xy 68.41419 -133.003084) (xy 68.427854 -133.020308) (xy 68.445782 -133.042726) (xy 68.475235 -133.091995)
			(xy 68.496784 -133.145197) (xy 68.509921 -133.201074) (xy 68.514334 -133.258305) (xy 68.509919 -133.315535)
			(xy 68.496781 -133.371412) (xy 68.47523 -133.424614) (xy 68.445777 -133.473882) (xy 68.427854 -133.496304)
			(xy 68.414229 -133.51356) (xy 68.392418 -133.551729) (xy 68.377504 -133.593082) (xy 68.369931 -133.636386)
			(xy 68.369925 -133.680347) (xy 68.377486 -133.723652) (xy 68.39239 -133.76501) (xy 68.41419 -133.803184)
			(xy 68.427854 -133.820408) (xy 68.445091 -133.841914) (xy 68.473659 -133.889045) (xy 68.494975 -133.93987)
			(xy 68.508572 -133.99328) (xy 68.514156 -134.04811) (xy 68.513643 -134.059168) (xy 70.169034 -134.059168)
			(xy 70.17301 -134.004842) (xy 70.184853 -133.951673) (xy 70.204312 -133.900796) (xy 70.230972 -133.853294)
			(xy 70.264263 -133.81018) (xy 70.303477 -133.772373) (xy 70.347779 -133.740678) (xy 70.396222 -133.715772)
			(xy 70.447776 -133.698184) (xy 70.501342 -133.68829) (xy 70.555777 -133.6863) (xy 70.609922 -133.692258)
			(xy 70.662622 -133.706036) (xy 70.712755 -133.72734) (xy 70.759251 -133.755716) (xy 70.801121 -133.79056)
			(xy 70.83747 -133.831129) (xy 70.867526 -133.876558) (xy 70.890647 -133.925879) (xy 70.90634 -133.978041)
			(xy 70.914271 -134.031932) (xy 70.914768 -134.059168) (xy 70.914271 -134.086404) (xy 70.90634 -134.140295)
			(xy 70.890647 -134.192457) (xy 70.867526 -134.241778) (xy 70.83747 -134.287207) (xy 70.801121 -134.327776)
			(xy 70.759251 -134.36262) (xy 70.712755 -134.390996) (xy 70.662622 -134.4123) (xy 70.609922 -134.426078)
			(xy 70.555777 -134.432036) (xy 70.501342 -134.430046) (xy 70.447776 -134.420152) (xy 70.396222 -134.402564)
			(xy 70.347779 -134.377658) (xy 70.303477 -134.345963) (xy 70.264263 -134.308156) (xy 70.230972 -134.265042)
			(xy 70.204312 -134.21754) (xy 70.184853 -134.166663) (xy 70.17301 -134.113494) (xy 70.169034 -134.059168)
			(xy 68.513643 -134.059168) (xy 68.511603 -134.103165) (xy 68.50097 -134.157243) (xy 68.482489 -134.209165)
			(xy 68.456562 -134.2578) (xy 68.423755 -134.302086) (xy 68.384784 -134.341057) (xy 68.340498 -134.373863)
			(xy 68.291863 -134.39979) (xy 68.239941 -134.418271) (xy 68.185862 -134.428904) (xy 68.130808 -134.431456)
			(xy 68.075978 -134.425872) (xy 68.022568 -134.412274) (xy 67.971743 -134.390958) (xy 67.924612 -134.362389)
			(xy 67.90309 -134.345172) (xy 67.885866 -134.331506) (xy 67.847689 -134.309701) (xy 67.806329 -134.294793)
			(xy 67.76302 -134.287225) (xy 67.719056 -134.287225) (xy 67.675747 -134.294793) (xy 67.634387 -134.309701)
			(xy 67.59621 -134.331506) (xy 67.578986 -134.345172) (xy 67.556563 -134.363094) (xy 67.507295 -134.392546)
			(xy 67.454094 -134.414095) (xy 67.398218 -134.427231) (xy 67.340988 -134.431645) (xy 67.283758 -134.427231)
			(xy 67.227882 -134.414095) (xy 67.174681 -134.392546) (xy 67.125413 -134.363094) (xy 67.10299 -134.345172)
			(xy 67.085766 -134.331506) (xy 67.047589 -134.309701) (xy 67.006229 -134.294793) (xy 66.96292 -134.287225)
			(xy 66.918956 -134.287225) (xy 66.875647 -134.294793) (xy 66.834287 -134.309701) (xy 66.79611 -134.331506)
			(xy 66.778886 -134.345172) (xy 66.75737 -134.362394) (xy 66.71024 -134.390959) (xy 66.659417 -134.412272)
			(xy 66.606009 -134.425867) (xy 66.551181 -134.431449) (xy 66.49613 -134.428896) (xy 66.442054 -134.418262)
			(xy 66.390134 -134.399781) (xy 66.341502 -134.373855) (xy 66.297219 -134.34105) (xy 66.25825 -134.302081)
			(xy 66.225444 -134.257797) (xy 66.199518 -134.209165) (xy 66.181037 -134.157245) (xy 66.170404 -134.10317)
			(xy 66.167851 -134.048118) (xy 66.173433 -133.99329) (xy 66.187028 -133.939883) (xy 66.208341 -133.88906)
			(xy 66.236906 -133.84193) (xy 66.254122 -133.820408) (xy 66.267829 -133.803215) (xy 66.289627 -133.76503)
			(xy 66.304529 -133.723664) (xy 66.31209 -133.68035) (xy 66.312084 -133.636382) (xy 66.304512 -133.59307)
			(xy 66.289599 -133.551708) (xy 66.26779 -133.513529) (xy 66.254122 -133.496304) (xy 66.236206 -133.473877)
			(xy 66.206755 -133.424609) (xy 66.185207 -133.371409) (xy 66.17207 -133.315534) (xy 66.167655 -133.258305)
			(xy 65.313281 -133.258305) (xy 65.313769 -133.268751) (xy 65.308214 -133.32353) (xy 65.294658 -133.376894)
			(xy 65.273396 -133.427683) (xy 65.244891 -133.474789) (xy 65.227708 -133.496304) (xy 65.214085 -133.513561)
			(xy 65.192278 -133.55173) (xy 65.177367 -133.593084) (xy 65.169795 -133.636386) (xy 65.169789 -133.680346)
			(xy 65.177349 -133.723651) (xy 65.19225 -133.765008) (xy 65.214046 -133.803183) (xy 65.227708 -133.820408)
			(xy 65.244852 -133.841966) (xy 65.273389 -133.889071) (xy 65.29468 -133.939865) (xy 65.308262 -133.993239)
			(xy 65.313837 -134.048032) (xy 65.311285 -134.103048) (xy 65.300661 -134.157089) (xy 65.282197 -134.208977)
			(xy 65.256295 -134.257582) (xy 65.22352 -134.301843) (xy 65.184585 -134.340797) (xy 65.14034 -134.373595)
			(xy 65.091749 -134.399521) (xy 65.03987 -134.418011) (xy 64.985834 -134.428662) (xy 64.930819 -134.431242)
			(xy 64.876024 -134.425694) (xy 64.822642 -134.41214) (xy 64.771838 -134.390874) (xy 64.724718 -134.362361)
			(xy 64.703198 -134.345172) (xy 64.685971 -134.331471) (xy 64.647773 -134.309606) (xy 64.606378 -134.294656)
			(xy 64.563025 -134.287066) (xy 64.519013 -134.287066) (xy 64.47566 -134.294656) (xy 64.434265 -134.309606)
			(xy 64.396067 -134.331471) (xy 64.37884 -134.345172) (xy 64.356433 -134.363093) (xy 64.307195 -134.392544)
			(xy 64.254022 -134.414093) (xy 64.198173 -134.427231) (xy 64.140969 -134.431644) (xy 64.083765 -134.427231)
			(xy 64.027916 -134.414093) (xy 63.974743 -134.392544) (xy 63.925505 -134.363093) (xy 63.903098 -134.345172)
			(xy 63.885874 -134.331506) (xy 63.847697 -134.309701) (xy 63.806337 -134.294793) (xy 63.763028 -134.287225)
			(xy 63.719064 -134.287225) (xy 63.675755 -134.294793) (xy 63.634395 -134.309701) (xy 63.596218 -134.331506)
			(xy 63.578994 -134.345172) (xy 63.557471 -134.362386) (xy 63.510342 -134.390951) (xy 63.459519 -134.412265)
			(xy 63.406112 -134.425861) (xy 63.351285 -134.431443) (xy 63.296233 -134.42889) (xy 63.242158 -134.418257)
			(xy 63.190238 -134.399776) (xy 63.141607 -134.373851) (xy 63.097323 -134.341046) (xy 63.058354 -134.302077)
			(xy 63.025549 -134.257793) (xy 62.999624 -134.209162) (xy 62.981143 -134.157242) (xy 62.97051 -134.103167)
			(xy 62.967957 -134.048116) (xy 62.348872 -134.048116) (xy 62.348872 -136.458319) (xy 62.967763 -136.458319)
			(xy 62.972174 -136.401117) (xy 62.98531 -136.345268) (xy 63.006858 -136.292096) (xy 63.036309 -136.24286)
			(xy 63.05423 -136.220454) (xy 63.067955 -136.203245) (xy 63.089818 -136.165044) (xy 63.104767 -136.123645)
			(xy 63.112353 -136.080288) (xy 63.11235 -136.036273) (xy 63.104757 -135.992918) (xy 63.089802 -135.951521)
			(xy 63.067933 -135.913323) (xy 63.05423 -135.896096) (xy 63.037103 -135.874536) (xy 63.008622 -135.827417)
			(xy 62.987385 -135.776619) (xy 62.973856 -135.72325) (xy 62.968328 -135.66847) (xy 62.970921 -135.613473)
			(xy 62.981581 -135.559456) (xy 63.000073 -135.507597) (xy 63.025996 -135.459023) (xy 63.058785 -135.414793)
			(xy 63.097726 -135.375871) (xy 63.141971 -135.343102) (xy 63.190557 -135.317202) (xy 63.242425 -135.298734)
			(xy 63.296447 -135.2881) (xy 63.351445 -135.285532) (xy 63.406222 -135.291086) (xy 63.459586 -135.304641)
			(xy 63.510373 -135.325901) (xy 63.557479 -135.354404) (xy 63.578994 -135.371586) (xy 63.596218 -135.385252)
			(xy 63.634395 -135.407057) (xy 63.675755 -135.421965) (xy 63.719064 -135.429533) (xy 63.763028 -135.429533)
			(xy 63.806337 -135.421965) (xy 63.847697 -135.407057) (xy 63.885874 -135.385252) (xy 63.903098 -135.371586)
			(xy 63.925518 -135.353695) (xy 63.97477 -135.324298) (xy 64.027942 -135.30279) (xy 64.083781 -135.289679)
			(xy 64.140969 -135.285275) (xy 64.198157 -135.289679) (xy 64.253996 -135.30279) (xy 64.307168 -135.324298)
			(xy 64.35642 -135.353695) (xy 64.37884 -135.371586) (xy 64.396082 -135.385254) (xy 64.434292 -135.407059)
			(xy 64.475683 -135.421967) (xy 64.519022 -135.429534) (xy 64.563016 -135.429534) (xy 64.606355 -135.421967)
			(xy 64.647746 -135.407059) (xy 64.685956 -135.385254) (xy 64.703198 -135.371586) (xy 64.724717 -135.354406)
			(xy 64.771822 -135.325894) (xy 64.822611 -135.304627) (xy 64.875977 -135.291068) (xy 64.930758 -135.285513)
			(xy 64.98576 -135.288082) (xy 65.039784 -135.29872) (xy 65.091654 -135.317195) (xy 65.14024 -135.343104)
			(xy 65.184482 -135.375883) (xy 65.223416 -135.414818) (xy 65.256195 -135.45906) (xy 65.282105 -135.507645)
			(xy 65.30058 -135.559515) (xy 65.311218 -135.613539) (xy 65.313787 -135.668541) (xy 65.308232 -135.723322)
			(xy 65.294673 -135.776689) (xy 65.273406 -135.827478) (xy 65.244895 -135.874583) (xy 65.227708 -135.896096)
			(xy 65.214063 -135.913355) (xy 65.192253 -135.951561) (xy 65.17734 -135.992949) (xy 65.169769 -136.036285)
			(xy 65.169766 -136.080277) (xy 65.17733 -136.123614) (xy 65.192237 -136.165004) (xy 65.214041 -136.203213)
			(xy 65.227708 -136.220454) (xy 65.245624 -136.242855) (xy 65.27502 -136.29211) (xy 65.296526 -136.345286)
			(xy 65.309635 -136.401128) (xy 65.314038 -136.458319) (xy 66.167657 -136.458319) (xy 66.172068 -136.401117)
			(xy 66.185203 -136.345269) (xy 66.206751 -136.292097) (xy 66.236202 -136.24286) (xy 66.254122 -136.220454)
			(xy 66.267848 -136.203245) (xy 66.289711 -136.165044) (xy 66.30466 -136.123645) (xy 66.312247 -136.080288)
			(xy 66.312244 -136.036273) (xy 66.304651 -135.992918) (xy 66.289695 -135.951521) (xy 66.267826 -135.913323)
			(xy 66.254122 -135.896096) (xy 66.236887 -135.874616) (xy 66.208392 -135.827487) (xy 66.187143 -135.776678)
			(xy 66.173604 -135.723295) (xy 66.16807 -135.668501) (xy 66.17066 -135.613489) (xy 66.18132 -135.559457)
			(xy 66.199815 -135.507582) (xy 66.225744 -135.458995) (xy 66.258542 -135.414753) (xy 66.297495 -135.37582)
			(xy 66.341753 -135.343044) (xy 66.390354 -135.317139) (xy 66.442237 -135.29867) (xy 66.496275 -135.288038)
			(xy 66.551288 -135.285475) (xy 66.60608 -135.291037) (xy 66.659456 -135.304603) (xy 66.710255 -135.325877)
			(xy 66.757369 -135.354396) (xy 66.778886 -135.371586) (xy 66.79611 -135.385252) (xy 66.834287 -135.407057)
			(xy 66.875647 -135.421965) (xy 66.918956 -135.429533) (xy 66.96292 -135.429533) (xy 67.006229 -135.421965)
			(xy 67.047589 -135.407057) (xy 67.085766 -135.385252) (xy 67.10299 -135.371586) (xy 67.125413 -135.353664)
			(xy 67.174681 -135.324212) (xy 67.227882 -135.302663) (xy 67.283758 -135.289527) (xy 67.340988 -135.285113)
			(xy 67.398218 -135.289527) (xy 67.454094 -135.302663) (xy 67.507295 -135.324212) (xy 67.556563 -135.353664)
			(xy 67.578986 -135.371586) (xy 67.59621 -135.385252) (xy 67.634387 -135.407057) (xy 67.675747 -135.421965)
			(xy 67.719056 -135.429533) (xy 67.76302 -135.429533) (xy 67.806329 -135.421965) (xy 67.847689 -135.407057)
			(xy 67.885866 -135.385252) (xy 67.90309 -135.371586) (xy 67.924582 -135.354351) (xy 67.971695 -135.325798)
			(xy 68.022499 -135.304493) (xy 68.075886 -135.290901) (xy 68.130692 -135.285318) (xy 68.185723 -135.287866)
			(xy 68.23978 -135.298488) (xy 68.291683 -135.316955) (xy 68.340301 -135.342862) (xy 68.384574 -135.375646)
			(xy 68.423538 -135.414591) (xy 68.456343 -135.458849) (xy 68.482274 -135.507455) (xy 68.500765 -135.559349)
			(xy 68.511413 -135.6134) (xy 68.513987 -135.66843) (xy 68.50843 -135.72324) (xy 68.494863 -135.776633)
			(xy 68.473582 -135.827447) (xy 68.445052 -135.874574) (xy 68.427854 -135.896096) (xy 68.414211 -135.913356)
			(xy 68.392406 -135.951563) (xy 68.377496 -135.99295) (xy 68.369927 -136.036285) (xy 68.369924 -136.080276)
			(xy 68.377486 -136.123612) (xy 68.392389 -136.165002) (xy 68.414189 -136.203212) (xy 68.427854 -136.220454)
			(xy 68.445768 -136.242856) (xy 68.47516 -136.292112) (xy 68.496664 -136.345288) (xy 68.509771 -136.401129)
			(xy 68.514173 -136.458319) (xy 68.509766 -136.515509) (xy 68.496652 -136.571349) (xy 68.475143 -136.624522)
			(xy 68.445745 -136.673775) (xy 68.427854 -136.696196) (xy 68.41414 -136.713385) (xy 68.392335 -136.751568)
			(xy 68.377429 -136.792936) (xy 68.369866 -136.836251) (xy 68.369872 -136.880222) (xy 68.377448 -136.923536)
			(xy 68.392366 -136.964899) (xy 68.414182 -137.003076) (xy 68.427854 -137.0203) (xy 68.445082 -137.041813)
			(xy 68.473651 -137.088943) (xy 68.494967 -137.139767) (xy 68.508566 -137.193177) (xy 68.51415 -137.248007)
			(xy 68.513626 -137.259311) (xy 70.168931 -137.259311) (xy 70.173343 -137.202083) (xy 70.186476 -137.146209)
			(xy 70.20802 -137.093008) (xy 70.237465 -137.04374) (xy 70.255384 -137.021316) (xy 70.269085 -137.004118)
			(xy 70.290887 -136.965935) (xy 70.305792 -136.92457) (xy 70.313355 -136.881257) (xy 70.31335 -136.837288)
			(xy 70.305778 -136.793976) (xy 70.290864 -136.752614) (xy 70.269053 -136.714437) (xy 70.255384 -136.697212)
			(xy 70.237503 -136.674775) (xy 70.20805 -136.625543) (xy 70.186497 -136.572375) (xy 70.173356 -136.516531)
			(xy 70.168938 -136.459332) (xy 70.173347 -136.402132) (xy 70.186478 -136.346285) (xy 70.208021 -136.293114)
			(xy 70.237466 -136.243877) (xy 70.255384 -136.22147) (xy 70.269096 -136.20425) (xy 70.290964 -136.166052)
			(xy 70.305916 -136.124656) (xy 70.313506 -136.0813) (xy 70.313505 -136.037286) (xy 70.305913 -135.993931)
			(xy 70.290958 -135.952535) (xy 70.269088 -135.914338) (xy 70.255384 -135.897112) (xy 70.2381 -135.875669)
			(xy 70.209572 -135.828556) (xy 70.188291 -135.777755) (xy 70.174722 -135.724376) (xy 70.169159 -135.66958)
			(xy 70.171724 -135.614562) (xy 70.182362 -135.560521) (xy 70.200839 -135.508636) (xy 70.226755 -135.460036)
			(xy 70.259543 -135.415781) (xy 70.298489 -135.376836) (xy 70.342745 -135.344049) (xy 70.391345 -135.318135)
			(xy 70.443232 -135.299659) (xy 70.497272 -135.289023) (xy 70.55229 -135.286459) (xy 70.607086 -135.292024)
			(xy 70.660466 -135.305595) (xy 70.711265 -135.326877) (xy 70.758378 -135.355406) (xy 70.779894 -135.372602)
			(xy 70.797136 -135.38627) (xy 70.835346 -135.408075) (xy 70.876737 -135.422983) (xy 70.920076 -135.43055)
			(xy 70.96407 -135.43055) (xy 71.007409 -135.422983) (xy 71.0488 -135.408075) (xy 71.08701 -135.38627)
			(xy 71.104252 -135.372602) (xy 71.126672 -135.354711) (xy 71.175924 -135.325314) (xy 71.229096 -135.303806)
			(xy 71.284935 -135.290695) (xy 71.342123 -135.286291) (xy 71.399311 -135.290695) (xy 71.45515 -135.303806)
			(xy 71.508322 -135.325314) (xy 71.557574 -135.354711) (xy 71.579994 -135.372602) (xy 71.597218 -135.386268)
			(xy 71.635395 -135.408073) (xy 71.676755 -135.422981) (xy 71.720064 -135.430549) (xy 71.764028 -135.430549)
			(xy 71.807337 -135.422981) (xy 71.848697 -135.408073) (xy 71.886874 -135.386268) (xy 71.904098 -135.372602)
			(xy 71.926521 -135.35468) (xy 71.975789 -135.325228) (xy 72.02899 -135.303679) (xy 72.084866 -135.290543)
			(xy 72.142096 -135.286129) (xy 72.199326 -135.290543) (xy 72.255202 -135.303679) (xy 72.308403 -135.325228)
			(xy 72.357671 -135.35468) (xy 72.380094 -135.372602) (xy 72.397318 -135.386268) (xy 72.435495 -135.408073)
			(xy 72.476855 -135.422981) (xy 72.520164 -135.430549) (xy 72.564128 -135.430549) (xy 72.607437 -135.422981)
			(xy 72.648797 -135.408073) (xy 72.686974 -135.386268) (xy 72.704198 -135.372602) (xy 72.726618 -135.354711)
			(xy 72.77587 -135.325314) (xy 72.829042 -135.303806) (xy 72.884881 -135.290695) (xy 72.942069 -135.286291)
			(xy 72.999257 -135.290695) (xy 73.055096 -135.303806) (xy 73.108268 -135.325314) (xy 73.15752 -135.354711)
			(xy 73.17994 -135.372602) (xy 73.197182 -135.38627) (xy 73.235392 -135.408075) (xy 73.276783 -135.422983)
			(xy 73.320122 -135.43055) (xy 73.364116 -135.43055) (xy 73.407455 -135.422983) (xy 73.448846 -135.408075)
			(xy 73.487056 -135.38627) (xy 73.504298 -135.372602) (xy 73.526718 -135.354711) (xy 73.57597 -135.325314)
			(xy 73.629142 -135.303806) (xy 73.684981 -135.290695) (xy 73.742169 -135.286291) (xy 73.799357 -135.290695)
			(xy 73.855196 -135.303806) (xy 73.908368 -135.325314) (xy 73.95762 -135.354711) (xy 73.98004 -135.372602)
			(xy 73.997264 -135.386268) (xy 74.035441 -135.408073) (xy 74.076801 -135.422981) (xy 74.12011 -135.430549)
			(xy 74.164074 -135.430549) (xy 74.207383 -135.422981) (xy 74.248743 -135.408073) (xy 74.28692 -135.386268)
			(xy 74.304144 -135.372602) (xy 74.325439 -135.355642) (xy 74.371945 -135.327348) (xy 74.422073 -135.306123)
			(xy 74.474755 -135.292418) (xy 74.528872 -135.286524) (xy 74.58327 -135.288568) (xy 74.636791 -135.298506)
			(xy 74.688297 -135.316125) (xy 74.736691 -135.341052) (xy 74.780943 -135.372755) (xy 74.82011 -135.41056)
			(xy 74.85336 -135.453662) (xy 74.879984 -135.501143) (xy 74.899416 -135.551993) (xy 74.911242 -135.605129)
			(xy 74.91521 -135.65942) (xy 74.911236 -135.713711) (xy 74.899404 -135.766846) (xy 74.879967 -135.817694)
			(xy 74.853338 -135.865172) (xy 74.820083 -135.908271) (xy 74.780911 -135.946071) (xy 74.736656 -135.977769)
			(xy 74.688259 -136.002691) (xy 74.636752 -136.020305) (xy 74.583229 -136.030236) (xy 74.528831 -136.032274)
			(xy 74.474715 -136.026375) (xy 74.422034 -136.012664) (xy 74.371908 -135.991433) (xy 74.325406 -135.963135)
			(xy 74.304144 -135.946134) (xy 74.28692 -135.932468) (xy 74.248743 -135.910663) (xy 74.207383 -135.895755)
			(xy 74.164074 -135.888187) (xy 74.12011 -135.888187) (xy 74.076801 -135.895755) (xy 74.035441 -135.910663)
			(xy 73.997264 -135.932468) (xy 73.98004 -135.946134) (xy 73.957633 -135.964055) (xy 73.908395 -135.993506)
			(xy 73.855222 -136.015055) (xy 73.799373 -136.028193) (xy 73.742169 -136.032606) (xy 73.684965 -136.028193)
			(xy 73.629116 -136.015055) (xy 73.575943 -135.993506) (xy 73.526705 -135.964055) (xy 73.504298 -135.946134)
			(xy 73.487071 -135.932433) (xy 73.448873 -135.910568) (xy 73.407478 -135.895618) (xy 73.364125 -135.888028)
			(xy 73.320113 -135.888028) (xy 73.27676 -135.895618) (xy 73.235365 -135.910568) (xy 73.197167 -135.932433)
			(xy 73.17994 -135.946134) (xy 73.157533 -135.964055) (xy 73.108295 -135.993506) (xy 73.055122 -136.015055)
			(xy 72.999273 -136.028193) (xy 72.942069 -136.032606) (xy 72.884865 -136.028193) (xy 72.829016 -136.015055)
			(xy 72.775843 -135.993506) (xy 72.726605 -135.964055) (xy 72.704198 -135.946134) (xy 72.686974 -135.932468)
			(xy 72.648797 -135.910663) (xy 72.607437 -135.895755) (xy 72.564128 -135.888187) (xy 72.520164 -135.888187)
			(xy 72.476855 -135.895755) (xy 72.435495 -135.910663) (xy 72.397318 -135.932468) (xy 72.380094 -135.946134)
			(xy 72.358605 -135.963269) (xy 72.311631 -135.991793) (xy 72.260975 -136.013108) (xy 72.207738 -136.026749)
			(xy 72.153075 -136.032422) (xy 72.098171 -136.030003) (xy 72.044219 -136.019545) (xy 71.992388 -136.001274)
			(xy 71.943803 -135.975588) (xy 71.899519 -135.943043) (xy 71.860496 -135.904345) (xy 71.843646 -135.882634)
			(xy 71.833131 -135.869442) (xy 71.806561 -135.848671) (xy 71.775474 -135.835597) (xy 71.742046 -135.831135)
			(xy 71.708618 -135.835597) (xy 71.677531 -135.848671) (xy 71.650961 -135.869442) (xy 71.640446 -135.882634)
			(xy 71.628762 -135.897112) (xy 71.615103 -135.914361) (xy 71.593298 -135.952569) (xy 71.57839 -135.993959)
			(xy 71.570822 -136.037297) (xy 71.570821 -136.08129) (xy 71.578386 -136.124627) (xy 71.590119 -136.157208)
			(xy 80.635854 -136.157208) (xy 80.639925 -136.101586) (xy 80.652051 -136.047149) (xy 80.671974 -135.995058)
			(xy 80.69927 -135.946423) (xy 80.733356 -135.90228) (xy 80.773505 -135.863571) (xy 80.818863 -135.83112)
			(xy 80.868463 -135.805619) (xy 80.921247 -135.787612) (xy 80.97609 -135.777482) (xy 81.031824 -135.775445)
			(xy 81.087261 -135.781545) (xy 81.141218 -135.795651) (xy 81.192547 -135.817463) (xy 81.240153 -135.846517)
			(xy 81.283021 -135.882192) (xy 81.320238 -135.923729) (xy 81.351011 -135.970242) (xy 81.374683 -136.020739)
			(xy 81.390751 -136.074146) (xy 81.398871 -136.129322) (xy 81.39938 -136.157208) (xy 81.398871 -136.185094)
			(xy 81.390751 -136.24027) (xy 81.374683 -136.293677) (xy 81.351011 -136.344174) (xy 81.320238 -136.390687)
			(xy 81.283021 -136.432224) (xy 81.240153 -136.467899) (xy 81.192547 -136.496953) (xy 81.141218 -136.518765)
			(xy 81.087261 -136.532871) (xy 81.031824 -136.538971) (xy 80.97609 -136.536934) (xy 80.921247 -136.526804)
			(xy 80.868463 -136.508797) (xy 80.818863 -136.483296) (xy 80.773505 -136.450845) (xy 80.733356 -136.412136)
			(xy 80.69927 -136.367993) (xy 80.671974 -136.319358) (xy 80.652051 -136.267267) (xy 80.639925 -136.21283)
			(xy 80.635854 -136.157208) (xy 71.590119 -136.157208) (xy 71.593292 -136.166018) (xy 71.615095 -136.204228)
			(xy 71.628762 -136.22147) (xy 71.645672 -136.242562) (xy 71.673796 -136.28873) (xy 71.694951 -136.338478)
			(xy 71.708694 -136.390761) (xy 71.714736 -136.444482) (xy 71.712949 -136.498512) (xy 71.703371 -136.551717)
			(xy 71.686204 -136.602978) (xy 71.661808 -136.651219) (xy 71.630695 -136.695428) (xy 71.593519 -136.734676)
			(xy 71.55106 -136.768138) (xy 71.504211 -136.795111) (xy 71.453954 -136.81503) (xy 71.401347 -136.827475)
			(xy 71.347493 -136.832186) (xy 71.293524 -136.829063) (xy 71.240573 -136.818172) (xy 71.189752 -136.799742)
			(xy 71.142128 -136.77416) (xy 71.098703 -136.741963) (xy 71.060387 -136.703827) (xy 71.0438 -136.68248)
			(xy 71.033276 -136.669263) (xy 71.006677 -136.648452) (xy 70.975549 -136.635351) (xy 70.942073 -136.63088)
			(xy 70.908597 -136.635351) (xy 70.877469 -136.648452) (xy 70.85087 -136.669263) (xy 70.840346 -136.68248)
			(xy 70.828916 -136.697212) (xy 70.815285 -136.714463) (xy 70.793478 -136.752634) (xy 70.778567 -136.793988)
			(xy 70.770996 -136.837292) (xy 70.770991 -136.881253) (xy 70.778552 -136.924558) (xy 70.793455 -136.965916)
			(xy 70.815253 -137.004092) (xy 70.828916 -137.021316) (xy 70.846047 -137.042806) (xy 70.874564 -137.089782)
			(xy 70.895872 -137.140438) (xy 70.909509 -137.193673) (xy 70.915179 -137.248334) (xy 70.91276 -137.303236)
			(xy 70.902303 -137.357186) (xy 70.884035 -137.409015) (xy 70.858353 -137.4576) (xy 70.825814 -137.501885)
			(xy 70.787124 -137.540911) (xy 70.765416 -137.557764) (xy 70.752263 -137.568323) (xy 70.731499 -137.594884)
			(xy 70.718427 -137.625961) (xy 70.713962 -137.659378) (xy 70.718416 -137.692797) (xy 70.731477 -137.723878)
			(xy 70.752232 -137.750447) (xy 70.765416 -137.760964) (xy 70.779894 -137.772648) (xy 70.797136 -137.786316)
			(xy 70.835346 -137.808121) (xy 70.876737 -137.823029) (xy 70.920076 -137.830596) (xy 70.96407 -137.830596)
			(xy 71.007409 -137.823029) (xy 71.0488 -137.808121) (xy 71.08701 -137.786316) (xy 71.104252 -137.772648)
			(xy 71.126672 -137.754757) (xy 71.175924 -137.72536) (xy 71.229096 -137.703852) (xy 71.284935 -137.690741)
			(xy 71.342123 -137.686337) (xy 71.399311 -137.690741) (xy 71.45515 -137.703852) (xy 71.508322 -137.72536)
			(xy 71.557574 -137.754757) (xy 71.579994 -137.772648) (xy 71.597218 -137.786314) (xy 71.635395 -137.808119)
			(xy 71.676755 -137.823027) (xy 71.720064 -137.830595) (xy 71.764028 -137.830595) (xy 71.807337 -137.823027)
			(xy 71.848697 -137.808119) (xy 71.886874 -137.786314) (xy 71.904098 -137.772648) (xy 71.925511 -137.755416)
			(xy 71.972499 -137.726896) (xy 72.023167 -137.705589) (xy 72.076415 -137.691956) (xy 72.131088 -137.686292)
			(xy 72.186 -137.68872) (xy 72.239959 -137.699189) (xy 72.291796 -137.71747) (xy 72.340384 -137.743167)
			(xy 72.384671 -137.775723) (xy 72.423695 -137.814432) (xy 72.440546 -137.836148) (xy 72.451061 -137.84934)
			(xy 72.477631 -137.870111) (xy 72.508718 -137.883185) (xy 72.542146 -137.887647) (xy 72.575574 -137.883185)
			(xy 72.606661 -137.870111) (xy 72.633231 -137.84934) (xy 72.643746 -137.836148) (xy 72.65543 -137.821416)
			(xy 72.669133 -137.804219) (xy 72.69094 -137.766037) (xy 72.705849 -137.724672) (xy 72.713413 -137.681357)
			(xy 72.713408 -137.637387) (xy 72.705834 -137.594074) (xy 72.690917 -137.552712) (xy 72.669102 -137.514535)
			(xy 72.65543 -137.497312) (xy 72.638263 -137.47577) (xy 72.609718 -137.428663) (xy 72.588421 -137.377866)
			(xy 72.574834 -137.324487) (xy 72.569255 -137.26969) (xy 72.571804 -137.214668) (xy 72.582427 -137.160621)
			(xy 72.600891 -137.108727) (xy 72.626795 -137.060118) (xy 72.659573 -137.015851) (xy 72.698511 -136.976894)
			(xy 72.742761 -136.944094) (xy 72.791358 -136.918166) (xy 72.843243 -136.899676) (xy 72.897284 -136.889026)
			(xy 72.952305 -136.88645) (xy 73.007105 -136.892002) (xy 73.060491 -136.905562) (xy 73.111298 -136.926834)
			(xy 73.158419 -136.955355) (xy 73.17994 -136.972548) (xy 73.197182 -136.986216) (xy 73.235392 -137.008021)
			(xy 73.276783 -137.022929) (xy 73.320122 -137.030496) (xy 73.364116 -137.030496) (xy 73.407455 -137.022929)
			(xy 73.448846 -137.008021) (xy 73.487056 -136.986216) (xy 73.504298 -136.972548) (xy 73.526718 -136.954657)
			(xy 73.57597 -136.92526) (xy 73.629142 -136.903752) (xy 73.684981 -136.890641) (xy 73.742169 -136.886237)
			(xy 73.799357 -136.890641) (xy 73.855196 -136.903752) (xy 73.908368 -136.92526) (xy 73.95762 -136.954657)
			(xy 73.98004 -136.972548) (xy 73.997264 -136.986214) (xy 74.035441 -137.008019) (xy 74.076801 -137.022927)
			(xy 74.12011 -137.030495) (xy 74.164074 -137.030495) (xy 74.207383 -137.022927) (xy 74.248743 -137.008019)
			(xy 74.28692 -136.986214) (xy 74.304144 -136.972548) (xy 74.325187 -136.955766) (xy 74.371117 -136.927709)
			(xy 74.420605 -136.90655) (xy 74.472622 -136.89273) (xy 74.526086 -136.886535) (xy 74.579885 -136.888094)
			(xy 74.6329 -136.897376) (xy 74.684029 -136.914186) (xy 74.732208 -136.938176) (xy 74.776436 -136.968846)
			(xy 74.815792 -137.005558) (xy 74.849459 -137.04755) (xy 74.876735 -137.093948) (xy 74.897054 -137.143786)
			(xy 74.909994 -137.196029) (xy 74.915284 -137.24959) (xy 74.912816 -137.303355) (xy 74.90264 -137.356206)
			(xy 74.884968 -137.407043) (xy 74.860167 -137.45481) (xy 74.828754 -137.498513) (xy 74.791381 -137.537243)
			(xy 74.748826 -137.570195) (xy 74.701974 -137.596684) (xy 74.6518 -137.616158) (xy 74.599345 -137.628212)
			(xy 74.545703 -137.632597) (xy 74.491987 -137.62922) (xy 74.439316 -137.618152) (xy 74.388785 -137.599623)
			(xy 74.341444 -137.574019) (xy 74.298278 -137.541872) (xy 74.260185 -137.50385) (xy 74.243692 -137.48258)
			(xy 74.233177 -137.469388) (xy 74.206607 -137.448617) (xy 74.17552 -137.435543) (xy 74.142092 -137.431081)
			(xy 74.108664 -137.435543) (xy 74.077577 -137.448617) (xy 74.051007 -137.469388) (xy 74.040492 -137.48258)
			(xy 74.028808 -137.497312) (xy 74.015177 -137.514563) (xy 73.993371 -137.552734) (xy 73.97846 -137.594088)
			(xy 73.970889 -137.637392) (xy 73.970885 -137.681353) (xy 73.978446 -137.724658) (xy 73.993348 -137.766016)
			(xy 74.015145 -137.804191) (xy 74.028808 -137.821416) (xy 74.04596 -137.842967) (xy 74.074497 -137.890073)
			(xy 74.095788 -137.940867) (xy 74.109368 -137.994243) (xy 74.114943 -138.049035) (xy 74.112391 -138.104052)
			(xy 74.101766 -138.158093) (xy 74.083302 -138.209982) (xy 74.0574 -138.258586) (xy 74.024624 -138.302848)
			(xy 73.985689 -138.341802) (xy 73.941444 -138.3746) (xy 73.892852 -138.400527) (xy 73.840973 -138.419017)
			(xy 73.786937 -138.429668) (xy 73.731922 -138.432248) (xy 73.677126 -138.426701) (xy 73.623744 -138.413147)
			(xy 73.572939 -138.391881) (xy 73.525819 -138.363368) (xy 73.504298 -138.34618) (xy 73.487071 -138.332479)
			(xy 73.448873 -138.310614) (xy 73.407478 -138.295664) (xy 73.364125 -138.288074) (xy 73.320113 -138.288074)
			(xy 73.27676 -138.295664) (xy 73.235365 -138.310614) (xy 73.197167 -138.332479) (xy 73.17994 -138.34618)
			(xy 73.157533 -138.364101) (xy 73.108295 -138.393552) (xy 73.055122 -138.415101) (xy 72.999273 -138.428239)
			(xy 72.942069 -138.432652) (xy 72.884865 -138.428239) (xy 72.829016 -138.415101) (xy 72.775843 -138.393552)
			(xy 72.726605 -138.364101) (xy 72.704198 -138.34618) (xy 72.686974 -138.332514) (xy 72.648797 -138.310709)
			(xy 72.607437 -138.295801) (xy 72.564128 -138.288233) (xy 72.520164 -138.288233) (xy 72.476855 -138.295801)
			(xy 72.435495 -138.310709) (xy 72.397318 -138.332514) (xy 72.380094 -138.34618) (xy 72.357671 -138.364102)
			(xy 72.308403 -138.393554) (xy 72.255202 -138.415103) (xy 72.199326 -138.428239) (xy 72.142096 -138.432653)
			(xy 72.084866 -138.428239) (xy 72.02899 -138.415103) (xy 71.975789 -138.393554) (xy 71.926521 -138.364102)
			(xy 71.904098 -138.34618) (xy 71.886874 -138.332514) (xy 71.848697 -138.310709) (xy 71.807337 -138.295801)
			(xy 71.764028 -138.288233) (xy 71.720064 -138.288233) (xy 71.676755 -138.295801) (xy 71.635395 -138.310709)
			(xy 71.597218 -138.332514) (xy 71.579994 -138.34618) (xy 71.557587 -138.364101) (xy 71.508349 -138.393552)
			(xy 71.455176 -138.415101) (xy 71.399327 -138.428239) (xy 71.342123 -138.432652) (xy 71.284919 -138.428239)
			(xy 71.22907 -138.415101) (xy 71.175897 -138.393552) (xy 71.126659 -138.364101) (xy 71.104252 -138.34618)
			(xy 71.087025 -138.332479) (xy 71.048827 -138.310614) (xy 71.007432 -138.295664) (xy 70.964079 -138.288074)
			(xy 70.920067 -138.288074) (xy 70.876714 -138.295664) (xy 70.835319 -138.310614) (xy 70.797121 -138.332479)
			(xy 70.779894 -138.34618) (xy 70.758414 -138.363415) (xy 70.711285 -138.39191) (xy 70.660476 -138.413158)
			(xy 70.607094 -138.426696) (xy 70.552299 -138.43223) (xy 70.497287 -138.42964) (xy 70.443256 -138.41898)
			(xy 70.391381 -138.400485) (xy 70.342794 -138.374556) (xy 70.298553 -138.341758) (xy 70.25962 -138.302806)
			(xy 70.226844 -138.258547) (xy 70.200939 -138.209947) (xy 70.18247 -138.158064) (xy 70.171838 -138.104027)
			(xy 70.169275 -138.049013) (xy 70.174836 -137.994222) (xy 70.188402 -137.940846) (xy 70.209675 -137.890047)
			(xy 70.238194 -137.842934) (xy 70.255384 -137.821416) (xy 70.269085 -137.804218) (xy 70.290887 -137.766035)
			(xy 70.305792 -137.72467) (xy 70.313355 -137.681357) (xy 70.31335 -137.637388) (xy 70.305778 -137.594076)
			(xy 70.290864 -137.552714) (xy 70.269053 -137.514537) (xy 70.255384 -137.497312) (xy 70.237478 -137.474878)
			(xy 70.208029 -137.425611) (xy 70.186482 -137.372412) (xy 70.173346 -137.316538) (xy 70.168931 -137.259311)
			(xy 68.513626 -137.259311) (xy 68.511598 -137.303061) (xy 68.500965 -137.357139) (xy 68.482484 -137.409061)
			(xy 68.456558 -137.457695) (xy 68.423751 -137.501981) (xy 68.38478 -137.540952) (xy 68.340494 -137.573758)
			(xy 68.29186 -137.599685) (xy 68.239938 -137.618166) (xy 68.185859 -137.628798) (xy 68.130805 -137.63135)
			(xy 68.075976 -137.625765) (xy 68.022566 -137.612167) (xy 67.971742 -137.590851) (xy 67.924611 -137.562282)
			(xy 67.90309 -137.545064) (xy 67.885866 -137.531398) (xy 67.847689 -137.509593) (xy 67.806329 -137.494685)
			(xy 67.76302 -137.487117) (xy 67.719056 -137.487117) (xy 67.675747 -137.494685) (xy 67.634387 -137.509593)
			(xy 67.59621 -137.531398) (xy 67.578986 -137.545064) (xy 67.556563 -137.562986) (xy 67.507295 -137.592438)
			(xy 67.454094 -137.613987) (xy 67.398218 -137.627123) (xy 67.340988 -137.631537) (xy 67.283758 -137.627123)
			(xy 67.227882 -137.613987) (xy 67.174681 -137.592438) (xy 67.125413 -137.562986) (xy 67.10299 -137.545064)
			(xy 67.085766 -137.531398) (xy 67.047589 -137.509593) (xy 67.006229 -137.494685) (xy 66.96292 -137.487117)
			(xy 66.918956 -137.487117) (xy 66.875647 -137.494685) (xy 66.834287 -137.509593) (xy 66.79611 -137.531398)
			(xy 66.778886 -137.545064) (xy 66.757377 -137.562295) (xy 66.710246 -137.590862) (xy 66.659422 -137.612176)
			(xy 66.606013 -137.625772) (xy 66.551184 -137.631354) (xy 66.496131 -137.628801) (xy 66.442054 -137.618168)
			(xy 66.390133 -137.599686) (xy 66.3415 -137.57376) (xy 66.297215 -137.540954) (xy 66.258245 -137.501983)
			(xy 66.225439 -137.457699) (xy 66.199513 -137.409065) (xy 66.181032 -137.357144) (xy 66.170399 -137.303067)
			(xy 66.167846 -137.248014) (xy 66.173428 -137.193185) (xy 66.187025 -137.139777) (xy 66.208339 -137.088953)
			(xy 66.236906 -137.041822) (xy 66.254122 -137.0203) (xy 66.26774 -137.00304) (xy 66.289544 -136.96487)
			(xy 66.304454 -136.923518) (xy 66.312025 -136.880216) (xy 66.312032 -136.836258) (xy 66.304473 -136.792954)
			(xy 66.289575 -136.751597) (xy 66.267782 -136.713421) (xy 66.254122 -136.696196) (xy 66.236224 -136.673771)
			(xy 66.206768 -136.624538) (xy 66.185215 -136.571368) (xy 66.172074 -136.515521) (xy 66.167657 -136.458319)
			(xy 65.314038 -136.458319) (xy 65.30963 -136.51551) (xy 65.296515 -136.571351) (xy 65.275003 -136.624524)
			(xy 65.245601 -136.673776) (xy 65.227708 -136.696196) (xy 65.213996 -136.713386) (xy 65.192195 -136.75157)
			(xy 65.177292 -136.792937) (xy 65.16973 -136.836252) (xy 65.169737 -136.880222) (xy 65.177311 -136.923534)
			(xy 65.192226 -136.964897) (xy 65.214038 -137.003075) (xy 65.227708 -137.0203) (xy 65.244844 -137.041864)
			(xy 65.273381 -137.088969) (xy 65.294673 -137.139762) (xy 65.308255 -137.193136) (xy 65.313831 -137.247929)
			(xy 65.311279 -137.302944) (xy 65.300656 -137.356985) (xy 65.282192 -137.408873) (xy 65.256291 -137.457478)
			(xy 65.223516 -137.501739) (xy 65.184582 -137.540693) (xy 65.140337 -137.57349) (xy 65.091746 -137.599416)
			(xy 65.039867 -137.617906) (xy 64.985832 -137.628557) (xy 64.930817 -137.631136) (xy 64.876022 -137.625588)
			(xy 64.822641 -137.612033) (xy 64.771837 -137.590767) (xy 64.724718 -137.562253) (xy 64.703198 -137.545064)
			(xy 64.685971 -137.531363) (xy 64.647773 -137.509498) (xy 64.606378 -137.494548) (xy 64.563025 -137.486958)
			(xy 64.519013 -137.486958) (xy 64.47566 -137.494548) (xy 64.434265 -137.509498) (xy 64.396067 -137.531363)
			(xy 64.37884 -137.545064) (xy 64.356433 -137.562985) (xy 64.307195 -137.592436) (xy 64.254022 -137.613985)
			(xy 64.198173 -137.627123) (xy 64.140969 -137.631536) (xy 64.083765 -137.627123) (xy 64.027916 -137.613985)
			(xy 63.974743 -137.592436) (xy 63.925505 -137.562985) (xy 63.903098 -137.545064) (xy 63.885874 -137.531398)
			(xy 63.847697 -137.509593) (xy 63.806337 -137.494685) (xy 63.763028 -137.487117) (xy 63.719064 -137.487117)
			(xy 63.675755 -137.494685) (xy 63.634395 -137.509593) (xy 63.596218 -137.531398) (xy 63.578994 -137.545064)
			(xy 63.557478 -137.562287) (xy 63.510348 -137.590854) (xy 63.459524 -137.612168) (xy 63.406116 -137.625765)
			(xy 63.351287 -137.631348) (xy 63.296235 -137.628795) (xy 63.242158 -137.618163) (xy 63.190237 -137.599682)
			(xy 63.141604 -137.573755) (xy 63.09732 -137.54095) (xy 63.05835 -137.501979) (xy 63.025544 -137.457695)
			(xy 62.999618 -137.409062) (xy 62.981137 -137.357141) (xy 62.970505 -137.303065) (xy 62.967952 -137.248012)
			(xy 62.973535 -137.193183) (xy 62.987132 -137.139775) (xy 63.008446 -137.088952) (xy 63.037014 -137.041821)
			(xy 63.05423 -137.0203) (xy 63.067852 -137.003042) (xy 63.089664 -136.964874) (xy 63.10458 -136.923521)
			(xy 63.112154 -136.880217) (xy 63.112161 -136.836256) (xy 63.104599 -136.792951) (xy 63.089695 -136.751593)
			(xy 63.067894 -136.713419) (xy 63.05423 -136.696196) (xy 63.036332 -136.673772) (xy 63.006875 -136.624538)
			(xy 62.985321 -136.571368) (xy 62.97218 -136.515521) (xy 62.967763 -136.458319) (xy 62.348872 -136.458319)
			(xy 62.348872 -139.580874) (xy 62.699392 -139.931394) (xy 63.514732 -139.931394) (xy 63.537081 -139.930921)
			(xy 63.58109 -139.923096) (xy 63.62305 -139.907692) (xy 63.661669 -139.885184) (xy 63.695754 -139.856268)
			(xy 63.724254 -139.821834) (xy 63.746291 -139.782945) (xy 63.761184 -139.7408) (xy 63.768475 -139.6967)
			(xy 63.768732 -139.674346) (xy 63.768074 -139.649748) (xy 63.772452 -139.600735) (xy 63.783234 -139.552723)
			(xy 63.800235 -139.506545) (xy 63.823158 -139.463003) (xy 63.837058 -139.442698) (xy 63.852416 -139.421789)
			(xy 63.887987 -139.384026) (xy 63.928458 -139.351569) (xy 63.973044 -139.325047) (xy 64.020881 -139.304974)
			(xy 64.045846 -139.297918) (xy 64.071042 -139.291697) (xy 64.122565 -139.285484) (xy 64.174452 -139.286491)
			(xy 64.225695 -139.294697) (xy 64.275302 -139.309944) (xy 64.322308 -139.331936) (xy 64.365803 -139.360246)
			(xy 64.385698 -139.376912) (xy 64.404934 -139.3911) (xy 64.447537 -139.412755) (xy 64.493439 -139.426062)
			(xy 64.541019 -139.43055) (xy 64.588599 -139.426062) (xy 64.634501 -139.412755) (xy 64.677104 -139.3911)
			(xy 64.69634 -139.376912) (xy 64.716222 -139.360237) (xy 64.759737 -139.331971) (xy 64.806751 -139.31001)
			(xy 64.856356 -139.294778) (xy 64.907593 -139.28657) (xy 64.959473 -139.285544) (xy 65.010994 -139.291719)
			(xy 65.036192 -139.297918) (xy 65.061153 -139.304983) (xy 65.108982 -139.325072) (xy 65.153565 -139.351596)
			(xy 65.194042 -139.384042) (xy 65.229633 -139.421783) (xy 65.24498 -139.442698) (xy 65.258897 -139.462995)
			(xy 65.281843 -139.506531) (xy 65.298854 -139.55271) (xy 65.309634 -139.600727) (xy 65.313995 -139.649746)
			(xy 65.313306 -139.674346) (xy 65.313507 -139.696703) (xy 65.320799 -139.740811) (xy 65.335697 -139.782962)
			(xy 65.357739 -139.821856) (xy 65.386246 -139.856294) (xy 65.42034 -139.885213) (xy 65.458967 -139.90772)
			(xy 65.500936 -139.923122) (xy 65.544953 -139.930943) (xy 65.567306 -139.931394) (xy 67.514724 -139.931394)
			(xy 67.53706 -139.930923) (xy 67.581042 -139.923109) (xy 67.622981 -139.907724) (xy 67.661584 -139.885244)
			(xy 67.695661 -139.856361) (xy 67.724164 -139.821964) (xy 67.746214 -139.783114) (xy 67.761131 -139.741007)
			(xy 67.768456 -139.69694) (xy 67.768724 -139.6746) (xy 67.768062 -139.650001) (xy 67.772433 -139.600985)
			(xy 67.78321 -139.552969) (xy 67.800205 -139.506787) (xy 67.823123 -139.463239) (xy 67.83705 -139.442952)
			(xy 67.852406 -139.42204) (xy 67.887974 -139.384272) (xy 67.928443 -139.35181) (xy 67.973028 -139.325283)
			(xy 68.020866 -139.305205) (xy 68.045838 -139.298172) (xy 68.071034 -139.291951) (xy 68.122558 -139.285738)
			(xy 68.174446 -139.286744) (xy 68.22569 -139.294948) (xy 68.275298 -139.310193) (xy 68.322307 -139.332182)
			(xy 68.365805 -139.360489) (xy 68.38569 -139.377166) (xy 68.404926 -139.391354) (xy 68.447529 -139.413009)
			(xy 68.493431 -139.426316) (xy 68.541011 -139.430804) (xy 68.588591 -139.426316) (xy 68.634493 -139.413009)
			(xy 68.677096 -139.391354) (xy 68.696332 -139.377166) (xy 68.716214 -139.360492) (xy 68.759731 -139.332228)
			(xy 68.806745 -139.310269) (xy 68.856349 -139.295039) (xy 68.907585 -139.28683) (xy 68.959465 -139.285803)
			(xy 69.010986 -139.291977) (xy 69.036184 -139.298172) (xy 69.061145 -139.305238) (xy 69.108972 -139.325328)
			(xy 69.153553 -139.351853) (xy 69.194027 -139.384301) (xy 69.229614 -139.422046) (xy 69.244972 -139.442952)
			(xy 69.258886 -139.463249) (xy 69.281826 -139.506786) (xy 69.298831 -139.552965) (xy 69.309604 -139.600982)
			(xy 69.313958 -139.65) (xy 69.313298 -139.6746) (xy 69.31352 -139.696943) (xy 69.320847 -139.741016)
			(xy 69.335767 -139.783129) (xy 69.357821 -139.821984) (xy 69.38633 -139.856385) (xy 69.420414 -139.885271)
			(xy 69.459023 -139.907752) (xy 69.500969 -139.923136) (xy 69.544959 -139.930949) (xy 69.567298 -139.931394)
			(xy 69.718936 -140.083032) (xy 69.766434 -140.086334) (xy 69.789509 -140.08826) (xy 69.834958 -140.097121)
			(xy 69.878953 -140.111562) (xy 69.900038 -140.121132) (xy 69.92959 -140.135888) (xy 69.983378 -140.174215)
			(xy 70.006972 -140.197332) (xy 70.023482 -140.214096) (xy 70.117716 -140.257022) (xy 70.193662 -140.257022)
		)
		(stroke
			(width 0)
			(type solid)
		)
		(fill yes)
		(layer "In6.Cu")
		(net "P1V26_BMC_NODE1")
	)
	(gr_poly
		(pts
			(xy 94.468188 -113.85423) (xy 95.011494 -113.31067) (xy 95.021302 -113.299481) (xy 95.035921 -113.273572)
			(xy 95.04417 -113.24499) (xy 95.045276 -113.230152) (xy 95.045276 -112.37976) (xy 95.152972 -112.27181)
			(xy 95.24746 -112.177322) (xy 95.24746 -109.568234) (xy 95.22587 -109.53623) (xy 95.209106 -109.51031)
			(xy 95.183272 -109.454248) (xy 95.166785 -109.394764) (xy 95.160073 -109.333402) (xy 95.1611 -109.30255)
			(xy 95.162554 -109.280839) (xy 95.169812 -109.237934) (xy 95.175578 -109.216952) (xy 95.18523 -109.183424)
			(xy 95.167958 -109.116368) (xy 95.14332 -109.09173) (xy 93.837252 -107.785662) (xy 93.837252 -106.01706)
			(xy 93.777816 -105.946194) (xy 93.731842 -105.93832) (xy 93.706351 -105.933473) (xy 93.656891 -105.917785)
			(xy 93.610017 -105.895532) (xy 93.588078 -105.881678) (xy 93.566279 -105.866847) (xy 93.526591 -105.832138)
			(xy 93.492054 -105.7923) (xy 93.477334 -105.770426) (xy 93.464775 -105.752908) (xy 93.434762 -105.721976)
			(xy 93.399963 -105.696546) (xy 93.361375 -105.677347) (xy 93.320103 -105.664928) (xy 93.277328 -105.659644)
			(xy 93.234274 -105.661648) (xy 93.192175 -105.670881) (xy 93.152234 -105.687079) (xy 93.133672 -105.698036)
			(xy 93.110552 -105.712467) (xy 93.061083 -105.735338) (xy 93.008863 -105.750937) (xy 92.954955 -105.758947)
			(xy 92.900455 -105.759205) (xy 92.846473 -105.751706) (xy 92.794108 -105.736602) (xy 92.744425 -105.714201)
			(xy 92.698434 -105.684959) (xy 92.657072 -105.64947) (xy 92.621181 -105.608457) (xy 92.59149 -105.562755)
			(xy 92.568604 -105.513293) (xy 92.552989 -105.461078) (xy 92.544962 -105.407172) (xy 92.544687 -105.352673)
			(xy 92.55217 -105.298689) (xy 92.567257 -105.246319) (xy 92.589643 -105.196628) (xy 92.618871 -105.150629)
			(xy 92.654347 -105.109256) (xy 92.695349 -105.073352) (xy 92.741042 -105.043647) (xy 92.790497 -105.020746)
			(xy 92.842708 -105.005115) (xy 92.896611 -104.997071) (xy 92.95111 -104.99678) (xy 93.005096 -105.004245)
			(xy 93.057471 -105.019317) (xy 93.107168 -105.041687) (xy 93.153177 -105.070901) (xy 93.194561 -105.106364)
			(xy 93.230477 -105.147355) (xy 93.245686 -105.16997) (xy 93.258245 -105.187487) (xy 93.288258 -105.218417)
			(xy 93.323056 -105.243844) (xy 93.361643 -105.26304) (xy 93.402914 -105.275457) (xy 93.445688 -105.280737)
			(xy 93.488739 -105.278731) (xy 93.530836 -105.269496) (xy 93.570774 -105.253296) (xy 93.589348 -105.24236)
			(xy 93.604806 -105.232629) (xy 93.637245 -105.21583) (xy 93.654118 -105.208832) (xy 93.673046 -105.201426)
			(xy 93.712119 -105.190226) (xy 93.732096 -105.18648) (xy 93.777816 -105.178606) (xy 93.837252 -105.10774)
			(xy 93.837252 -101.696012) (xy 85.910674 -93.769434) (xy 85.809074 -93.769434) (xy 85.790786 -93.775022)
			(xy 85.765598 -93.782339) (xy 85.713834 -93.790793) (xy 85.661399 -93.792075) (xy 85.609284 -93.786162)
			(xy 85.558469 -93.773165) (xy 85.509914 -93.753329) (xy 85.464535 -93.727028) (xy 85.443568 -93.711268)
			(xy 85.429689 -93.701134) (xy 85.397963 -93.687959) (xy 85.363874 -93.683719) (xy 85.329887 -93.68872)
			(xy 85.298464 -93.7026) (xy 85.284818 -93.713046) (xy 85.271261 -93.723886) (xy 85.242516 -93.743349)
			(xy 85.227414 -93.751908) (xy 85.205824 -93.763084) (xy 85.182611 -93.773575) (xy 85.134063 -93.788997)
			(xy 85.10905 -93.793818) (xy 85.077559 -93.798657) (xy 85.013851 -93.799041) (xy 84.982304 -93.79458)
			(xy 84.961009 -93.790815) (xy 84.919379 -93.779104) (xy 84.899246 -93.771212) (xy 84.874293 -93.760543)
			(xy 84.827433 -93.733173) (xy 84.784925 -93.699438) (xy 84.747627 -93.660019) (xy 84.716293 -93.615711)
			(xy 84.691556 -93.56741) (xy 84.673913 -93.51609) (xy 84.66836 -93.489526) (xy 84.660486 -93.448124)
			(xy 84.536534 -93.334332) (xy 82.114898 -93.334332) (xy 82.099418 -93.334771) (xy 82.069373 -93.342235)
			(xy 82.042012 -93.356722) (xy 82.018951 -93.377377) (xy 82.001549 -93.402983) (xy 81.990834 -93.432028)
			(xy 81.98866 -93.447362) (xy 81.985133 -93.475033) (xy 81.971033 -93.529002) (xy 81.949224 -93.580343)
			(xy 81.920172 -93.627961) (xy 81.884495 -93.670841) (xy 81.842955 -93.708069) (xy 81.796436 -93.73885)
			(xy 81.74593 -93.762529) (xy 81.692515 -93.778602) (xy 81.637328 -93.786725) (xy 81.581548 -93.786725)
			(xy 81.526361 -93.778602) (xy 81.472946 -93.762529) (xy 81.42244 -93.73885) (xy 81.375921 -93.708069)
			(xy 81.334381 -93.670841) (xy 81.298704 -93.627961) (xy 81.269652 -93.580343) (xy 81.247843 -93.529002)
			(xy 81.233743 -93.475033) (xy 81.230216 -93.447362) (xy 81.224882 -93.398848) (xy 81.152746 -93.334332)
			(xy 80.602836 -93.334332) (xy 80.57261 -93.304106) (xy 80.560439 -93.292753) (xy 80.5316 -93.276164)
			(xy 80.499456 -93.267579) (xy 80.466186 -93.267579) (xy 80.434042 -93.276164) (xy 80.405203 -93.292753)
			(xy 80.393032 -93.304106) (xy 80.356964 -93.340428) (xy 80.355948 -93.391736) (xy 80.35496 -93.418966)
			(xy 80.346215 -93.472747) (xy 80.329907 -93.524736) (xy 80.306368 -93.573876) (xy 80.276078 -93.619168)
			(xy 80.239652 -93.659689) (xy 80.197831 -93.694615) (xy 80.151467 -93.723237) (xy 80.101502 -93.744971)
			(xy 80.048953 -93.759375) (xy 79.99489 -93.766156) (xy 79.940412 -93.765176) (xy 79.886627 -93.756456)
			(xy 79.83463 -93.740172) (xy 79.785479 -93.716657) (xy 79.740173 -93.686387) (xy 79.699635 -93.64998)
			(xy 79.664689 -93.608176) (xy 79.636046 -93.561824) (xy 79.614289 -93.51187) (xy 79.606648 -93.485716)
			(xy 79.602457 -93.469833) (xy 79.596482 -93.43753) (xy 79.59471 -93.4212) (xy 79.591674 -93.398727)
			(xy 79.578683 -93.355285) (xy 79.558195 -93.314835) (xy 79.53086 -93.278658) (xy 79.497543 -93.2479)
			(xy 79.459301 -93.223538) (xy 79.417346 -93.206341) (xy 79.373006 -93.196855) (xy 79.350362 -93.195648)
			(xy 79.038196 -93.195648) (xy 78.872842 -93.030548) (xy 78.728062 -92.885768) (xy 77.520546 -91.678252)
			(xy 77.487272 -91.669616) (xy 77.458857 -91.661659) (xy 77.404716 -91.638196) (xy 77.354832 -91.60668)
			(xy 77.310393 -91.56786) (xy 77.27246 -91.522662) (xy 77.241937 -91.472164) (xy 77.230224 -91.44508)
			(xy 77.220686 -91.420658) (xy 77.207633 -91.369878) (xy 77.201649 -91.31779) (xy 77.202847 -91.265374)
			(xy 77.211205 -91.213614) (xy 77.226565 -91.163484) (xy 77.248639 -91.115927) (xy 77.277011 -91.071836)
			(xy 77.293724 -91.051634) (xy 77.30752 -91.033554) (xy 77.329123 -90.99354) (xy 77.343255 -90.950318)
			(xy 77.349464 -90.905271) (xy 77.347554 -90.859838) (xy 77.337583 -90.815471) (xy 77.319872 -90.773589)
			(xy 77.294986 -90.73553) (xy 77.279754 -90.71864) (xy 77.188822 -90.627454) (xy 75.360276 -88.799162)
			(xy 75.341888 -88.783632) (xy 75.300496 -88.759084) (xy 75.255221 -88.74277) (xy 75.207685 -88.735273)
			(xy 75.159587 -88.736863) (xy 75.112649 -88.747481) (xy 75.06855 -88.766748) (xy 75.048364 -88.779858)
			(xy 75.024978 -88.79526) (xy 74.974634 -88.819777) (xy 74.921245 -88.836661) (xy 74.893678 -88.84158)
			(xy 74.864434 -88.845731) (xy 74.805372 -88.846026) (xy 74.74697 -88.837214) (xy 74.690624 -88.819505)
			(xy 74.637682 -88.793322) (xy 74.589408 -88.759291) (xy 74.546956 -88.718226) (xy 74.52868 -88.695022)
			(xy 74.5109 -88.669622) (xy 74.498038 -88.648648) (xy 74.477229 -88.604063) (xy 74.46233 -88.557172)
			(xy 74.453587 -88.508753) (xy 74.451972 -88.484202) (xy 74.449432 -88.433402) (xy 74.376026 -88.363552)
			(xy 73.415906 -88.363552) (xy 72.280272 -87.227918) (xy 72.280272 -86.345014) (xy 72.262746 -86.315042)
			(xy 72.251213 -86.294761) (xy 72.232623 -86.251967) (xy 72.225662 -86.229698) (xy 72.22236 -86.21776)
			(xy 72.215708 -86.190073) (xy 72.209713 -86.13345) (xy 72.210422 -86.104984) (xy 72.211345 -86.088587)
			(xy 72.215665 -86.056029) (xy 72.219058 -86.03996) (xy 72.225035 -86.014744) (xy 72.242893 -85.966096)
			(xy 72.26718 -85.920318) (xy 72.297446 -85.878252) (xy 72.333133 -85.840676) (xy 72.373582 -85.808283)
			(xy 72.395588 -85.794596) (xy 72.41453 -85.782743) (xy 72.448298 -85.753486) (xy 72.47643 -85.718775)
			(xy 72.498058 -85.679679) (xy 72.512517 -85.637404) (xy 72.519359 -85.593251) (xy 72.518375 -85.548583)
			(xy 72.509595 -85.504774) (xy 72.49329 -85.463176) (xy 72.469961 -85.425071) (xy 72.455532 -85.408008)
			(xy 72.345042 -85.297518) (xy 72.249284 -85.20176) (xy 72.12457 -85.077046) (xy 72.113899 -85.067007)
			(xy 72.088976 -85.051618) (xy 72.061205 -85.042305) (xy 72.032043 -85.039556) (xy 72.003021 -85.043514)
			(xy 71.989188 -85.048344) (xy 71.944738 -85.065616) (xy 71.92899 -85.078316) (xy 71.90796 -85.094939)
			(xy 71.862131 -85.122746) (xy 71.81286 -85.143863) (xy 71.761118 -85.157874) (xy 71.707925 -85.164504)
			(xy 71.654327 -85.163621) (xy 71.60138 -85.155243) (xy 71.550128 -85.139536) (xy 71.501579 -85.116807)
			(xy 71.456691 -85.087506) (xy 71.43623 -85.070188) (xy 71.422807 -85.059232) (xy 71.391563 -85.04429)
			(xy 71.357452 -85.038293) (xy 71.322985 -85.041683) (xy 71.290696 -85.054209) (xy 71.276464 -85.064092)
			(xy 71.26986 -85.068918) (xy 71.246882 -85.084676) (xy 71.197295 -85.110076) (xy 71.144541 -85.127998)
			(xy 71.089743 -85.138059) (xy 71.034064 -85.140048) (xy 70.978688 -85.13392) (xy 70.92479 -85.119807)
			(xy 70.873517 -85.098008) (xy 70.84949 -85.083904) (xy 70.792594 -85.111844) (xy 70.734682 -85.140292)
			(xy 70.717918 -85.159342) (xy 70.698603 -85.180565) (xy 70.654719 -85.217537) (xy 70.605793 -85.247519)
			(xy 70.552928 -85.269835) (xy 70.497316 -85.283982) (xy 70.440213 -85.28964) (xy 70.382907 -85.286682)
			(xy 70.326691 -85.275174) (xy 70.29958 -85.265768) (xy 70.274259 -85.255958) (xy 70.226448 -85.230213)
			(xy 70.20433 -85.21446) (xy 70.193502 -85.206284) (xy 70.172906 -85.188617) (xy 70.163182 -85.179154)
			(xy 70.147434 -85.162644) (xy 70.13067 -85.144102) (xy 70.033134 -85.096858) (xy 69.96938 -85.114384)
			(xy 69.956426 -85.121496) (xy 69.932373 -85.134013) (xy 69.88154 -85.152882) (xy 69.82855 -85.164373)
			(xy 69.774467 -85.168254) (xy 69.720379 -85.164448) (xy 69.667373 -85.153032) (xy 69.616514 -85.134234)
			(xy 69.592444 -85.12175) (xy 69.57729 -85.114169) (xy 69.544304 -85.10647) (xy 69.510455 -85.107706)
			(xy 69.478118 -85.117788) (xy 69.449565 -85.13601) (xy 69.437758 -85.148166) (xy 69.416274 -85.171029)
			(xy 69.367197 -85.210106) (xy 69.312391 -85.240631) (xy 69.283072 -85.251798) (xy 69.273558 -85.255101)
			(xy 69.254243 -85.260819) (xy 69.244464 -85.263228) (xy 69.223567 -85.26797) (xy 69.181049 -85.273317)
			(xy 69.159628 -85.273896) (xy 69.159374 -85.273896) (xy 69.14214 -85.274461) (xy 69.108927 -85.283681)
			(xy 69.079402 -85.301467) (xy 69.055726 -85.326517) (xy 69.039631 -85.356996) (xy 69.035422 -85.373718)
			(xy 69.030342 -85.394038) (xy 69.025262 -85.411056) (xy 69.020076 -85.426296) (xy 69.007485 -85.455926)
			(xy 69.000116 -85.470238) (xy 68.992134 -85.484953) (xy 68.973945 -85.51306) (xy 68.963794 -85.526372)
			(xy 68.950811 -85.544401) (xy 68.930696 -85.584011) (xy 68.917775 -85.626516) (xy 68.912443 -85.670619)
			(xy 68.914861 -85.714979) (xy 68.924956 -85.758241) (xy 68.94242 -85.799089) (xy 68.954142 -85.817964)
			(xy 68.97512 -85.836401) (xy 69.012077 -85.878272) (xy 69.042636 -85.925017) (xy 69.066165 -85.975666)
			(xy 69.082174 -86.02917) (xy 69.08673 -86.056724) (xy 69.092826 -86.098126) (xy 69.19976 -86.205314)
			(xy 69.240146 -86.212172) (xy 69.256242 -86.215039) (xy 69.28791 -86.223175) (xy 69.303392 -86.228428)
			(xy 69.324896 -86.235421) (xy 69.369543 -86.24255) (xy 69.414748 -86.241668) (xy 69.459084 -86.232803)
			(xy 69.501152 -86.216234) (xy 69.539626 -86.192484) (xy 69.573291 -86.162303) (xy 69.601085 -86.126642)
			(xy 69.622133 -86.086626) (xy 69.635769 -86.043518) (xy 69.63918 -86.021164) (xy 69.64318 -85.993827)
			(xy 69.658039 -85.940615) (xy 69.680418 -85.890103) (xy 69.709848 -85.843346) (xy 69.745715 -85.801324)
			(xy 69.787268 -85.764914) (xy 69.833638 -85.734879) (xy 69.883855 -85.711846) (xy 69.936869 -85.696297)
			(xy 69.991572 -85.688557) (xy 70.046819 -85.688789) (xy 70.101455 -85.696986) (xy 70.154338 -85.712979)
			(xy 70.20436 -85.736432) (xy 70.250477 -85.766854) (xy 70.291724 -85.803611) (xy 70.327237 -85.845932)
			(xy 70.356275 -85.892933) (xy 70.37823 -85.943631) (xy 70.392643 -85.996966) (xy 70.399212 -86.051821)
			(xy 70.3978 -86.107051) (xy 70.388437 -86.161499) (xy 70.371318 -86.214028) (xy 70.346802 -86.263538)
			(xy 70.315401 -86.308994) (xy 70.277772 -86.349446) (xy 70.234701 -86.384047) (xy 70.187091 -86.412074)
			(xy 70.135935 -86.432941) (xy 70.082305 -86.446211) (xy 70.027321 -86.451607) (xy 69.972134 -86.449015)
			(xy 69.917898 -86.438491) (xy 69.891656 -86.42985) (xy 69.87015 -86.422853) (xy 69.825496 -86.415716)
			(xy 69.780283 -86.416592) (xy 69.735939 -86.425452) (xy 69.693861 -86.442018) (xy 69.655379 -86.465767)
			(xy 69.621704 -86.495949) (xy 69.593901 -86.531613) (xy 69.572845 -86.571633) (xy 69.559202 -86.614746)
			(xy 69.557554 -86.625803) (xy 71.044168 -86.625803) (xy 71.046422 -86.570028) (xy 71.05678 -86.515176)
			(xy 71.07502 -86.46242) (xy 71.100753 -86.412885) (xy 71.116698 -86.389972) (xy 71.129563 -86.371381)
			(xy 71.149112 -86.330619) (xy 71.161139 -86.28704) (xy 71.165265 -86.242022) (xy 71.161359 -86.196983)
			(xy 71.149545 -86.153346) (xy 71.130196 -86.112489) (xy 71.11746 -86.093808) (xy 71.101646 -86.070803)
			(xy 71.076158 -86.021138) (xy 71.05818 -85.968289) (xy 71.048095 -85.913384) (xy 71.046119 -85.857596)
			(xy 71.052293 -85.802115) (xy 71.066486 -85.748126) (xy 71.088395 -85.696782) (xy 71.117553 -85.649179)
			(xy 71.153336 -85.606333) (xy 71.194981 -85.569158) (xy 71.241598 -85.538449) (xy 71.292193 -85.514861)
			(xy 71.345685 -85.498898) (xy 71.400933 -85.4909) (xy 71.456756 -85.491038) (xy 71.511963 -85.49931)
			(xy 71.565375 -85.515538) (xy 71.615853 -85.539377) (xy 71.662317 -85.570316) (xy 71.703777 -85.607697)
			(xy 71.739348 -85.65072) (xy 71.768269 -85.698467) (xy 71.789923 -85.749919) (xy 71.803849 -85.803978)
			(xy 71.809748 -85.859489) (xy 71.807495 -85.915266) (xy 71.797138 -85.97012) (xy 71.778898 -86.02288)
			(xy 71.753165 -86.072418) (xy 71.73722 -86.095332) (xy 71.72435 -86.11392) (xy 71.704801 -86.154683)
			(xy 71.692773 -86.198262) (xy 71.688648 -86.243282) (xy 71.692554 -86.288321) (xy 71.70437 -86.331958)
			(xy 71.723721 -86.372815) (xy 71.736458 -86.391496) (xy 71.752247 -86.414517) (xy 71.777732 -86.464181)
			(xy 71.795707 -86.517028) (xy 71.80579 -86.57193) (xy 71.807764 -86.627716) (xy 71.801588 -86.683194)
			(xy 71.787394 -86.73718) (xy 71.765484 -86.788521) (xy 71.736326 -86.836121) (xy 71.700544 -86.878964)
			(xy 71.6589 -86.916136) (xy 71.612284 -86.946842) (xy 71.56169 -86.970427) (xy 71.5082 -86.986388)
			(xy 71.452955 -86.994384) (xy 71.397135 -86.994244) (xy 71.341931 -86.985971) (xy 71.288521 -86.969743)
			(xy 71.238047 -86.945904) (xy 71.191585 -86.914964) (xy 71.150128 -86.877585) (xy 71.114561 -86.834563)
			(xy 71.085642 -86.786817) (xy 71.06399 -86.735367) (xy 71.050066 -86.681311) (xy 71.044168 -86.625803)
			(xy 69.557554 -86.625803) (xy 69.555868 -86.637114) (xy 69.551931 -86.664033) (xy 69.537421 -86.716463)
			(xy 69.51561 -86.766301) (xy 69.486943 -86.812536) (xy 69.451998 -86.854231) (xy 69.411487 -86.890539)
			(xy 69.366229 -86.920726) (xy 69.317142 -86.944178) (xy 69.265222 -86.960421) (xy 69.211522 -86.969125)
			(xy 69.157129 -86.970114) (xy 69.103148 -86.963367) (xy 69.050672 -86.949022) (xy 69.000766 -86.927369)
			(xy 68.954441 -86.898847) (xy 68.912636 -86.864034) (xy 68.8762 -86.823637) (xy 68.845871 -86.778475)
			(xy 68.822264 -86.729462) (xy 68.805857 -86.677594) (xy 68.80098 -86.65083) (xy 68.794376 -86.610698)
			(xy 68.687442 -86.50351) (xy 68.645786 -86.49716) (xy 68.616742 -86.492243) (xy 68.560489 -86.47477)
			(xy 68.533772 -86.462362) (xy 68.520466 -86.456378) (xy 68.49201 -86.449969) (xy 68.462843 -86.450169)
			(xy 68.434478 -86.456969) (xy 68.42125 -86.463124) (xy 68.363846 -86.491826) (xy 68.347082 -86.51113)
			(xy 68.346828 -86.511384) (xy 68.32882 -86.531594) (xy 68.288076 -86.567232) (xy 68.242706 -86.596758)
			(xy 68.193622 -86.61958) (xy 68.141806 -86.63524) (xy 68.088297 -86.643424) (xy 68.034169 -86.643968)
			(xy 67.980507 -86.636862) (xy 67.928386 -86.622247) (xy 67.878853 -86.600416) (xy 67.855592 -86.586568)
			(xy 67.834502 -86.572922) (xy 67.795765 -86.540942) (xy 67.778376 -86.522814) (xy 67.756285 -86.498027)
			(xy 67.720142 -86.442338) (xy 67.706494 -86.41207) (xy 67.696412 -86.387202) (xy 67.682535 -86.335367)
			(xy 67.676055 -86.282099) (xy 67.6771 -86.228449) (xy 67.68565 -86.175475) (xy 67.701536 -86.12422)
			(xy 67.724445 -86.075695) (xy 67.753926 -86.030858) (xy 67.789396 -85.990593) (xy 67.830156 -85.955693)
			(xy 67.852544 -85.9409) (xy 67.875197 -85.927011) (xy 67.92354 -85.904958) (xy 67.974477 -85.889832)
			(xy 68.027021 -85.881926) (xy 68.080154 -85.881394) (xy 68.132846 -85.888246) (xy 68.184076 -85.902349)
			(xy 68.208652 -85.912452) (xy 68.219828 -85.917024) (xy 68.293234 -85.93328) (xy 68.388484 -85.88502)
			(xy 68.405248 -85.864954) (xy 68.424298 -85.843872) (xy 68.434078 -85.824055) (xy 68.447398 -85.781924)
			(xy 68.453236 -85.738125) (xy 68.451416 -85.693976) (xy 68.441993 -85.650805) (xy 68.425251 -85.609913)
			(xy 68.401694 -85.57253) (xy 68.387214 -85.555836) (xy 68.365116 -85.530436) (xy 68.347467 -85.507531)
			(xy 68.318555 -85.457455) (xy 68.297523 -85.403594) (xy 68.290694 -85.375496) (xy 68.284731 -85.346441)
			(xy 68.280816 -85.287261) (xy 68.286104 -85.228188) (xy 68.300468 -85.170643) (xy 68.323561 -85.116014)
			(xy 68.3387 -85.090508) (xy 68.35521 -85.066124) (xy 68.366386 -85.050884) (xy 68.393564 -84.97316)
			(xy 68.35013 -84.878418) (xy 68.332858 -84.861654) (xy 68.312481 -84.84121) (xy 68.277504 -84.795295)
			(xy 68.249836 -84.744638) (xy 68.230109 -84.690394) (xy 68.218771 -84.633799) (xy 68.216081 -84.576141)
			(xy 68.2221 -84.518736) (xy 68.236691 -84.462891) (xy 68.259522 -84.409878) (xy 68.290072 -84.360906)
			(xy 68.308474 -84.338668) (xy 68.322444 -84.322666) (xy 68.356734 -84.236814) (xy 68.340986 -84.184744)
			(xy 68.322444 -84.156804) (xy 68.306188 -84.129372) (xy 68.261992 -84.102956) (xy 68.248656 -84.095438)
			(xy 68.219437 -84.086335) (xy 68.188889 -84.084477) (xy 68.158782 -84.089972) (xy 68.144644 -84.095844)
			(xy 68.11264 -84.110068) (xy 68.095876 -84.126832) (xy 68.074254 -84.147695) (xy 68.025668 -84.183037)
			(xy 67.972144 -84.210329) (xy 67.915004 -84.228898) (xy 67.855661 -84.238284) (xy 67.82562 -84.238846)
			(xy 67.79597 -84.238282) (xy 67.737384 -84.229117) (xy 67.680914 -84.211019) (xy 67.65417 -84.198206)
			(xy 67.628832 -84.184882) (xy 67.582111 -84.151804) (xy 67.540849 -84.112124) (xy 67.50597 -84.066732)
			(xy 67.478255 -84.016642) (xy 67.458326 -83.962978) (xy 67.451986 -83.935062) (xy 67.448409 -83.916661)
			(xy 67.444461 -83.879382) (xy 67.444112 -83.86064) (xy 67.444112 -83.856576) (xy 67.444618 -83.829567)
			(xy 67.452312 -83.776098) (xy 67.467472 -83.724249) (xy 67.489794 -83.675058) (xy 67.518832 -83.629507)
			(xy 67.554006 -83.588508) (xy 67.594611 -83.552881) (xy 67.639837 -83.523338) (xy 67.688777 -83.50047)
			(xy 67.740454 -83.484735) (xy 67.793834 -83.476448) (xy 67.847849 -83.475773) (xy 67.90142 -83.482725)
			(xy 67.953473 -83.497164) (xy 68.00297 -83.518803) (xy 68.048919 -83.547207) (xy 68.090401 -83.581809)
			(xy 68.10883 -83.60156) (xy 68.12458 -83.618294) (xy 68.16098 -83.646335) (xy 68.201832 -83.667372)
			(xy 68.2458 -83.680716) (xy 68.291452 -83.685935) (xy 68.337298 -83.682856) (xy 68.381843 -83.671581)
			(xy 68.402962 -83.66252) (xy 68.423068 -83.645946) (xy 68.466904 -83.617779) (xy 68.490338 -83.606386)
			(xy 68.510658 -83.596734) (xy 68.593462 -83.51393) (xy 68.619624 -83.487514) (xy 68.635525 -83.469985)
			(xy 68.661168 -83.430213) (xy 68.679004 -83.386381) (xy 68.688416 -83.340005) (xy 68.689078 -83.292687)
			(xy 68.680968 -83.246066) (xy 68.664366 -83.201752) (xy 68.639846 -83.161278) (xy 68.608256 -83.126044)
			(xy 68.570689 -83.097268) (xy 68.549774 -83.086194) (xy 68.52158 -83.071462) (xy 68.512064 -83.065845)
			(xy 68.493637 -83.053645) (xy 68.48475 -83.047078) (xy 68.469256 -83.035394) (xy 68.389754 -83.006946)
			(xy 68.304918 -83.040474) (xy 68.288916 -83.053936) (xy 68.267189 -83.071665) (xy 68.219529 -83.10121)
			(xy 68.16805 -83.123443) (xy 68.141088 -83.131152) (xy 68.112114 -83.138326) (xy 68.052759 -83.144619)
			(xy 67.993149 -83.141585) (xy 67.934739 -83.1293) (xy 67.906646 -83.119214) (xy 67.884802 -83.110832)
			(xy 67.7672 -83.110832) (xy 67.70751 -83.142328) (xy 67.690746 -83.163664) (xy 67.684542 -83.171383)
			(xy 67.671454 -83.186249) (xy 67.664584 -83.193382) (xy 67.643158 -83.214638) (xy 67.594835 -83.250792)
			(xy 67.541422 -83.278886) (xy 67.484251 -83.29822) (xy 67.42475 -83.308312) (xy 67.394582 -83.309206)
			(xy 67.382939 -83.309258) (xy 67.359682 -83.308113) (xy 67.3481 -83.30692) (xy 67.325838 -83.305443)
			(xy 67.281401 -83.309381) (xy 67.238333 -83.321016) (xy 67.197957 -83.339991) (xy 67.161515 -83.365723)
			(xy 67.130124 -83.397422) (xy 67.104749 -83.434114) (xy 67.08617 -83.474673) (xy 67.08013 -83.49615)
			(xy 67.074034 -83.516978) (xy 67.070808 -83.526798) (xy 67.06344 -83.546114) (xy 67.059302 -83.555586)
			(xy 67.052758 -83.569898) (xy 67.037627 -83.597493) (xy 67.029076 -83.610704) (xy 67.018916 -83.625182)
			(xy 67.007147 -83.6432) (xy 66.9892 -83.682311) (xy 66.978107 -83.723889) (xy 66.974185 -83.766742)
			(xy 66.977548 -83.809643) (xy 66.988098 -83.851362) (xy 67.005533 -83.890704) (xy 67.029355 -83.926542)
			(xy 67.058879 -83.957848) (xy 67.075812 -83.97113) (xy 67.098181 -83.988649) (xy 67.137973 -84.029202)
			(xy 67.15506 -84.051902) (xy 67.170146 -84.073488) (xy 67.194875 -84.119985) (xy 67.212971 -84.169441)
			(xy 67.224089 -84.220918) (xy 67.228019 -84.273435) (xy 67.224685 -84.325992) (xy 67.21983 -84.351876)
			(xy 67.213703 -84.379415) (xy 67.194424 -84.432435) (xy 67.167544 -84.482036) (xy 67.133648 -84.527134)
			(xy 67.093477 -84.566745) (xy 67.070986 -84.583778) (xy 67.06743 -84.586318) (xy 67.050402 -84.599874)
			(xy 67.020811 -84.631788) (xy 66.997096 -84.668281) (xy 66.97995 -84.708282) (xy 66.969876 -84.750622)
			(xy 66.967168 -84.794059) (xy 66.971908 -84.837321) (xy 66.977514 -84.858352) (xy 66.980271 -84.868208)
			(xy 66.984847 -84.888157) (xy 66.986658 -84.89823) (xy 66.989973 -84.914411) (xy 67.003745 -84.94442)
			(xy 67.024776 -84.969873) (xy 67.05165 -84.989056) (xy 67.082555 -85.000678) (xy 67.098926 -85.002878)
			(xy 67.136518 -85.00872) (xy 67.137026 -85.00872) (xy 67.166341 -85.015334) (xy 67.222567 -85.036546)
			(xy 67.274764 -85.066323) (xy 67.29857 -85.084666) (xy 67.319959 -85.102464) (xy 67.357852 -85.143211)
			(xy 67.389423 -85.18903) (xy 67.414003 -85.238949) (xy 67.431072 -85.291909) (xy 67.440265 -85.346787)
			(xy 67.441389 -85.402419) (xy 67.43442 -85.457623) (xy 67.419505 -85.51123) (xy 67.396961 -85.562101)
			(xy 67.367266 -85.609158) (xy 67.331051 -85.651402) (xy 67.289083 -85.687937) (xy 67.242253 -85.717988)
			(xy 67.191554 -85.740917) (xy 67.164966 -85.74913) (xy 67.127628 -85.759798) (xy 67.027806 -85.878924)
			(xy 67.023742 -85.917532) (xy 67.022195 -85.931261) (xy 67.017365 -85.958466) (xy 67.01409 -85.971888)
			(xy 67.008768 -85.995001) (xy 67.005824 -86.042334) (xy 67.01171 -86.089391) (xy 67.026222 -86.134541)
			(xy 67.048855 -86.176216) (xy 67.078824 -86.21297) (xy 67.11509 -86.243529) (xy 67.135502 -86.255606)
			(xy 67.159733 -86.269821) (xy 67.204114 -86.304261) (xy 67.242966 -86.344836) (xy 67.275449 -86.39067)
			(xy 67.300861 -86.44077) (xy 67.318653 -86.494055) (xy 67.328439 -86.549373) (xy 67.330009 -86.605528)
			(xy 67.323328 -86.661306) (xy 67.308542 -86.715502) (xy 67.285969 -86.766944) (xy 67.256097 -86.814521)
			(xy 67.219573 -86.857203) (xy 67.177185 -86.894069) (xy 67.12985 -86.924322) (xy 67.078591 -86.947307)
			(xy 67.051682 -86.955376) (xy 67.025755 -86.962202) (xy 66.97262 -86.969361) (xy 66.919007 -86.969012)
			(xy 66.865971 -86.96116) (xy 66.814556 -86.945961) (xy 66.765776 -86.923714) (xy 66.72059 -86.894857)
			(xy 66.679889 -86.859959) (xy 66.644474 -86.819706) (xy 66.615043 -86.774892) (xy 66.592175 -86.726399)
			(xy 66.576321 -86.675183) (xy 66.567793 -86.622251) (xy 66.566796 -86.595458) (xy 66.56675 -86.569928)
			(xy 66.572616 -86.519213) (xy 66.57848 -86.494366) (xy 66.583798 -86.471255) (xy 66.586734 -86.423928)
			(xy 66.580841 -86.376877) (xy 66.566324 -86.331735) (xy 66.543687 -86.29007) (xy 66.513715 -86.253325)
			(xy 66.477447 -86.222777) (xy 66.457068 -86.210648) (xy 66.433935 -86.197105) (xy 66.391363 -86.164531)
			(xy 66.35377 -86.126318) (xy 66.321897 -86.083219) (xy 66.296371 -86.036082) (xy 66.277695 -85.985836)
			(xy 66.266236 -85.933471) (xy 66.26222 -85.880017) (xy 66.265727 -85.826528) (xy 66.276687 -85.774056)
			(xy 66.294884 -85.723634) (xy 66.319961 -85.676257) (xy 66.351423 -85.632857) (xy 66.369692 -85.61324)
			(xy 66.385082 -85.596548) (xy 66.410273 -85.558782) (xy 66.428354 -85.517141) (xy 66.43875 -85.47295)
			(xy 66.441129 -85.427616) (xy 66.435415 -85.38258) (xy 66.421791 -85.339275) (xy 66.400691 -85.29908)
			(xy 66.372784 -85.263273) (xy 66.35623 -85.247734) (xy 66.335656 -85.227922) (xy 66.317745 -85.208649)
			(xy 66.286845 -85.166064) (xy 66.262088 -85.119639) (xy 66.243944 -85.070252) (xy 66.232757 -85.018841)
			(xy 66.228739 -84.966381) (xy 66.231966 -84.913866) (xy 66.242376 -84.862292) (xy 66.259774 -84.812637)
			(xy 66.283827 -84.765844) (xy 66.298572 -84.744052) (xy 66.317741 -84.718018) (xy 66.36332 -84.672175)
			(xy 66.38925 -84.652866) (xy 66.406278 -84.63931) (xy 66.435869 -84.607396) (xy 66.459584 -84.570904)
			(xy 66.476729 -84.530903) (xy 66.486801 -84.488563) (xy 66.489506 -84.445127) (xy 66.484764 -84.401865)
			(xy 66.479166 -84.380832) (xy 66.475864 -84.36864) (xy 66.469184 -84.339731) (xy 66.463813 -84.280644)
			(xy 66.467653 -84.221437) (xy 66.473578 -84.192364) (xy 66.479844 -84.166486) (xy 66.498586 -84.116649)
			(xy 66.510916 -84.09305) (xy 66.517037 -84.08207) (xy 66.530512 -84.060846) (xy 66.53784 -84.050632)
			(xy 66.550074 -84.031758) (xy 66.568417 -83.990695) (xy 66.579276 -83.947051) (xy 66.581274 -83.924648)
			(xy 66.491866 -83.804506) (xy 66.458338 -83.791298) (xy 66.432961 -83.780711) (xy 66.385294 -83.753304)
			(xy 66.342054 -83.71934) (xy 66.304136 -83.679522) (xy 66.272326 -83.634674) (xy 66.247281 -83.585724)
			(xy 66.229521 -83.533687) (xy 66.219413 -83.47964) (xy 66.217167 -83.424701) (xy 66.222829 -83.370009)
			(xy 66.236281 -83.316696) (xy 66.257246 -83.265865) (xy 66.285289 -83.21857) (xy 66.31983 -83.175789)
			(xy 66.33972 -83.156806) (xy 66.355805 -83.140089) (xy 66.382214 -83.101955) (xy 66.401254 -83.059656)
			(xy 66.412291 -83.014602) (xy 66.414956 -82.968293) (xy 66.409163 -82.92227) (xy 66.395102 -82.878066)
			(xy 66.384678 -82.85734) (xy 66.372464 -82.833399) (xy 66.354034 -82.782911) (xy 66.342773 -82.730358)
			(xy 66.338897 -82.676751) (xy 66.342481 -82.623124) (xy 66.353457 -82.570511) (xy 66.371613 -82.519924)
			(xy 66.383662 -82.495898) (xy 66.388474 -82.473506) (xy 66.390899 -82.427775) (xy 66.385101 -82.382348)
			(xy 66.371267 -82.338692) (xy 66.349845 -82.298216) (xy 66.321524 -82.262228) (xy 66.304668 -82.246724)
			(xy 66.277744 -82.220562) (xy 66.259548 -82.200321) (xy 66.228485 -82.155631) (xy 66.204088 -82.106979)
			(xy 66.186852 -82.055354) (xy 66.177128 -82.001804) (xy 66.175113 -81.947415) (xy 66.180847 -81.893292)
			(xy 66.194215 -81.840533) (xy 66.214944 -81.790209) (xy 66.242615 -81.743342) (xy 66.276665 -81.700883)
			(xy 66.316404 -81.663694) (xy 66.361024 -81.632529) (xy 66.40962 -81.608022) (xy 66.461205 -81.590669)
			(xy 66.514733 -81.580823) (xy 66.541904 -81.579212) (xy 66.568081 -81.578615) (xy 66.620193 -81.583729)
			(xy 66.671116 -81.595919) (xy 66.719894 -81.614955) (xy 66.765613 -81.64048) (xy 66.78676 -81.65592)
			(xy 66.808873 -81.67324) (xy 66.848255 -81.71329) (xy 66.881344 -81.758678) (xy 66.907426 -81.808424)
			(xy 66.925938 -81.861454) (xy 66.93648 -81.916625) (xy 66.938825 -81.972745) (xy 66.932921 -82.028602)
			(xy 66.918897 -82.082992) (xy 66.908426 -82.109056) (xy 66.900962 -82.13019) (xy 66.892746 -82.174247)
			(xy 66.892385 -82.219062) (xy 66.899889 -82.263246) (xy 66.915026 -82.305429) (xy 66.937327 -82.344303)
			(xy 66.951352 -82.361786) (xy 66.973949 -82.378629) (xy 67.014478 -82.41779) (xy 67.048889 -82.462423)
			(xy 67.063112 -82.486754) (xy 67.078606 -82.51444) (xy 67.186048 -82.582766) (xy 67.25793 -82.570066)
			(xy 67.267074 -82.566764) (xy 67.294925 -82.557831) (xy 67.352503 -82.547569) (xy 67.410974 -82.546209)
			(xy 67.468967 -82.553784) (xy 67.497198 -82.56143) (xy 67.498468 -82.561684) (xy 67.509727 -82.56508)
			(xy 67.531842 -82.573083) (xy 67.542664 -82.577686) (xy 67.553586 -82.582512) (xy 67.628516 -82.599022)
			(xy 67.725544 -82.547968) (xy 67.742308 -82.526632) (xy 67.759598 -82.505404) (xy 67.79924 -82.467643)
			(xy 67.843873 -82.435938) (xy 67.89258 -82.410939) (xy 67.944361 -82.393159) (xy 67.998152 -82.382965)
			(xy 68.052848 -82.380565) (xy 68.080128 -82.382868) (xy 68.105913 -82.385869) (xy 68.156394 -82.397965)
			(xy 68.204765 -82.416805) (xy 68.250129 -82.44204) (xy 68.271136 -82.45729) (xy 68.286376 -82.46872)
			(xy 68.365878 -82.497168) (xy 68.451222 -82.46364) (xy 68.467224 -82.449924) (xy 68.482718 -82.437478)
			(xy 68.494545 -82.428705) (xy 68.519339 -82.412814) (xy 68.532248 -82.405728) (xy 68.54161 -82.400752)
			(xy 68.560797 -82.391726) (xy 68.570602 -82.387694) (xy 68.582286 -82.383122) (xy 68.609179 -82.373841)
			(xy 68.664915 -82.362445) (xy 68.721725 -82.359459) (xy 68.778349 -82.364949) (xy 68.833527 -82.378793)
			(xy 68.886036 -82.400684) (xy 68.934708 -82.430135) (xy 68.956936 -82.447892) (xy 68.970121 -82.458153)
			(xy 69.000493 -82.472045) (xy 69.033427 -82.477592) (xy 69.066674 -82.474415) (xy 69.097962 -82.462731)
			(xy 69.111876 -82.45348) (xy 69.135164 -82.437448) (xy 69.185494 -82.411696) (xy 69.239074 -82.393652)
			(xy 69.266816 -82.388202) (xy 69.276974 -82.386453) (xy 69.297433 -82.383913) (xy 69.30771 -82.383122)
			(xy 69.337595 -82.381658) (xy 69.397185 -82.387014) (xy 69.426328 -82.39379) (xy 69.426836 -82.39379)
			(xy 69.451202 -82.400404) (xy 69.498071 -82.419177) (xy 69.542061 -82.443954) (xy 69.562472 -82.458814)
			(xy 69.577966 -82.470244) (xy 69.657468 -82.498692) (xy 69.73697 -82.470244) (xy 69.752464 -82.458814)
			(xy 69.77457 -82.442812) (xy 69.822445 -82.41662) (xy 69.873565 -82.39752) (xy 69.926886 -82.385901)
			(xy 69.981318 -82.382002) (xy 70.03575 -82.385901) (xy 70.089071 -82.39752) (xy 70.140191 -82.41662)
			(xy 70.188066 -82.442812) (xy 70.210172 -82.458814) (xy 70.225666 -82.470244) (xy 70.305168 -82.498692)
			(xy 70.38467 -82.470244) (xy 70.400164 -82.458814) (xy 70.421924 -82.443068) (xy 70.468989 -82.417188)
			(xy 70.519218 -82.398163) (xy 70.571619 -82.386371) (xy 70.625155 -82.382042) (xy 70.67877 -82.385264)
			(xy 70.731403 -82.395973) (xy 70.782014 -82.413956) (xy 70.829604 -82.438859) (xy 70.873231 -82.470189)
			(xy 70.912033 -82.507327) (xy 70.928992 -82.528156) (xy 70.945756 -82.549492) (xy 71.048626 -82.603594)
			(xy 71.115428 -82.58429) (xy 71.128636 -82.576924) (xy 71.13768 -82.571848) (xy 71.156234 -82.562574)
			(xy 71.16572 -82.558382) (xy 71.18604 -82.550254) (xy 71.196962 -82.546444) (xy 71.200518 -82.545428)
			(xy 71.20382 -82.544412) (xy 71.217875 -82.539646) (xy 71.243426 -82.524563) (xy 71.264796 -82.50398)
			(xy 71.280828 -82.479013) (xy 71.290653 -82.451016) (xy 71.293738 -82.421506) (xy 71.292212 -82.406744)
			(xy 71.289211 -82.380221) (xy 71.289766 -82.326846) (xy 71.297751 -82.274069) (xy 71.313009 -82.222919)
			(xy 71.323708 -82.198464) (xy 71.329553 -82.184688) (xy 71.335317 -82.15533) (xy 71.334085 -82.125438)
			(xy 71.325926 -82.096654) (xy 71.311289 -82.070561) (xy 71.290977 -82.048594) (xy 71.27875 -82.039968)
			(xy 71.2551 -82.023487) (xy 71.212582 -81.984564) (xy 71.176401 -81.93969) (xy 71.14738 -81.889885)
			(xy 71.126179 -81.836283) (xy 71.113279 -81.780101) (xy 71.108975 -81.722619) (xy 71.113364 -81.665143)
			(xy 71.126346 -81.608981) (xy 71.13651 -81.582006) (xy 71.147192 -81.556475) (xy 71.174854 -81.508543)
			(xy 71.209151 -81.465109) (xy 71.249362 -81.427085) (xy 71.294644 -81.395268) (xy 71.344047 -81.370326)
			(xy 71.396535 -81.352783) (xy 71.451006 -81.343006) (xy 71.506319 -81.341199) (xy 71.561312 -81.347403)
			(xy 71.614833 -81.361485) (xy 71.665758 -81.38315) (xy 71.713019 -81.411945) (xy 71.755625 -81.447265)
			(xy 71.774558 -81.467452) (xy 71.792709 -81.488349) (xy 71.823417 -81.5344) (xy 71.847156 -81.584401)
			(xy 71.863429 -81.637305) (xy 71.871895 -81.692004) (xy 71.872602 -81.719674) (xy 71.87203 -81.739486)
			(xy 72.186798 -81.739486) (xy 72.190869 -81.683864) (xy 72.202995 -81.629427) (xy 72.222918 -81.577336)
			(xy 72.250214 -81.528701) (xy 72.2843 -81.484558) (xy 72.324449 -81.445849) (xy 72.369807 -81.413398)
			(xy 72.419407 -81.387897) (xy 72.472191 -81.36989) (xy 72.527034 -81.35976) (xy 72.582768 -81.357723)
			(xy 72.638205 -81.363823) (xy 72.692162 -81.377929) (xy 72.743491 -81.399741) (xy 72.791097 -81.428795)
			(xy 72.833965 -81.46447) (xy 72.871182 -81.506007) (xy 72.901955 -81.55252) (xy 72.925627 -81.603017)
			(xy 72.941695 -81.656424) (xy 72.949815 -81.7116) (xy 72.950324 -81.739486) (xy 72.949815 -81.767372)
			(xy 72.941695 -81.822548) (xy 72.925627 -81.875955) (xy 72.901955 -81.926452) (xy 72.871182 -81.972965)
			(xy 72.833965 -82.014502) (xy 72.791097 -82.050177) (xy 72.743491 -82.079231) (xy 72.692162 -82.101043)
			(xy 72.638205 -82.115149) (xy 72.582768 -82.121249) (xy 72.527034 -82.119212) (xy 72.472191 -82.109082)
			(xy 72.419407 -82.091075) (xy 72.369807 -82.065574) (xy 72.324449 -82.033123) (xy 72.2843 -81.994414)
			(xy 72.250214 -81.950271) (xy 72.222918 -81.901636) (xy 72.202995 -81.849545) (xy 72.190869 -81.795108)
			(xy 72.186798 -81.739486) (xy 71.87203 -81.739486) (xy 71.87184 -81.74609) (xy 71.87007 -81.769515)
			(xy 71.86148 -81.815702) (xy 71.847277 -81.860482) (xy 71.837804 -81.88198) (xy 71.831964 -81.895754)
			(xy 71.82621 -81.925107) (xy 71.82745 -81.954992) (xy 71.835615 -81.983767) (xy 71.850256 -82.00985)
			(xy 71.870569 -82.031806) (xy 71.882762 -82.040476) (xy 71.906049 -82.056699) (xy 71.948002 -82.094917)
			(xy 71.983829 -82.13893) (xy 72.01274 -82.187765) (xy 72.034096 -82.240344) (xy 72.041258 -82.267806)
			(xy 72.042274 -82.272124) (xy 72.048156 -82.300169) (xy 72.052497 -82.357305) (xy 72.05091 -82.385916)
			(xy 72.048264 -82.414299) (xy 72.035614 -82.469881) (xy 72.01483 -82.52296) (xy 71.986375 -82.572353)
			(xy 71.950883 -82.616959) (xy 71.909145 -82.655783) (xy 71.862092 -82.687961) (xy 71.810773 -82.712774)
			(xy 71.783702 -82.721704) (xy 71.769646 -82.726469) (xy 71.744094 -82.741551) (xy 71.722722 -82.762133)
			(xy 71.70669 -82.7871) (xy 71.696866 -82.815099) (xy 71.693784 -82.84461) (xy 71.69531 -82.859372)
			(xy 71.697088 -82.875882) (xy 71.698104 -82.889598) (xy 71.700913 -82.912858) (xy 71.71393 -82.957858)
			(xy 71.73497 -82.999712) (xy 71.763321 -83.037004) (xy 71.798023 -83.068472) (xy 71.837903 -83.09305)
			(xy 71.88161 -83.109907) (xy 71.927665 -83.118472) (xy 71.951088 -83.11896) (xy 72.131174 -83.11896)
			(xy 72.361806 -82.888328) (xy 72.634856 -82.888328) (xy 72.656969 -82.887854) (xy 72.700528 -82.880206)
			(xy 72.742105 -82.865133) (xy 72.780446 -82.84309) (xy 72.814392 -82.814743) (xy 72.842918 -82.780947)
			(xy 72.865163 -82.742724) (xy 72.880456 -82.701226) (xy 72.888334 -82.657708) (xy 72.888856 -82.635598)
			(xy 72.888856 -82.633312) (xy 72.88969 -82.604339) (xy 72.899036 -82.547139) (xy 72.916924 -82.492009)
			(xy 72.942942 -82.440218) (xy 72.976492 -82.392956) (xy 73.016801 -82.35131) (xy 73.062945 -82.316237)
			(xy 73.11386 -82.288545) (xy 73.168378 -82.26887) (xy 73.196704 -82.262726) (xy 73.224033 -82.257854)
			(xy 73.279476 -82.255137) (xy 73.334728 -82.260485) (xy 73.388621 -82.273785) (xy 73.440018 -82.294756)
			(xy 73.464166 -82.308446) (xy 73.487971 -82.323046) (xy 73.531428 -82.358117) (xy 73.569308 -82.399148)
			(xy 73.600802 -82.445263) (xy 73.625238 -82.495476) (xy 73.642092 -82.548714) (xy 73.651006 -82.603841)
			(xy 73.651789 -82.659679) (xy 73.644423 -82.715034) (xy 73.629067 -82.768724) (xy 73.606049 -82.819603)
			(xy 73.575859 -82.866582) (xy 73.539144 -82.908658) (xy 73.496687 -82.944933) (xy 73.47331 -82.96021)
			(xy 73.454857 -82.972322) (xy 73.422056 -83.001855) (xy 73.394852 -83.036611) (xy 73.374062 -83.075545)
			(xy 73.360312 -83.117485) (xy 73.354015 -83.16117) (xy 73.35536 -83.205286) (xy 73.364307 -83.248506)
			(xy 73.380588 -83.28953) (xy 73.403711 -83.327125) (xy 73.417938 -83.344004) (xy 73.983596 -83.909662)
			(xy 74.011536 -83.937602) (xy 74.48804 -84.413852) (xy 75.017884 -84.413852) (xy 75.034538 -84.413359)
			(xy 75.066711 -84.40474) (xy 75.095555 -84.388085) (xy 75.119104 -84.36453) (xy 75.135752 -84.335681)
			(xy 75.144363 -84.303506) (xy 75.144884 -84.286852) (xy 75.144884 -83.829144) (xy 75.127358 -83.799426)
			(xy 75.111864 -83.769708) (xy 75.1048 -83.75582) (xy 75.08505 -83.731731) (xy 75.060042 -83.713159)
			(xy 75.031273 -83.701215) (xy 75.000465 -83.696613) (xy 74.969461 -83.699629) (xy 74.954638 -83.70443)
			(xy 74.928225 -83.713237) (xy 74.873595 -83.723977) (xy 74.817984 -83.726664) (xy 74.762573 -83.72124)
			(xy 74.708539 -83.707821) (xy 74.657028 -83.686692) (xy 74.609135 -83.658301) (xy 74.565877 -83.623251)
			(xy 74.528172 -83.582287) (xy 74.49682 -83.536277) (xy 74.472488 -83.4862) (xy 74.455691 -83.433118)
			(xy 74.446788 -83.378159) (xy 74.445966 -83.32249) (xy 74.453244 -83.267292) (xy 74.460354 -83.240372)
			(xy 74.468248 -83.214344) (xy 74.49039 -83.164666) (xy 74.519363 -83.118637) (xy 74.55458 -83.077189)
			(xy 74.595328 -83.041164) (xy 74.640779 -83.011292) (xy 74.690012 -82.988178) (xy 74.742029 -82.972292)
			(xy 74.795775 -82.963955) (xy 74.850161 -82.963336) (xy 74.904083 -82.970449) (xy 74.956448 -82.985148)
			(xy 75.006194 -83.007136) (xy 75.052312 -83.035967) (xy 75.093868 -83.071057) (xy 75.130019 -83.111693)
			(xy 75.160031 -83.157051) (xy 75.172062 -83.181444) (xy 75.17913 -83.195325) (xy 75.198884 -83.219399)
			(xy 75.223891 -83.237958) (xy 75.252655 -83.249892) (xy 75.283455 -83.254486) (xy 75.314449 -83.251467)
			(xy 75.329288 -83.246722) (xy 75.355348 -83.238015) (xy 75.409241 -83.227317) (xy 75.464111 -83.224459)
			(xy 75.518823 -83.2295) (xy 75.567244 -83.241134) (xy 81.600292 -83.241134) (xy 81.604363 -83.185512)
			(xy 81.616489 -83.131075) (xy 81.636412 -83.078984) (xy 81.663708 -83.030349) (xy 81.697794 -82.986206)
			(xy 81.737943 -82.947497) (xy 81.783301 -82.915046) (xy 81.832901 -82.889545) (xy 81.885685 -82.871538)
			(xy 81.940528 -82.861408) (xy 81.996262 -82.859371) (xy 82.051699 -82.865471) (xy 82.105656 -82.879577)
			(xy 82.156985 -82.901389) (xy 82.204591 -82.930443) (xy 82.247459 -82.966118) (xy 82.284676 -83.007655)
			(xy 82.315449 -83.054168) (xy 82.339121 -83.104665) (xy 82.355189 -83.158072) (xy 82.363309 -83.213248)
			(xy 82.363818 -83.241134) (xy 82.363309 -83.26902) (xy 82.355189 -83.324196) (xy 82.339121 -83.377603)
			(xy 82.315449 -83.4281) (xy 82.284676 -83.474613) (xy 82.247459 -83.51615) (xy 82.204591 -83.551825)
			(xy 82.156985 -83.580879) (xy 82.105656 -83.602691) (xy 82.051699 -83.616797) (xy 81.996262 -83.622897)
			(xy 81.940528 -83.62086) (xy 81.885685 -83.61073) (xy 81.832901 -83.592723) (xy 81.783301 -83.567222)
			(xy 81.737943 -83.534771) (xy 81.697794 -83.496062) (xy 81.663708 -83.451919) (xy 81.636412 -83.403284)
			(xy 81.616489 -83.351193) (xy 81.604363 -83.296756) (xy 81.600292 -83.241134) (xy 75.567244 -83.241134)
			(xy 75.572247 -83.242336) (xy 75.623278 -83.262701) (xy 75.670861 -83.290174) (xy 75.714011 -83.324187)
			(xy 75.751838 -83.364037) (xy 75.783558 -83.4089) (xy 75.808517 -83.457848) (xy 75.826197 -83.50987)
			(xy 75.8317 -83.53679) (xy 75.836642 -83.5603) (xy 75.854142 -83.605034) (xy 75.879731 -83.645685)
			(xy 75.912498 -83.680809) (xy 75.951277 -83.709155) (xy 75.99469 -83.729715) (xy 76.041191 -83.741757)
			(xy 76.065126 -83.7438) (xy 76.092489 -83.745357) (xy 76.14638 -83.755334) (xy 76.19829 -83.772912)
			(xy 76.247156 -83.79773) (xy 76.291971 -83.829278) (xy 76.331816 -83.866909) (xy 76.365873 -83.909849)
			(xy 76.380086 -83.933284) (xy 76.394025 -83.958281) (xy 76.415075 -84.011501) (xy 76.427937 -84.067269)
			(xy 76.432324 -84.124333) (xy 76.428136 -84.181412) (xy 76.424959 -84.195412) (xy 76.772768 -84.195412)
			(xy 76.776839 -84.13979) (xy 76.788965 -84.085353) (xy 76.808888 -84.033262) (xy 76.836184 -83.984627)
			(xy 76.87027 -83.940484) (xy 76.910419 -83.901775) (xy 76.955777 -83.869324) (xy 77.005377 -83.843823)
			(xy 77.058161 -83.825816) (xy 77.113004 -83.815686) (xy 77.168738 -83.813649) (xy 77.224175 -83.819749)
			(xy 77.278132 -83.833855) (xy 77.329461 -83.855667) (xy 77.377067 -83.884721) (xy 77.419935 -83.920396)
			(xy 77.457152 -83.961933) (xy 77.487925 -84.008446) (xy 77.511597 -84.058943) (xy 77.527665 -84.11235)
			(xy 77.535785 -84.167526) (xy 77.536294 -84.195412) (xy 77.536271 -84.196652) (xy 79.514345 -84.196652)
			(xy 79.521283 -84.141968) (xy 79.536021 -84.088852) (xy 79.558253 -84.038412) (xy 79.587513 -83.991696)
			(xy 79.623194 -83.94968) (xy 79.664552 -83.913238) (xy 79.710726 -83.883129) (xy 79.760752 -83.859981)
			(xy 79.81359 -83.844276) (xy 79.868139 -83.836341) (xy 79.923261 -83.836341) (xy 79.97781 -83.844276)
			(xy 80.030648 -83.859981) (xy 80.080674 -83.883129) (xy 80.126848 -83.913238) (xy 80.168206 -83.94968)
			(xy 80.203887 -83.991696) (xy 80.233147 -84.038412) (xy 80.255379 -84.088852) (xy 80.270117 -84.141968)
			(xy 80.277055 -84.196652) (xy 80.276049 -84.251766) (xy 80.267119 -84.30616) (xy 80.250452 -84.358703)
			(xy 80.226395 -84.408299) (xy 80.195448 -84.453915) (xy 80.158257 -84.4946) (xy 80.115596 -84.529509)
			(xy 80.068355 -84.557912) (xy 80.017517 -84.579219) (xy 79.99095 -84.586572) (xy 79.974839 -84.591255)
			(xy 79.945666 -84.607806) (xy 79.921812 -84.631384) (xy 79.904922 -84.660362) (xy 79.896162 -84.692738)
			(xy 79.895774 -84.706804) (xy 79.892679 -84.679852) (xy 79.882035 -84.651149) (xy 79.864855 -84.62581)
			(xy 79.842129 -84.605299) (xy 79.815168 -84.590797) (xy 79.80045 -84.586572) (xy 79.773883 -84.579219)
			(xy 79.723045 -84.557912) (xy 79.675804 -84.529509) (xy 79.633143 -84.4946) (xy 79.595952 -84.453915)
			(xy 79.565005 -84.408299) (xy 79.540948 -84.358703) (xy 79.524281 -84.30616) (xy 79.515351 -84.251766)
			(xy 79.514345 -84.196652) (xy 77.536271 -84.196652) (xy 77.535785 -84.223298) (xy 77.527665 -84.278474)
			(xy 77.511597 -84.331881) (xy 77.487925 -84.382378) (xy 77.457152 -84.428891) (xy 77.419935 -84.470428)
			(xy 77.377067 -84.506103) (xy 77.329461 -84.535157) (xy 77.278132 -84.556969) (xy 77.224175 -84.571075)
			(xy 77.168738 -84.577175) (xy 77.113004 -84.575138) (xy 77.058161 -84.565008) (xy 77.005377 -84.547001)
			(xy 76.955777 -84.5215) (xy 76.910419 -84.489049) (xy 76.87027 -84.45034) (xy 76.836184 -84.406197)
			(xy 76.808888 -84.357562) (xy 76.788965 -84.305471) (xy 76.776839 -84.251034) (xy 76.772768 -84.195412)
			(xy 76.424959 -84.195412) (xy 76.415469 -84.237224) (xy 76.394606 -84.290518) (xy 76.366015 -84.340097)
			(xy 76.330338 -84.384848) (xy 76.309728 -84.404708) (xy 76.293419 -84.420518) (xy 76.266139 -84.456829)
			(xy 76.245749 -84.497411) (xy 76.232898 -84.540972) (xy 76.227997 -84.586123) (xy 76.2312 -84.631427)
			(xy 76.242406 -84.675439) (xy 76.261258 -84.716758) (xy 76.287156 -84.754068) (xy 76.30287 -84.770468)
			(xy 76.860146 -85.327744) (xy 78.250796 -85.327744) (xy 78.28661 -85.297264) (xy 78.307425 -85.28012)
			(xy 78.352969 -85.251248) (xy 78.402124 -85.229076) (xy 78.453911 -85.214044) (xy 78.507298 -85.206453)
			(xy 78.561222 -85.206453) (xy 78.614609 -85.214044) (xy 78.666396 -85.229076) (xy 78.715551 -85.251248)
			(xy 78.761095 -85.28012) (xy 78.78191 -85.297264) (xy 78.817724 -85.327744) (xy 79.05242 -85.327744)
			(xy 79.543402 -84.836508) (xy 79.7687 -84.836508) (xy 79.784007 -84.836052) (xy 79.813738 -84.828753)
			(xy 79.840871 -84.814577) (xy 79.863842 -84.79434) (xy 79.881326 -84.76921) (xy 79.892314 -84.740636)
			(xy 79.8957 -84.713981) (xy 79.8957 -84.76234) (xy 79.969868 -84.836508) (xy 79.989934 -84.836508)
			(xy 79.989934 -84.836762) (xy 80.148176 -84.836762) (xy 80.207612 -84.896198) (xy 80.223276 -84.911227)
			(xy 80.258748 -84.936245) (xy 80.297957 -84.954868) (xy 80.339761 -84.966554) (xy 80.382943 -84.970963)
			(xy 80.426246 -84.967967) (xy 80.46841 -84.957653) (xy 80.508206 -84.940321) (xy 80.544477 -84.916476)
			(xy 80.576166 -84.886812) (xy 80.589628 -84.869782) (xy 80.60637 -84.84839) (xy 80.644908 -84.810107)
			(xy 80.688486 -84.777677) (xy 80.736224 -84.751755) (xy 80.787155 -84.732866) (xy 80.84025 -84.721391)
			(xy 80.894436 -84.717563) (xy 80.948617 -84.721458) (xy 81.001698 -84.732998) (xy 81.052606 -84.75195)
			(xy 81.100311 -84.777931) (xy 81.143849 -84.810415) (xy 81.18234 -84.848745) (xy 81.215005 -84.892147)
			(xy 81.241185 -84.939743) (xy 81.260349 -84.990571) (xy 81.272111 -85.043604) (xy 81.276233 -85.097768)
			(xy 81.272631 -85.15197) (xy 81.261378 -85.205112) (xy 81.242702 -85.256122) (xy 81.230216 -85.280246)
			(xy 81.221097 -85.298067) (xy 81.207966 -85.335881) (xy 81.200927 -85.375287) (xy 81.200153 -85.415309)
			(xy 81.20253 -85.435186) (xy 81.20761 -85.472524) (xy 81.232502 -85.501226) (xy 81.243812 -85.513447)
			(xy 81.271438 -85.532019) (xy 81.302931 -85.542801) (xy 81.336143 -85.545058) (xy 81.368805 -85.538634)
			(xy 81.398689 -85.52397) (xy 81.411572 -85.513418) (xy 81.460848 -85.470492) (xy 81.4705 -85.431122)
			(xy 81.477173 -85.405459) (xy 81.49665 -85.356141) (xy 81.522768 -85.309995) (xy 81.555024 -85.267909)
			(xy 81.592796 -85.230695) (xy 81.635357 -85.199069) (xy 81.681886 -85.17364) (xy 81.731488 -85.154898)
			(xy 81.783207 -85.143204) (xy 81.80959 -85.140546) (xy 81.835531 -85.138837) (xy 81.887443 -85.14162)
			(xy 81.938497 -85.151428) (xy 81.96326 -85.159342) (xy 81.989163 -85.168604) (xy 82.038208 -85.193518)
			(xy 82.083166 -85.225218) (xy 82.123106 -85.263045) (xy 82.157199 -85.306216) (xy 82.184739 -85.353836)
			(xy 82.205155 -85.404917) (xy 82.218023 -85.458401) (xy 82.223077 -85.513179) (xy 82.220212 -85.568114)
			(xy 82.209488 -85.622068) (xy 82.191126 -85.673923) (xy 82.165507 -85.722604) (xy 82.133163 -85.767101)
			(xy 82.094764 -85.806491) (xy 82.051106 -85.839959) (xy 82.003094 -85.86681) (xy 81.951724 -85.886487)
			(xy 81.89806 -85.898583) (xy 81.843216 -85.902847) (xy 81.788328 -85.899191) (xy 81.76133 -85.89391)
			(xy 81.738762 -85.889586) (xy 81.692835 -85.888208) (xy 81.64741 -85.895115) (xy 81.603968 -85.910081)
			(xy 81.563928 -85.932618) (xy 81.528596 -85.96199) (xy 81.499124 -85.99724) (xy 81.476474 -86.037217)
			(xy 81.468468 -86.058756) (xy 81.459338 -86.08354) (xy 81.435221 -86.13053) (xy 81.404868 -86.173754)
			(xy 81.387188 -86.193376) (xy 81.376407 -86.205604) (xy 81.360873 -86.234254) (xy 81.35311 -86.265906)
			(xy 81.353625 -86.298492) (xy 81.362385 -86.329883) (xy 81.378817 -86.358027) (xy 81.389982 -86.369906)
			(xy 81.525364 -86.505288) (xy 81.613756 -86.59368) (xy 81.649824 -86.601808) (xy 81.676105 -86.608135)
			(xy 81.726687 -86.627202) (xy 81.77407 -86.653218) (xy 81.817307 -86.685663) (xy 81.855531 -86.723886)
			(xy 81.887977 -86.767121) (xy 81.913994 -86.814504) (xy 81.933062 -86.865086) (xy 81.933213 -86.865714)
			(xy 83.123532 -86.865714) (xy 83.123532 -82.496914) (xy 83.37931 -82.241136) (xy 85.55609 -82.241136)
			(xy 85.773768 -82.458814) (xy 85.773768 -84.547041) (xy 90.307078 -84.547041) (xy 90.315025 -84.492285)
			(xy 90.330797 -84.439252) (xy 90.354062 -84.389052) (xy 90.384333 -84.342739) (xy 90.420975 -84.301283)
			(xy 90.44178 -84.283042) (xy 90.45797 -84.268712) (xy 90.48579 -84.235622) (xy 90.507607 -84.1983)
			(xy 90.522792 -84.157823) (xy 90.530907 -84.115361) (xy 90.531716 -84.072137) (xy 90.525198 -84.029401)
			(xy 90.51154 -83.988384) (xy 90.491136 -83.950271) (xy 90.464575 -83.916162) (xy 90.448892 -83.90128)
			(xy 90.428617 -83.882079) (xy 90.39328 -83.838845) (xy 90.364621 -83.790923) (xy 90.343253 -83.739335)
			(xy 90.329631 -83.685184) (xy 90.324048 -83.629626) (xy 90.326621 -83.573848) (xy 90.337297 -83.51904)
			(xy 90.355847 -83.466373) (xy 90.381874 -83.416972) (xy 90.414824 -83.371893) (xy 90.453992 -83.332096)
			(xy 90.498542 -83.298434) (xy 90.547522 -83.271624) (xy 90.599887 -83.252239) (xy 90.654519 -83.240692)
			(xy 90.710249 -83.237232) (xy 90.765889 -83.241931) (xy 90.82025 -83.254689) (xy 90.872171 -83.275234)
			(xy 90.920543 -83.303127) (xy 90.964333 -83.337772) (xy 91.002607 -83.37843) (xy 91.034545 -83.424231)
			(xy 91.059468 -83.474199) (xy 91.076842 -83.527265) (xy 91.086296 -83.582297) (xy 91.087448 -83.610196)
			(xy 91.088404 -83.626613) (xy 91.097574 -83.65818) (xy 91.114503 -83.686356) (xy 91.138069 -83.709273)
			(xy 91.166708 -83.725408) (xy 91.198519 -83.733692) (xy 91.214956 -83.734148) (xy 91.242632 -83.734505)
			(xy 91.297431 -83.74228) (xy 91.350532 -83.75789) (xy 91.400821 -83.781009) (xy 91.447242 -83.81115)
			(xy 91.488822 -83.847682) (xy 91.524687 -83.889838) (xy 91.554085 -83.936734) (xy 91.5764 -83.987384)
			(xy 91.591162 -84.040727) (xy 91.598063 -84.095644) (xy 91.596957 -84.150981) (xy 91.587869 -84.205578)
			(xy 91.570987 -84.258289) (xy 91.546667 -84.308008) (xy 91.515419 -84.353691) (xy 91.477899 -84.394381)
			(xy 91.434894 -84.429223) (xy 91.387306 -84.457487) (xy 91.336134 -84.478578) (xy 91.282451 -84.492055)
			(xy 91.227385 -84.497635) (xy 91.199716 -84.49691) (xy 91.183634 -84.49669) (xy 91.152185 -84.503376)
			(xy 91.123409 -84.51772) (xy 91.099139 -84.538808) (xy 91.080919 -84.5653) (xy 91.069908 -84.595508)
			(xy 91.06789 -84.611464) (xy 91.064809 -84.638959) (xy 91.051537 -84.692673) (xy 91.030647 -84.743906)
			(xy 91.002576 -84.791586) (xy 90.967915 -84.834711) (xy 90.927388 -84.872379) (xy 90.881846 -84.903799)
			(xy 90.832243 -84.928312) (xy 90.779621 -84.945405) (xy 90.725082 -84.954718) (xy 90.669769 -84.956058)
			(xy 90.614843 -84.949395) (xy 90.561455 -84.934869) (xy 90.510724 -84.912785) (xy 90.463715 -84.883607)
			(xy 90.421413 -84.847945) (xy 90.384704 -84.806547) (xy 90.354359 -84.760282) (xy 90.331013 -84.71012)
			(xy 90.315157 -84.657112) (xy 90.307123 -84.602369) (xy 90.307078 -84.547041) (xy 85.773768 -84.547041)
			(xy 85.773768 -86.919054) (xy 85.52815 -87.164672) (xy 83.42249 -87.164672) (xy 83.123532 -86.865714)
			(xy 81.933213 -86.865714) (xy 81.939384 -86.891368) (xy 81.947512 -86.927436) (xy 83.566762 -88.546686)
			(xy 84.27085 -88.546686) (xy 84.286461 -88.546229) (xy 84.316751 -88.538652) (xy 84.344302 -88.52396)
			(xy 84.367472 -88.503031) (xy 84.376514 -88.490298) (xy 84.391757 -88.468285) (xy 84.427424 -88.428353)
			(xy 84.468324 -88.3938) (xy 84.513655 -88.365305) (xy 84.562524 -88.34343) (xy 84.613973 -88.328603)
			(xy 84.666989 -88.321116) (xy 84.720531 -88.321116) (xy 84.773547 -88.328603) (xy 84.824996 -88.34343)
			(xy 84.873865 -88.365305) (xy 84.919196 -88.3938) (xy 84.960096 -88.428353) (xy 84.995763 -88.468285)
			(xy 85.011006 -88.490298) (xy 85.020053 -88.503035) (xy 85.043193 -88.524011) (xy 85.070746 -88.538715)
			(xy 85.101053 -88.546262) (xy 85.11667 -88.546686) (xy 87.431372 -88.546686) (xy 88.43518 -87.542878)
			(xy 88.481219 -87.486595) (xy 88.580257 -87.380106) (xy 88.686741 -87.281065) (xy 88.743028 -87.23503)
			(xy 89.56294 -86.415118) (xy 91.379802 -86.415118) (xy 92.37472 -85.4202) (xy 92.37472 -84.620608)
			(xy 92.364814 -84.596986) (xy 92.353622 -84.568798) (xy 92.339303 -84.509866) (xy 92.334489 -84.449411)
			(xy 92.3393 -84.388956) (xy 92.353615 -84.330023) (xy 92.364814 -84.301838) (xy 92.37472 -84.278216)
			(xy 92.37472 -81.149952) (xy 92.374251 -81.127659) (xy 92.366463 -81.083759) (xy 92.351134 -81.041891)
			(xy 92.328734 -81.00334) (xy 92.299951 -80.969289) (xy 92.265668 -80.940784) (xy 92.226937 -80.918697)
			(xy 92.184946 -80.903708) (xy 92.140984 -80.896276) (xy 92.118688 -80.895952) (xy 92.090752 -80.895679)
			(xy 92.035414 -80.888026) (xy 92.008452 -80.880712) (xy 91.984195 -80.873158) (xy 91.937779 -80.852502)
			(xy 91.894523 -80.825856) (xy 91.874594 -80.8101) (xy 91.856799 -80.796591) (xy 91.817477 -80.77539)
			(xy 91.775052 -80.761396) (xy 91.730833 -80.755041) (xy 91.686185 -80.756521) (xy 91.642483 -80.765789)
			(xy 91.601078 -80.782561) (xy 91.563246 -80.806319) (xy 91.546426 -80.821022) (xy 91.525305 -80.839505)
			(xy 91.478657 -80.870709) (xy 91.427939 -80.894739) (xy 91.374246 -80.911078) (xy 91.31874 -80.919373)
			(xy 91.262617 -80.919443) (xy 91.207089 -80.911288) (xy 91.153356 -80.895084) (xy 91.102578 -80.871181)
			(xy 91.055851 -80.840094) (xy 91.014184 -80.802496) (xy 90.978477 -80.759197) (xy 90.9495 -80.711133)
			(xy 90.92788 -80.659341) (xy 90.914083 -80.604941) (xy 90.908407 -80.549105) (xy 90.90914 -80.521048)
			(xy 90.910918 -80.492998) (xy 90.921686 -80.437834) (xy 90.940431 -80.384848) (xy 90.966749 -80.335186)
			(xy 91.000069 -80.289924) (xy 91.039671 -80.25004) (xy 91.084696 -80.2164) (xy 91.134169 -80.18973)
			(xy 91.187021 -80.170609) (xy 91.242107 -80.15945) (xy 91.298233 -80.156495) (xy 91.354186 -80.161807)
			(xy 91.408754 -80.175273) (xy 91.460755 -80.1966) (xy 91.509063 -80.225326) (xy 91.531186 -80.242664)
			(xy 91.54898 -80.256168) (xy 91.588298 -80.277357) (xy 91.630718 -80.29134) (xy 91.67493 -80.297684)
			(xy 91.71957 -80.296194) (xy 91.763261 -80.286916) (xy 91.804654 -80.270135) (xy 91.842472 -80.24637)
			(xy 91.859354 -80.231742) (xy 91.883703 -80.210584) (xy 91.938092 -80.175914) (xy 91.997528 -80.150863)
			(xy 92.028772 -80.142842) (xy 92.05388 -80.137404) (xy 92.105023 -80.13253) (xy 92.156357 -80.134564)
			(xy 92.206954 -80.14347) (xy 92.255897 -80.159086) (xy 92.302302 -80.18113) (xy 92.345329 -80.209202)
			(xy 92.365068 -80.225646) (xy 92.383521 -80.239639) (xy 92.424405 -80.261383) (xy 92.46855 -80.275367)
			(xy 92.514496 -80.28113) (xy 92.560727 -80.278481) (xy 92.605715 -80.267509) (xy 92.647973 -80.248574)
			(xy 92.686107 -80.222304) (xy 92.702888 -80.206342) (xy 94.68104 -78.22819) (xy 94.68104 -77.66685)
			(xy 94.66707 -77.639418) (xy 94.655604 -77.616187) (xy 94.638352 -77.567338) (xy 94.627872 -77.516604)
			(xy 94.624355 -77.464918) (xy 94.627867 -77.413231) (xy 94.638343 -77.362496) (xy 94.655589 -77.313645)
			(xy 94.66707 -77.290422) (xy 94.68104 -77.26299) (xy 94.68104 -76.806806) (xy 93.94444 -76.070206)
			(xy 93.401642 -76.070206) (xy 93.288866 -76.182982) (xy 93.280992 -76.195682) (xy 93.264993 -76.220541)
			(xy 93.226553 -76.265449) (xy 93.181645 -76.30389) (xy 93.156786 -76.319888) (xy 93.144086 -76.327762)
			(xy 93.104462 -76.367386) (xy 93.092918 -76.379701) (xy 93.07619 -76.409006) (xy 93.067736 -76.441673)
			(xy 93.068148 -76.475413) (xy 93.077398 -76.507864) (xy 93.085666 -76.52258) (xy 93.115638 -76.572618)
			(xy 93.125388 -76.587663) (xy 93.151658 -76.612038) (xy 93.183672 -76.628142) (xy 93.218902 -76.634702)
			(xy 93.236796 -76.633578) (xy 93.265116 -76.631336) (xy 93.321849 -76.634255) (xy 93.377521 -76.645555)
			(xy 93.430903 -76.664984) (xy 93.480814 -76.692114) (xy 93.52615 -76.726344) (xy 93.56591 -76.766918)
			(xy 93.599214 -76.812939) (xy 93.625327 -76.86339) (xy 93.64367 -76.917154) (xy 93.653839 -76.973044)
			(xy 93.655608 -77.029824) (xy 93.648939 -77.086239) (xy 93.633978 -77.141042) (xy 93.611057 -77.19302)
			(xy 93.580682 -77.241025) (xy 93.543525 -77.283996) (xy 93.522292 -77.302868) (xy 93.501994 -77.319708)
			(xy 93.457624 -77.348221) (xy 93.409747 -77.370344) (xy 93.359276 -77.385654) (xy 93.307177 -77.39386)
			(xy 93.254444 -77.394803) (xy 93.202084 -77.388467) (xy 93.151099 -77.374972) (xy 93.102461 -77.354576)
			(xy 93.07957 -77.341476) (xy 93.053805 -77.325586) (xy 93.007206 -77.286954) (xy 92.967301 -77.241441)
			(xy 92.935094 -77.19019) (xy 92.911396 -77.134492) (xy 92.903548 -77.105256) (xy 92.897223 -77.08407)
			(xy 92.878296 -77.044116) (xy 92.852744 -77.008038) (xy 92.821337 -76.976923) (xy 92.785021 -76.95171)
			(xy 92.744892 -76.933157) (xy 92.702159 -76.921825) (xy 92.65811 -76.918055) (xy 92.614072 -76.92196)
			(xy 92.571374 -76.933423) (xy 92.531302 -76.952099) (xy 92.495064 -76.977424) (xy 92.479114 -76.992734)
			(xy 92.330524 -77.141324) (xy 88.10117 -77.141324) (xy 87.107776 -78.134718) (xy 87.107776 -78.474753)
			(xy 89.577362 -78.474753) (xy 89.580271 -78.418971) (xy 89.591286 -78.364211) (xy 89.61017 -78.311643)
			(xy 89.636519 -78.262391) (xy 89.669771 -78.21751) (xy 89.709213 -78.177959) (xy 89.754003 -78.144583)
			(xy 89.803182 -78.118098) (xy 89.855697 -78.099069) (xy 89.910427 -78.087904) (xy 89.9662 -78.084841)
			(xy 90.021824 -78.089946) (xy 90.076107 -78.10311) (xy 90.102182 -78.113128) (xy 90.122528 -78.120921)
			(xy 90.16511 -78.130127) (xy 90.208639 -78.131936) (xy 90.251839 -78.126293) (xy 90.293443 -78.113365)
			(xy 90.332233 -78.093529) (xy 90.36707 -78.067369) (xy 90.396935 -78.035649) (xy 90.420952 -77.9993)
			(xy 90.430096 -77.979524) (xy 90.441738 -77.954135) (xy 90.47135 -77.906777) (xy 90.507553 -77.864245)
			(xy 90.549573 -77.827449) (xy 90.59651 -77.797174) (xy 90.64736 -77.774069) (xy 90.701037 -77.758628)
			(xy 90.756392 -77.751181) (xy 90.812241 -77.751887) (xy 90.86739 -77.760732) (xy 90.920659 -77.777525)
			(xy 90.97091 -77.801909) (xy 91.017066 -77.833361) (xy 91.058141 -77.871209) (xy 91.093257 -77.914642)
			(xy 91.121663 -77.962734) (xy 91.14275 -78.014454) (xy 91.156068 -78.068696) (xy 91.161333 -78.124301)
			(xy 91.158431 -78.180079) (xy 91.147424 -78.234838) (xy 91.128549 -78.287405) (xy 91.102208 -78.336658)
			(xy 91.068966 -78.381542) (xy 91.029532 -78.421097) (xy 90.984751 -78.454478) (xy 90.93558 -78.48097)
			(xy 90.883071 -78.500007) (xy 90.828346 -78.511182) (xy 90.772577 -78.514256) (xy 90.716956 -78.509163)
			(xy 90.662673 -78.496012) (xy 90.636598 -78.486) (xy 90.616248 -78.478222) (xy 90.573667 -78.469022)
			(xy 90.530142 -78.467218) (xy 90.486946 -78.472862) (xy 90.445345 -78.485789) (xy 90.406558 -78.505621)
			(xy 90.37172 -78.531777) (xy 90.341853 -78.56349) (xy 90.317831 -78.599831) (xy 90.308684 -78.619604)
			(xy 90.296968 -78.644963) (xy 90.267354 -78.692323) (xy 90.231149 -78.734858) (xy 90.189127 -78.771657)
			(xy 90.142187 -78.801933) (xy 90.091332 -78.825038) (xy 90.037652 -78.840478) (xy 89.982293 -78.847924)
			(xy 89.926441 -78.847215) (xy 89.871289 -78.838367) (xy 89.818017 -78.82157) (xy 89.767766 -78.797181)
			(xy 89.721609 -78.765724) (xy 89.680534 -78.727871) (xy 89.64542 -78.684431) (xy 89.617017 -78.636334)
			(xy 89.595934 -78.584609) (xy 89.58262 -78.530362) (xy 89.577362 -78.474753) (xy 87.107776 -78.474753)
			(xy 87.107776 -79.77159) (xy 89.509275 -79.77159) (xy 89.513971 -79.715846) (xy 89.526756 -79.661385)
			(xy 89.547358 -79.609375) (xy 89.575334 -79.560932) (xy 89.610084 -79.517093) (xy 89.650864 -79.478799)
			(xy 89.696799 -79.44687) (xy 89.746904 -79.421992) (xy 89.800105 -79.404697) (xy 89.855261 -79.395357)
			(xy 89.91119 -79.394171) (xy 89.966692 -79.401166) (xy 90.020578 -79.416191) (xy 90.071692 -79.438923)
			(xy 90.095578 -79.453486) (xy 90.115125 -79.465205) (xy 90.157353 -79.482325) (xy 90.201958 -79.491643)
			(xy 90.247509 -79.492859) (xy 90.292547 -79.485935) (xy 90.335629 -79.471092) (xy 90.375375 -79.448806)
			(xy 90.393266 -79.43469) (xy 90.415129 -79.41724) (xy 90.463008 -79.388313) (xy 90.514598 -79.366688)
			(xy 90.568792 -79.352828) (xy 90.62443 -79.34703) (xy 90.680318 -79.34942) (xy 90.735258 -79.359944)
			(xy 90.788072 -79.378379) (xy 90.837628 -79.404328) (xy 90.882863 -79.437235) (xy 90.922809 -79.476395)
			(xy 90.956608 -79.520969) (xy 90.983535 -79.57) (xy 91.003015 -79.622437) (xy 91.014628 -79.677158)
			(xy 91.018126 -79.732987) (xy 91.013434 -79.788729) (xy 91.000653 -79.843188) (xy 90.980056 -79.895197)
			(xy 90.952086 -79.943641) (xy 90.917341 -79.987481) (xy 90.876567 -80.025777) (xy 90.830638 -80.057709)
			(xy 90.780538 -80.082592) (xy 90.727342 -80.099893) (xy 90.672189 -80.109239) (xy 90.616263 -80.110432)
			(xy 90.560762 -80.103446) (xy 90.506876 -80.08843) (xy 90.455761 -80.065706) (xy 90.431874 -80.051148)
			(xy 90.412355 -80.03938) (xy 90.370119 -80.022262) (xy 90.325507 -80.012949) (xy 90.27995 -80.011739)
			(xy 90.234907 -80.018672) (xy 90.191823 -80.033525) (xy 90.152077 -80.055822) (xy 90.134186 -80.069944)
			(xy 90.112285 -80.08735) (xy 90.064405 -80.11628) (xy 90.012813 -80.137908) (xy 89.958617 -80.15177)
			(xy 89.902976 -80.157568) (xy 89.847086 -80.15518) (xy 89.792144 -80.144655) (xy 89.739327 -80.12622)
			(xy 89.689769 -80.100269) (xy 89.644532 -80.06736) (xy 89.604586 -80.028197) (xy 89.570786 -79.98362)
			(xy 89.543859 -79.934586) (xy 89.524381 -79.882145) (xy 89.51277 -79.827422) (xy 89.509275 -79.77159)
			(xy 87.107776 -79.77159) (xy 87.107776 -80.780128) (xy 88.12022 -81.792572) (xy 88.12022 -82.908648)
			(xy 87.81034 -83.218528) (xy 87.724996 -83.218528) (xy 87.706962 -83.224116) (xy 87.694101 -83.227953)
			(xy 87.668052 -83.234433) (xy 87.654892 -83.23707) (xy 87.631117 -83.2413) (xy 87.583028 -83.245753)
			(xy 87.55888 -83.24596) (xy 86.84514 -83.24596) (xy 86.812246 -83.245437) (xy 86.747008 -83.236943)
			(xy 86.683411 -83.220103) (xy 86.622517 -83.195199) (xy 86.565346 -83.162649) (xy 86.512851 -83.122994)
			(xy 86.46591 -83.0769) (xy 86.425308 -83.025134) (xy 86.391724 -82.968564) (xy 86.365718 -82.908133)
			(xy 86.35619 -82.876644) (xy 86.355682 -82.875374) (xy 86.355682 -82.87512) (xy 86.349332 -82.852768)
			(xy 86.346284 -82.836004) (xy 86.34603 -82.834988) (xy 86.34046 -82.803698) (xy 86.336229 -82.740283)
			(xy 86.33994 -82.676836) (xy 86.345268 -82.645504) (xy 86.3473 -82.634074) (xy 86.3473 -81.947004)
			(xy 86.222586 -81.82229) (xy 82.173064 -81.82229) (xy 82.157685 -81.822757) (xy 82.12782 -81.830122)
			(xy 82.100584 -81.844415) (xy 82.077557 -81.864807) (xy 82.060074 -81.890115) (xy 82.054192 -81.904332)
			(xy 82.044603 -81.928495) (xy 82.019814 -81.974189) (xy 81.989051 -82.016095) (xy 81.952883 -82.053436)
			(xy 81.91198 -82.085521) (xy 81.8671 -82.111756) (xy 81.819074 -82.131654) (xy 81.768791 -82.144848)
			(xy 81.743042 -82.148426) (xy 81.730962 -82.149808) (xy 81.706686 -82.151208) (xy 81.694528 -82.15122)
			(xy 81.67751 -82.150712) (xy 81.673446 -82.150458) (xy 81.644344 -82.148077) (xy 81.587307 -82.135586)
			(xy 81.532841 -82.114548) (xy 81.482217 -82.085454) (xy 81.45907 -82.067654) (xy 81.445322 -82.057398)
			(xy 81.413797 -82.043918) (xy 81.379822 -82.039314) (xy 81.345847 -82.043918) (xy 81.314322 -82.057398)
			(xy 81.300574 -82.067654) (xy 81.277913 -82.085121) (xy 81.228393 -82.113779) (xy 81.17515 -82.134721)
			(xy 81.119376 -82.147477) (xy 81.062322 -82.151762) (xy 81.005268 -82.147477) (xy 80.949494 -82.134721)
			(xy 80.896251 -82.113779) (xy 80.846731 -82.085121) (xy 80.82407 -82.067654) (xy 80.810322 -82.057398)
			(xy 80.778797 -82.043918) (xy 80.744822 -82.039314) (xy 80.710847 -82.043918) (xy 80.679322 -82.057398)
			(xy 80.665574 -82.067654) (xy 80.642913 -82.085121) (xy 80.593393 -82.113779) (xy 80.54015 -82.134721)
			(xy 80.484376 -82.147477) (xy 80.427322 -82.151762) (xy 80.370268 -82.147477) (xy 80.314494 -82.134721)
			(xy 80.261251 -82.113779) (xy 80.211731 -82.085121) (xy 80.18907 -82.067654) (xy 80.175322 -82.057398)
			(xy 80.143797 -82.043918) (xy 80.109822 -82.039314) (xy 80.075847 -82.043918) (xy 80.044322 -82.057398)
			(xy 80.030574 -82.067654) (xy 80.007913 -82.085121) (xy 79.958393 -82.113779) (xy 79.90515 -82.134721)
			(xy 79.849376 -82.147477) (xy 79.792322 -82.151762) (xy 79.735268 -82.147477) (xy 79.679494 -82.134721)
			(xy 79.626251 -82.113779) (xy 79.576731 -82.085121) (xy 79.55407 -82.067654) (xy 79.540322 -82.057398)
			(xy 79.508797 -82.043918) (xy 79.474822 -82.039314) (xy 79.440847 -82.043918) (xy 79.409322 -82.057398)
			(xy 79.395574 -82.067654) (xy 79.373646 -82.084559) (xy 79.325859 -82.11252) (xy 79.274526 -82.133265)
			(xy 79.247746 -82.140298) (xy 79.232608 -82.144451) (xy 79.204844 -82.159078) (xy 79.181495 -82.180045)
			(xy 79.163974 -82.20608) (xy 79.153344 -82.235606) (xy 79.150249 -82.266834) (xy 79.154875 -82.297873)
			(xy 79.166944 -82.326841) (xy 79.185723 -82.351983) (xy 79.210075 -82.371776) (xy 79.238524 -82.385021)
			(xy 79.253842 -82.388456) (xy 79.281459 -82.394276) (xy 79.334714 -82.412964) (xy 79.384634 -82.439293)
			(xy 79.430133 -82.472687) (xy 79.470216 -82.512419) (xy 79.50401 -82.557621) (xy 79.530777 -82.607308)
			(xy 79.549933 -82.660396) (xy 79.561062 -82.715726) (xy 79.563919 -82.772092) (xy 79.558442 -82.828264)
			(xy 79.544752 -82.883017) (xy 79.523146 -82.935156) (xy 79.494096 -82.983543) (xy 79.458235 -83.027125)
			(xy 79.416347 -83.064948) (xy 79.369344 -83.09619) (xy 79.318252 -83.120167) (xy 79.264186 -83.136357)
			(xy 79.236316 -83.140804) (xy 79.209097 -83.144245) (xy 79.154235 -83.144212) (xy 79.099943 -83.13632)
			(xy 79.047341 -83.120732) (xy 78.997515 -83.09777) (xy 78.951491 -83.067908) (xy 78.91022 -83.031762)
			(xy 78.874552 -82.990076) (xy 78.845223 -82.943711) (xy 78.822839 -82.893623) (xy 78.807859 -82.840845)
			(xy 78.800594 -82.786465) (xy 78.801194 -82.731606) (xy 78.809646 -82.677399) (xy 78.825775 -82.624961)
			(xy 78.849249 -82.575374) (xy 78.879584 -82.529661) (xy 78.916155 -82.488765) (xy 78.93685 -82.470752)
			(xy 78.953856 -82.455829) (xy 78.982806 -82.421065) (xy 79.005145 -82.381725) (xy 79.020167 -82.339053)
			(xy 79.027397 -82.294395) (xy 79.026608 -82.249162) (xy 79.017825 -82.204783) (xy 79.001324 -82.16266)
			(xy 78.977626 -82.124124) (xy 78.947482 -82.09039) (xy 78.929992 -82.076036) (xy 78.91907 -82.067654)
			(xy 78.905322 -82.057398) (xy 78.873797 -82.043918) (xy 78.839822 -82.039314) (xy 78.805847 -82.043918)
			(xy 78.774322 -82.057398) (xy 78.760574 -82.067654) (xy 78.737427 -82.085453) (xy 78.686802 -82.114546)
			(xy 78.632336 -82.135585) (xy 78.5753 -82.148079) (xy 78.546198 -82.150458) (xy 78.542134 -82.150712)
			(xy 78.525116 -82.15122) (xy 78.498355 -82.150987) (xy 78.445306 -82.143938) (xy 78.393763 -82.129541)
			(xy 78.344739 -82.108079) (xy 78.299198 -82.079973) (xy 78.258033 -82.045777) (xy 78.222054 -82.00616)
			(xy 78.191968 -81.961903) (xy 78.168365 -81.913873) (xy 78.15961 -81.888584) (xy 78.15961 -81.88833)
			(xy 78.147672 -81.852262) (xy 78.026514 -81.755234) (xy 75.433682 -81.755234) (xy 75.366118 -81.805526)
			(xy 75.35418 -81.846166) (xy 75.344371 -81.876871) (xy 75.315918 -81.934705) (xy 75.278148 -81.986933)
			(xy 75.255628 -82.009996) (xy 75.235298 -82.029251) (xy 75.190025 -82.062202) (xy 75.140424 -82.088182)
			(xy 75.087558 -82.106635) (xy 75.032563 -82.117164) (xy 74.976619 -82.119543) (xy 74.920929 -82.11372)
			(xy 74.893678 -82.107278) (xy 74.866949 -82.099915) (xy 74.815802 -82.078522) (xy 74.768289 -82.049952)
			(xy 74.725413 -82.014806) (xy 74.688074 -81.973824) (xy 74.657061 -81.927869) (xy 74.633025 -81.877909)
			(xy 74.616474 -81.824997) (xy 74.607755 -81.770246) (xy 74.606912 -81.742534) (xy 74.604372 -81.731104)
			(xy 74.596752 -81.693766) (xy 74.500232 -81.5975) (xy 73.849738 -81.5975) (xy 73.299828 -81.047844)
			(xy 65.334388 -81.047844) (xy 64.989202 -81.392776) (xy 64.570102 -81.811876) (xy 64.072008 -81.811876)
			(xy 63.78702 -82.096864) (xy 63.78702 -82.473839) (xy 64.29427 -82.473839) (xy 64.29887 -82.418662)
			(xy 64.3114 -82.36473) (xy 64.331595 -82.313176) (xy 64.359031 -82.265084) (xy 64.393132 -82.221464)
			(xy 64.433182 -82.183232) (xy 64.478338 -82.151193) (xy 64.527652 -82.126019) (xy 64.580088 -82.108239)
			(xy 64.634543 -82.098227) (xy 64.689874 -82.096194) (xy 64.744918 -82.102181) (xy 64.798517 -82.116064)
			(xy 64.849546 -82.13755) (xy 64.896932 -82.166189) (xy 64.93968 -82.201377) (xy 64.976891 -82.242376)
			(xy 65.007784 -82.288325) (xy 65.031709 -82.338257) (xy 65.048163 -82.391124) (xy 65.056801 -82.445814)
			(xy 65.057441 -82.501178) (xy 65.05007 -82.556053) (xy 65.034842 -82.609286) (xy 65.012078 -82.659758)
			(xy 64.997584 -82.68335) (xy 64.988757 -82.698201) (xy 64.978661 -82.731227) (xy 64.977785 -82.765751)
			(xy 64.986192 -82.799248) (xy 65.003268 -82.829266) (xy 65.01511 -82.841846) (xy 65.03433 -82.861692)
			(xy 65.067459 -82.905901) (xy 65.093863 -82.954428) (xy 65.112988 -83.006257) (xy 65.124435 -83.060303)
			(xy 65.127964 -83.115436) (xy 65.123502 -83.1705) (xy 65.11114 -83.224344) (xy 65.09114 -83.275842)
			(xy 65.063917 -83.323914) (xy 65.047368 -83.346036) (xy 65.038626 -83.357928) (xy 65.026397 -83.384785)
			(xy 65.020661 -83.413732) (xy 65.021727 -83.443223) (xy 65.029536 -83.471681) (xy 65.043671 -83.497585)
			(xy 65.05321 -83.50885) (xy 65.070558 -83.528873) (xy 65.100184 -83.572793) (xy 65.123447 -83.620389)
			(xy 65.1399 -83.670747) (xy 65.149227 -83.722897) (xy 65.151248 -83.775836) (xy 65.145924 -83.828546)
			(xy 65.133357 -83.880011) (xy 65.11379 -83.929243) (xy 65.087599 -83.975293) (xy 65.055287 -84.017276)
			(xy 65.0367 -84.036154) (xy 65.025987 -84.04724) (xy 65.00985 -84.073501) (xy 65.00049 -84.102869)
			(xy 64.998455 -84.133625) (xy 65.003863 -84.16397) (xy 65.016399 -84.192129) (xy 65.025524 -84.204556)
			(xy 65.042449 -84.227269) (xy 65.070187 -84.276652) (xy 65.090314 -84.329595) (xy 65.102385 -84.384934)
			(xy 65.106136 -84.441449) (xy 65.101483 -84.497898) (xy 65.088529 -84.553037) (xy 65.067559 -84.605652)
			(xy 65.039036 -84.654585) (xy 65.021714 -84.676996) (xy 65.011835 -84.69033) (xy 64.998558 -84.720725)
			(xy 64.993559 -84.753515) (xy 64.997174 -84.786486) (xy 65.009162 -84.817413) (xy 65.028711 -84.844208)
			(xy 65.041272 -84.85505) (xy 65.062456 -84.872767) (xy 65.099979 -84.913284) (xy 65.131266 -84.958791)
			(xy 65.155662 -85.008334) (xy 65.172656 -85.060878) (xy 65.181892 -85.115324) (xy 65.183179 -85.170533)
			(xy 65.176488 -85.22535) (xy 65.16196 -85.278628) (xy 65.139899 -85.329254) (xy 65.110766 -85.376168)
			(xy 65.093342 -85.397594) (xy 65.078312 -85.416377) (xy 65.054811 -85.458341) (xy 65.039622 -85.503976)
			(xy 65.033287 -85.551654) (xy 65.036032 -85.599673) (xy 65.047758 -85.646318) (xy 65.068048 -85.689925)
			(xy 65.081658 -85.70976) (xy 65.097291 -85.732373) (xy 65.122697 -85.781121) (xy 65.140842 -85.83301)
			(xy 65.15135 -85.886968) (xy 65.154002 -85.941875) (xy 65.148744 -85.996594) (xy 65.135685 -86.049991)
			(xy 65.115095 -86.10096) (xy 65.087402 -86.148446) (xy 65.053178 -86.191463) (xy 65.013133 -86.229122)
			(xy 64.968096 -86.260641) (xy 64.919 -86.285369) (xy 64.866863 -86.302792) (xy 64.812765 -86.312549)
			(xy 64.757827 -86.314439) (xy 64.703186 -86.308423) (xy 64.649976 -86.294624) (xy 64.599297 -86.273329)
			(xy 64.552201 -86.244978) (xy 64.509662 -86.210161) (xy 64.472563 -86.169597) (xy 64.441671 -86.124127)
			(xy 64.417628 -86.074693) (xy 64.40093 -86.022319) (xy 64.391924 -85.968091) (xy 64.390797 -85.913132)
			(xy 64.397572 -85.85858) (xy 64.412108 -85.805566) (xy 64.434104 -85.755187) (xy 64.463105 -85.708489)
			(xy 64.48044 -85.687154) (xy 64.495518 -85.668408) (xy 64.519017 -85.626435) (xy 64.534201 -85.580791)
			(xy 64.54053 -85.533106) (xy 64.537777 -85.485082) (xy 64.526041 -85.438432) (xy 64.50574 -85.394823)
			(xy 64.492124 -85.374988) (xy 64.476399 -85.352347) (xy 64.450918 -85.303466) (xy 64.432743 -85.251424)
			(xy 64.422252 -85.197308) (xy 64.419664 -85.142245) (xy 64.425033 -85.087383) (xy 64.438247 -85.033867)
			(xy 64.45903 -84.982811) (xy 64.48695 -84.935281) (xy 64.503808 -84.91347) (xy 64.513738 -84.90017)
			(xy 64.527022 -84.869765) (xy 64.532019 -84.836963) (xy 64.528394 -84.803982) (xy 64.516391 -84.773049)
			(xy 64.496822 -84.746254) (xy 64.48425 -84.735416) (xy 64.463663 -84.718222) (xy 64.427089 -84.678986)
			(xy 64.396367 -84.635017) (xy 64.372102 -84.58718) (xy 64.354771 -84.536418) (xy 64.344717 -84.48373)
			(xy 64.342137 -84.430153) (xy 64.347082 -84.376743) (xy 64.359454 -84.32455) (xy 64.37901 -84.274603)
			(xy 64.405365 -84.227886) (xy 64.438 -84.185317) (xy 64.456818 -84.166202) (xy 64.467479 -84.15507)
			(xy 64.483618 -84.128821) (xy 64.492983 -84.099465) (xy 64.495027 -84.06872) (xy 64.489632 -84.038382)
			(xy 64.477111 -84.010227) (xy 64.467994 -83.9978) (xy 64.45119 -83.975405) (xy 64.423703 -83.926626)
			(xy 64.403638 -83.874355) (xy 64.391425 -83.819713) (xy 64.387328 -83.763873) (xy 64.391433 -83.708034)
			(xy 64.403653 -83.653393) (xy 64.423726 -83.601125) (xy 64.45122 -83.55235) (xy 64.467994 -83.529932)
			(xy 64.476673 -83.517996) (xy 64.488913 -83.491154) (xy 64.494661 -83.462217) (xy 64.493607 -83.432735)
			(xy 64.48581 -83.404282) (xy 64.471686 -83.378382) (xy 64.462152 -83.367118) (xy 64.444044 -83.346304)
			(xy 64.413482 -83.300371) (xy 64.389854 -83.250515) (xy 64.37365 -83.197777) (xy 64.365209 -83.143256)
			(xy 64.364706 -83.088087) (xy 64.372153 -83.033421) (xy 64.387393 -82.980396) (xy 64.41011 -82.930119)
			(xy 64.42456 -82.906616) (xy 64.433331 -82.891734) (xy 64.443443 -82.85872) (xy 64.444334 -82.824204)
			(xy 64.435939 -82.790713) (xy 64.418872 -82.760699) (xy 64.407034 -82.74812) (xy 64.387743 -82.728258)
			(xy 64.354577 -82.683923) (xy 64.32817 -82.635258) (xy 64.309076 -82.583287) (xy 64.297696 -82.529101)
			(xy 64.29427 -82.473839) (xy 63.78702 -82.473839) (xy 63.78702 -82.535268) (xy 63.428372 -82.893916)
			(xy 63.428372 -85.929216) (xy 63.446914 -85.959696) (xy 63.460185 -85.982248) (xy 63.481105 -86.030211)
			(xy 63.495274 -86.080583) (xy 63.502427 -86.132418) (xy 63.502429 -86.184745) (xy 63.495281 -86.236581)
			(xy 63.481117 -86.286954) (xy 63.460202 -86.334919) (xy 63.446914 -86.35746) (xy 63.428372 -86.38794)
			(xy 63.428372 -86.849712) (xy 63.671958 -87.093298) (xy 63.70701 -87.10168) (xy 63.732476 -87.108212)
			(xy 63.781452 -87.127327) (xy 63.82734 -87.152985) (xy 63.869271 -87.184701) (xy 63.90645 -87.221872)
			(xy 63.938174 -87.263797) (xy 63.963841 -87.30968) (xy 63.982965 -87.358652) (xy 63.989458 -87.384128)
			(xy 63.99784 -87.41918) (xy 64.000634 -87.421974) (xy 67.81749 -87.421974) (xy 67.821561 -87.366352)
			(xy 67.833687 -87.311915) (xy 67.85361 -87.259824) (xy 67.880906 -87.211189) (xy 67.914992 -87.167046)
			(xy 67.955141 -87.128337) (xy 68.000499 -87.095886) (xy 68.050099 -87.070385) (xy 68.102883 -87.052378)
			(xy 68.157726 -87.042248) (xy 68.21346 -87.040211) (xy 68.268897 -87.046311) (xy 68.322854 -87.060417)
			(xy 68.374183 -87.082229) (xy 68.421789 -87.111283) (xy 68.464657 -87.146958) (xy 68.501874 -87.188495)
			(xy 68.532647 -87.235008) (xy 68.556319 -87.285505) (xy 68.569102 -87.327994) (xy 69.62089 -87.327994)
			(xy 69.624961 -87.272372) (xy 69.637087 -87.217935) (xy 69.65701 -87.165844) (xy 69.684306 -87.117209)
			(xy 69.718392 -87.073066) (xy 69.758541 -87.034357) (xy 69.803899 -87.001906) (xy 69.853499 -86.976405)
			(xy 69.906283 -86.958398) (xy 69.961126 -86.948268) (xy 70.01686 -86.946231) (xy 70.072297 -86.952331)
			(xy 70.126254 -86.966437) (xy 70.177583 -86.988249) (xy 70.225189 -87.017303) (xy 70.268057 -87.052978)
			(xy 70.305274 -87.094515) (xy 70.336047 -87.141028) (xy 70.359719 -87.191525) (xy 70.375787 -87.244932)
			(xy 70.383907 -87.300108) (xy 70.384416 -87.327994) (xy 70.383907 -87.35588) (xy 70.375787 -87.411056)
			(xy 70.359719 -87.464463) (xy 70.336047 -87.51496) (xy 70.305274 -87.561473) (xy 70.268057 -87.60301)
			(xy 70.225189 -87.638685) (xy 70.177583 -87.667739) (xy 70.126254 -87.689551) (xy 70.072297 -87.703657)
			(xy 70.01686 -87.709757) (xy 69.961126 -87.70772) (xy 69.906283 -87.69759) (xy 69.853499 -87.679583)
			(xy 69.803899 -87.654082) (xy 69.758541 -87.621631) (xy 69.718392 -87.582922) (xy 69.684306 -87.538779)
			(xy 69.65701 -87.490144) (xy 69.637087 -87.438053) (xy 69.624961 -87.383616) (xy 69.62089 -87.327994)
			(xy 68.569102 -87.327994) (xy 68.572387 -87.338912) (xy 68.580507 -87.394088) (xy 68.581016 -87.421974)
			(xy 68.580507 -87.44986) (xy 68.572387 -87.505036) (xy 68.556319 -87.558443) (xy 68.532647 -87.60894)
			(xy 68.501874 -87.655453) (xy 68.464657 -87.69699) (xy 68.421789 -87.732665) (xy 68.374183 -87.761719)
			(xy 68.322854 -87.783531) (xy 68.268897 -87.797637) (xy 68.21346 -87.803737) (xy 68.157726 -87.8017)
			(xy 68.102883 -87.79157) (xy 68.050099 -87.773563) (xy 68.000499 -87.748062) (xy 67.955141 -87.715611)
			(xy 67.914992 -87.676902) (xy 67.880906 -87.632759) (xy 67.85361 -87.584124) (xy 67.833687 -87.532033)
			(xy 67.821561 -87.477596) (xy 67.81749 -87.421974) (xy 64.000634 -87.421974) (xy 64.694816 -88.116156)
			(xy 70.469504 -88.116156) (xy 70.473575 -88.060534) (xy 70.485701 -88.006097) (xy 70.505624 -87.954006)
			(xy 70.53292 -87.905371) (xy 70.567006 -87.861228) (xy 70.607155 -87.822519) (xy 70.652513 -87.790068)
			(xy 70.702113 -87.764567) (xy 70.754897 -87.74656) (xy 70.80974 -87.73643) (xy 70.865474 -87.734393)
			(xy 70.920911 -87.740493) (xy 70.974868 -87.754599) (xy 71.026197 -87.776411) (xy 71.073803 -87.805465)
			(xy 71.116671 -87.84114) (xy 71.153888 -87.882677) (xy 71.168543 -87.904828) (xy 71.535542 -87.904828)
			(xy 71.539613 -87.849206) (xy 71.551739 -87.794769) (xy 71.571662 -87.742678) (xy 71.598958 -87.694043)
			(xy 71.633044 -87.6499) (xy 71.673193 -87.611191) (xy 71.718551 -87.57874) (xy 71.768151 -87.553239)
			(xy 71.820935 -87.535232) (xy 71.875778 -87.525102) (xy 71.931512 -87.523065) (xy 71.986949 -87.529165)
			(xy 72.040906 -87.543271) (xy 72.092235 -87.565083) (xy 72.139841 -87.594137) (xy 72.182709 -87.629812)
			(xy 72.219926 -87.671349) (xy 72.250699 -87.717862) (xy 72.274371 -87.768359) (xy 72.290439 -87.821766)
			(xy 72.298559 -87.876942) (xy 72.299068 -87.904828) (xy 72.298559 -87.932714) (xy 72.290439 -87.98789)
			(xy 72.274371 -88.041297) (xy 72.250699 -88.091794) (xy 72.219926 -88.138307) (xy 72.182709 -88.179844)
			(xy 72.139841 -88.215519) (xy 72.092235 -88.244573) (xy 72.040906 -88.266385) (xy 71.986949 -88.280491)
			(xy 71.931512 -88.286591) (xy 71.875778 -88.284554) (xy 71.820935 -88.274424) (xy 71.768151 -88.256417)
			(xy 71.718551 -88.230916) (xy 71.673193 -88.198465) (xy 71.633044 -88.159756) (xy 71.598958 -88.115613)
			(xy 71.571662 -88.066978) (xy 71.551739 -88.014887) (xy 71.539613 -87.96045) (xy 71.535542 -87.904828)
			(xy 71.168543 -87.904828) (xy 71.184661 -87.92919) (xy 71.208333 -87.979687) (xy 71.224401 -88.033094)
			(xy 71.232521 -88.08827) (xy 71.23303 -88.116156) (xy 71.232521 -88.144042) (xy 71.224401 -88.199218)
			(xy 71.208333 -88.252625) (xy 71.184661 -88.303122) (xy 71.153888 -88.349635) (xy 71.116671 -88.391172)
			(xy 71.073803 -88.426847) (xy 71.026197 -88.455901) (xy 70.974868 -88.477713) (xy 70.920911 -88.491819)
			(xy 70.865474 -88.497919) (xy 70.80974 -88.495882) (xy 70.754897 -88.485752) (xy 70.702113 -88.467745)
			(xy 70.652513 -88.442244) (xy 70.607155 -88.409793) (xy 70.567006 -88.371084) (xy 70.53292 -88.326941)
			(xy 70.505624 -88.278306) (xy 70.485701 -88.226215) (xy 70.473575 -88.171778) (xy 70.469504 -88.116156)
			(xy 64.694816 -88.116156) (xy 67.749674 -91.171014) (xy 67.765879 -91.186577) (xy 67.802707 -91.212306)
			(xy 67.843484 -91.23116) (xy 67.886941 -91.242552) (xy 67.931724 -91.246125) (xy 67.976438 -91.241769)
			(xy 68.019689 -91.229621) (xy 68.060131 -91.210057) (xy 68.096504 -91.183688) (xy 68.127674 -91.151334)
			(xy 68.15267 -91.114005) (xy 68.170714 -91.072863) (xy 68.176394 -91.051126) (xy 68.182429 -91.022623)
			(xy 68.201983 -90.967743) (xy 68.229645 -90.916468) (xy 68.246752 -90.892884) (xy 68.259593 -90.873182)
			(xy 68.278523 -90.830138) (xy 68.289215 -90.784347) (xy 68.291304 -90.73737) (xy 68.284717 -90.690811)
			(xy 68.26968 -90.646257) (xy 68.246706 -90.605228) (xy 68.216578 -90.569124) (xy 68.198746 -90.553794)
			(xy 68.17818 -90.536183) (xy 68.141739 -90.496136) (xy 68.111323 -90.451342) (xy 68.087543 -90.402699)
			(xy 68.070876 -90.351183) (xy 68.061657 -90.297829) (xy 68.06007 -90.243708) (xy 68.066149 -90.189905)
			(xy 68.07977 -90.137502) (xy 68.10066 -90.08755) (xy 68.114164 -90.064082) (xy 68.122504 -90.049067)
			(xy 68.131659 -90.015978) (xy 68.131662 -89.981645) (xy 68.122513 -89.948554) (xy 68.104873 -89.919099)
			(xy 68.092828 -89.906856) (xy 68.072192 -89.886466) (xy 68.03671 -89.840574) (xy 68.008578 -89.789842)
			(xy 67.988444 -89.735438) (xy 67.976771 -89.678615) (xy 67.973827 -89.62068) (xy 67.979681 -89.562967)
			(xy 67.986402 -89.534746) (xy 67.987418 -89.530936) (xy 67.995201 -89.504044) (xy 68.017554 -89.452716)
			(xy 68.047164 -89.405205) (xy 68.083397 -89.362528) (xy 68.125474 -89.325601) (xy 68.172494 -89.295215)
			(xy 68.223448 -89.272024) (xy 68.277243 -89.256523) (xy 68.304918 -89.252298) (xy 68.333271 -89.249028)
			(xy 68.390337 -89.249942) (xy 68.446629 -89.259345) (xy 68.500894 -89.277027) (xy 68.551919 -89.302594)
			(xy 68.598568 -89.335476) (xy 68.639799 -89.374938) (xy 68.674693 -89.420101) (xy 68.702471 -89.469958)
			(xy 68.722514 -89.523395) (xy 68.734375 -89.579222) (xy 68.734571 -89.582498) (xy 70.158354 -89.582498)
			(xy 70.162425 -89.526876) (xy 70.174551 -89.472439) (xy 70.194474 -89.420348) (xy 70.22177 -89.371713)
			(xy 70.255856 -89.32757) (xy 70.296005 -89.288861) (xy 70.341363 -89.25641) (xy 70.390963 -89.230909)
			(xy 70.443747 -89.212902) (xy 70.49859 -89.202772) (xy 70.554324 -89.200735) (xy 70.609761 -89.206835)
			(xy 70.663718 -89.220941) (xy 70.715047 -89.242753) (xy 70.762653 -89.271807) (xy 70.805521 -89.307482)
			(xy 70.842738 -89.349019) (xy 70.873511 -89.395532) (xy 70.897183 -89.446029) (xy 70.913251 -89.499436)
			(xy 70.921371 -89.554612) (xy 70.921409 -89.556667) (xy 71.45472 -89.556667) (xy 71.462439 -89.501935)
			(xy 71.477976 -89.44889) (xy 71.501008 -89.398643) (xy 71.53105 -89.352246) (xy 71.567475 -89.310671)
			(xy 71.609519 -89.274789) (xy 71.656301 -89.245351) (xy 71.706843 -89.222973) (xy 71.760085 -89.208125)
			(xy 71.814913 -89.201117) (xy 71.870179 -89.202096) (xy 71.924724 -89.211041) (xy 71.977407 -89.227765)
			(xy 72.027125 -89.251918) (xy 72.072836 -89.282995) (xy 72.113583 -89.320343) (xy 72.131428 -89.341452)
			(xy 72.14612 -89.358709) (xy 72.180552 -89.388176) (xy 72.219663 -89.41107) (xy 72.262214 -89.426667)
			(xy 72.306856 -89.434471) (xy 72.352175 -89.434236) (xy 72.396734 -89.425969) (xy 72.439121 -89.409932)
			(xy 72.477992 -89.386633) (xy 72.512116 -89.35681) (xy 72.526652 -89.33942) (xy 72.544503 -89.317877)
			(xy 72.585453 -89.279755) (xy 72.631532 -89.248023) (xy 72.68175 -89.223361) (xy 72.735032 -89.206297)
			(xy 72.790235 -89.197199) (xy 72.846175 -89.19626) (xy 72.901652 -89.203501) (xy 72.955477 -89.218766)
			(xy 73.006495 -89.241729) (xy 73.053613 -89.271897) (xy 73.075038 -89.28989) (xy 73.091759 -89.303821)
			(xy 73.128964 -89.326393) (xy 73.16947 -89.342298) (xy 73.212093 -89.35107) (xy 73.255588 -89.352453)
			(xy 73.298683 -89.346406) (xy 73.340117 -89.333107) (xy 73.378681 -89.312944) (xy 73.413246 -89.286506)
			(xy 73.428352 -89.27084) (xy 73.446643 -89.251697) (xy 73.487645 -89.218199) (xy 73.532885 -89.190693)
			(xy 73.581495 -89.169708) (xy 73.63254 -89.155647) (xy 73.685039 -89.148781) (xy 73.737983 -89.149241)
			(xy 73.790354 -89.157019) (xy 73.841147 -89.171964) (xy 73.889385 -89.193791) (xy 73.934141 -89.222079)
			(xy 73.95464 -89.238836) (xy 73.972325 -89.253056) (xy 74.011633 -89.27572) (xy 74.054338 -89.291049)
			(xy 74.099085 -89.298559) (xy 74.144455 -89.298009) (xy 74.189008 -89.289419) (xy 74.231329 -89.273061)
			(xy 74.270077 -89.249453) (xy 74.28738 -89.234772) (xy 74.308081 -89.217033) (xy 74.353583 -89.187011)
			(xy 74.402895 -89.16377) (xy 74.455012 -89.147785) (xy 74.508875 -89.139379) (xy 74.563385 -89.138726)
			(xy 74.617433 -89.145837) (xy 74.669919 -89.160568) (xy 74.719774 -89.182619) (xy 74.765983 -89.211541)
			(xy 74.807606 -89.246746) (xy 74.843794 -89.287516) (xy 74.873811 -89.333022) (xy 74.897046 -89.382337)
			(xy 74.913025 -89.434456) (xy 74.921424 -89.488319) (xy 74.922072 -89.54283) (xy 74.914954 -89.596877)
			(xy 74.900217 -89.649361) (xy 74.87816 -89.699214) (xy 74.849232 -89.74542) (xy 74.814023 -89.787038)
			(xy 74.773248 -89.823221) (xy 74.727739 -89.853233) (xy 74.678422 -89.876462) (xy 74.6263 -89.892435)
			(xy 74.572436 -89.900828) (xy 74.517926 -89.901469) (xy 74.463879 -89.894345) (xy 74.411396 -89.879602)
			(xy 74.361546 -89.857539) (xy 74.315344 -89.828606) (xy 74.294238 -89.811352) (xy 74.276569 -89.79711)
			(xy 74.237258 -89.774449) (xy 74.194549 -89.759123) (xy 74.149799 -89.751616) (xy 74.104427 -89.752168)
			(xy 74.059873 -89.760761) (xy 74.01755 -89.777123) (xy 73.978801 -89.800733) (xy 73.961498 -89.815416)
			(xy 73.94062 -89.833347) (xy 73.89461 -89.863546) (xy 73.84474 -89.886826) (xy 73.792044 -89.902703)
			(xy 73.737614 -89.910848) (xy 73.682579 -89.911093) (xy 73.628079 -89.903433) (xy 73.575244 -89.888025)
			(xy 73.525169 -89.86519) (xy 73.478892 -89.835402) (xy 73.457816 -89.817702) (xy 73.441133 -89.803724)
			(xy 73.40392 -89.781155) (xy 73.363407 -89.765254) (xy 73.320777 -89.756487) (xy 73.277277 -89.755109)
			(xy 73.234178 -89.761162) (xy 73.19274 -89.774468) (xy 73.154174 -89.794637) (xy 73.119608 -89.821082)
			(xy 73.104502 -89.836752) (xy 73.083932 -89.858181) (xy 73.037369 -89.895054) (xy 73.011792 -89.910158)
			(xy 72.992563 -89.921464) (xy 72.958117 -89.949803) (xy 72.929148 -89.983721) (xy 72.906547 -90.022176)
			(xy 72.891007 -90.063987) (xy 72.883006 -90.107868) (xy 72.882789 -90.152473) (xy 72.890364 -90.19643)
			(xy 72.905498 -90.23839) (xy 72.927726 -90.277062) (xy 72.941688 -90.29446) (xy 72.958993 -90.31582)
			(xy 72.987857 -90.362607) (xy 73.009708 -90.413052) (xy 73.024093 -90.46611) (xy 73.030715 -90.520684)
			(xy 73.029437 -90.575643) (xy 73.020284 -90.62985) (xy 73.003446 -90.682182) (xy 72.979273 -90.731556)
			(xy 72.948264 -90.77695) (xy 72.911062 -90.817423) (xy 72.868436 -90.852139) (xy 72.821269 -90.880378)
			(xy 72.770538 -90.901556) (xy 72.717293 -90.915234) (xy 72.662636 -90.921129) (xy 72.607699 -90.919119)
			(xy 72.553619 -90.909246) (xy 72.501515 -90.891714) (xy 72.452467 -90.866886) (xy 72.40749 -90.835275)
			(xy 72.367515 -90.797538) (xy 72.33337 -90.754454) (xy 72.305761 -90.706916) (xy 72.28526 -90.655907)
			(xy 72.272292 -90.602485) (xy 72.267125 -90.547754) (xy 72.269865 -90.492848) (xy 72.280457 -90.438904)
			(xy 72.298681 -90.387039) (xy 72.32416 -90.338326) (xy 72.356366 -90.293773) (xy 72.394632 -90.254304)
			(xy 72.438167 -90.220735) (xy 72.461882 -90.20683) (xy 72.481118 -90.195534) (xy 72.515567 -90.167195)
			(xy 72.544538 -90.133277) (xy 72.567141 -90.09482) (xy 72.582682 -90.053008) (xy 72.590682 -90.009124)
			(xy 72.590897 -89.964517) (xy 72.583319 -89.920558) (xy 72.568182 -89.878598) (xy 72.54595 -89.839925)
			(xy 72.531986 -89.822528) (xy 72.528938 -89.818718) (xy 72.514171 -89.801529) (xy 72.47975 -89.772066)
			(xy 72.44065 -89.749172) (xy 72.398111 -89.733574) (xy 72.35348 -89.725765) (xy 72.308172 -89.725992)
			(xy 72.263622 -89.73425) (xy 72.221242 -89.750275) (xy 72.182374 -89.77356) (xy 72.148251 -89.803368)
			(xy 72.133714 -89.82075) (xy 72.116053 -89.842014) (xy 72.075662 -89.879747) (xy 72.030247 -89.911255)
			(xy 71.980761 -89.935878) (xy 71.928238 -89.9531) (xy 71.87378 -89.962562) (xy 71.818527 -89.964064)
			(xy 71.763635 -89.957575) (xy 71.710254 -89.943232) (xy 71.659503 -89.921334) (xy 71.612443 -89.892341)
			(xy 71.570062 -89.856858) (xy 71.533245 -89.81563) (xy 71.502764 -89.76952) (xy 71.479258 -89.719493)
			(xy 71.463219 -89.666598) (xy 71.454982 -89.611941) (xy 71.45472 -89.556667) (xy 70.921409 -89.556667)
			(xy 70.92188 -89.582498) (xy 70.921371 -89.610384) (xy 70.913251 -89.66556) (xy 70.897183 -89.718967)
			(xy 70.873511 -89.769464) (xy 70.842738 -89.815977) (xy 70.805521 -89.857514) (xy 70.762653 -89.893189)
			(xy 70.715047 -89.922243) (xy 70.663718 -89.944055) (xy 70.609761 -89.958161) (xy 70.554324 -89.964261)
			(xy 70.49859 -89.962224) (xy 70.443747 -89.952094) (xy 70.390963 -89.934087) (xy 70.341363 -89.908586)
			(xy 70.296005 -89.876135) (xy 70.255856 -89.837426) (xy 70.22177 -89.793283) (xy 70.194474 -89.744648)
			(xy 70.174551 -89.692557) (xy 70.162425 -89.63812) (xy 70.158354 -89.582498) (xy 68.734571 -89.582498)
			(xy 68.737789 -89.636192) (xy 68.732679 -89.693036) (xy 68.719161 -89.748484) (xy 68.697535 -89.801301)
			(xy 68.683378 -89.826084) (xy 68.675031 -89.841099) (xy 68.665864 -89.874192) (xy 68.665853 -89.908531)
			(xy 68.675 -89.941629) (xy 68.692642 -89.97109) (xy 68.704714 -89.98331) (xy 68.722408 -90.000694)
			(xy 68.753615 -90.039251) (xy 68.779572 -90.081522) (xy 68.799842 -90.126794) (xy 68.80733 -90.150442)
			(xy 68.815344 -90.179208) (xy 68.823358 -90.238378) (xy 68.822052 -90.298075) (xy 68.811459 -90.356838)
			(xy 68.791837 -90.413233) (xy 68.763666 -90.465881) (xy 68.746116 -90.49004) (xy 68.733279 -90.509742)
			(xy 68.714355 -90.552785) (xy 68.703668 -90.598575) (xy 68.701584 -90.645548) (xy 68.708173 -90.692104)
			(xy 68.72321 -90.736654) (xy 68.746183 -90.777679) (xy 68.776308 -90.813781) (xy 68.794122 -90.82913)
			(xy 68.81378 -90.845936) (xy 68.848831 -90.883964) (xy 68.878428 -90.926377) (xy 68.902027 -90.972396)
			(xy 68.919198 -91.021181) (xy 68.929626 -91.071836) (xy 68.93179 -91.097608) (xy 68.933162 -91.125151)
			(xy 68.928915 -91.180132) (xy 68.916795 -91.233929) (xy 68.897055 -91.28542) (xy 68.870106 -91.333531)
			(xy 68.83651 -91.377261) (xy 68.821092 -91.392248) (xy 74.68184 -91.392248) (xy 74.685911 -91.336626)
			(xy 74.698037 -91.282189) (xy 74.71796 -91.230098) (xy 74.745256 -91.181463) (xy 74.779342 -91.13732)
			(xy 74.819491 -91.098611) (xy 74.864849 -91.06616) (xy 74.914449 -91.040659) (xy 74.967233 -91.022652)
			(xy 75.022076 -91.012522) (xy 75.07781 -91.010485) (xy 75.133247 -91.016585) (xy 75.187204 -91.030691)
			(xy 75.238533 -91.052503) (xy 75.286139 -91.081557) (xy 75.329007 -91.117232) (xy 75.366224 -91.158769)
			(xy 75.396997 -91.205282) (xy 75.420669 -91.255779) (xy 75.436737 -91.309186) (xy 75.444857 -91.364362)
			(xy 75.445366 -91.392248) (xy 75.444857 -91.420134) (xy 75.436737 -91.47531) (xy 75.420669 -91.528717)
			(xy 75.396997 -91.579214) (xy 75.366224 -91.625727) (xy 75.329007 -91.667264) (xy 75.286139 -91.702939)
			(xy 75.238533 -91.731993) (xy 75.187204 -91.753805) (xy 75.133247 -91.767911) (xy 75.07781 -91.774011)
			(xy 75.022076 -91.771974) (xy 74.967233 -91.761844) (xy 74.914449 -91.743837) (xy 74.864849 -91.718336)
			(xy 74.819491 -91.685885) (xy 74.779342 -91.647176) (xy 74.745256 -91.603033) (xy 74.71796 -91.554398)
			(xy 74.698037 -91.502307) (xy 74.685911 -91.44787) (xy 74.68184 -91.392248) (xy 68.821092 -91.392248)
			(xy 68.796968 -91.415698) (xy 68.752303 -91.44804) (xy 68.703446 -91.473613) (xy 68.651416 -91.491885)
			(xy 68.62445 -91.497658) (xy 68.602661 -91.503312) (xy 68.561368 -91.521229) (xy 68.523875 -91.546136)
			(xy 68.491353 -91.577254) (xy 68.464815 -91.613611) (xy 68.445093 -91.654072) (xy 68.432802 -91.697373)
			(xy 68.428325 -91.742162) (xy 68.431803 -91.787039) (xy 68.443126 -91.830604) (xy 68.461942 -91.871494)
			(xy 68.487662 -91.908434) (xy 68.503292 -91.924632) (xy 68.6435 -92.06484) (xy 68.68922 -92.068904)
			(xy 68.715563 -92.071774) (xy 68.767154 -92.083863) (xy 68.816577 -92.102975) (xy 68.86288 -92.128742)
			(xy 68.905172 -92.160666) (xy 68.942641 -92.198136) (xy 68.974564 -92.240429) (xy 69.000329 -92.286733)
			(xy 69.01944 -92.336156) (xy 69.031528 -92.387748) (xy 69.034406 -92.41409) (xy 69.03847 -92.45981)
			(xy 69.926962 -93.348302) (xy 70.703184 -93.348302) (xy 70.707255 -93.29268) (xy 70.719381 -93.238243)
			(xy 70.739304 -93.186152) (xy 70.7666 -93.137517) (xy 70.800686 -93.093374) (xy 70.840835 -93.054665)
			(xy 70.886193 -93.022214) (xy 70.935793 -92.996713) (xy 70.988577 -92.978706) (xy 71.04342 -92.968576)
			(xy 71.099154 -92.966539) (xy 71.154591 -92.972639) (xy 71.208548 -92.986745) (xy 71.259877 -93.008557)
			(xy 71.307483 -93.037611) (xy 71.350351 -93.073286) (xy 71.387568 -93.114823) (xy 71.418341 -93.161336)
			(xy 71.442013 -93.211833) (xy 71.458081 -93.26524) (xy 71.466201 -93.320416) (xy 71.46671 -93.348302)
			(xy 71.466201 -93.376188) (xy 71.458081 -93.431364) (xy 71.442013 -93.484771) (xy 71.418341 -93.535268)
			(xy 71.387568 -93.581781) (xy 71.350351 -93.623318) (xy 71.307483 -93.658993) (xy 71.259877 -93.688047)
			(xy 71.208548 -93.709859) (xy 71.154591 -93.723965) (xy 71.099154 -93.730065) (xy 71.04342 -93.728028)
			(xy 70.988577 -93.717898) (xy 70.935793 -93.699891) (xy 70.886193 -93.67439) (xy 70.840835 -93.641939)
			(xy 70.800686 -93.60323) (xy 70.7666 -93.559087) (xy 70.739304 -93.510452) (xy 70.719381 -93.458361)
			(xy 70.707255 -93.403924) (xy 70.703184 -93.348302) (xy 69.926962 -93.348302) (xy 70.960742 -94.382082)
			(xy 71.021448 -94.40037) (xy 71.05269 -94.394274) (xy 71.079271 -94.389449) (xy 71.133212 -94.386453)
			(xy 71.187036 -94.391087) (xy 71.239671 -94.403257) (xy 71.265034 -94.412562) (xy 71.275194 -94.416626)
			(xy 71.323454 -94.426278) (xy 71.36384 -94.41942) (xy 71.37273 -94.41688) (xy 71.399079 -94.409008)
			(xy 71.453334 -94.400045) (xy 71.508315 -94.398966) (xy 71.56288 -94.405793) (xy 71.6159 -94.420385)
			(xy 71.666275 -94.442439) (xy 71.71296 -94.471498) (xy 71.754989 -94.50696) (xy 71.771821 -94.525926)
			(xy 80.736111 -94.525926) (xy 80.74014 -94.470371) (xy 80.752204 -94.415993) (xy 80.772049 -94.363947)
			(xy 80.799252 -94.315341) (xy 80.833234 -94.271207) (xy 80.873273 -94.232485) (xy 80.918518 -94.199997)
			(xy 80.968006 -94.174435) (xy 81.020686 -94.156341) (xy 81.075438 -94.146101) (xy 81.131096 -94.143932)
			(xy 81.186478 -94.149881) (xy 81.240406 -94.163821) (xy 81.291734 -94.185455) (xy 81.315814 -94.199456)
			(xy 81.335273 -94.210661) (xy 81.377153 -94.226843) (xy 81.421227 -94.235407) (xy 81.466119 -94.236086)
			(xy 81.510431 -94.228858) (xy 81.552781 -94.213948) (xy 81.591848 -94.191823) (xy 81.609438 -94.177866)
			(xy 81.631192 -94.160473) (xy 81.678791 -94.131554) (xy 81.73009 -94.109864) (xy 81.783998 -94.095865)
			(xy 81.839369 -94.089854) (xy 81.895025 -94.091959) (xy 81.949783 -94.102135) (xy 82.00248 -94.120165)
			(xy 82.051994 -94.145667) (xy 82.097274 -94.178099) (xy 82.137356 -94.21677) (xy 82.171388 -94.260859)
			(xy 82.198648 -94.309428) (xy 82.218554 -94.361445) (xy 82.230685 -94.415804) (xy 82.234782 -94.471348)
			(xy 82.230758 -94.526899) (xy 82.218699 -94.581274) (xy 82.199285 -94.632205) (xy 84.661303 -94.632205)
			(xy 84.666853 -94.57706) (xy 84.680322 -94.523298) (xy 84.701425 -94.47205) (xy 84.72972 -94.424393)
			(xy 84.764611 -94.381331) (xy 84.805364 -94.343768) (xy 84.851121 -94.312495) (xy 84.900921 -94.28817)
			(xy 84.953716 -94.271305) (xy 85.008396 -94.262253) (xy 85.063809 -94.261207) (xy 85.118792 -94.268187)
			(xy 85.172186 -94.283047) (xy 85.222869 -94.305474) (xy 85.269775 -94.334996) (xy 85.291168 -94.352618)
			(xy 85.304689 -94.363348) (xy 85.335982 -94.377876) (xy 85.370025 -94.383477) (xy 85.404323 -94.379741)
			(xy 85.436361 -94.36694) (xy 85.450426 -94.356936) (xy 85.472762 -94.340529) (xy 85.521231 -94.313655)
			(xy 85.573078 -94.294076) (xy 85.627212 -94.282201) (xy 85.682493 -94.278283) (xy 85.737761 -94.282402)
			(xy 85.791851 -94.294472) (xy 85.843626 -94.31424) (xy 85.891997 -94.34129) (xy 85.935946 -94.375052)
			(xy 85.97455 -94.414816) (xy 86.006996 -94.459746) (xy 86.032601 -94.508897) (xy 86.050826 -94.561235)
			(xy 86.06129 -94.615659) (xy 86.06377 -94.671024) (xy 86.058216 -94.726165) (xy 86.044744 -94.779924)
			(xy 86.023637 -94.831168) (xy 85.99534 -94.878819) (xy 85.960447 -94.921877) (xy 85.919693 -94.959434)
			(xy 85.873934 -94.990701) (xy 85.824135 -95.015019) (xy 85.771341 -95.031879) (xy 85.716663 -95.040924)
			(xy 85.661253 -95.041965) (xy 85.606274 -95.03498) (xy 85.552884 -95.020115) (xy 85.502206 -94.997683)
			(xy 85.455306 -94.968157) (xy 85.433916 -94.950534) (xy 85.420406 -94.939787) (xy 85.389111 -94.925255)
			(xy 85.355063 -94.919654) (xy 85.320761 -94.923396) (xy 85.288722 -94.936206) (xy 85.274658 -94.946216)
			(xy 85.252366 -94.962684) (xy 85.203896 -94.989561) (xy 85.152047 -95.009144) (xy 85.097911 -95.021022)
			(xy 85.042627 -95.024943) (xy 84.987357 -95.020827) (xy 84.933263 -95.008759) (xy 84.881484 -94.988993)
			(xy 84.833109 -94.961945) (xy 84.789155 -94.928184) (xy 84.750546 -94.88842) (xy 84.718096 -94.84349)
			(xy 84.692486 -94.794338) (xy 84.674256 -94.741999) (xy 84.663788 -94.687573) (xy 84.661303 -94.632205)
			(xy 82.199285 -94.632205) (xy 82.198861 -94.633317) (xy 82.171666 -94.681922) (xy 82.137691 -94.726055)
			(xy 82.09766 -94.764779) (xy 82.052423 -94.79727) (xy 82.002942 -94.822837) (xy 81.95027 -94.840937)
			(xy 81.895525 -94.851185) (xy 81.839871 -94.853363) (xy 81.784493 -94.847425) (xy 81.730567 -94.833497)
			(xy 81.679239 -94.811875) (xy 81.655158 -94.79788) (xy 81.63571 -94.786656) (xy 81.593826 -94.770481)
			(xy 81.549751 -94.761923) (xy 81.504857 -94.761249) (xy 81.460544 -94.768479) (xy 81.418194 -94.783389)
			(xy 81.379125 -94.805514) (xy 81.361534 -94.81947) (xy 81.339737 -94.836815) (xy 81.292136 -94.86574)
			(xy 81.240834 -94.887434) (xy 81.186922 -94.901438) (xy 81.131547 -94.907452) (xy 81.075886 -94.905349)
			(xy 81.021123 -94.895174) (xy 80.968422 -94.877142) (xy 80.918903 -94.851638) (xy 80.87362 -94.819204)
			(xy 80.833535 -94.780529) (xy 80.7995 -94.736436) (xy 80.77224 -94.687862) (xy 80.752334 -94.63584)
			(xy 80.740205 -94.581476) (xy 80.736111 -94.525926) (xy 71.771821 -94.525926) (xy 71.791491 -94.54809)
			(xy 71.821708 -94.594035) (xy 71.845014 -94.643843) (xy 71.860926 -94.696481) (xy 71.869115 -94.750859)
			(xy 71.86941 -94.805849) (xy 71.861806 -94.860312) (xy 71.84646 -94.913118) (xy 71.82369 -94.963173)
			(xy 71.793968 -95.00944) (xy 71.776336 -95.030544) (xy 71.743316 -95.06839) (xy 71.744375 -95.098108)
			(xy 72.401682 -95.098108) (xy 72.405753 -95.042486) (xy 72.417879 -94.988049) (xy 72.437802 -94.935958)
			(xy 72.465098 -94.887323) (xy 72.499184 -94.84318) (xy 72.539333 -94.804471) (xy 72.584691 -94.77202)
			(xy 72.634291 -94.746519) (xy 72.687075 -94.728512) (xy 72.741918 -94.718382) (xy 72.797652 -94.716345)
			(xy 72.853089 -94.722445) (xy 72.907046 -94.736551) (xy 72.958375 -94.758363) (xy 73.005981 -94.787417)
			(xy 73.048849 -94.823092) (xy 73.086066 -94.864629) (xy 73.116839 -94.911142) (xy 73.140511 -94.961639)
			(xy 73.156579 -95.015046) (xy 73.164699 -95.070222) (xy 73.165208 -95.098108) (xy 73.164699 -95.125994)
			(xy 73.156579 -95.18117) (xy 73.140511 -95.234577) (xy 73.116839 -95.285074) (xy 73.104975 -95.303006)
			(xy 73.706422 -95.303006) (xy 73.709329 -95.247293) (xy 73.720321 -95.192598) (xy 73.739163 -95.140087)
			(xy 73.765453 -95.090881) (xy 73.798631 -95.046029) (xy 73.837988 -95.006489) (xy 73.882685 -94.973104)
			(xy 73.931768 -94.946586) (xy 73.984191 -94.9275) (xy 74.038835 -94.916255) (xy 74.094534 -94.913089)
			(xy 74.1501 -94.918071) (xy 74.204348 -94.931094) (xy 74.25612 -94.95188) (xy 74.304312 -94.979986)
			(xy 74.347895 -95.014813) (xy 74.385941 -95.055616) (xy 74.402188 -95.078296) (xy 74.416149 -95.097546)
			(xy 74.449948 -95.130987) (xy 74.489373 -95.157562) (xy 74.533051 -95.176347) (xy 74.57946 -95.186686)
			(xy 74.626981 -95.18822) (xy 74.67396 -95.180894) (xy 74.718758 -95.164965) (xy 74.759815 -95.140987)
			(xy 74.778108 -95.125794) (xy 74.798962 -95.108302) (xy 74.844662 -95.07874) (xy 74.894101 -95.055979)
			(xy 74.946276 -95.040481) (xy 75.000124 -95.032561) (xy 75.054551 -95.032381) (xy 75.108451 -95.039943)
			(xy 75.134724 -95.047054) (xy 75.157377 -95.053068) (xy 75.204018 -95.057619) (xy 75.250703 -95.053538)
			(xy 75.295848 -95.040964) (xy 75.33792 -95.020323) (xy 75.375493 -94.992315) (xy 75.407292 -94.957892)
			(xy 75.42022 -94.938342) (xy 75.435105 -94.915455) (xy 75.470441 -94.873834) (xy 75.511347 -94.837675)
			(xy 75.55699 -94.807715) (xy 75.606437 -94.784566) (xy 75.658679 -94.768702) (xy 75.712648 -94.760445)
			(xy 75.767243 -94.759964) (xy 75.821349 -94.76727) (xy 75.873862 -94.782213) (xy 75.923709 -94.804487)
			(xy 75.969872 -94.833639) (xy 76.011409 -94.869072) (xy 76.047472 -94.910064) (xy 76.077324 -94.955778)
			(xy 76.100355 -95.005279) (xy 76.114693 -95.052896) (xy 76.623416 -95.052896) (xy 76.627487 -94.997274)
			(xy 76.639613 -94.942837) (xy 76.659536 -94.890746) (xy 76.686832 -94.842111) (xy 76.720918 -94.797968)
			(xy 76.761067 -94.759259) (xy 76.806425 -94.726808) (xy 76.856025 -94.701307) (xy 76.908809 -94.6833)
			(xy 76.963652 -94.67317) (xy 77.019386 -94.671133) (xy 77.074823 -94.677233) (xy 77.12878 -94.691339)
			(xy 77.180109 -94.713151) (xy 77.227715 -94.742205) (xy 77.270583 -94.77788) (xy 77.3078 -94.819417)
			(xy 77.338573 -94.86593) (xy 77.362245 -94.916427) (xy 77.378313 -94.969834) (xy 77.386433 -95.02501)
			(xy 77.386942 -95.052896) (xy 77.386433 -95.080782) (xy 77.378313 -95.135958) (xy 77.376633 -95.141542)
			(xy 78.137256 -95.141542) (xy 78.141327 -95.08592) (xy 78.153453 -95.031483) (xy 78.173376 -94.979392)
			(xy 78.200672 -94.930757) (xy 78.234758 -94.886614) (xy 78.274907 -94.847905) (xy 78.320265 -94.815454)
			(xy 78.369865 -94.789953) (xy 78.422649 -94.771946) (xy 78.477492 -94.761816) (xy 78.533226 -94.759779)
			(xy 78.588663 -94.765879) (xy 78.64262 -94.779985) (xy 78.693949 -94.801797) (xy 78.741555 -94.830851)
			(xy 78.784423 -94.866526) (xy 78.82164 -94.908063) (xy 78.852413 -94.954576) (xy 78.876085 -95.005073)
			(xy 78.890855 -95.054166) (xy 79.17637 -95.054166) (xy 79.180441 -94.998544) (xy 79.192567 -94.944107)
			(xy 79.21249 -94.892016) (xy 79.239786 -94.843381) (xy 79.273872 -94.799238) (xy 79.314021 -94.760529)
			(xy 79.359379 -94.728078) (xy 79.408979 -94.702577) (xy 79.461763 -94.68457) (xy 79.516606 -94.67444)
			(xy 79.57234 -94.672403) (xy 79.627777 -94.678503) (xy 79.681734 -94.692609) (xy 79.733063 -94.714421)
			(xy 79.780669 -94.743475) (xy 79.823537 -94.77915) (xy 79.860754 -94.820687) (xy 79.891527 -94.8672)
			(xy 79.915199 -94.917697) (xy 79.931267 -94.971104) (xy 79.939387 -95.02628) (xy 79.939896 -95.054166)
			(xy 79.939387 -95.082052) (xy 79.931267 -95.137228) (xy 79.915199 -95.190635) (xy 79.891527 -95.241132)
			(xy 79.860754 -95.287645) (xy 79.823537 -95.329182) (xy 79.780669 -95.364857) (xy 79.733063 -95.393911)
			(xy 79.681734 -95.415723) (xy 79.627777 -95.429829) (xy 79.57234 -95.435929) (xy 79.516606 -95.433892)
			(xy 79.461763 -95.423762) (xy 79.408979 -95.405755) (xy 79.359379 -95.380254) (xy 79.314021 -95.347803)
			(xy 79.273872 -95.309094) (xy 79.239786 -95.264951) (xy 79.21249 -95.216316) (xy 79.192567 -95.164225)
			(xy 79.180441 -95.109788) (xy 79.17637 -95.054166) (xy 78.890855 -95.054166) (xy 78.892153 -95.05848)
			(xy 78.900273 -95.113656) (xy 78.900782 -95.141542) (xy 78.900273 -95.169428) (xy 78.892153 -95.224604)
			(xy 78.876085 -95.278011) (xy 78.852413 -95.328508) (xy 78.82164 -95.375021) (xy 78.784423 -95.416558)
			(xy 78.741555 -95.452233) (xy 78.693949 -95.481287) (xy 78.64262 -95.503099) (xy 78.588663 -95.517205)
			(xy 78.533226 -95.523305) (xy 78.477492 -95.521268) (xy 78.422649 -95.511138) (xy 78.369865 -95.493131)
			(xy 78.320265 -95.46763) (xy 78.274907 -95.435179) (xy 78.234758 -95.39647) (xy 78.200672 -95.352327)
			(xy 78.173376 -95.303692) (xy 78.153453 -95.251601) (xy 78.141327 -95.197164) (xy 78.137256 -95.141542)
			(xy 77.376633 -95.141542) (xy 77.362245 -95.189365) (xy 77.338573 -95.239862) (xy 77.3078 -95.286375)
			(xy 77.270583 -95.327912) (xy 77.227715 -95.363587) (xy 77.180109 -95.392641) (xy 77.12878 -95.414453)
			(xy 77.074823 -95.428559) (xy 77.019386 -95.434659) (xy 76.963652 -95.432622) (xy 76.908809 -95.422492)
			(xy 76.856025 -95.404485) (xy 76.806425 -95.378984) (xy 76.761067 -95.346533) (xy 76.720918 -95.307824)
			(xy 76.686832 -95.263681) (xy 76.659536 -95.215046) (xy 76.639613 -95.162955) (xy 76.627487 -95.108518)
			(xy 76.623416 -95.052896) (xy 76.114693 -95.052896) (xy 76.116097 -95.057558) (xy 76.124226 -95.111547)
			(xy 76.124578 -95.166143) (xy 76.117145 -95.220232) (xy 76.102078 -95.272709) (xy 76.079686 -95.322503)
			(xy 76.050426 -95.368597) (xy 76.014894 -95.410051) (xy 75.973817 -95.446016) (xy 75.928033 -95.47576)
			(xy 75.878478 -95.498675) (xy 75.826162 -95.514293) (xy 75.772154 -95.522296) (xy 75.717558 -95.522519)
			(xy 75.663486 -95.514958) (xy 75.637136 -95.50781) (xy 75.61449 -95.501772) (xy 75.567846 -95.497228)
			(xy 75.52116 -95.501315) (xy 75.476015 -95.513894) (xy 75.433942 -95.534538) (xy 75.396369 -95.562547)
			(xy 75.364569 -95.596972) (xy 75.35164 -95.616522) (xy 75.336904 -95.639082) (xy 75.302098 -95.680216)
			(xy 75.261851 -95.716043) (xy 75.216964 -95.745852) (xy 75.168328 -95.769048) (xy 75.116913 -95.785171)
			(xy 75.063741 -95.793899) (xy 75.00987 -95.79506) (xy 74.956372 -95.788629) (xy 74.90431 -95.774735)
			(xy 74.854721 -95.753654) (xy 74.808592 -95.725806) (xy 74.766839 -95.691744) (xy 74.730295 -95.652147)
			(xy 74.714608 -95.630238) (xy 74.700659 -95.610981) (xy 74.666854 -95.577547) (xy 74.627426 -95.550977)
			(xy 74.583747 -95.532197) (xy 74.537339 -95.521861) (xy 74.489818 -95.520327) (xy 74.44284 -95.527651)
			(xy 74.398042 -95.543577) (xy 74.356983 -95.56755) (xy 74.338688 -95.58274) (xy 74.317325 -95.600683)
			(xy 74.270353 -95.630785) (xy 74.219498 -95.653722) (xy 74.165844 -95.669008) (xy 74.110536 -95.676314)
			(xy 74.054753 -95.675486) (xy 73.999686 -95.66654) (xy 73.946509 -95.649669) (xy 73.896357 -95.625231)
			(xy 73.8503 -95.593749) (xy 73.80932 -95.555893) (xy 73.774292 -95.512471) (xy 73.745963 -95.46441)
			(xy 73.724936 -95.412735) (xy 73.711662 -95.358549) (xy 73.706422 -95.303006) (xy 73.104975 -95.303006)
			(xy 73.086066 -95.331587) (xy 73.048849 -95.373124) (xy 73.005981 -95.408799) (xy 72.958375 -95.437853)
			(xy 72.907046 -95.459665) (xy 72.853089 -95.473771) (xy 72.797652 -95.479871) (xy 72.741918 -95.477834)
			(xy 72.687075 -95.467704) (xy 72.634291 -95.449697) (xy 72.584691 -95.424196) (xy 72.539333 -95.391745)
			(xy 72.499184 -95.353036) (xy 72.465098 -95.308893) (xy 72.437802 -95.260258) (xy 72.417879 -95.208167)
			(xy 72.405753 -95.15373) (xy 72.401682 -95.098108) (xy 71.744375 -95.098108) (xy 71.746872 -95.168212)
			(xy 71.782432 -95.203772) (xy 72.744838 -96.166178) (xy 75.537568 -96.166178) (xy 75.571604 -96.140524)
			(xy 75.57262 -96.139762) (xy 75.578208 -96.135444) (xy 75.603608 -96.11868) (xy 75.626079 -96.105565)
			(xy 75.673815 -96.084873) (xy 75.723918 -96.070851) (xy 75.77546 -96.063759) (xy 75.801474 -96.063308)
			(xy 78.461616 -96.063308) (xy 78.490572 -96.092264) (xy 78.526894 -96.12884) (xy 78.53906 -96.14033)
			(xy 78.568021 -96.157072) (xy 78.600337 -96.165719) (xy 78.617064 -96.166178) (xy 79.059278 -96.166178)
			(xy 79.059278 -96.604328) (xy 85.177882 -96.604328) (xy 85.181953 -96.548706) (xy 85.194079 -96.494269)
			(xy 85.214002 -96.442178) (xy 85.241298 -96.393543) (xy 85.275384 -96.3494) (xy 85.315533 -96.310691)
			(xy 85.360891 -96.27824) (xy 85.410491 -96.252739) (xy 85.463275 -96.234732) (xy 85.518118 -96.224602)
			(xy 85.573852 -96.222565) (xy 85.629289 -96.228665) (xy 85.683246 -96.242771) (xy 85.734575 -96.264583)
			(xy 85.782181 -96.293637) (xy 85.825049 -96.329312) (xy 85.862266 -96.370849) (xy 85.893039 -96.417362)
			(xy 85.916711 -96.467859) (xy 85.932779 -96.521266) (xy 85.940899 -96.576442) (xy 85.941408 -96.604328)
			(xy 85.940899 -96.632214) (xy 85.932779 -96.68739) (xy 85.916711 -96.740797) (xy 85.893039 -96.791294)
			(xy 85.862266 -96.837807) (xy 85.825049 -96.879344) (xy 85.782181 -96.915019) (xy 85.734575 -96.944073)
			(xy 85.683246 -96.965885) (xy 85.629289 -96.979991) (xy 85.573852 -96.986091) (xy 85.518118 -96.984054)
			(xy 85.463275 -96.973924) (xy 85.410491 -96.955917) (xy 85.360891 -96.930416) (xy 85.315533 -96.897965)
			(xy 85.275384 -96.859256) (xy 85.241298 -96.815113) (xy 85.214002 -96.766478) (xy 85.194079 -96.714387)
			(xy 85.181953 -96.65995) (xy 85.177882 -96.604328) (xy 79.059278 -96.604328) (xy 79.059278 -96.968818)
			(xy 79.05965 -96.982832) (xy 79.065777 -97.010181) (xy 79.07773 -97.035532) (xy 79.094932 -97.057659)
			(xy 79.105506 -97.066862) (xy 79.126824 -97.085075) (xy 79.164404 -97.126687) (xy 79.195486 -97.173351)
			(xy 79.219403 -97.224063) (xy 79.235638 -97.27773) (xy 79.243842 -97.333196) (xy 79.243837 -97.389265)
			(xy 79.235625 -97.444729) (xy 79.219381 -97.498394) (xy 79.195456 -97.549102) (xy 79.164366 -97.595762)
			(xy 79.12678 -97.637367) (xy 79.105506 -97.655634) (xy 79.094925 -97.664832) (xy 79.077713 -97.686955)
			(xy 79.065759 -97.712308) (xy 79.059643 -97.739663) (xy 79.059278 -97.753678) (xy 79.059278 -98.490775)
			(xy 79.72628 -98.490775) (xy 79.734091 -98.436081) (xy 79.74971 -98.383085) (xy 79.772809 -98.332897)
			(xy 79.802905 -98.286564) (xy 79.82077 -98.265488) (xy 79.834472 -98.249084) (xy 79.856857 -98.21268)
			(xy 79.872842 -98.173047) (xy 79.881978 -98.1313) (xy 79.884007 -98.088612) (xy 79.878873 -98.046186)
			(xy 79.86672 -98.005215) (xy 79.847889 -97.966852) (xy 79.835756 -97.949258) (xy 79.820063 -97.926524)
			(xy 79.794571 -97.87752) (xy 79.776413 -97.825352) (xy 79.76597 -97.771111) (xy 79.763458 -97.71593)
			(xy 79.768932 -97.660964) (xy 79.782276 -97.607362) (xy 79.803212 -97.556246) (xy 79.831301 -97.508683)
			(xy 79.865957 -97.465669) (xy 79.906454 -97.428104) (xy 79.951946 -97.396772) (xy 80.001482 -97.372329)
			(xy 80.054024 -97.355286) (xy 80.108476 -97.345999) (xy 80.163697 -97.344663) (xy 80.218534 -97.351306)
			(xy 80.27184 -97.365789) (xy 80.322499 -97.387808) (xy 80.369453 -97.416904) (xy 80.411719 -97.452467)
			(xy 80.448414 -97.493755) (xy 80.47877 -97.539904) (xy 80.502153 -97.589948) (xy 80.518073 -97.642842)
			(xy 80.526199 -97.697479) (xy 80.526358 -97.752717) (xy 80.51855 -97.8074) (xy 80.502935 -97.860385)
			(xy 80.479843 -97.910563) (xy 80.449754 -97.956887) (xy 80.431894 -97.97796) (xy 80.418148 -97.994329)
			(xy 80.401942 -98.020685) (xy 86.849323 -98.020685) (xy 86.854257 -97.966366) (xy 86.866876 -97.913303)
			(xy 86.886922 -97.862578) (xy 86.913988 -97.815225) (xy 86.947521 -97.772208) (xy 86.986837 -97.734405)
			(xy 87.008716 -97.718118) (xy 87.026161 -97.705015) (xy 87.056749 -97.673911) (xy 87.081572 -97.638038)
			(xy 87.099899 -97.598449) (xy 87.11119 -97.556311) (xy 87.115113 -97.512864) (xy 87.111553 -97.469385)
			(xy 87.100615 -97.427154) (xy 87.08262 -97.387414) (xy 87.058099 -97.351334) (xy 87.04326 -97.33534)
			(xy 87.024602 -97.31545) (xy 86.992665 -97.271243) (xy 86.967347 -97.222939) (xy 86.949166 -97.171523)
			(xy 86.938491 -97.118041) (xy 86.935541 -97.063584) (xy 86.940375 -97.009262) (xy 86.952896 -96.956182)
			(xy 86.972847 -96.905426) (xy 86.999822 -96.858028) (xy 87.033271 -96.814954) (xy 87.072514 -96.777082)
			(xy 87.116749 -96.745184) (xy 87.165075 -96.71991) (xy 87.216508 -96.701775) (xy 87.27 -96.691148)
			(xy 87.324459 -96.688247) (xy 87.378776 -96.69313) (xy 87.431845 -96.705698) (xy 87.482583 -96.725695)
			(xy 87.529957 -96.752713) (xy 87.573001 -96.786201) (xy 87.610838 -96.825477) (xy 87.642696 -96.869741)
			(xy 87.667927 -96.91809) (xy 87.686016 -96.969539) (xy 87.696594 -97.02304) (xy 87.699446 -97.077502)
			(xy 87.694514 -97.131815) (xy 87.681899 -97.184873) (xy 87.661857 -97.235593) (xy 87.634796 -97.282942)
			(xy 87.601269 -97.325956) (xy 87.561959 -97.363758) (xy 87.540084 -97.380044) (xy 87.522583 -97.393076)
			(xy 87.491994 -97.42419) (xy 87.467172 -97.460074) (xy 87.448848 -97.499673) (xy 87.437561 -97.54182)
			(xy 87.433644 -97.585277) (xy 87.437211 -97.628764) (xy 87.448158 -97.671001) (xy 87.466163 -97.710745)
			(xy 87.490696 -97.746828) (xy 87.50554 -97.762822) (xy 87.524204 -97.78271) (xy 87.556149 -97.826919)
			(xy 87.581472 -97.875226) (xy 87.599659 -97.926648) (xy 87.610337 -97.980134) (xy 87.613291 -98.034597)
			(xy 87.608458 -98.088925) (xy 87.595939 -98.142011) (xy 87.575988 -98.192774) (xy 87.549012 -98.240178)
			(xy 87.51556 -98.283258) (xy 87.476315 -98.321135) (xy 87.432075 -98.353038) (xy 87.383744 -98.378316)
			(xy 87.332306 -98.396454) (xy 87.278809 -98.407082) (xy 87.224344 -98.409984) (xy 87.17002 -98.405101)
			(xy 87.116946 -98.392532) (xy 87.066202 -98.372533) (xy 87.018823 -98.345512) (xy 86.975775 -98.31202)
			(xy 86.937935 -98.272739) (xy 86.906074 -98.22847) (xy 86.880841 -98.180115) (xy 86.862752 -98.128659)
			(xy 86.852173 -98.075152) (xy 86.849323 -98.020685) (xy 80.401942 -98.020685) (xy 80.39576 -98.030739)
			(xy 80.379775 -98.070379) (xy 80.370642 -98.112133) (xy 80.368618 -98.154827) (xy 80.37376 -98.197258)
			(xy 80.385925 -98.238233) (xy 80.404768 -98.276597) (xy 80.416908 -98.29419) (xy 80.432657 -98.316891)
			(xy 80.458162 -98.365901) (xy 80.476332 -98.418077) (xy 80.486786 -98.472328) (xy 80.489305 -98.52752)
			(xy 80.483837 -98.582498) (xy 80.470497 -98.636112) (xy 80.449563 -98.687242) (xy 80.421473 -98.734818)
			(xy 80.386815 -98.777844) (xy 80.346313 -98.815422) (xy 80.300814 -98.846764) (xy 80.251271 -98.871217)
			(xy 80.198719 -98.888267) (xy 80.144256 -98.89756) (xy 80.089024 -98.898899) (xy 80.034175 -98.892259)
			(xy 79.980858 -98.877776) (xy 79.930187 -98.855754) (xy 79.883222 -98.826654) (xy 79.840946 -98.791085)
			(xy 79.804242 -98.749789) (xy 79.773879 -98.703632) (xy 79.750491 -98.653577) (xy 79.734566 -98.600673)
			(xy 79.72644 -98.546024) (xy 79.72628 -98.490775) (xy 79.059278 -98.490775) (xy 79.059278 -98.627438)
			(xy 80.983582 -100.551742) (xy 91.146882 -100.551742) (xy 91.150953 -100.49612) (xy 91.163079 -100.441683)
			(xy 91.183002 -100.389592) (xy 91.210298 -100.340957) (xy 91.244384 -100.296814) (xy 91.284533 -100.258105)
			(xy 91.329891 -100.225654) (xy 91.379491 -100.200153) (xy 91.432275 -100.182146) (xy 91.487118 -100.172016)
			(xy 91.542852 -100.169979) (xy 91.598289 -100.176079) (xy 91.652246 -100.190185) (xy 91.703575 -100.211997)
			(xy 91.751181 -100.241051) (xy 91.794049 -100.276726) (xy 91.831266 -100.318263) (xy 91.862039 -100.364776)
			(xy 91.885711 -100.415273) (xy 91.901779 -100.46868) (xy 91.909899 -100.523856) (xy 91.910408 -100.551742)
			(xy 91.909899 -100.579628) (xy 91.901779 -100.634804) (xy 91.885711 -100.688211) (xy 91.862039 -100.738708)
			(xy 91.831266 -100.785221) (xy 91.794049 -100.826758) (xy 91.751181 -100.862433) (xy 91.703575 -100.891487)
			(xy 91.652246 -100.913299) (xy 91.598289 -100.927405) (xy 91.542852 -100.933505) (xy 91.487118 -100.931468)
			(xy 91.432275 -100.921338) (xy 91.379491 -100.903331) (xy 91.329891 -100.87783) (xy 91.284533 -100.845379)
			(xy 91.244384 -100.80667) (xy 91.210298 -100.762527) (xy 91.183002 -100.713892) (xy 91.163079 -100.661801)
			(xy 91.150953 -100.607364) (xy 91.146882 -100.551742) (xy 80.983582 -100.551742) (xy 81.557114 -101.125274)
			(xy 81.603342 -101.129338) (xy 81.631272 -101.132228) (xy 81.685908 -101.145174) (xy 81.738052 -101.166001)
			(xy 81.786572 -101.194258) (xy 81.808828 -101.21138) (xy 81.822576 -101.221636) (xy 81.854101 -101.235116)
			(xy 81.888076 -101.23972) (xy 81.922051 -101.235116) (xy 81.953576 -101.221636) (xy 81.967324 -101.21138)
			(xy 81.988959 -101.194678) (xy 82.036081 -101.166985) (xy 82.086673 -101.146303) (xy 82.139699 -101.133056)
			(xy 82.194074 -101.127515) (xy 82.248683 -101.129794) (xy 82.302407 -101.139845) (xy 82.354145 -101.157464)
			(xy 82.402839 -101.182288) (xy 82.447489 -101.21381) (xy 82.467704 -101.232208) (xy 82.47909 -101.242387)
			(xy 82.505604 -101.257522) (xy 82.534961 -101.26591) (xy 82.565469 -101.267066) (xy 82.595376 -101.260924)
			(xy 82.62296 -101.247838) (xy 82.63509 -101.238558) (xy 82.656225 -101.221983) (xy 82.702257 -101.194304)
			(xy 82.751715 -101.173355) (xy 82.803623 -101.159551) (xy 82.856954 -101.153164) (xy 82.910653 -101.15432)
			(xy 82.96366 -101.162997) (xy 83.014925 -101.179023) (xy 83.063436 -101.202082) (xy 83.108233 -101.231716)
			(xy 83.14843 -101.267341) (xy 83.183234 -101.308252) (xy 83.211955 -101.35364) (xy 83.234026 -101.402608)
			(xy 83.24901 -101.454187) (xy 83.256612 -101.507359) (xy 83.257136 -101.534214) (xy 83.257136 -101.53777)
			(xy 83.255358 -101.572568) (xy 83.252027 -101.600739) (xy 83.238106 -101.65573) (xy 83.216198 -101.708055)
			(xy 83.186786 -101.75656) (xy 83.150519 -101.800178) (xy 83.108195 -101.837947) (xy 83.060746 -101.869035)
			(xy 83.009219 -101.892757) (xy 82.954748 -101.908591) (xy 82.898533 -101.916188) (xy 82.841813 -101.91538)
			(xy 82.785837 -101.906185) (xy 82.731839 -101.888807) (xy 82.681008 -101.863627) (xy 82.634464 -101.8312)
			(xy 82.6135 -101.81209) (xy 82.602438 -101.80215) (xy 82.576716 -101.78724) (xy 82.548239 -101.778695)
			(xy 82.518557 -101.77698) (xy 82.489285 -101.78219) (xy 82.462018 -101.79404) (xy 82.449924 -101.802692)
			(xy 82.437224 -101.812344) (xy 82.43062 -101.818948) (xy 82.419156 -101.831081) (xy 82.40244 -101.859962)
			(xy 82.393783 -101.89219) (xy 82.393776 -101.92556) (xy 82.40242 -101.95779) (xy 82.419125 -101.986678)
			(xy 82.43062 -101.99878) (xy 83.972146 -103.540306) (xy 92.617542 -103.540306) (xy 92.621613 -103.484684)
			(xy 92.633739 -103.430247) (xy 92.653662 -103.378156) (xy 92.680958 -103.329521) (xy 92.715044 -103.285378)
			(xy 92.755193 -103.246669) (xy 92.800551 -103.214218) (xy 92.850151 -103.188717) (xy 92.902935 -103.17071)
			(xy 92.957778 -103.16058) (xy 93.013512 -103.158543) (xy 93.068949 -103.164643) (xy 93.122906 -103.178749)
			(xy 93.174235 -103.200561) (xy 93.221841 -103.229615) (xy 93.264709 -103.26529) (xy 93.301926 -103.306827)
			(xy 93.332699 -103.35334) (xy 93.356371 -103.403837) (xy 93.372439 -103.457244) (xy 93.380559 -103.51242)
			(xy 93.381068 -103.540306) (xy 93.380559 -103.568192) (xy 93.372439 -103.623368) (xy 93.356371 -103.676775)
			(xy 93.332699 -103.727272) (xy 93.301926 -103.773785) (xy 93.264709 -103.815322) (xy 93.221841 -103.850997)
			(xy 93.174235 -103.880051) (xy 93.122906 -103.901863) (xy 93.068949 -103.915969) (xy 93.013512 -103.922069)
			(xy 92.957778 -103.920032) (xy 92.902935 -103.909902) (xy 92.850151 -103.891895) (xy 92.800551 -103.866394)
			(xy 92.755193 -103.833943) (xy 92.715044 -103.795234) (xy 92.680958 -103.751091) (xy 92.653662 -103.702456)
			(xy 92.633739 -103.650365) (xy 92.621613 -103.595928) (xy 92.617542 -103.540306) (xy 83.972146 -103.540306)
			(xy 84.281518 -103.849678) (xy 84.281518 -104.107742) (xy 85.46719 -105.293414) (xy 85.725254 -105.293414)
			(xy 87.192235 -106.760395) (xy 88.937159 -106.760395) (xy 88.939417 -106.705357) (xy 88.949565 -106.651215)
			(xy 88.967392 -106.599095) (xy 88.992527 -106.550079) (xy 89.024449 -106.505187) (xy 89.062493 -106.46535)
			(xy 89.10587 -106.431398) (xy 89.153678 -106.404035) (xy 89.204923 -106.38383) (xy 89.258541 -106.371203)
			(xy 89.313418 -106.366416) (xy 89.368412 -106.369569) (xy 89.422382 -106.380596) (xy 89.474205 -106.399268)
			(xy 89.522806 -106.425197) (xy 89.567173 -106.457845) (xy 89.606385 -106.496532) (xy 89.623392 -106.518202)
			(xy 89.637614 -106.5361) (xy 89.67126 -106.567038) (xy 89.709899 -106.591454) (xy 89.752285 -106.608561)
			(xy 89.797048 -106.617805) (xy 89.842743 -106.618889) (xy 89.887894 -106.611776) (xy 89.931042 -106.596698)
			(xy 89.970796 -106.57414) (xy 89.988644 -106.559858) (xy 90.010118 -106.542606) (xy 90.057009 -106.513709)
			(xy 90.107568 -106.491855) (xy 90.160744 -106.477497) (xy 90.215432 -106.470933) (xy 90.270495 -106.472301)
			(xy 90.32479 -106.481572) (xy 90.377187 -106.498552) (xy 90.426599 -106.52289) (xy 90.471998 -106.554079)
			(xy 90.512441 -106.591472) (xy 90.547087 -106.634291) (xy 90.575217 -106.681646) (xy 90.596246 -106.732554)
			(xy 90.609737 -106.785957) (xy 90.61541 -106.840744) (xy 90.613146 -106.895778) (xy 90.602994 -106.949914)
			(xy 90.585163 -107.002029) (xy 90.560024 -107.051038) (xy 90.528101 -107.095923) (xy 90.490055 -107.135752)
			(xy 90.446678 -107.169698) (xy 90.398871 -107.197053) (xy 90.347628 -107.217251) (xy 90.294013 -107.229872)
			(xy 90.23914 -107.234652) (xy 90.184151 -107.231494) (xy 90.130187 -107.220462) (xy 90.078369 -107.201785)
			(xy 90.029776 -107.175853) (xy 89.985416 -107.143203) (xy 89.946211 -107.104514) (xy 89.929208 -107.082844)
			(xy 89.914982 -107.064948) (xy 89.881339 -107.034006) (xy 89.842701 -107.009585) (xy 89.800315 -106.992476)
			(xy 89.755552 -106.98323) (xy 89.709856 -106.982147) (xy 89.664704 -106.989261) (xy 89.621555 -107.004342)
			(xy 89.581803 -107.026904) (xy 89.563956 -107.041188) (xy 89.542529 -107.0585) (xy 89.495637 -107.087403)
			(xy 89.445076 -107.109264) (xy 89.391897 -107.123628) (xy 89.337205 -107.130197) (xy 89.282137 -107.128835)
			(xy 89.227838 -107.119569) (xy 89.175434 -107.102592) (xy 89.126016 -107.078257) (xy 89.080611 -107.047069)
			(xy 89.040161 -107.009677) (xy 89.005507 -106.966858) (xy 88.977371 -106.919502) (xy 88.956335 -106.868592)
			(xy 88.942837 -106.815187) (xy 88.937159 -106.760395) (xy 87.192235 -106.760395) (xy 87.515954 -107.084114)
			(xy 87.515954 -107.370626) (xy 87.516421 -107.392918) (xy 87.524204 -107.436817) (xy 87.539526 -107.478685)
			(xy 87.561919 -107.517238) (xy 87.590694 -107.551292) (xy 87.624969 -107.579804) (xy 87.663693 -107.601899)
			(xy 87.705678 -107.616899) (xy 87.749636 -107.624344) (xy 87.794218 -107.624005) (xy 87.838058 -107.615893)
			(xy 87.87981 -107.600257) (xy 87.89924 -107.58932) (xy 87.923255 -107.574748) (xy 87.974636 -107.55205)
			(xy 88.02879 -107.537131) (xy 88.084547 -107.530315) (xy 88.1407 -107.531749) (xy 88.196036 -107.541401)
			(xy 88.249359 -107.559063) (xy 88.299515 -107.584354) (xy 88.34542 -107.616726) (xy 88.386082 -107.655479)
			(xy 88.420622 -107.699777) (xy 88.448293 -107.74866) (xy 88.468497 -107.801072) (xy 88.480796 -107.85588)
			(xy 88.484926 -107.9119) (xy 88.480796 -107.96792) (xy 88.468497 -108.022728) (xy 88.448293 -108.07514)
			(xy 88.420622 -108.124023) (xy 88.386082 -108.168321) (xy 88.34542 -108.207074) (xy 88.299515 -108.239446)
			(xy 88.249359 -108.264737) (xy 88.196036 -108.282399) (xy 88.1407 -108.292051) (xy 88.084547 -108.293485)
			(xy 88.02879 -108.286669) (xy 87.974636 -108.27175) (xy 87.923255 -108.249052) (xy 87.89924 -108.23448)
			(xy 87.879815 -108.223536) (xy 87.838067 -108.207895) (xy 87.79423 -108.199779) (xy 87.749649 -108.199438)
			(xy 87.705693 -108.206882) (xy 87.66371 -108.221883) (xy 87.62499 -108.243981) (xy 87.590721 -108.272496)
			(xy 87.561953 -108.306555) (xy 87.539571 -108.345112) (xy 87.524262 -108.386983) (xy 87.516494 -108.430883)
			(xy 87.515954 -108.453174) (xy 87.515954 -110.943644) (xy 89.44737 -112.87506) (xy 89.464037 -112.891013)
			(xy 89.502013 -112.917204) (xy 89.544093 -112.936108) (xy 89.588895 -112.947105) (xy 89.634946 -112.949832)
			(xy 89.680733 -112.944199) (xy 89.72475 -112.930393) (xy 89.765551 -112.908866) (xy 89.801796 -112.880327)
			(xy 89.817448 -112.863376) (xy 89.835877 -112.842739) (xy 89.877666 -112.806477) (xy 89.924254 -112.776632)
			(xy 89.974665 -112.753829) (xy 90.02784 -112.738547) (xy 90.082665 -112.731105) (xy 90.137991 -112.731661)
			(xy 90.192655 -112.740202) (xy 90.245513 -112.75655) (xy 90.295455 -112.780361) (xy 90.341434 -112.811136)
			(xy 90.382486 -112.84823) (xy 90.417749 -112.890865) (xy 90.446484 -112.938146) (xy 90.468089 -112.989081)
			(xy 90.482109 -113.042603) (xy 90.488252 -113.097589) (xy 90.486388 -113.152886) (xy 90.476556 -113.207333)
			(xy 90.468196 -113.233708) (xy 90.459859 -113.257392) (xy 90.43783 -113.302511) (xy 90.410066 -113.344348)
			(xy 90.377051 -113.382176) (xy 90.358468 -113.399062) (xy 90.341747 -113.414434) (xy 90.313514 -113.450007)
			(xy 90.292048 -113.49003) (xy 90.278033 -113.533229) (xy 90.271915 -113.578231) (xy 90.273887 -113.623603)
			(xy 90.283888 -113.667904) (xy 90.3016 -113.709724) (xy 90.326458 -113.747732) (xy 90.341704 -113.764568)
			(xy 90.643964 -114.066828) (xy 90.904822 -114.327432) (xy 93.994732 -114.327432)
		)
		(stroke
			(width 0)
			(type solid)
		)
		(fill yes)
		(layer "In6.Cu")
		(net "P1V05_SUS_NODE1")
	)
	(gr_poly
		(pts
			(xy 17.828006 -199.996044) (xy 17.852586 -199.982783) (xy 17.90474 -199.962802) (xy 17.959249 -199.95064)
			(xy 18.01495 -199.946557) (xy 18.070651 -199.95064) (xy 18.12516 -199.962802) (xy 18.177314 -199.982783)
			(xy 18.201894 -199.996044) (xy 18.23085 -200.0123) (xy 18.52168 -200.0123) (xy 18.538336 -200.011808)
			(xy 18.570515 -200.00319) (xy 18.599367 -199.986537) (xy 18.622924 -199.962983) (xy 18.639582 -199.934134)
			(xy 18.648205 -199.901956) (xy 18.64868 -199.8853) (xy 18.64868 -199.88403) (xy 21.60524 -196.92747)
			(xy 44.533312 -196.92747) (xy 46.760384 -194.700398) (xy 46.760384 -190.401448) (xy 46.750478 -190.377826)
			(xy 46.74101 -190.354298) (xy 46.727676 -190.305366) (xy 46.720947 -190.255099) (xy 46.720942 -190.204382)
			(xy 46.72766 -190.154113) (xy 46.740984 -190.105179) (xy 46.750478 -190.081662) (xy 46.760384 -190.05804)
			(xy 46.760384 -187.035186) (xy 46.750478 -187.011564) (xy 46.740955 -186.987962) (xy 46.727543 -186.938866)
			(xy 46.720778 -186.888423) (xy 46.720781 -186.837529) (xy 46.727552 -186.787087) (xy 46.740971 -186.737993)
			(xy 46.750478 -186.714384) (xy 46.760384 -186.690762) (xy 46.760384 -186.178698) (xy 46.759935 -186.156909)
			(xy 46.752503 -186.11397) (xy 46.737855 -186.072928) (xy 46.716423 -186.034985) (xy 46.688833 -186.001254)
			(xy 46.655895 -185.972722) (xy 46.618573 -185.950226) (xy 46.577961 -185.934425) (xy 46.535249 -185.925782)
			(xy 46.491689 -185.92455) (xy 46.470062 -185.927238) (xy 46.442499 -185.931949) (xy 46.386628 -185.934204)
			(xy 46.331026 -185.92828) (xy 46.276884 -185.914305) (xy 46.225361 -185.892577) (xy 46.177561 -185.863563)
			(xy 46.134507 -185.827883) (xy 46.097122 -185.786302) (xy 46.066205 -185.73971) (xy 46.042419 -185.689105)
			(xy 46.026273 -185.63557) (xy 46.018113 -185.580252) (xy 46.018114 -185.524335) (xy 46.026276 -185.469018)
			(xy 46.042423 -185.415483) (xy 46.066211 -185.364879) (xy 46.097129 -185.318288) (xy 46.134516 -185.276708)
			(xy 46.177571 -185.24103) (xy 46.225372 -185.212017) (xy 46.276896 -185.190291) (xy 46.331038 -185.176318)
			(xy 46.386641 -185.170396) (xy 46.442512 -185.172652) (xy 46.470062 -185.17743) (xy 46.491691 -185.180103)
			(xy 46.535253 -185.178887) (xy 46.577968 -185.170255) (xy 46.618583 -185.154461) (xy 46.655907 -185.131967)
			(xy 46.688846 -185.103434) (xy 46.716432 -185.069698) (xy 46.737856 -185.03175) (xy 46.75249 -184.990702)
			(xy 46.759905 -184.947759) (xy 46.760384 -184.92597) (xy 46.760384 -183.98617) (xy 46.759837 -183.969525)
			(xy 46.751214 -183.937371) (xy 46.734563 -183.908544) (xy 46.711019 -183.885009) (xy 46.682186 -183.868368)
			(xy 46.650029 -183.859757) (xy 46.633384 -183.85917) (xy 46.628812 -183.85917) (xy 46.601421 -183.858913)
			(xy 46.547149 -183.851507) (xy 46.494494 -183.836415) (xy 46.444538 -183.813947) (xy 46.39831 -183.784565)
			(xy 46.356759 -183.748873) (xy 46.320741 -183.707606) (xy 46.290995 -183.661611) (xy 46.268133 -183.611835)
			(xy 46.252626 -183.5593) (xy 46.244791 -183.505088) (xy 46.244791 -183.450313) (xy 46.252625 -183.3961)
			(xy 46.268133 -183.343566) (xy 46.290995 -183.293789) (xy 46.32074 -183.247795) (xy 46.356759 -183.206527)
			(xy 46.39831 -183.170835) (xy 46.444538 -183.141453) (xy 46.494493 -183.118985) (xy 46.547148 -183.103893)
			(xy 46.601421 -183.096487) (xy 46.628812 -183.096154) (xy 46.633384 -183.096154) (xy 46.650038 -183.095661)
			(xy 46.682211 -183.087042) (xy 46.711056 -183.070387) (xy 46.734605 -183.046832) (xy 46.751253 -183.017983)
			(xy 46.759865 -182.985808) (xy 46.760384 -182.969154) (xy 46.760384 -181.146958) (xy 46.750478 -181.123336)
			(xy 46.740951 -181.099734) (xy 46.727528 -181.050637) (xy 46.720754 -181.000192) (xy 46.720748 -180.949293)
			(xy 46.727511 -180.898846) (xy 46.740923 -180.849746) (xy 46.750478 -180.826156) (xy 46.760384 -180.802534)
			(xy 46.760384 -176.409096) (xy 46.283372 -175.932084) (xy 44.076366 -175.932084) (xy 44.05972 -175.932631)
			(xy 44.027563 -175.941254) (xy 43.998733 -175.957905) (xy 43.975194 -175.981448) (xy 43.958548 -176.01028)
			(xy 43.949929 -176.042438) (xy 43.949366 -176.059084) (xy 43.949366 -179.317902) (xy 44.900615 -179.317902)
			(xy 44.90449 -179.26363) (xy 44.916037 -179.210459) (xy 44.935021 -179.159468) (xy 44.961057 -179.111691)
			(xy 44.993617 -179.068098) (xy 45.03204 -179.029573) (xy 45.053504 -179.01285) (xy 45.071995 -178.998287)
			(xy 45.10375 -178.963552) (xy 45.128567 -178.923565) (xy 45.145599 -178.879692) (xy 45.154264 -178.833434)
			(xy 45.154264 -178.786371) (xy 45.145601 -178.740113) (xy 45.12857 -178.69624) (xy 45.103753 -178.656252)
			(xy 45.071999 -178.621516) (xy 45.053504 -178.606958) (xy 45.032044 -178.59023) (xy 44.99362 -178.551706)
			(xy 44.961059 -178.508113) (xy 44.935023 -178.460337) (xy 44.916038 -178.409346) (xy 44.904491 -178.356175)
			(xy 44.900615 -178.301902) (xy 44.90449 -178.24763) (xy 44.916037 -178.194459) (xy 44.935021 -178.143468)
			(xy 44.961057 -178.095691) (xy 44.993617 -178.052098) (xy 45.03204 -178.013573) (xy 45.053504 -177.99685)
			(xy 45.071995 -177.982287) (xy 45.10375 -177.947552) (xy 45.128567 -177.907565) (xy 45.145599 -177.863692)
			(xy 45.154264 -177.817434) (xy 45.154264 -177.770371) (xy 45.145601 -177.724113) (xy 45.12857 -177.68024)
			(xy 45.103753 -177.640252) (xy 45.071999 -177.605516) (xy 45.053504 -177.590958) (xy 45.031383 -177.573725)
			(xy 44.991958 -177.53385) (xy 44.958794 -177.488633) (xy 44.932607 -177.439049) (xy 44.91396 -177.386166)
			(xy 44.903254 -177.331123) (xy 44.900722 -177.275106) (xy 44.906416 -177.219321) (xy 44.920214 -177.164971)
			(xy 44.94182 -177.113226) (xy 44.970767 -177.065201) (xy 45.006433 -177.02193) (xy 45.048048 -176.984347)
			(xy 45.094717 -176.95326) (xy 45.145433 -176.929339) (xy 45.199104 -176.913099) (xy 45.254575 -176.904891)
			(xy 45.310649 -176.904891) (xy 45.36612 -176.913099) (xy 45.419791 -176.929339) (xy 45.470507 -176.95326)
			(xy 45.517176 -176.984347) (xy 45.558791 -177.02193) (xy 45.594457 -177.065201) (xy 45.623404 -177.113226)
			(xy 45.64501 -177.164971) (xy 45.658808 -177.219321) (xy 45.664502 -177.275106) (xy 45.66197 -177.331123)
			(xy 45.651264 -177.386166) (xy 45.632617 -177.439049) (xy 45.60643 -177.488633) (xy 45.573266 -177.53385)
			(xy 45.533841 -177.573725) (xy 45.51172 -177.590958) (xy 45.493219 -177.60551) (xy 45.461462 -177.640246)
			(xy 45.436642 -177.680235) (xy 45.419609 -177.724109) (xy 45.410944 -177.77037) (xy 45.410945 -177.817435)
			(xy 45.41961 -177.863695) (xy 45.436644 -177.90757) (xy 45.461465 -177.947558) (xy 45.493223 -177.982293)
			(xy 45.51172 -177.99685) (xy 45.533187 -178.013569) (xy 45.571609 -178.052095) (xy 45.604168 -178.095689)
			(xy 45.630202 -178.143467) (xy 45.649185 -178.194459) (xy 45.660731 -178.24763) (xy 45.664606 -178.301902)
			(xy 45.660731 -178.356175) (xy 45.649184 -178.409346) (xy 45.6302 -178.460338) (xy 45.604165 -178.508115)
			(xy 45.571606 -178.551708) (xy 45.533183 -178.590234) (xy 45.51172 -178.606958) (xy 45.493219 -178.62151)
			(xy 45.461462 -178.656246) (xy 45.436642 -178.696235) (xy 45.419609 -178.740109) (xy 45.410944 -178.78637)
			(xy 45.410945 -178.833435) (xy 45.41961 -178.879695) (xy 45.436644 -178.92357) (xy 45.461465 -178.963558)
			(xy 45.493223 -178.998293) (xy 45.51172 -179.01285) (xy 45.533187 -179.029569) (xy 45.571609 -179.068095)
			(xy 45.604168 -179.111689) (xy 45.630202 -179.159467) (xy 45.649185 -179.210459) (xy 45.660731 -179.26363)
			(xy 45.664606 -179.317902) (xy 45.660731 -179.372175) (xy 45.649184 -179.425346) (xy 45.6302 -179.476338)
			(xy 45.604165 -179.524115) (xy 45.571606 -179.567708) (xy 45.533183 -179.606234) (xy 45.51172 -179.622958)
			(xy 45.493219 -179.63751) (xy 45.461462 -179.672246) (xy 45.436642 -179.712235) (xy 45.419609 -179.756109)
			(xy 45.410944 -179.80237) (xy 45.410945 -179.849435) (xy 45.41961 -179.895695) (xy 45.436644 -179.93957)
			(xy 45.461465 -179.979558) (xy 45.493223 -180.014293) (xy 45.51172 -180.02885) (xy 45.533841 -180.046083)
			(xy 45.573266 -180.085958) (xy 45.60643 -180.131175) (xy 45.632617 -180.180759) (xy 45.651264 -180.233642)
			(xy 45.66197 -180.288685) (xy 45.664502 -180.344702) (xy 45.658808 -180.400487) (xy 45.64501 -180.454837)
			(xy 45.623404 -180.506582) (xy 45.594457 -180.554607) (xy 45.558791 -180.597878) (xy 45.517176 -180.635461)
			(xy 45.470507 -180.666548) (xy 45.419791 -180.690469) (xy 45.36612 -180.706709) (xy 45.310649 -180.714917)
			(xy 45.254575 -180.714917) (xy 45.199104 -180.706709) (xy 45.145433 -180.690469) (xy 45.094717 -180.666548)
			(xy 45.048048 -180.635461) (xy 45.006433 -180.597878) (xy 44.970767 -180.554607) (xy 44.94182 -180.506582)
			(xy 44.920214 -180.454837) (xy 44.906416 -180.400487) (xy 44.900722 -180.344702) (xy 44.903254 -180.288685)
			(xy 44.91396 -180.233642) (xy 44.932607 -180.180759) (xy 44.958794 -180.131175) (xy 44.991958 -180.085958)
			(xy 45.031383 -180.046083) (xy 45.053504 -180.02885) (xy 45.071995 -180.014287) (xy 45.10375 -179.979552)
			(xy 45.128567 -179.939565) (xy 45.145599 -179.895692) (xy 45.154264 -179.849434) (xy 45.154264 -179.802371)
			(xy 45.145601 -179.756113) (xy 45.12857 -179.71224) (xy 45.103753 -179.672252) (xy 45.071999 -179.637516)
			(xy 45.053504 -179.622958) (xy 45.032044 -179.60623) (xy 44.99362 -179.567706) (xy 44.961059 -179.524113)
			(xy 44.935023 -179.476337) (xy 44.916038 -179.425346) (xy 44.904491 -179.372175) (xy 44.900615 -179.317902)
			(xy 43.949366 -179.317902) (xy 43.949366 -180.667914) (xy 43.582082 -181.035198) (xy 43.565727 -181.052296)
			(xy 43.539042 -181.091362) (xy 43.520048 -181.134692) (xy 43.509398 -181.180788) (xy 43.507461 -181.228058)
			(xy 43.514304 -181.274871) (xy 43.529691 -181.319609) (xy 43.553089 -181.360727) (xy 43.583692 -181.396807)
			(xy 43.620442 -181.4266) (xy 43.64101 -181.438296) (xy 43.666158 -181.451186) (xy 43.712682 -181.48326)
			(xy 43.753967 -181.521844) (xy 43.789112 -181.566094) (xy 43.817348 -181.615042) (xy 43.838057 -181.667619)
			(xy 43.850786 -181.722675) (xy 43.855258 -181.779007) (xy 43.851374 -181.835382) (xy 43.839219 -181.890567)
			(xy 43.81906 -181.943358) (xy 43.791337 -181.992598) (xy 43.756655 -182.037212) (xy 43.715775 -182.076224)
			(xy 43.669588 -182.108782) (xy 43.619105 -182.134173) (xy 43.56543 -182.151842) (xy 43.509736 -182.161403)
			(xy 43.481498 -182.16245) (xy 43.430698 -182.163466) (xy 43.244008 -182.350156) (xy 45.546262 -182.350156)
			(xy 45.550333 -182.294534) (xy 45.562459 -182.240097) (xy 45.582382 -182.188006) (xy 45.609678 -182.139371)
			(xy 45.643764 -182.095228) (xy 45.683913 -182.056519) (xy 45.729271 -182.024068) (xy 45.778871 -181.998567)
			(xy 45.831655 -181.98056) (xy 45.886498 -181.97043) (xy 45.942232 -181.968393) (xy 45.997669 -181.974493)
			(xy 46.051626 -181.988599) (xy 46.102955 -182.010411) (xy 46.150561 -182.039465) (xy 46.193429 -182.07514)
			(xy 46.230646 -182.116677) (xy 46.261419 -182.16319) (xy 46.285091 -182.213687) (xy 46.301159 -182.267094)
			(xy 46.309279 -182.32227) (xy 46.309788 -182.350156) (xy 46.309279 -182.378042) (xy 46.301159 -182.433218)
			(xy 46.285091 -182.486625) (xy 46.261419 -182.537122) (xy 46.230646 -182.583635) (xy 46.193429 -182.625172)
			(xy 46.150561 -182.660847) (xy 46.102955 -182.689901) (xy 46.051626 -182.711713) (xy 45.997669 -182.725819)
			(xy 45.942232 -182.731919) (xy 45.886498 -182.729882) (xy 45.831655 -182.719752) (xy 45.778871 -182.701745)
			(xy 45.729271 -182.676244) (xy 45.683913 -182.643793) (xy 45.643764 -182.605084) (xy 45.609678 -182.560941)
			(xy 45.582382 -182.512306) (xy 45.562459 -182.460215) (xy 45.550333 -182.405778) (xy 45.546262 -182.350156)
			(xy 43.244008 -182.350156) (xy 42.651934 -182.94223) (xy 44.185584 -182.94223) (xy 44.189655 -182.886608)
			(xy 44.201781 -182.832171) (xy 44.221704 -182.78008) (xy 44.249 -182.731445) (xy 44.283086 -182.687302)
			(xy 44.323235 -182.648593) (xy 44.368593 -182.616142) (xy 44.418193 -182.590641) (xy 44.470977 -182.572634)
			(xy 44.52582 -182.562504) (xy 44.581554 -182.560467) (xy 44.636991 -182.566567) (xy 44.690948 -182.580673)
			(xy 44.742277 -182.602485) (xy 44.789883 -182.631539) (xy 44.832751 -182.667214) (xy 44.869968 -182.708751)
			(xy 44.900741 -182.755264) (xy 44.924413 -182.805761) (xy 44.940481 -182.859168) (xy 44.948601 -182.914344)
			(xy 44.94911 -182.94223) (xy 44.948601 -182.970116) (xy 44.940481 -183.025292) (xy 44.924413 -183.078699)
			(xy 44.900741 -183.129196) (xy 44.869968 -183.175709) (xy 44.832751 -183.217246) (xy 44.789883 -183.252921)
			(xy 44.742277 -183.281975) (xy 44.690948 -183.303787) (xy 44.636991 -183.317893) (xy 44.581554 -183.323993)
			(xy 44.52582 -183.321956) (xy 44.470977 -183.311826) (xy 44.418193 -183.293819) (xy 44.368593 -183.268318)
			(xy 44.323235 -183.235867) (xy 44.283086 -183.197158) (xy 44.249 -183.153015) (xy 44.221704 -183.10438)
			(xy 44.201781 -183.052289) (xy 44.189655 -182.997852) (xy 44.185584 -182.94223) (xy 42.651934 -182.94223)
			(xy 41.814496 -183.779668) (xy 35.630358 -183.779668) (xy 35.627818 -183.782208) (xy 32.75584 -183.782208)
			(xy 32.42945 -183.455818) (xy 32.416754 -183.443878) (xy 32.386383 -183.426808) (xy 32.352527 -183.418584)
			(xy 32.317709 -183.419819) (xy 32.284522 -183.43042) (xy 32.269684 -183.439562) (xy 32.24562 -183.454778)
			(xy 32.193947 -183.478674) (xy 32.139296 -183.494625) (xy 32.082881 -183.502276) (xy 32.025955 -183.501457)
			(xy 31.969784 -183.492185) (xy 31.915615 -183.474668) (xy 31.86465 -183.449294) (xy 31.818024 -183.416627)
			(xy 31.77677 -183.377393) (xy 31.741807 -183.332462) (xy 31.71391 -183.282834) (xy 31.703264 -183.256428)
			(xy 31.694313 -183.23168) (xy 31.682529 -183.180388) (xy 31.677914 -183.127964) (xy 31.680557 -183.075403)
			(xy 31.690408 -183.023705) (xy 31.707278 -182.973855) (xy 31.730847 -182.9268) (xy 31.745428 -182.904892)
			(xy 31.76778 -182.87238) (xy 31.76778 -172.52823) (xy 30.954726 -171.715176) (xy 30.942055 -171.703251)
			(xy 30.911741 -171.686193) (xy 30.877947 -171.677955) (xy 30.843184 -171.679147) (xy 30.826456 -171.683934)
			(xy 30.799802 -171.69188) (xy 30.744914 -171.700855) (xy 30.689304 -171.701761) (xy 30.634152 -171.694581)
			(xy 30.580629 -171.679465) (xy 30.529868 -171.656735) (xy 30.482948 -171.626873) (xy 30.440863 -171.590512)
			(xy 30.404506 -171.548424) (xy 30.374648 -171.501501) (xy 30.351923 -171.450738) (xy 30.336812 -171.397213)
			(xy 30.329637 -171.342061) (xy 30.330548 -171.286451) (xy 30.339528 -171.231564) (xy 30.347412 -171.20489)
			(xy 30.35808 -171.170854) (xy 30.341316 -171.101766) (xy 28.824936 -169.585386) (xy 22.1361 -169.585386)
			(xy 19.06778 -166.517066) (xy 19.06778 -157.098238) (xy 16.79956 -154.830018) (xy 16.79956 -150.18258)
			(xy 15.374874 -148.757894) (xy 15.359228 -148.742882) (xy 15.323802 -148.717884) (xy 15.284647 -148.699262)
			(xy 15.2429 -148.687556) (xy 15.199772 -148.683105) (xy 15.156514 -148.686038) (xy 15.114381 -148.696271)
			(xy 15.074596 -148.713506) (xy 15.038314 -148.737243) (xy 15.006586 -148.766793) (xy 14.980335 -148.8013)
			(xy 14.96032 -148.839762) (xy 14.953234 -148.860256) (xy 14.944282 -148.886692) (xy 14.919739 -148.936819)
			(xy 14.888154 -148.982834) (xy 14.850202 -149.023757) (xy 14.806693 -149.058714) (xy 14.758555 -149.086959)
			(xy 14.706815 -149.107888) (xy 14.652578 -149.121056) (xy 14.597002 -149.126182) (xy 14.541271 -149.123155)
			(xy 14.486576 -149.112041) (xy 14.434085 -149.093076) (xy 14.384916 -149.066666) (xy 14.34012 -149.033374)
			(xy 14.300652 -148.993911) (xy 14.267356 -148.949118) (xy 14.24094 -148.899952) (xy 14.22197 -148.847462)
			(xy 14.21085 -148.792769) (xy 14.207818 -148.737039) (xy 14.212937 -148.681461) (xy 14.226099 -148.627223)
			(xy 14.247023 -148.575481) (xy 14.275263 -148.52734) (xy 14.310215 -148.483827) (xy 14.351134 -148.445871)
			(xy 14.397147 -148.414281) (xy 14.447271 -148.389733) (xy 14.473682 -148.380704) (xy 14.494217 -148.3737)
			(xy 14.532718 -148.353703) (xy 14.567262 -148.327455) (xy 14.596846 -148.295722) (xy 14.620609 -148.259424)
			(xy 14.63786 -148.219617) (xy 14.648099 -148.177458) (xy 14.651028 -148.134173) (xy 14.646561 -148.091019)
			(xy 14.634829 -148.049251) (xy 14.616172 -148.010083) (xy 14.591132 -147.974653) (xy 14.576044 -147.959064)
			(xy 12.857988 -146.241008) (xy 12.845031 -146.228915) (xy 12.814031 -146.211762) (xy 12.779511 -146.203786)
			(xy 12.744128 -146.205602) (xy 12.727178 -146.210782) (xy 12.700152 -146.219491) (xy 12.644305 -146.229731)
			(xy 12.587556 -146.231583) (xy 12.531159 -146.225006) (xy 12.47636 -146.210145) (xy 12.424368 -146.187327)
			(xy 12.376331 -146.157057) (xy 12.333309 -146.120003) (xy 12.296253 -146.076983) (xy 12.265981 -146.028948)
			(xy 12.243161 -145.976956) (xy 12.228297 -145.922158) (xy 12.221717 -145.865761) (xy 12.223567 -145.809013)
			(xy 12.233805 -145.753165) (xy 12.242546 -145.72615) (xy 12.247736 -145.7092) (xy 12.249559 -145.673814)
			(xy 12.241585 -145.639289) (xy 12.224428 -145.608286) (xy 12.21232 -145.59534) (xy 11.458448 -144.841468)
			(xy 10.35304 -144.841468) (xy 10.352532 -144.84096) (xy 7.813548 -144.84096) (xy 5.5118 -142.539212)
			(xy 5.5118 -141.804136) (xy 5.511352 -141.782609) (xy 5.5041 -141.740169) (xy 5.489792 -141.699561)
			(xy 5.46884 -141.661948) (xy 5.441843 -141.62841) (xy 5.409574 -141.599906) (xy 5.37296 -141.577254)
			(xy 5.33305 -141.561103) (xy 5.290986 -141.551916) (xy 5.247976 -141.549957) (xy 5.226558 -141.552168)
			(xy 5.199403 -141.55584) (xy 5.144608 -141.556287) (xy 5.090312 -141.54889) (xy 5.037633 -141.533803)
			(xy 4.987655 -141.511336) (xy 4.941403 -141.48195) (xy 4.899832 -141.44625) (xy 4.863794 -141.40497)
			(xy 4.834032 -141.35896) (xy 4.811158 -141.309166) (xy 4.795642 -141.256612) (xy 4.787804 -141.202379)
			(xy 4.787804 -141.147582) (xy 4.795642 -141.093349) (xy 4.811158 -141.040794) (xy 4.834032 -140.991)
			(xy 4.863794 -140.94499) (xy 4.899831 -140.903711) (xy 4.941403 -140.868011) (xy 4.987654 -140.838625)
			(xy 5.037633 -140.816157) (xy 5.090312 -140.80107) (xy 5.144607 -140.793673) (xy 5.199402 -140.79412)
			(xy 5.226558 -140.797788) (xy 5.247974 -140.799986) (xy 5.290975 -140.798004) (xy 5.333028 -140.788802)
			(xy 5.372927 -140.772644) (xy 5.409532 -140.749992) (xy 5.441796 -140.721494) (xy 5.468794 -140.687965)
			(xy 5.489755 -140.650366) (xy 5.504078 -140.609771) (xy 5.511354 -140.567343) (xy 5.5118 -140.54582)
			(xy 5.5118 -140.325856) (xy 5.511341 -140.303881) (xy 5.503788 -140.260586) (xy 5.488895 -140.219238)
			(xy 5.467106 -140.18107) (xy 5.439072 -140.147223) (xy 5.40563 -140.118708) (xy 5.367779 -140.096374)
			(xy 5.326647 -140.080891) (xy 5.283465 -140.072719) (xy 5.23952 -140.072103) (xy 5.196126 -140.079061)
			(xy 5.154576 -140.093385) (xy 5.135118 -140.103606) (xy 5.110435 -140.117659) (xy 5.057842 -140.139103)
			(xy 5.002652 -140.152512) (xy 4.946083 -140.157591) (xy 4.889386 -140.154227) (xy 4.833815 -140.142494)
			(xy 4.780597 -140.122652) (xy 4.730909 -140.09514) (xy 4.685849 -140.060565) (xy 4.646413 -140.019692)
			(xy 4.613472 -139.973423) (xy 4.587755 -139.922783) (xy 4.56983 -139.868889) (xy 4.560094 -139.812933)
			(xy 4.558761 -139.756152) (xy 4.56586 -139.699801) (xy 4.573016 -139.672314) (xy 4.580847 -139.646164)
			(xy 4.602951 -139.596253) (xy 4.63194 -139.550001) (xy 4.667225 -139.508351) (xy 4.708084 -139.472154)
			(xy 4.753683 -139.442149) (xy 4.803093 -139.418947) (xy 4.855305 -139.403022) (xy 4.909254 -139.394699)
			(xy 4.963837 -139.394149) (xy 5.017942 -139.401381) (xy 5.070465 -139.416249) (xy 5.120333 -139.43845)
			(xy 5.166529 -139.46753) (xy 5.20811 -139.502895) (xy 5.244227 -139.543824) (xy 5.259578 -139.566396)
			(xy 5.275834 -139.591288) (xy 5.320284 -139.61745) (xy 5.334952 -139.625517) (xy 5.367204 -139.634441)
			(xy 5.400668 -139.63467) (xy 5.43304 -139.626187) (xy 5.462091 -139.609578) (xy 5.485824 -139.585984)
			(xy 5.502603 -139.55703) (xy 5.511275 -139.524709) (xy 5.5118 -139.507976) (xy 5.5118 -139.38123)
			(xy 5.511317 -139.358765) (xy 5.503412 -139.314537) (xy 5.487856 -139.272386) (xy 5.465133 -139.233627)
			(xy 5.435951 -139.199465) (xy 5.401218 -139.170965) (xy 5.362016 -139.149013) (xy 5.319566 -139.134295)
			(xy 5.27519 -139.127267) (xy 5.25272 -139.12723) (xy 5.226366 -139.127312) (xy 5.174034 -139.121101)
			(xy 5.123055 -139.107744) (xy 5.0744 -139.087495) (xy 5.028996 -139.060741) (xy 4.987708 -139.027991)
			(xy 4.951322 -138.989868) (xy 4.920531 -138.947099) (xy 4.907788 -138.92403) (xy 4.895215 -138.899164)
			(xy 4.876614 -138.846641) (xy 4.865852 -138.791971) (xy 4.863157 -138.736317) (xy 4.868588 -138.680863)
			(xy 4.882028 -138.626788) (xy 4.903191 -138.575245) (xy 4.931627 -138.527328) (xy 4.966732 -138.484058)
			(xy 5.007757 -138.446354) (xy 5.053832 -138.415021) (xy 5.103974 -138.390723) (xy 5.157118 -138.373978)
			(xy 5.212132 -138.365142) (xy 5.267846 -138.364403) (xy 5.323076 -138.371777) (xy 5.350002 -138.378946)
			(xy 5.36702 -138.383772) (xy 5.3848 -138.383772) (xy 5.401453 -138.383277) (xy 5.433625 -138.374656)
			(xy 5.462468 -138.358) (xy 5.486017 -138.334446) (xy 5.502666 -138.305599) (xy 5.511281 -138.273426)
			(xy 5.5118 -138.256772) (xy 5.5118 -138.185144) (xy 5.511292 -138.184636) (xy 5.511292 -137.78357)
			(xy 5.198872 -137.47115) (xy 4.819396 -137.09142) (xy 4.819396 -97.695258) (xy 4.818163 -97.679115)
			(xy 4.808585 -97.6482) (xy 4.791552 -97.620679) (xy 4.768155 -97.598316) (xy 4.739894 -97.582542)
			(xy 4.708578 -97.574369) (xy 4.692396 -97.573846) (xy 1.8669 -97.573846) (xy 1.850247 -97.574341)
			(xy 1.818078 -97.582963) (xy 1.789237 -97.599619) (xy 1.765691 -97.623173) (xy 1.749045 -97.65202)
			(xy 1.740435 -97.684193) (xy 1.7399 -97.700846) (xy 1.7399 -143.997934) (xy 3.732782 -143.997934)
			(xy 3.736853 -143.942312) (xy 3.748979 -143.887875) (xy 3.768902 -143.835784) (xy 3.796198 -143.787149)
			(xy 3.830284 -143.743006) (xy 3.870433 -143.704297) (xy 3.915791 -143.671846) (xy 3.965391 -143.646345)
			(xy 4.018175 -143.628338) (xy 4.073018 -143.618208) (xy 4.128752 -143.616171) (xy 4.184189 -143.622271)
			(xy 4.238146 -143.636377) (xy 4.289475 -143.658189) (xy 4.337081 -143.687243) (xy 4.379949 -143.722918)
			(xy 4.417166 -143.764455) (xy 4.447939 -143.810968) (xy 4.471611 -143.861465) (xy 4.487679 -143.914872)
			(xy 4.495799 -143.970048) (xy 4.496308 -143.997934) (xy 4.495799 -144.02582) (xy 4.487679 -144.080996)
			(xy 4.471611 -144.134403) (xy 4.447939 -144.1849) (xy 4.417166 -144.231413) (xy 4.379949 -144.27295)
			(xy 4.347212 -144.300194) (xy 5.614922 -144.300194) (xy 5.618993 -144.244572) (xy 5.631119 -144.190135)
			(xy 5.651042 -144.138044) (xy 5.678338 -144.089409) (xy 5.712424 -144.045266) (xy 5.752573 -144.006557)
			(xy 5.797931 -143.974106) (xy 5.847531 -143.948605) (xy 5.900315 -143.930598) (xy 5.955158 -143.920468)
			(xy 6.010892 -143.918431) (xy 6.066329 -143.924531) (xy 6.120286 -143.938637) (xy 6.171615 -143.960449)
			(xy 6.219221 -143.989503) (xy 6.262089 -144.025178) (xy 6.299306 -144.066715) (xy 6.330079 -144.113228)
			(xy 6.353751 -144.163725) (xy 6.369819 -144.217132) (xy 6.377939 -144.272308) (xy 6.378448 -144.300194)
			(xy 6.377939 -144.32808) (xy 6.369819 -144.383256) (xy 6.353751 -144.436663) (xy 6.330079 -144.48716)
			(xy 6.299306 -144.533673) (xy 6.262089 -144.57521) (xy 6.219221 -144.610885) (xy 6.171615 -144.639939)
			(xy 6.120286 -144.661751) (xy 6.066329 -144.675857) (xy 6.010892 -144.681957) (xy 5.955158 -144.67992)
			(xy 5.900315 -144.66979) (xy 5.847531 -144.651783) (xy 5.797931 -144.626282) (xy 5.752573 -144.593831)
			(xy 5.712424 -144.555122) (xy 5.678338 -144.510979) (xy 5.651042 -144.462344) (xy 5.631119 -144.410253)
			(xy 5.618993 -144.355816) (xy 5.614922 -144.300194) (xy 4.347212 -144.300194) (xy 4.337081 -144.308625)
			(xy 4.289475 -144.337679) (xy 4.238146 -144.359491) (xy 4.184189 -144.373597) (xy 4.128752 -144.379697)
			(xy 4.073018 -144.37766) (xy 4.018175 -144.36753) (xy 3.965391 -144.349523) (xy 3.915791 -144.324022)
			(xy 3.870433 -144.291571) (xy 3.830284 -144.252862) (xy 3.796198 -144.208719) (xy 3.768902 -144.160084)
			(xy 3.748979 -144.107993) (xy 3.736853 -144.053556) (xy 3.732782 -143.997934) (xy 1.7399 -143.997934)
			(xy 1.7399 -145.303494) (xy 4.433822 -145.303494) (xy 4.437893 -145.247872) (xy 4.450019 -145.193435)
			(xy 4.469942 -145.141344) (xy 4.497238 -145.092709) (xy 4.531324 -145.048566) (xy 4.571473 -145.009857)
			(xy 4.616831 -144.977406) (xy 4.666431 -144.951905) (xy 4.719215 -144.933898) (xy 4.774058 -144.923768)
			(xy 4.829792 -144.921731) (xy 4.885229 -144.927831) (xy 4.939186 -144.941937) (xy 4.990515 -144.963749)
			(xy 5.038121 -144.992803) (xy 5.080989 -145.028478) (xy 5.118206 -145.070015) (xy 5.148979 -145.116528)
			(xy 5.172651 -145.167025) (xy 5.188719 -145.220432) (xy 5.196839 -145.275608) (xy 5.197348 -145.303494)
			(xy 5.196839 -145.33138) (xy 5.188719 -145.386556) (xy 5.172651 -145.439963) (xy 5.148979 -145.49046)
			(xy 5.118206 -145.536973) (xy 5.080989 -145.57851) (xy 5.038121 -145.614185) (xy 4.990515 -145.643239)
			(xy 4.939186 -145.665051) (xy 4.885229 -145.679157) (xy 4.829792 -145.685257) (xy 4.774058 -145.68322)
			(xy 4.719215 -145.67309) (xy 4.666431 -145.655083) (xy 4.616831 -145.629582) (xy 4.571473 -145.597131)
			(xy 4.531324 -145.558422) (xy 4.497238 -145.514279) (xy 4.469942 -145.465644) (xy 4.450019 -145.413553)
			(xy 4.437893 -145.359116) (xy 4.433822 -145.303494) (xy 1.7399 -145.303494) (xy 1.7399 -146.919188)
			(xy 4.158486 -146.919188) (xy 4.162557 -146.863566) (xy 4.174683 -146.809129) (xy 4.194606 -146.757038)
			(xy 4.221902 -146.708403) (xy 4.255988 -146.66426) (xy 4.296137 -146.625551) (xy 4.341495 -146.5931)
			(xy 4.391095 -146.567599) (xy 4.443879 -146.549592) (xy 4.498722 -146.539462) (xy 4.554456 -146.537425)
			(xy 4.609893 -146.543525) (xy 4.66385 -146.557631) (xy 4.715179 -146.579443) (xy 4.762785 -146.608497)
			(xy 4.805653 -146.644172) (xy 4.84287 -146.685709) (xy 4.873643 -146.732222) (xy 4.897315 -146.782719)
			(xy 4.913383 -146.836126) (xy 4.921503 -146.891302) (xy 4.922012 -146.919188) (xy 4.921503 -146.947074)
			(xy 4.913383 -147.00225) (xy 4.897315 -147.055657) (xy 4.873643 -147.106154) (xy 4.84287 -147.152667)
			(xy 4.805653 -147.194204) (xy 4.762785 -147.229879) (xy 4.736229 -147.246086) (xy 12.236702 -147.246086)
			(xy 12.240773 -147.190464) (xy 12.252899 -147.136027) (xy 12.272822 -147.083936) (xy 12.300118 -147.035301)
			(xy 12.334204 -146.991158) (xy 12.374353 -146.952449) (xy 12.419711 -146.919998) (xy 12.469311 -146.894497)
			(xy 12.522095 -146.87649) (xy 12.576938 -146.86636) (xy 12.632672 -146.864323) (xy 12.688109 -146.870423)
			(xy 12.742066 -146.884529) (xy 12.793395 -146.906341) (xy 12.841001 -146.935395) (xy 12.883869 -146.97107)
			(xy 12.921086 -147.012607) (xy 12.951859 -147.05912) (xy 12.975531 -147.109617) (xy 12.991599 -147.163024)
			(xy 12.999719 -147.2182) (xy 13.000228 -147.246086) (xy 12.999719 -147.273972) (xy 12.991599 -147.329148)
			(xy 12.975531 -147.382555) (xy 12.951859 -147.433052) (xy 12.921086 -147.479565) (xy 12.883869 -147.521102)
			(xy 12.841001 -147.556777) (xy 12.793395 -147.585831) (xy 12.742066 -147.607643) (xy 12.688109 -147.621749)
			(xy 12.632672 -147.627849) (xy 12.576938 -147.625812) (xy 12.522095 -147.615682) (xy 12.469311 -147.597675)
			(xy 12.419711 -147.572174) (xy 12.374353 -147.539723) (xy 12.334204 -147.501014) (xy 12.300118 -147.456871)
			(xy 12.272822 -147.408236) (xy 12.252899 -147.356145) (xy 12.240773 -147.301708) (xy 12.236702 -147.246086)
			(xy 4.736229 -147.246086) (xy 4.715179 -147.258933) (xy 4.66385 -147.280745) (xy 4.609893 -147.294851)
			(xy 4.554456 -147.300951) (xy 4.498722 -147.298914) (xy 4.443879 -147.288784) (xy 4.391095 -147.270777)
			(xy 4.341495 -147.245276) (xy 4.296137 -147.212825) (xy 4.255988 -147.174116) (xy 4.221902 -147.129973)
			(xy 4.194606 -147.081338) (xy 4.174683 -147.029247) (xy 4.162557 -146.97481) (xy 4.158486 -146.919188)
			(xy 1.7399 -146.919188) (xy 1.7399 -149.781514) (xy 10.008614 -149.781514) (xy 10.012685 -149.725892)
			(xy 10.024811 -149.671455) (xy 10.044734 -149.619364) (xy 10.07203 -149.570729) (xy 10.106116 -149.526586)
			(xy 10.146265 -149.487877) (xy 10.191623 -149.455426) (xy 10.241223 -149.429925) (xy 10.294007 -149.411918)
			(xy 10.34885 -149.401788) (xy 10.404584 -149.399751) (xy 10.460021 -149.405851) (xy 10.513978 -149.419957)
			(xy 10.565307 -149.441769) (xy 10.612913 -149.470823) (xy 10.655781 -149.506498) (xy 10.692998 -149.548035)
			(xy 10.723771 -149.594548) (xy 10.725686 -149.598634) (xy 11.69746 -149.598634) (xy 11.701531 -149.543012)
			(xy 11.713657 -149.488575) (xy 11.73358 -149.436484) (xy 11.760876 -149.387849) (xy 11.794962 -149.343706)
			(xy 11.835111 -149.304997) (xy 11.880469 -149.272546) (xy 11.930069 -149.247045) (xy 11.982853 -149.229038)
			(xy 12.037696 -149.218908) (xy 12.09343 -149.216871) (xy 12.148867 -149.222971) (xy 12.202824 -149.237077)
			(xy 12.254153 -149.258889) (xy 12.301759 -149.287943) (xy 12.344627 -149.323618) (xy 12.381844 -149.365155)
			(xy 12.412617 -149.411668) (xy 12.436289 -149.462165) (xy 12.452357 -149.515572) (xy 12.460477 -149.570748)
			(xy 12.460986 -149.598634) (xy 12.460477 -149.62652) (xy 12.452357 -149.681696) (xy 12.436289 -149.735103)
			(xy 12.412617 -149.7856) (xy 12.381844 -149.832113) (xy 12.344627 -149.87365) (xy 12.301759 -149.909325)
			(xy 12.254153 -149.938379) (xy 12.202824 -149.960191) (xy 12.148867 -149.974297) (xy 12.09343 -149.980397)
			(xy 12.037696 -149.97836) (xy 11.982853 -149.96823) (xy 11.930069 -149.950223) (xy 11.880469 -149.924722)
			(xy 11.835111 -149.892271) (xy 11.794962 -149.853562) (xy 11.760876 -149.809419) (xy 11.73358 -149.760784)
			(xy 11.713657 -149.708693) (xy 11.701531 -149.654256) (xy 11.69746 -149.598634) (xy 10.725686 -149.598634)
			(xy 10.747443 -149.645045) (xy 10.763511 -149.698452) (xy 10.771631 -149.753628) (xy 10.77214 -149.781514)
			(xy 10.771631 -149.8094) (xy 10.763511 -149.864576) (xy 10.747443 -149.917983) (xy 10.723771 -149.96848)
			(xy 10.692998 -150.014993) (xy 10.655781 -150.05653) (xy 10.612913 -150.092205) (xy 10.565307 -150.121259)
			(xy 10.513978 -150.143071) (xy 10.460021 -150.157177) (xy 10.404584 -150.163277) (xy 10.34885 -150.16124)
			(xy 10.294007 -150.15111) (xy 10.241223 -150.133103) (xy 10.191623 -150.107602) (xy 10.146265 -150.075151)
			(xy 10.106116 -150.036442) (xy 10.07203 -149.992299) (xy 10.044734 -149.943664) (xy 10.024811 -149.891573)
			(xy 10.012685 -149.837136) (xy 10.008614 -149.781514) (xy 1.7399 -149.781514) (xy 1.7399 -150.357548)
			(xy 3.049578 -150.357548) (xy 3.052851 -150.302413) (xy 3.064041 -150.248326) (xy 3.082914 -150.196418)
			(xy 3.109075 -150.147775) (xy 3.141977 -150.103412) (xy 3.180933 -150.064257) (xy 3.225128 -150.03113)
			(xy 3.273638 -150.004722) (xy 3.325449 -149.985586) (xy 3.379478 -149.974121) (xy 3.434596 -149.970568)
			(xy 3.489651 -149.975) (xy 3.54349 -149.987325) (xy 3.59499 -150.007285) (xy 3.643073 -150.034463)
			(xy 3.686733 -150.068291) (xy 3.72506 -150.108062) (xy 3.75725 -150.152944) (xy 3.770376 -150.177246)
			(xy 3.781425 -150.197507) (xy 3.809713 -150.233965) (xy 3.844116 -150.264718) (xy 3.883505 -150.288757)
			(xy 3.926587 -150.305291) (xy 3.971945 -150.313778) (xy 4.018089 -150.313939) (xy 4.063505 -150.305768)
			(xy 4.106701 -150.289534) (xy 4.126738 -150.278084) (xy 4.150668 -150.264291) (xy 4.201629 -150.242992)
			(xy 4.255128 -150.229265) (xy 4.310048 -150.223397) (xy 4.36524 -150.225509) (xy 4.41955 -150.235559)
			(xy 4.471844 -150.253336) (xy 4.521027 -150.278468) (xy 4.54626 -150.296372) (xy 6.75843 -150.296372)
			(xy 6.762501 -150.24075) (xy 6.774627 -150.186313) (xy 6.79455 -150.134222) (xy 6.821846 -150.085587)
			(xy 6.855932 -150.041444) (xy 6.896081 -150.002735) (xy 6.941439 -149.970284) (xy 6.991039 -149.944783)
			(xy 7.043823 -149.926776) (xy 7.098666 -149.916646) (xy 7.1544 -149.914609) (xy 7.209837 -149.920709)
			(xy 7.263794 -149.934815) (xy 7.315123 -149.956627) (xy 7.362729 -149.985681) (xy 7.405597 -150.021356)
			(xy 7.442814 -150.062893) (xy 7.473587 -150.109406) (xy 7.497259 -150.159903) (xy 7.513327 -150.21331)
			(xy 7.521447 -150.268486) (xy 7.521956 -150.296372) (xy 7.521447 -150.324258) (xy 7.513327 -150.379434)
			(xy 7.497259 -150.432841) (xy 7.473587 -150.483338) (xy 7.442814 -150.529851) (xy 7.405597 -150.571388)
			(xy 7.362729 -150.607063) (xy 7.315123 -150.636117) (xy 7.263794 -150.657929) (xy 7.209837 -150.672035)
			(xy 7.1544 -150.678135) (xy 7.098666 -150.676098) (xy 7.043823 -150.665968) (xy 6.991039 -150.647961)
			(xy 6.941439 -150.62246) (xy 6.896081 -150.590009) (xy 6.855932 -150.5513) (xy 6.821846 -150.507157)
			(xy 6.79455 -150.458522) (xy 6.774627 -150.406431) (xy 6.762501 -150.351994) (xy 6.75843 -150.296372)
			(xy 4.54626 -150.296372) (xy 4.566072 -150.310429) (xy 4.606038 -150.348553) (xy 4.640087 -150.392041)
			(xy 4.66751 -150.439985) (xy 4.687732 -150.491383) (xy 4.700331 -150.545159) (xy 4.705043 -150.60019)
			(xy 4.70177 -150.655326) (xy 4.69058 -150.709413) (xy 4.671708 -150.761321) (xy 4.645547 -150.809965)
			(xy 4.612645 -150.854328) (xy 4.573689 -150.893482) (xy 4.569225 -150.896828) (xy 10.92276 -150.896828)
			(xy 10.926831 -150.841206) (xy 10.938957 -150.786769) (xy 10.95888 -150.734678) (xy 10.986176 -150.686043)
			(xy 11.020262 -150.6419) (xy 11.060411 -150.603191) (xy 11.105769 -150.57074) (xy 11.155369 -150.545239)
			(xy 11.208153 -150.527232) (xy 11.262996 -150.517102) (xy 11.31873 -150.515065) (xy 11.374167 -150.521165)
			(xy 11.428124 -150.535271) (xy 11.479453 -150.557083) (xy 11.527059 -150.586137) (xy 11.569927 -150.621812)
			(xy 11.607144 -150.663349) (xy 11.637917 -150.709862) (xy 11.661589 -150.760359) (xy 11.677657 -150.813766)
			(xy 11.685777 -150.868942) (xy 11.686286 -150.896828) (xy 11.685777 -150.924714) (xy 11.677657 -150.97989)
			(xy 11.661589 -151.033297) (xy 11.637917 -151.083794) (xy 11.607144 -151.130307) (xy 11.569927 -151.171844)
			(xy 11.527059 -151.207519) (xy 11.479453 -151.236573) (xy 11.428124 -151.258385) (xy 11.374167 -151.272491)
			(xy 11.31873 -151.278591) (xy 11.262996 -151.276554) (xy 11.208153 -151.266424) (xy 11.155369 -151.248417)
			(xy 11.105769 -151.222916) (xy 11.060411 -151.190465) (xy 11.020262 -151.151756) (xy 10.986176 -151.107613)
			(xy 10.95888 -151.058978) (xy 10.938957 -151.006887) (xy 10.926831 -150.95245) (xy 10.92276 -150.896828)
			(xy 4.569225 -150.896828) (xy 4.529494 -150.92661) (xy 4.480984 -150.953018) (xy 4.429173 -150.972155)
			(xy 4.375143 -150.98362) (xy 4.320025 -150.987173) (xy 4.264971 -150.982741) (xy 4.211131 -150.970417)
			(xy 4.159631 -150.950457) (xy 4.111548 -150.923279) (xy 4.067887 -150.889451) (xy 4.029561 -150.84968)
			(xy 3.99737 -150.804798) (xy 3.984244 -150.780496) (xy 3.97316 -150.760255) (xy 3.944879 -150.723795)
			(xy 3.910482 -150.693038) (xy 3.871098 -150.668996) (xy 3.828021 -150.652459) (xy 3.782666 -150.643969)
			(xy 3.736524 -150.643806) (xy 3.691111 -150.651975) (xy 3.647918 -150.668208) (xy 3.627882 -150.679658)
			(xy 3.603951 -150.693449) (xy 3.55299 -150.714747) (xy 3.499491 -150.728474) (xy 3.444571 -150.734343)
			(xy 3.389379 -150.73223) (xy 3.335069 -150.72218) (xy 3.282775 -150.704403) (xy 3.233592 -150.679271)
			(xy 3.188547 -150.647309) (xy 3.148582 -150.609186) (xy 3.114533 -150.565697) (xy 3.08711 -150.517753)
			(xy 3.066889 -150.466356) (xy 3.05429 -150.412579) (xy 3.049578 -150.357548) (xy 1.7399 -150.357548)
			(xy 1.7399 -151.331168) (xy 5.175756 -151.331168) (xy 5.179827 -151.275546) (xy 5.191953 -151.221109)
			(xy 5.211876 -151.169018) (xy 5.239172 -151.120383) (xy 5.273258 -151.07624) (xy 5.313407 -151.037531)
			(xy 5.358765 -151.00508) (xy 5.408365 -150.979579) (xy 5.461149 -150.961572) (xy 5.515992 -150.951442)
			(xy 5.571726 -150.949405) (xy 5.627163 -150.955505) (xy 5.68112 -150.969611) (xy 5.732449 -150.991423)
			(xy 5.780055 -151.020477) (xy 5.822923 -151.056152) (xy 5.86014 -151.097689) (xy 5.890913 -151.144202)
			(xy 5.914585 -151.194699) (xy 5.930653 -151.248106) (xy 5.938773 -151.303282) (xy 5.939282 -151.331168)
			(xy 5.938773 -151.359054) (xy 5.930653 -151.41423) (xy 5.914585 -151.467637) (xy 5.890913 -151.518134)
			(xy 5.86014 -151.564647) (xy 5.822923 -151.606184) (xy 5.780055 -151.641859) (xy 5.732449 -151.670913)
			(xy 5.68112 -151.692725) (xy 5.627163 -151.706831) (xy 5.594819 -151.71039) (xy 8.365742 -151.71039)
			(xy 8.369813 -151.654768) (xy 8.381939 -151.600331) (xy 8.401862 -151.54824) (xy 8.429158 -151.499605)
			(xy 8.463244 -151.455462) (xy 8.503393 -151.416753) (xy 8.548751 -151.384302) (xy 8.598351 -151.358801)
			(xy 8.651135 -151.340794) (xy 8.705978 -151.330664) (xy 8.761712 -151.328627) (xy 8.817149 -151.334727)
			(xy 8.871106 -151.348833) (xy 8.922435 -151.370645) (xy 8.970041 -151.399699) (xy 9.012909 -151.435374)
			(xy 9.050126 -151.476911) (xy 9.080899 -151.523424) (xy 9.104571 -151.573921) (xy 9.120639 -151.627328)
			(xy 9.128759 -151.682504) (xy 9.129268 -151.71039) (xy 9.128759 -151.738276) (xy 9.120639 -151.793452)
			(xy 9.104571 -151.846859) (xy 9.080899 -151.897356) (xy 9.050126 -151.943869) (xy 9.012909 -151.985406)
			(xy 8.970041 -152.021081) (xy 8.922435 -152.050135) (xy 8.871106 -152.071947) (xy 8.817149 -152.086053)
			(xy 8.761712 -152.092153) (xy 8.705978 -152.090116) (xy 8.651135 -152.079986) (xy 8.598351 -152.061979)
			(xy 8.548751 -152.036478) (xy 8.503393 -152.004027) (xy 8.463244 -151.965318) (xy 8.429158 -151.921175)
			(xy 8.401862 -151.87254) (xy 8.381939 -151.820449) (xy 8.369813 -151.766012) (xy 8.365742 -151.71039)
			(xy 5.594819 -151.71039) (xy 5.571726 -151.712931) (xy 5.515992 -151.710894) (xy 5.461149 -151.700764)
			(xy 5.408365 -151.682757) (xy 5.358765 -151.657256) (xy 5.313407 -151.624805) (xy 5.273258 -151.586096)
			(xy 5.239172 -151.541953) (xy 5.211876 -151.493318) (xy 5.191953 -151.441227) (xy 5.179827 -151.38679)
			(xy 5.175756 -151.331168) (xy 1.7399 -151.331168) (xy 1.7399 -152.897078) (xy 3.300982 -152.897078)
			(xy 3.305053 -152.841456) (xy 3.317179 -152.787019) (xy 3.337102 -152.734928) (xy 3.364398 -152.686293)
			(xy 3.398484 -152.64215) (xy 3.438633 -152.603441) (xy 3.483991 -152.57099) (xy 3.533591 -152.545489)
			(xy 3.586375 -152.527482) (xy 3.641218 -152.517352) (xy 3.696952 -152.515315) (xy 3.752389 -152.521415)
			(xy 3.806346 -152.535521) (xy 3.857675 -152.557333) (xy 3.905281 -152.586387) (xy 3.948149 -152.622062)
			(xy 3.985366 -152.663599) (xy 4.016139 -152.710112) (xy 4.039811 -152.760609) (xy 4.055879 -152.814016)
			(xy 4.063999 -152.869192) (xy 4.064508 -152.897078) (xy 4.063999 -152.924964) (xy 4.059244 -152.957276)
			(xy 6.798562 -152.957276) (xy 6.802633 -152.901654) (xy 6.814759 -152.847217) (xy 6.834682 -152.795126)
			(xy 6.861978 -152.746491) (xy 6.896064 -152.702348) (xy 6.936213 -152.663639) (xy 6.981571 -152.631188)
			(xy 7.031171 -152.605687) (xy 7.083955 -152.58768) (xy 7.138798 -152.57755) (xy 7.194532 -152.575513)
			(xy 7.249969 -152.581613) (xy 7.303926 -152.595719) (xy 7.355255 -152.617531) (xy 7.402861 -152.646585)
			(xy 7.445729 -152.68226) (xy 7.482946 -152.723797) (xy 7.513719 -152.77031) (xy 7.537391 -152.820807)
			(xy 7.553459 -152.874214) (xy 7.561579 -152.92939) (xy 7.562088 -152.957276) (xy 7.561912 -152.966928)
			(xy 8.035542 -152.966928) (xy 8.039613 -152.911306) (xy 8.051739 -152.856869) (xy 8.071662 -152.804778)
			(xy 8.098958 -152.756143) (xy 8.133044 -152.712) (xy 8.173193 -152.673291) (xy 8.218551 -152.64084)
			(xy 8.268151 -152.615339) (xy 8.320935 -152.597332) (xy 8.375778 -152.587202) (xy 8.431512 -152.585165)
			(xy 8.486949 -152.591265) (xy 8.540906 -152.605371) (xy 8.592235 -152.627183) (xy 8.639841 -152.656237)
			(xy 8.682709 -152.691912) (xy 8.719926 -152.733449) (xy 8.750699 -152.779962) (xy 8.774371 -152.830459)
			(xy 8.790439 -152.883866) (xy 8.798559 -152.939042) (xy 8.799068 -152.966928) (xy 8.798559 -152.994814)
			(xy 8.790439 -153.04999) (xy 8.774371 -153.103397) (xy 8.750699 -153.153894) (xy 8.719926 -153.200407)
			(xy 8.682709 -153.241944) (xy 8.639841 -153.277619) (xy 8.592235 -153.306673) (xy 8.540906 -153.328485)
			(xy 8.486949 -153.342591) (xy 8.431512 -153.348691) (xy 8.375778 -153.346654) (xy 8.320935 -153.336524)
			(xy 8.268151 -153.318517) (xy 8.218551 -153.293016) (xy 8.173193 -153.260565) (xy 8.133044 -153.221856)
			(xy 8.098958 -153.177713) (xy 8.071662 -153.129078) (xy 8.051739 -153.076987) (xy 8.039613 -153.02255)
			(xy 8.035542 -152.966928) (xy 7.561912 -152.966928) (xy 7.561579 -152.985162) (xy 7.553459 -153.040338)
			(xy 7.537391 -153.093745) (xy 7.513719 -153.144242) (xy 7.482946 -153.190755) (xy 7.445729 -153.232292)
			(xy 7.402861 -153.267967) (xy 7.355255 -153.297021) (xy 7.303926 -153.318833) (xy 7.249969 -153.332939)
			(xy 7.194532 -153.339039) (xy 7.138798 -153.337002) (xy 7.083955 -153.326872) (xy 7.031171 -153.308865)
			(xy 6.981571 -153.283364) (xy 6.936213 -153.250913) (xy 6.896064 -153.212204) (xy 6.861978 -153.168061)
			(xy 6.834682 -153.119426) (xy 6.814759 -153.067335) (xy 6.802633 -153.012898) (xy 6.798562 -152.957276)
			(xy 4.059244 -152.957276) (xy 4.055879 -152.98014) (xy 4.039811 -153.033547) (xy 4.016139 -153.084044)
			(xy 3.985366 -153.130557) (xy 3.948149 -153.172094) (xy 3.905281 -153.207769) (xy 3.857675 -153.236823)
			(xy 3.806346 -153.258635) (xy 3.752389 -153.272741) (xy 3.696952 -153.278841) (xy 3.641218 -153.276804)
			(xy 3.586375 -153.266674) (xy 3.533591 -153.248667) (xy 3.483991 -153.223166) (xy 3.438633 -153.190715)
			(xy 3.398484 -153.152006) (xy 3.364398 -153.107863) (xy 3.337102 -153.059228) (xy 3.317179 -153.007137)
			(xy 3.305053 -152.9527) (xy 3.300982 -152.897078) (xy 1.7399 -152.897078) (xy 1.7399 -153.55833)
			(xy 9.615329 -153.55833) (xy 9.620508 -153.503394) (xy 9.633545 -153.449777) (xy 9.654167 -153.398596)
			(xy 9.681945 -153.350918) (xy 9.7163 -153.307738) (xy 9.736074 -153.288492) (xy 9.752498 -153.27242)
			(xy 9.779783 -153.235449) (xy 9.799972 -153.194173) (xy 9.812406 -153.149938) (xy 9.81668 -153.104187)
			(xy 9.812653 -153.058415) (xy 9.800459 -153.014113) (xy 9.780493 -152.972728) (xy 9.753408 -152.93561)
			(xy 9.73709 -152.91943) (xy 9.717424 -152.900074) (xy 9.683321 -152.856696) (xy 9.655821 -152.808858)
			(xy 9.635496 -152.757559) (xy 9.62277 -152.703868) (xy 9.61791 -152.648903) (xy 9.621015 -152.593812)
			(xy 9.632022 -152.539742) (xy 9.650701 -152.487821) (xy 9.676662 -152.439131) (xy 9.709365 -152.394688)
			(xy 9.748127 -152.355417) (xy 9.79214 -152.322137) (xy 9.840487 -152.295543) (xy 9.89216 -152.276188)
			(xy 9.946082 -152.264477) (xy 10.001128 -152.260653) (xy 10.056151 -152.264796) (xy 10.110004 -152.27682)
			(xy 10.161564 -152.296473) (xy 10.209756 -152.323348) (xy 10.253575 -152.356882) (xy 10.292109 -152.396377)
			(xy 10.324553 -152.441009) (xy 10.350232 -152.489849) (xy 10.368609 -152.541877) (xy 10.379302 -152.59601)
			(xy 10.382088 -152.651119) (xy 10.376909 -152.706054) (xy 10.363873 -152.75967) (xy 10.343251 -152.810851)
			(xy 10.315474 -152.858528) (xy 10.28112 -152.901708) (xy 10.261346 -152.920954) (xy 10.244935 -152.937039)
			(xy 10.217649 -152.974007) (xy 10.197458 -153.015281) (xy 10.185023 -153.059514) (xy 10.180747 -153.105263)
			(xy 10.181202 -153.110438) (xy 10.755882 -153.110438) (xy 10.759953 -153.054816) (xy 10.772079 -153.000379)
			(xy 10.792002 -152.948288) (xy 10.819298 -152.899653) (xy 10.853384 -152.85551) (xy 10.893533 -152.816801)
			(xy 10.938891 -152.78435) (xy 10.988491 -152.758849) (xy 11.041275 -152.740842) (xy 11.096118 -152.730712)
			(xy 11.151852 -152.728675) (xy 11.207289 -152.734775) (xy 11.261246 -152.748881) (xy 11.312575 -152.770693)
			(xy 11.360181 -152.799747) (xy 11.403049 -152.835422) (xy 11.440266 -152.876959) (xy 11.471039 -152.923472)
			(xy 11.494711 -152.973969) (xy 11.510779 -153.027376) (xy 11.518899 -153.082552) (xy 11.519408 -153.110438)
			(xy 11.518899 -153.138324) (xy 11.510779 -153.1935) (xy 11.494711 -153.246907) (xy 11.471039 -153.297404)
			(xy 11.440266 -153.343917) (xy 11.403049 -153.385454) (xy 11.360181 -153.421129) (xy 11.312575 -153.450183)
			(xy 11.261246 -153.471995) (xy 11.207289 -153.486101) (xy 11.151852 -153.492201) (xy 11.096118 -153.490164)
			(xy 11.041275 -153.480034) (xy 10.988491 -153.462027) (xy 10.938891 -153.436526) (xy 10.893533 -153.404075)
			(xy 10.853384 -153.365366) (xy 10.819298 -153.321223) (xy 10.792002 -153.272588) (xy 10.772079 -153.220497)
			(xy 10.759953 -153.16606) (xy 10.755882 -153.110438) (xy 10.181202 -153.110438) (xy 10.184772 -153.151034)
			(xy 10.196965 -153.195335) (xy 10.216929 -153.236719) (xy 10.244012 -153.273836) (xy 10.26033 -153.290016)
			(xy 10.279996 -153.309372) (xy 10.3141 -153.352751) (xy 10.341601 -153.400588) (xy 10.361926 -153.451888)
			(xy 10.374652 -153.50558) (xy 10.379513 -153.560545) (xy 10.376408 -153.615637) (xy 10.365401 -153.669707)
			(xy 10.346722 -153.721629) (xy 10.320761 -153.770319) (xy 10.288058 -153.814764) (xy 10.249296 -153.854035)
			(xy 10.205282 -153.887315) (xy 10.156935 -153.91391) (xy 10.105261 -153.933264) (xy 10.051339 -153.944976)
			(xy 9.996292 -153.9488) (xy 9.941269 -153.944657) (xy 9.887415 -153.932633) (xy 9.835855 -153.912979)
			(xy 9.787662 -153.886105) (xy 9.743842 -153.85257) (xy 9.705308 -153.813074) (xy 9.672864 -153.768441)
			(xy 9.647185 -153.719601) (xy 9.628808 -153.667572) (xy 9.618115 -153.613439) (xy 9.615329 -153.55833)
			(xy 1.7399 -153.55833) (xy 1.7399 -155.973832) (xy 3.516963 -155.973832) (xy 3.523686 -155.918458)
			(xy 3.5384 -155.864654) (xy 3.560791 -155.813565) (xy 3.590382 -155.76628) (xy 3.626542 -155.723808)
			(xy 3.647186 -155.705048) (xy 3.663471 -155.69016) (xy 3.691139 -155.655792) (xy 3.712453 -155.617161)
			(xy 3.726773 -155.575429) (xy 3.733668 -155.531851) (xy 3.732931 -155.487736) (xy 3.724583 -155.444413)
			(xy 3.708876 -155.403183) (xy 3.697986 -155.383992) (xy 3.684166 -155.359761) (xy 3.662932 -155.308181)
			(xy 3.649434 -155.254058) (xy 3.643961 -155.198546) (xy 3.646628 -155.14283) (xy 3.657379 -155.088095)
			(xy 3.675985 -155.035509) (xy 3.702049 -154.986193) (xy 3.735016 -154.941196) (xy 3.774183 -154.901479)
			(xy 3.818715 -154.867888) (xy 3.867663 -154.841139) (xy 3.919984 -154.821802) (xy 3.974563 -154.810288)
			(xy 4.030237 -154.806844) (xy 4.08582 -154.811542) (xy 4.140126 -154.824283) (xy 4.191998 -154.844796)
			(xy 4.24033 -154.872642) (xy 4.284094 -154.907228) (xy 4.322355 -154.947818) (xy 4.354299 -154.993546)
			(xy 4.379244 -155.043438) (xy 4.39666 -155.09643) (xy 4.406174 -155.151393) (xy 4.407585 -155.207156)
			(xy 4.400861 -155.262529) (xy 4.386147 -155.316334) (xy 4.363756 -155.367423) (xy 4.334165 -155.414708)
			(xy 4.298004 -155.45718) (xy 4.283509 -155.470352) (xy 6.776972 -155.470352) (xy 6.781043 -155.41473)
			(xy 6.793169 -155.360293) (xy 6.813092 -155.308202) (xy 6.840388 -155.259567) (xy 6.874474 -155.215424)
			(xy 6.914623 -155.176715) (xy 6.959981 -155.144264) (xy 7.009581 -155.118763) (xy 7.062365 -155.100756)
			(xy 7.117208 -155.090626) (xy 7.172942 -155.088589) (xy 7.228379 -155.094689) (xy 7.282336 -155.108795)
			(xy 7.333665 -155.130607) (xy 7.381271 -155.159661) (xy 7.424139 -155.195336) (xy 7.441604 -155.214828)
			(xy 8.998202 -155.214828) (xy 9.002273 -155.159206) (xy 9.014399 -155.104769) (xy 9.034322 -155.052678)
			(xy 9.061618 -155.004043) (xy 9.095704 -154.9599) (xy 9.135853 -154.921191) (xy 9.181211 -154.88874)
			(xy 9.230811 -154.863239) (xy 9.283595 -154.845232) (xy 9.338438 -154.835102) (xy 9.394172 -154.833065)
			(xy 9.449609 -154.839165) (xy 9.503566 -154.853271) (xy 9.554895 -154.875083) (xy 9.602501 -154.904137)
			(xy 9.645369 -154.939812) (xy 9.682586 -154.981349) (xy 9.713359 -155.027862) (xy 9.737031 -155.078359)
			(xy 9.753099 -155.131766) (xy 9.761219 -155.186942) (xy 9.761728 -155.214828) (xy 9.761219 -155.242714)
			(xy 9.753099 -155.29789) (xy 9.737031 -155.351297) (xy 9.713359 -155.401794) (xy 9.682586 -155.448307)
			(xy 9.645369 -155.489844) (xy 9.602501 -155.525519) (xy 9.554895 -155.554573) (xy 9.514596 -155.571698)
			(xy 10.527282 -155.571698) (xy 10.531353 -155.516076) (xy 10.543479 -155.461639) (xy 10.563402 -155.409548)
			(xy 10.590698 -155.360913) (xy 10.624784 -155.31677) (xy 10.664933 -155.278061) (xy 10.710291 -155.24561)
			(xy 10.759891 -155.220109) (xy 10.812675 -155.202102) (xy 10.867518 -155.191972) (xy 10.923252 -155.189935)
			(xy 10.978689 -155.196035) (xy 11.032646 -155.210141) (xy 11.083975 -155.231953) (xy 11.131581 -155.261007)
			(xy 11.174449 -155.296682) (xy 11.211666 -155.338219) (xy 11.242439 -155.384732) (xy 11.266111 -155.435229)
			(xy 11.282179 -155.488636) (xy 11.290299 -155.543812) (xy 11.290808 -155.571698) (xy 11.290299 -155.599584)
			(xy 11.282179 -155.65476) (xy 11.266111 -155.708167) (xy 11.242439 -155.758664) (xy 11.211666 -155.805177)
			(xy 11.174449 -155.846714) (xy 11.131581 -155.882389) (xy 11.083975 -155.911443) (xy 11.032646 -155.933255)
			(xy 10.978689 -155.947361) (xy 10.923252 -155.953461) (xy 10.867518 -155.951424) (xy 10.812675 -155.941294)
			(xy 10.759891 -155.923287) (xy 10.710291 -155.897786) (xy 10.664933 -155.865335) (xy 10.624784 -155.826626)
			(xy 10.590698 -155.782483) (xy 10.563402 -155.733848) (xy 10.543479 -155.681757) (xy 10.531353 -155.62732)
			(xy 10.527282 -155.571698) (xy 9.514596 -155.571698) (xy 9.503566 -155.576385) (xy 9.449609 -155.590491)
			(xy 9.394172 -155.596591) (xy 9.338438 -155.594554) (xy 9.283595 -155.584424) (xy 9.230811 -155.566417)
			(xy 9.181211 -155.540916) (xy 9.135853 -155.508465) (xy 9.095704 -155.469756) (xy 9.061618 -155.425613)
			(xy 9.034322 -155.376978) (xy 9.014399 -155.324887) (xy 9.002273 -155.27045) (xy 8.998202 -155.214828)
			(xy 7.441604 -155.214828) (xy 7.461356 -155.236873) (xy 7.492129 -155.283386) (xy 7.515801 -155.333883)
			(xy 7.531869 -155.38729) (xy 7.539989 -155.442466) (xy 7.540498 -155.470352) (xy 7.539989 -155.498238)
			(xy 7.531869 -155.553414) (xy 7.515801 -155.606821) (xy 7.492129 -155.657318) (xy 7.461356 -155.703831)
			(xy 7.424139 -155.745368) (xy 7.381271 -155.781043) (xy 7.333665 -155.810097) (xy 7.282336 -155.831909)
			(xy 7.228379 -155.846015) (xy 7.172942 -155.852115) (xy 7.117208 -155.850078) (xy 7.062365 -155.839948)
			(xy 7.009581 -155.821941) (xy 6.959981 -155.79644) (xy 6.914623 -155.763989) (xy 6.874474 -155.72528)
			(xy 6.840388 -155.681137) (xy 6.813092 -155.632502) (xy 6.793169 -155.580411) (xy 6.781043 -155.525974)
			(xy 6.776972 -155.470352) (xy 4.283509 -155.470352) (xy 4.27736 -155.47594) (xy 4.261076 -155.49083)
			(xy 4.233409 -155.525197) (xy 4.212095 -155.563828) (xy 4.197775 -155.605559) (xy 4.19088 -155.649138)
			(xy 4.191617 -155.693252) (xy 4.199964 -155.736575) (xy 4.21567 -155.777805) (xy 4.22656 -155.796996)
			(xy 4.240381 -155.821226) (xy 4.261615 -155.872807) (xy 4.275112 -155.926929) (xy 4.280585 -155.98244)
			(xy 4.277918 -156.038157) (xy 4.267167 -156.092891) (xy 4.248561 -156.145477) (xy 4.226944 -156.186378)
			(xy 12.884402 -156.186378) (xy 12.888473 -156.130756) (xy 12.900599 -156.076319) (xy 12.920522 -156.024228)
			(xy 12.947818 -155.975593) (xy 12.981904 -155.93145) (xy 13.022053 -155.892741) (xy 13.067411 -155.86029)
			(xy 13.117011 -155.834789) (xy 13.169795 -155.816782) (xy 13.224638 -155.806652) (xy 13.280372 -155.804615)
			(xy 13.335809 -155.810715) (xy 13.389766 -155.824821) (xy 13.441095 -155.846633) (xy 13.488701 -155.875687)
			(xy 13.531569 -155.911362) (xy 13.551992 -155.934156) (xy 15.764762 -155.934156) (xy 15.768833 -155.878534)
			(xy 15.780959 -155.824097) (xy 15.800882 -155.772006) (xy 15.828178 -155.723371) (xy 15.862264 -155.679228)
			(xy 15.902413 -155.640519) (xy 15.947771 -155.608068) (xy 15.997371 -155.582567) (xy 16.050155 -155.56456)
			(xy 16.104998 -155.55443) (xy 16.160732 -155.552393) (xy 16.216169 -155.558493) (xy 16.270126 -155.572599)
			(xy 16.321455 -155.594411) (xy 16.369061 -155.623465) (xy 16.411929 -155.65914) (xy 16.449146 -155.700677)
			(xy 16.479919 -155.74719) (xy 16.503591 -155.797687) (xy 16.519659 -155.851094) (xy 16.527779 -155.90627)
			(xy 16.528288 -155.934156) (xy 16.527779 -155.962042) (xy 16.519659 -156.017218) (xy 16.503591 -156.070625)
			(xy 16.479919 -156.121122) (xy 16.449146 -156.167635) (xy 16.411929 -156.209172) (xy 16.369061 -156.244847)
			(xy 16.321455 -156.273901) (xy 16.270126 -156.295713) (xy 16.216169 -156.309819) (xy 16.160732 -156.315919)
			(xy 16.104998 -156.313882) (xy 16.050155 -156.303752) (xy 15.997371 -156.285745) (xy 15.947771 -156.260244)
			(xy 15.902413 -156.227793) (xy 15.862264 -156.189084) (xy 15.828178 -156.144941) (xy 15.800882 -156.096306)
			(xy 15.780959 -156.044215) (xy 15.768833 -155.989778) (xy 15.764762 -155.934156) (xy 13.551992 -155.934156)
			(xy 13.568786 -155.952899) (xy 13.599559 -155.999412) (xy 13.623231 -156.049909) (xy 13.639299 -156.103316)
			(xy 13.647419 -156.158492) (xy 13.647928 -156.186378) (xy 13.647419 -156.214264) (xy 13.639299 -156.26944)
			(xy 13.623231 -156.322847) (xy 13.599559 -156.373344) (xy 13.568786 -156.419857) (xy 13.531569 -156.461394)
			(xy 13.488701 -156.497069) (xy 13.441095 -156.526123) (xy 13.389766 -156.547935) (xy 13.335809 -156.562041)
			(xy 13.280372 -156.568141) (xy 13.224638 -156.566104) (xy 13.169795 -156.555974) (xy 13.117011 -156.537967)
			(xy 13.067411 -156.512466) (xy 13.022053 -156.480015) (xy 12.981904 -156.441306) (xy 12.947818 -156.397163)
			(xy 12.920522 -156.348528) (xy 12.900599 -156.296437) (xy 12.888473 -156.242) (xy 12.884402 -156.186378)
			(xy 4.226944 -156.186378) (xy 4.222497 -156.194793) (xy 4.18953 -156.239789) (xy 4.150364 -156.279506)
			(xy 4.105832 -156.313097) (xy 4.056884 -156.339846) (xy 4.004563 -156.359184) (xy 3.949984 -156.370697)
			(xy 3.89431 -156.374141) (xy 3.838728 -156.369443) (xy 3.784422 -156.356702) (xy 3.73255 -156.33619)
			(xy 3.684218 -156.308344) (xy 3.640454 -156.273758) (xy 3.602193 -156.233168) (xy 3.570249 -156.18744)
			(xy 3.545304 -156.137549) (xy 3.527888 -156.084557) (xy 3.518374 -156.029594) (xy 3.516963 -155.973832)
			(xy 1.7399 -155.973832) (xy 1.7399 -156.960824) (xy 2.660902 -156.960824) (xy 2.664973 -156.905202)
			(xy 2.677099 -156.850765) (xy 2.697022 -156.798674) (xy 2.724318 -156.750039) (xy 2.758404 -156.705896)
			(xy 2.798553 -156.667187) (xy 2.843911 -156.634736) (xy 2.893511 -156.609235) (xy 2.946295 -156.591228)
			(xy 3.001138 -156.581098) (xy 3.056872 -156.579061) (xy 3.112309 -156.585161) (xy 3.166266 -156.599267)
			(xy 3.217595 -156.621079) (xy 3.265201 -156.650133) (xy 3.308069 -156.685808) (xy 3.345286 -156.727345)
			(xy 3.376059 -156.773858) (xy 3.399731 -156.824355) (xy 3.415799 -156.877762) (xy 3.423919 -156.932938)
			(xy 3.424159 -156.946092) (xy 7.426958 -156.946092) (xy 7.431029 -156.89047) (xy 7.443155 -156.836033)
			(xy 7.463078 -156.783942) (xy 7.490374 -156.735307) (xy 7.52446 -156.691164) (xy 7.564609 -156.652455)
			(xy 7.609967 -156.620004) (xy 7.659567 -156.594503) (xy 7.712351 -156.576496) (xy 7.767194 -156.566366)
			(xy 7.822928 -156.564329) (xy 7.878365 -156.570429) (xy 7.932322 -156.584535) (xy 7.983651 -156.606347)
			(xy 8.031257 -156.635401) (xy 8.074125 -156.671076) (xy 8.111342 -156.712613) (xy 8.123644 -156.731208)
			(xy 8.72693 -156.731208) (xy 8.731001 -156.675586) (xy 8.743127 -156.621149) (xy 8.76305 -156.569058)
			(xy 8.790346 -156.520423) (xy 8.824432 -156.47628) (xy 8.864581 -156.437571) (xy 8.909939 -156.40512)
			(xy 8.959539 -156.379619) (xy 9.012323 -156.361612) (xy 9.067166 -156.351482) (xy 9.1229 -156.349445)
			(xy 9.178337 -156.355545) (xy 9.232294 -156.369651) (xy 9.283623 -156.391463) (xy 9.331229 -156.420517)
			(xy 9.374097 -156.456192) (xy 9.411314 -156.497729) (xy 9.442087 -156.544242) (xy 9.465759 -156.594739)
			(xy 9.481827 -156.648146) (xy 9.486425 -156.679392) (xy 11.677902 -156.679392) (xy 11.681973 -156.62377)
			(xy 11.694099 -156.569333) (xy 11.714022 -156.517242) (xy 11.741318 -156.468607) (xy 11.775404 -156.424464)
			(xy 11.815553 -156.385755) (xy 11.860911 -156.353304) (xy 11.910511 -156.327803) (xy 11.963295 -156.309796)
			(xy 12.018138 -156.299666) (xy 12.073872 -156.297629) (xy 12.129309 -156.303729) (xy 12.183266 -156.317835)
			(xy 12.234595 -156.339647) (xy 12.282201 -156.368701) (xy 12.325069 -156.404376) (xy 12.362286 -156.445913)
			(xy 12.393059 -156.492426) (xy 12.416731 -156.542923) (xy 12.432799 -156.59633) (xy 12.440919 -156.651506)
			(xy 12.441428 -156.679392) (xy 12.440919 -156.707278) (xy 12.432799 -156.762454) (xy 12.416731 -156.815861)
			(xy 12.393059 -156.866358) (xy 12.362286 -156.912871) (xy 12.325069 -156.954408) (xy 12.282201 -156.990083)
			(xy 12.234595 -157.019137) (xy 12.183266 -157.040949) (xy 12.129309 -157.055055) (xy 12.073872 -157.061155)
			(xy 12.018138 -157.059118) (xy 11.963295 -157.048988) (xy 11.910511 -157.030981) (xy 11.860911 -157.00548)
			(xy 11.815553 -156.973029) (xy 11.775404 -156.93432) (xy 11.741318 -156.890177) (xy 11.714022 -156.841542)
			(xy 11.694099 -156.789451) (xy 11.681973 -156.735014) (xy 11.677902 -156.679392) (xy 9.486425 -156.679392)
			(xy 9.489947 -156.703322) (xy 9.490456 -156.731208) (xy 9.489947 -156.759094) (xy 9.481827 -156.81427)
			(xy 9.465759 -156.867677) (xy 9.442087 -156.918174) (xy 9.411314 -156.964687) (xy 9.374097 -157.006224)
			(xy 9.331229 -157.041899) (xy 9.283623 -157.070953) (xy 9.232294 -157.092765) (xy 9.178337 -157.106871)
			(xy 9.1229 -157.112971) (xy 9.067166 -157.110934) (xy 9.012323 -157.100804) (xy 8.959539 -157.082797)
			(xy 8.909939 -157.057296) (xy 8.864581 -157.024845) (xy 8.824432 -156.986136) (xy 8.790346 -156.941993)
			(xy 8.76305 -156.893358) (xy 8.743127 -156.841267) (xy 8.731001 -156.78683) (xy 8.72693 -156.731208)
			(xy 8.123644 -156.731208) (xy 8.142115 -156.759126) (xy 8.165787 -156.809623) (xy 8.181855 -156.86303)
			(xy 8.189975 -156.918206) (xy 8.190484 -156.946092) (xy 8.189975 -156.973978) (xy 8.181855 -157.029154)
			(xy 8.165787 -157.082561) (xy 8.142115 -157.133058) (xy 8.111342 -157.179571) (xy 8.074125 -157.221108)
			(xy 8.031257 -157.256783) (xy 7.983651 -157.285837) (xy 7.932322 -157.307649) (xy 7.878365 -157.321755)
			(xy 7.822928 -157.327855) (xy 7.767194 -157.325818) (xy 7.712351 -157.315688) (xy 7.659567 -157.297681)
			(xy 7.609967 -157.27218) (xy 7.564609 -157.239729) (xy 7.52446 -157.20102) (xy 7.490374 -157.156877)
			(xy 7.463078 -157.108242) (xy 7.443155 -157.056151) (xy 7.431029 -157.001714) (xy 7.426958 -156.946092)
			(xy 3.424159 -156.946092) (xy 3.424428 -156.960824) (xy 3.423919 -156.98871) (xy 3.415799 -157.043886)
			(xy 3.399731 -157.097293) (xy 3.376059 -157.14779) (xy 3.345286 -157.194303) (xy 3.308069 -157.23584)
			(xy 3.265201 -157.271515) (xy 3.217595 -157.300569) (xy 3.166266 -157.322381) (xy 3.112309 -157.336487)
			(xy 3.056872 -157.342587) (xy 3.001138 -157.34055) (xy 2.946295 -157.33042) (xy 2.893511 -157.312413)
			(xy 2.843911 -157.286912) (xy 2.798553 -157.254461) (xy 2.758404 -157.215752) (xy 2.724318 -157.171609)
			(xy 2.697022 -157.122974) (xy 2.677099 -157.070883) (xy 2.664973 -157.016446) (xy 2.660902 -156.960824)
			(xy 1.7399 -156.960824) (xy 1.7399 -157.802518) (xy 11.825404 -157.802518) (xy 11.82797 -157.74682)
			(xy 11.838615 -157.692088) (xy 11.857114 -157.639489) (xy 11.883072 -157.590142) (xy 11.915937 -157.5451)
			(xy 11.955008 -157.505321) (xy 11.999453 -157.471653) (xy 12.048325 -157.444813) (xy 12.100584 -157.425372)
			(xy 12.155116 -157.413746) (xy 12.210759 -157.410181) (xy 12.266329 -157.414753) (xy 12.2936 -157.420564)
			(xy 12.315036 -157.424985) (xy 12.35873 -157.427422) (xy 12.402195 -157.422336) (xy 12.444146 -157.409877)
			(xy 12.483341 -157.390414) (xy 12.518621 -157.364522) (xy 12.548943 -157.332968) (xy 12.57341 -157.296685)
			(xy 12.591297 -157.256746) (xy 12.59713 -157.235652) (xy 12.60448 -157.208643) (xy 12.62601 -157.156976)
			(xy 12.654859 -157.109009) (xy 12.690407 -157.065772) (xy 12.731891 -157.028194) (xy 12.77842 -156.99708)
			(xy 12.828997 -156.973099) (xy 12.882535 -156.956766) (xy 12.937884 -156.94843) (xy 12.993858 -156.948272)
			(xy 13.049254 -156.956294) (xy 13.102883 -156.972324) (xy 13.153594 -156.996018) (xy 13.2003 -157.026867)
			(xy 13.241996 -157.06421) (xy 13.277788 -157.107245) (xy 13.306908 -157.155047) (xy 13.328731 -157.206592)
			(xy 13.342788 -157.260772) (xy 13.348778 -157.316424) (xy 13.346571 -157.372354) (xy 13.336216 -157.427362)
			(xy 13.317935 -157.480266) (xy 13.292119 -157.529931) (xy 13.259324 -157.575291) (xy 13.220253 -157.615373)
			(xy 13.175745 -157.649315) (xy 13.126754 -157.676389) (xy 13.074334 -157.696015) (xy 13.019609 -157.70777)
			(xy 12.963753 -157.711404) (xy 12.907966 -157.706836) (xy 12.880594 -157.70098) (xy 12.859164 -157.69652)
			(xy 12.815466 -157.694083) (xy 12.771997 -157.699171) (xy 12.730043 -157.711633) (xy 12.690845 -157.731101)
			(xy 12.655563 -157.756998) (xy 12.625241 -157.788559) (xy 12.600777 -157.824849) (xy 12.582894 -157.864795)
			(xy 12.577064 -157.885892) (xy 12.569156 -157.914884) (xy 12.545473 -157.970111) (xy 12.513407 -158.020931)
			(xy 12.494006 -158.04388) (xy 12.48006 -158.060343) (xy 12.457458 -158.097095) (xy 12.441396 -158.137139)
			(xy 12.432339 -158.179323) (xy 12.430547 -158.222431) (xy 12.436071 -158.265222) (xy 12.448752 -158.306461)
			(xy 12.468225 -158.344962) (xy 12.493928 -158.379616) (xy 12.525123 -158.409422) (xy 12.542774 -158.421832)
			(xy 12.565362 -158.437699) (xy 12.585151 -158.455729) (xy 15.164285 -158.455729) (xy 15.169485 -158.399798)
			(xy 15.182831 -158.345233) (xy 15.204035 -158.293216) (xy 15.232637 -158.244871) (xy 15.26802 -158.201243)
			(xy 15.309419 -158.163275) (xy 15.355938 -158.131789) (xy 15.406571 -158.107466) (xy 15.460224 -158.090831)
			(xy 15.487904 -158.086044) (xy 15.510696 -158.081984) (xy 15.554412 -158.066767) (xy 15.594646 -158.043877)
			(xy 15.630064 -158.014074) (xy 15.659494 -157.978344) (xy 15.681959 -157.937872) (xy 15.696716 -157.893998)
			(xy 15.700502 -157.87116) (xy 15.705206 -157.84257) (xy 15.722089 -157.787146) (xy 15.747149 -157.734909)
			(xy 15.779812 -157.687055) (xy 15.819328 -157.644684) (xy 15.841726 -157.626304) (xy 15.854612 -157.615454)
			(xy 15.874691 -157.588424) (xy 15.887003 -157.557084) (xy 15.890689 -157.523614) (xy 15.885493 -157.490345)
			(xy 15.871777 -157.459593) (xy 15.861538 -157.446218) (xy 15.844604 -157.424735) (xy 15.816409 -157.377859)
			(xy 15.795199 -157.327438) (xy 15.781406 -157.274504) (xy 15.775315 -157.220142) (xy 15.77705 -157.165469)
			(xy 15.786575 -157.111603) (xy 15.803695 -157.05965) (xy 15.82806 -157.010674) (xy 15.859169 -156.96568)
			(xy 15.896385 -156.92559) (xy 15.938946 -156.891226) (xy 15.985977 -156.863293) (xy 16.036516 -156.842363)
			(xy 16.089526 -156.828865) (xy 16.14392 -156.823076) (xy 16.198584 -156.825115) (xy 16.252396 -156.834939)
			(xy 16.304253 -156.852348) (xy 16.353092 -156.876985) (xy 16.397912 -156.908344) (xy 16.437795 -156.945782)
			(xy 16.471921 -156.988533) (xy 16.499593 -157.035719) (xy 16.520242 -157.086373) (xy 16.533445 -157.139458)
			(xy 16.538931 -157.193883) (xy 16.536589 -157.248534) (xy 16.526465 -157.302291) (xy 16.508768 -157.354051)
			(xy 16.48386 -157.402752) (xy 16.452253 -157.447397) (xy 16.414593 -157.487071) (xy 16.393414 -157.504384)
			(xy 16.38054 -157.515248) (xy 16.360455 -157.542272) (xy 16.348138 -157.57361) (xy 16.344449 -157.607079)
			(xy 16.349645 -157.640346) (xy 16.363362 -157.671097) (xy 16.373602 -157.68447) (xy 16.390234 -157.70542)
			(xy 16.417949 -157.751174) (xy 16.439 -157.800352) (xy 16.452973 -157.851988) (xy 16.459596 -157.90507)
			(xy 16.458738 -157.958557) (xy 16.450415 -158.011399) (xy 16.434792 -158.06256) (xy 16.412174 -158.111037)
			(xy 16.383005 -158.155879) (xy 16.347858 -158.196205) (xy 16.307422 -158.231226) (xy 16.262489 -158.260254)
			(xy 16.213941 -158.282719) (xy 16.162731 -158.298182) (xy 16.136366 -158.302706) (xy 16.113578 -158.306785)
			(xy 16.069865 -158.322003) (xy 16.029634 -158.344891) (xy 15.994218 -158.374692) (xy 15.964788 -158.410417)
			(xy 15.94232 -158.450885) (xy 15.927558 -158.494754) (xy 15.923768 -158.51759) (xy 15.919257 -158.545316)
			(xy 15.903157 -158.599132) (xy 15.879339 -158.650005) (xy 15.848317 -158.696835) (xy 15.810764 -158.73861)
			(xy 15.76749 -158.774425) (xy 15.719432 -158.803508) (xy 15.667629 -158.825228) (xy 15.6132 -158.839117)
			(xy 15.557323 -158.844873) (xy 15.501206 -158.842373) (xy 15.446062 -158.831671) (xy 15.393084 -158.812997)
			(xy 15.343417 -158.786756) (xy 15.298136 -158.753516) (xy 15.258219 -158.713994) (xy 15.224529 -158.669045)
			(xy 15.197795 -158.619642) (xy 15.178595 -158.566853) (xy 15.167344 -158.511818) (xy 15.164285 -158.455729)
			(xy 12.585151 -158.455729) (xy 12.606164 -158.474875) (xy 12.641187 -158.517539) (xy 12.669699 -158.564804)
			(xy 12.691107 -158.615682) (xy 12.704963 -158.669113) (xy 12.710979 -158.723983) (xy 12.70903 -158.779147)
			(xy 12.704572 -158.806388) (xy 12.700905 -158.829189) (xy 12.701011 -158.875369) (xy 12.709453 -158.92077)
			(xy 12.725954 -158.9639) (xy 12.749972 -159.003342) (xy 12.780718 -159.037799) (xy 12.817179 -159.066137)
			(xy 12.858159 -159.087426) (xy 12.880086 -159.094678) (xy 12.906161 -159.10314) (xy 12.955748 -159.126512)
			(xy 13.001479 -159.156741) (xy 13.042414 -159.193203) (xy 13.077708 -159.235149) (xy 13.106635 -159.281715)
			(xy 13.128599 -159.331941) (xy 13.143149 -159.384794) (xy 13.149984 -159.439186) (xy 13.148964 -159.493995)
			(xy 13.140109 -159.548095) (xy 13.123603 -159.60037) (xy 13.099785 -159.649744) (xy 13.069145 -159.695201)
			(xy 13.032315 -159.735805) (xy 12.990052 -159.770719) (xy 12.943228 -159.799225) (xy 12.892805 -159.820735)
			(xy 12.839823 -159.834807) (xy 12.785372 -159.841152) (xy 12.730574 -159.839637) (xy 12.676557 -159.830295)
			(xy 12.624433 -159.813318) (xy 12.575275 -159.789056) (xy 12.530097 -159.758007) (xy 12.489827 -159.720812)
			(xy 12.455295 -159.678236) (xy 12.427213 -159.631156) (xy 12.406158 -159.580541) (xy 12.392564 -159.527435)
			(xy 12.386712 -159.472929) (xy 12.38872 -159.418146) (xy 12.393168 -159.391096) (xy 12.396719 -159.368279)
			(xy 12.396627 -159.322111) (xy 12.3882 -159.276718) (xy 12.371715 -159.233593) (xy 12.347713 -159.194154)
			(xy 12.316984 -159.159698) (xy 12.280538 -159.131356) (xy 12.239574 -159.110062) (xy 12.217654 -159.102806)
			(xy 12.191794 -159.094396) (xy 12.142568 -159.071296) (xy 12.097121 -159.041439) (xy 12.056375 -159.005431)
			(xy 12.021157 -158.964) (xy 11.99218 -158.917987) (xy 11.970031 -158.868326) (xy 11.95516 -158.816022)
			(xy 11.947869 -158.762136) (xy 11.948305 -158.707761) (xy 11.956458 -158.653999) (xy 11.972165 -158.60194)
			(xy 11.995107 -158.552639) (xy 12.024817 -158.507097) (xy 12.042394 -158.486348) (xy 12.056309 -158.46986)
			(xy 12.078913 -158.433113) (xy 12.094976 -158.393073) (xy 12.104035 -158.350893) (xy 12.105831 -158.307788)
			(xy 12.100311 -158.265001) (xy 12.087633 -158.223764) (xy 12.068165 -158.185264) (xy 12.042465 -158.150612)
			(xy 12.011275 -158.120806) (xy 11.993626 -158.108396) (xy 11.970867 -158.092284) (xy 11.929705 -158.054672)
			(xy 11.894456 -158.01147) (xy 11.865871 -157.963598) (xy 11.844559 -157.912074) (xy 11.830974 -157.857997)
			(xy 11.825404 -157.802518) (xy 1.7399 -157.802518) (xy 1.7399 -159.587438) (xy 3.313682 -159.587438)
			(xy 3.317753 -159.531816) (xy 3.329879 -159.477379) (xy 3.349802 -159.425288) (xy 3.377098 -159.376653)
			(xy 3.411184 -159.33251) (xy 3.451333 -159.293801) (xy 3.496691 -159.26135) (xy 3.546291 -159.235849)
			(xy 3.599075 -159.217842) (xy 3.653918 -159.207712) (xy 3.709652 -159.205675) (xy 3.765089 -159.211775)
			(xy 3.819046 -159.225881) (xy 3.870375 -159.247693) (xy 3.917981 -159.276747) (xy 3.960849 -159.312422)
			(xy 3.998066 -159.353959) (xy 4.028839 -159.400472) (xy 4.052511 -159.450969) (xy 4.068579 -159.504376)
			(xy 4.076699 -159.559552) (xy 4.077208 -159.587438) (xy 4.076699 -159.615324) (xy 4.068579 -159.6705)
			(xy 4.052511 -159.723907) (xy 4.028839 -159.774404) (xy 3.998066 -159.820917) (xy 3.960849 -159.862454)
			(xy 3.917981 -159.898129) (xy 3.870375 -159.927183) (xy 3.819046 -159.948995) (xy 3.765089 -159.963101)
			(xy 3.709652 -159.969201) (xy 3.653918 -159.967164) (xy 3.599075 -159.957034) (xy 3.546291 -159.939027)
			(xy 3.496691 -159.913526) (xy 3.451333 -159.881075) (xy 3.411184 -159.842366) (xy 3.377098 -159.798223)
			(xy 3.349802 -159.749588) (xy 3.329879 -159.697497) (xy 3.317753 -159.64306) (xy 3.313682 -159.587438)
			(xy 1.7399 -159.587438) (xy 1.7399 -159.875982) (xy 1.740398 -159.898965) (xy 1.748667 -159.944182)
			(xy 1.764933 -159.987175) (xy 1.788664 -160.026542) (xy 1.819087 -160.060999) (xy 1.855211 -160.089425)
			(xy 1.895857 -160.110892) (xy 1.939701 -160.124699) (xy 1.985313 -160.130398) (xy 2.031207 -160.127802)
			(xy 2.075885 -160.116995) (xy 2.117892 -160.098331) (xy 2.137156 -160.085786) (xy 2.16007 -160.069661)
			(xy 2.209662 -160.043585) (xy 2.262534 -160.025043) (xy 2.317549 -160.014433) (xy 2.373525 -160.011983)
			(xy 2.429257 -160.017745) (xy 2.483548 -160.031597) (xy 2.484424 -160.031964) (xy 13.903107 -160.031964)
			(xy 13.908373 -159.976853) (xy 13.92155 -159.923082) (xy 13.942363 -159.871781) (xy 13.970373 -159.824028)
			(xy 14.004993 -159.780826) (xy 14.045494 -159.743083) (xy 14.091027 -159.711591) (xy 14.140634 -159.687013)
			(xy 14.193273 -159.669864) (xy 14.247839 -159.660506) (xy 14.303183 -159.659134) (xy 14.358145 -159.665778)
			(xy 14.411569 -159.680297) (xy 14.462333 -159.702388) (xy 14.50937 -159.731585) (xy 14.551692 -159.767276)
			(xy 14.588409 -159.80871) (xy 14.618751 -159.855017) (xy 14.64208 -159.905223) (xy 14.650466 -159.931608)
			(xy 14.65769 -159.9537) (xy 14.678849 -159.995075) (xy 14.707172 -160.031917) (xy 14.741718 -160.063)
			(xy 14.781337 -160.087288) (xy 14.824709 -160.103975) (xy 14.870391 -160.112503) (xy 14.916862 -160.11259)
			(xy 14.962575 -160.104232) (xy 14.984476 -160.096454) (xy 15.000986 -160.090612) (xy 15.022498 -160.082986)
			(xy 15.062586 -160.061177) (xy 15.09813 -160.032553) (xy 15.127986 -159.998037) (xy 15.151192 -159.958741)
			(xy 15.167 -159.915929) (xy 15.174902 -159.870982) (xy 15.174644 -159.825346) (xy 15.170912 -159.80283)
			(xy 15.166335 -159.775464) (xy 15.164174 -159.720023) (xy 15.170066 -159.664854) (xy 15.183886 -159.611121)
			(xy 15.205343 -159.559955) (xy 15.233986 -159.512437) (xy 15.269208 -159.469569) (xy 15.310269 -159.432255)
			(xy 15.356301 -159.401281) (xy 15.406334 -159.377302) (xy 15.459313 -159.360822) (xy 15.51412 -159.352189)
			(xy 15.569599 -159.351587) (xy 15.624581 -159.359026) (xy 15.677905 -159.37435) (xy 15.728448 -159.397237)
			(xy 15.775142 -159.427203) (xy 15.817004 -159.463616) (xy 15.85315 -159.505709) (xy 15.882818 -159.552593)
			(xy 15.905382 -159.60328) (xy 15.913354 -159.629856) (xy 15.919949 -159.651534) (xy 15.939706 -159.692305)
			(xy 15.966381 -159.728926) (xy 15.999127 -159.760236) (xy 16.036907 -159.785243) (xy 16.078523 -159.803152)
			(xy 16.122656 -159.813397) (xy 16.145256 -159.815022) (xy 16.173129 -159.81679) (xy 16.227917 -159.82764)
			(xy 16.280538 -159.846362) (xy 16.329867 -159.872555) (xy 16.37485 -159.905661) (xy 16.414526 -159.944971)
			(xy 16.448047 -159.989645) (xy 16.474696 -160.038729) (xy 16.493905 -160.091174) (xy 16.505262 -160.14586)
			(xy 16.508525 -160.201616) (xy 16.503624 -160.257253) (xy 16.490664 -160.311581) (xy 16.469922 -160.363438)
			(xy 16.441842 -160.411718) (xy 16.407022 -160.455388) (xy 16.366208 -160.493514) (xy 16.320271 -160.525283)
			(xy 16.270193 -160.550015) (xy 16.217045 -160.567182) (xy 16.161961 -160.576417) (xy 16.10612 -160.577522)
			(xy 16.050714 -160.570474) (xy 15.996928 -160.555424) (xy 15.945911 -160.532693) (xy 15.898753 -160.502767)
			(xy 15.856462 -160.466285) (xy 15.819942 -160.424027) (xy 15.789972 -160.376897) (xy 15.767195 -160.325901)
			(xy 15.759176 -160.299146) (xy 15.751545 -160.274292) (xy 15.727628 -160.228136) (xy 15.694846 -160.187791)
			(xy 15.675102 -160.170876) (xy 15.66182 -160.160784) (xy 15.631374 -160.147184) (xy 15.598444 -160.141937)
			(xy 15.56528 -160.1454) (xy 15.534144 -160.157336) (xy 15.507164 -160.176931) (xy 15.486181 -160.202847)
			(xy 15.472629 -160.233314) (xy 15.467432 -160.266251) (xy 15.470946 -160.299411) (xy 15.476474 -160.315148)
			(xy 15.486078 -160.341411) (xy 15.498484 -160.395934) (xy 15.502798 -160.451684) (xy 15.498927 -160.507466)
			(xy 15.486954 -160.562086) (xy 15.467135 -160.614372) (xy 15.439896 -160.663206) (xy 15.40582 -160.707539)
			(xy 15.365637 -160.746423) (xy 15.320207 -160.779024) (xy 15.270505 -160.804644) (xy 15.217596 -160.822734)
			(xy 15.162612 -160.832906) (xy 15.106733 -160.834942) (xy 15.051154 -160.828799) (xy 14.997069 -160.814607)
			(xy 14.945634 -160.792673) (xy 14.897952 -160.763464) (xy 14.855046 -160.727608) (xy 14.817833 -160.685871)
			(xy 14.787113 -160.63915) (xy 14.763541 -160.588444) (xy 14.755114 -160.561782) (xy 14.74792 -160.539679)
			(xy 14.726757 -160.498303) (xy 14.698429 -160.461461) (xy 14.663879 -160.430378) (xy 14.624257 -160.40609)
			(xy 14.580881 -160.389405) (xy 14.535196 -160.380879) (xy 14.488722 -160.380795) (xy 14.443006 -160.389156)
			(xy 14.421104 -160.396936) (xy 14.395073 -160.406362) (xy 14.341044 -160.41844) (xy 14.285837 -160.42258)
			(xy 14.230612 -160.418696) (xy 14.176528 -160.406869) (xy 14.124722 -160.387348) (xy 14.076282 -160.360542)
			(xy 14.032227 -160.327015) (xy 13.993481 -160.287471) (xy 13.96086 -160.242741) (xy 13.935047 -160.193765)
			(xy 13.916586 -160.141571) (xy 13.905864 -160.087257) (xy 13.903107 -160.031964) (xy 2.484424 -160.031964)
			(xy 2.535228 -160.05324) (xy 2.583188 -160.082208) (xy 2.626395 -160.117879) (xy 2.663921 -160.159485)
			(xy 2.694959 -160.206132) (xy 2.71884 -160.256817) (xy 2.735053 -160.31045) (xy 2.743247 -160.365877)
			(xy 2.743247 -160.421906) (xy 2.735052 -160.477333) (xy 2.71884 -160.530965) (xy 2.694958 -160.58165)
			(xy 2.66392 -160.628297) (xy 2.626394 -160.669903) (xy 2.583186 -160.705574) (xy 2.535226 -160.734541)
			(xy 2.483545 -160.756184) (xy 2.429255 -160.770035) (xy 2.373523 -160.775797) (xy 2.317547 -160.773347)
			(xy 2.262532 -160.762736) (xy 2.209659 -160.744194) (xy 2.160068 -160.718118) (xy 2.137156 -160.70199)
			(xy 2.117896 -160.689434) (xy 2.07589 -160.670754) (xy 2.03121 -160.659936) (xy 1.985312 -160.657331)
			(xy 1.939694 -160.663026) (xy 1.895845 -160.676833) (xy 1.855195 -160.698304) (xy 1.81907 -160.726736)
			(xy 1.788649 -160.761203) (xy 1.764925 -160.80058) (xy 1.748671 -160.843583) (xy 1.740418 -160.888808)
			(xy 1.7399 -160.911794) (xy 1.7399 -161.245804) (xy 3.12496 -161.245804) (xy 3.129031 -161.190182)
			(xy 3.141157 -161.135745) (xy 3.16108 -161.083654) (xy 3.188376 -161.035019) (xy 3.222462 -160.990876)
			(xy 3.262611 -160.952167) (xy 3.307969 -160.919716) (xy 3.357569 -160.894215) (xy 3.410353 -160.876208)
			(xy 3.465196 -160.866078) (xy 3.52093 -160.864041) (xy 3.576367 -160.870141) (xy 3.630324 -160.884247)
			(xy 3.681653 -160.906059) (xy 3.713108 -160.925256) (xy 11.528042 -160.925256) (xy 11.532113 -160.869634)
			(xy 11.544239 -160.815197) (xy 11.564162 -160.763106) (xy 11.591458 -160.714471) (xy 11.625544 -160.670328)
			(xy 11.665693 -160.631619) (xy 11.711051 -160.599168) (xy 11.760651 -160.573667) (xy 11.813435 -160.55566)
			(xy 11.868278 -160.54553) (xy 11.924012 -160.543493) (xy 11.979449 -160.549593) (xy 12.033406 -160.563699)
			(xy 12.084735 -160.585511) (xy 12.132341 -160.614565) (xy 12.175209 -160.65024) (xy 12.212426 -160.691777)
			(xy 12.243199 -160.73829) (xy 12.266871 -160.788787) (xy 12.282939 -160.842194) (xy 12.291059 -160.89737)
			(xy 12.291568 -160.925256) (xy 12.291059 -160.953142) (xy 12.282939 -161.008318) (xy 12.266871 -161.061725)
			(xy 12.243199 -161.112222) (xy 12.212426 -161.158735) (xy 12.175209 -161.200272) (xy 12.132341 -161.235947)
			(xy 12.084735 -161.265001) (xy 12.033406 -161.286813) (xy 11.979449 -161.300919) (xy 11.924012 -161.307019)
			(xy 11.868278 -161.304982) (xy 11.813435 -161.294852) (xy 11.760651 -161.276845) (xy 11.711051 -161.251344)
			(xy 11.665693 -161.218893) (xy 11.625544 -161.180184) (xy 11.591458 -161.136041) (xy 11.564162 -161.087406)
			(xy 11.544239 -161.035315) (xy 11.532113 -160.980878) (xy 11.528042 -160.925256) (xy 3.713108 -160.925256)
			(xy 3.729259 -160.935113) (xy 3.772127 -160.970788) (xy 3.809344 -161.012325) (xy 3.840117 -161.058838)
			(xy 3.863789 -161.109335) (xy 3.879857 -161.162742) (xy 3.887977 -161.217918) (xy 3.888486 -161.245804)
			(xy 3.887977 -161.27369) (xy 3.879857 -161.328866) (xy 3.863789 -161.382273) (xy 3.840117 -161.43277)
			(xy 3.809344 -161.479283) (xy 3.772127 -161.52082) (xy 3.729259 -161.556495) (xy 3.681653 -161.585549)
			(xy 3.630324 -161.607361) (xy 3.576367 -161.621467) (xy 3.52093 -161.627567) (xy 3.465196 -161.62553)
			(xy 3.410353 -161.6154) (xy 3.357569 -161.597393) (xy 3.307969 -161.571892) (xy 3.262611 -161.539441)
			(xy 3.222462 -161.500732) (xy 3.188376 -161.456589) (xy 3.16108 -161.407954) (xy 3.141157 -161.355863)
			(xy 3.129031 -161.301426) (xy 3.12496 -161.245804) (xy 1.7399 -161.245804) (xy 1.7399 -161.701226)
			(xy 1.740402 -161.723954) (xy 1.748486 -161.768684) (xy 1.749475 -161.77133) (xy 12.361162 -161.77133)
			(xy 12.365233 -161.715708) (xy 12.377359 -161.661271) (xy 12.397282 -161.60918) (xy 12.424578 -161.560545)
			(xy 12.458664 -161.516402) (xy 12.498813 -161.477693) (xy 12.544171 -161.445242) (xy 12.593771 -161.419741)
			(xy 12.646555 -161.401734) (xy 12.701398 -161.391604) (xy 12.757132 -161.389567) (xy 12.812569 -161.395667)
			(xy 12.866526 -161.409773) (xy 12.917855 -161.431585) (xy 12.965461 -161.460639) (xy 13.008329 -161.496314)
			(xy 13.045546 -161.537851) (xy 13.076319 -161.584364) (xy 13.099991 -161.634861) (xy 13.116059 -161.688268)
			(xy 13.124179 -161.743444) (xy 13.124688 -161.77133) (xy 13.124179 -161.799216) (xy 13.116059 -161.854392)
			(xy 13.099991 -161.907799) (xy 13.076319 -161.958296) (xy 13.045546 -162.004809) (xy 13.008329 -162.046346)
			(xy 12.965461 -162.082021) (xy 12.917855 -162.111075) (xy 12.866526 -162.132887) (xy 12.812569 -162.146993)
			(xy 12.757132 -162.153093) (xy 12.701398 -162.151056) (xy 12.646555 -162.140926) (xy 12.593771 -162.122919)
			(xy 12.544171 -162.097418) (xy 12.498813 -162.064967) (xy 12.458664 -162.026258) (xy 12.424578 -161.982115)
			(xy 12.397282 -161.93348) (xy 12.377359 -161.881389) (xy 12.365233 -161.826952) (xy 12.361162 -161.77133)
			(xy 1.749475 -161.77133) (xy 1.764398 -161.811264) (xy 1.787632 -161.850333) (xy 1.817445 -161.884646)
			(xy 1.852886 -161.913107) (xy 1.892826 -161.93481) (xy 1.93599 -161.949062) (xy 1.981 -161.955407)
			(xy 2.026421 -161.953645) (xy 2.070804 -161.943829) (xy 2.112733 -161.926275) (xy 2.132076 -161.914332)
			(xy 2.155153 -161.899191) (xy 2.204762 -161.874999) (xy 2.257339 -161.858208) (xy 2.311787 -161.849169)
			(xy 2.366969 -161.848071) (xy 2.421734 -161.854936) (xy 2.474938 -161.869621) (xy 2.52547 -161.89182)
			(xy 2.572275 -161.92107) (xy 2.614377 -161.956759) (xy 2.650897 -161.998143) (xy 2.681072 -162.044357)
			(xy 2.704272 -162.094438) (xy 2.720013 -162.147338) (xy 2.727966 -162.201956) (xy 2.727966 -162.257149)
			(xy 2.720012 -162.311766) (xy 2.70427 -162.364667) (xy 2.681069 -162.414747) (xy 2.650894 -162.460961)
			(xy 2.614374 -162.502344) (xy 2.572272 -162.538033) (xy 2.525466 -162.567282) (xy 2.474933 -162.58948)
			(xy 2.42173 -162.604165) (xy 2.366965 -162.61103) (xy 2.311783 -162.609931) (xy 2.257335 -162.600891)
			(xy 2.204758 -162.5841) (xy 2.155149 -162.559907) (xy 2.132076 -162.54476) (xy 2.112732 -162.532819)
			(xy 2.070803 -162.515272) (xy 2.026421 -162.505462) (xy 1.981002 -162.503703) (xy 1.935994 -162.510051)
			(xy 1.892833 -162.524302) (xy 1.852895 -162.546004) (xy 1.817454 -162.574463) (xy 1.78764 -162.608772)
			(xy 1.764404 -162.647837) (xy 1.748486 -162.690412) (xy 1.740396 -162.735139) (xy 1.7399 -162.757866)
			(xy 1.7399 -163.557712) (xy 12.581634 -163.557712) (xy 12.585705 -163.50209) (xy 12.597831 -163.447653)
			(xy 12.617754 -163.395562) (xy 12.64505 -163.346927) (xy 12.679136 -163.302784) (xy 12.719285 -163.264075)
			(xy 12.764643 -163.231624) (xy 12.814243 -163.206123) (xy 12.867027 -163.188116) (xy 12.92187 -163.177986)
			(xy 12.977604 -163.175949) (xy 13.033041 -163.182049) (xy 13.086998 -163.196155) (xy 13.138327 -163.217967)
			(xy 13.185933 -163.247021) (xy 13.228801 -163.282696) (xy 13.251148 -163.307637) (xy 14.703189 -163.307637)
			(xy 14.705729 -163.253107) (xy 14.716016 -163.199495) (xy 14.73384 -163.147897) (xy 14.758837 -163.099367)
			(xy 14.790496 -163.054895) (xy 14.828171 -163.01539) (xy 14.871093 -162.981659) (xy 14.918384 -162.954391)
			(xy 14.96908 -162.934142) (xy 15.022144 -162.921327) (xy 15.076493 -162.916206) (xy 15.131017 -162.918884)
			(xy 15.184603 -162.929308) (xy 15.236155 -162.947263) (xy 15.284622 -162.972383) (xy 15.329013 -163.004155)
			(xy 15.368422 -163.04193) (xy 15.402043 -163.084938) (xy 15.416022 -163.108386) (xy 15.428153 -163.128474)
			(xy 15.45856 -163.164209) (xy 15.495006 -163.19376) (xy 15.536255 -163.216123) (xy 15.580906 -163.23054)
			(xy 15.627444 -163.236521) (xy 15.67429 -163.233863) (xy 15.6972 -163.228782) (xy 15.724254 -163.222632)
			(xy 15.779471 -163.217267) (xy 15.834884 -163.219958) (xy 15.889322 -163.230648) (xy 15.941637 -163.249112)
			(xy 15.990726 -163.27496) (xy 16.035552 -163.307646) (xy 16.07517 -163.346481) (xy 16.108745 -163.390647)
			(xy 16.135567 -163.43921) (xy 16.15507 -163.491146) (xy 16.166845 -163.54536) (xy 16.170641 -163.600708)
			(xy 16.166379 -163.656022) (xy 16.16075 -163.683188) (xy 16.156276 -163.705051) (xy 16.154169 -163.749622)
			(xy 16.159882 -163.793877) (xy 16.173238 -163.836453) (xy 16.193827 -163.876041) (xy 16.221014 -163.911423)
			(xy 16.253965 -163.941512) (xy 16.291666 -163.965382) (xy 16.312134 -163.974272) (xy 16.337832 -163.985344)
			(xy 16.385923 -164.01395) (xy 16.42932 -164.049274) (xy 16.467091 -164.090559) (xy 16.498427 -164.136918)
			(xy 16.522654 -164.187357) (xy 16.539253 -164.240794) (xy 16.547868 -164.296083) (xy 16.548315 -164.352037)
			(xy 16.540583 -164.407456) (xy 16.524838 -164.461152) (xy 16.501419 -164.511971) (xy 16.470827 -164.558824)
			(xy 16.43372 -164.600706) (xy 16.390892 -164.636718) (xy 16.343264 -164.666088) (xy 16.291856 -164.688185)
			(xy 16.237771 -164.702536) (xy 16.182171 -164.708832) (xy 16.126247 -164.706939) (xy 16.071199 -164.696897)
			(xy 16.018209 -164.678921) (xy 15.968413 -164.653398) (xy 15.92288 -164.620874) (xy 15.882586 -164.582048)
			(xy 15.848396 -164.537752) (xy 15.821043 -164.488937) (xy 15.801115 -164.43665) (xy 15.789038 -164.382013)
			(xy 15.785072 -164.326198) (xy 15.789301 -164.270402) (xy 15.79499 -164.243004) (xy 15.799449 -164.221139)
			(xy 15.801553 -164.176569) (xy 15.79584 -164.132317) (xy 15.782485 -164.089744) (xy 15.761899 -164.050157)
			(xy 15.734715 -164.014775) (xy 15.701768 -163.984685) (xy 15.664072 -163.960813) (xy 15.643606 -163.95192)
			(xy 15.620452 -163.941975) (xy 15.576765 -163.916858) (xy 15.536769 -163.886204) (xy 15.50116 -163.850548)
			(xy 15.470559 -163.81051) (xy 15.457678 -163.788852) (xy 15.445534 -163.768772) (xy 15.415132 -163.733034)
			(xy 15.378689 -163.703481) (xy 15.337442 -163.681115) (xy 15.292792 -163.666697) (xy 15.246254 -163.660716)
			(xy 15.19941 -163.663375) (xy 15.1765 -163.668456) (xy 15.14989 -163.674549) (xy 15.095567 -163.679946)
			(xy 15.041031 -163.677544) (xy 14.987393 -163.667394) (xy 14.93575 -163.649701) (xy 14.887156 -163.624827)
			(xy 14.842604 -163.593281) (xy 14.803004 -163.555706) (xy 14.769164 -163.51287) (xy 14.741776 -163.465648)
			(xy 14.721398 -163.415004) (xy 14.708448 -163.361973) (xy 14.703189 -163.307637) (xy 13.251148 -163.307637)
			(xy 13.266018 -163.324233) (xy 13.296791 -163.370746) (xy 13.320463 -163.421243) (xy 13.336531 -163.47465)
			(xy 13.344651 -163.529826) (xy 13.34516 -163.557712) (xy 13.344651 -163.585598) (xy 13.336531 -163.640774)
			(xy 13.320463 -163.694181) (xy 13.296791 -163.744678) (xy 13.266018 -163.791191) (xy 13.228801 -163.832728)
			(xy 13.185933 -163.868403) (xy 13.138327 -163.897457) (xy 13.086998 -163.919269) (xy 13.033041 -163.933375)
			(xy 12.977604 -163.939475) (xy 12.92187 -163.937438) (xy 12.867027 -163.927308) (xy 12.814243 -163.909301)
			(xy 12.764643 -163.8838) (xy 12.719285 -163.851349) (xy 12.679136 -163.81264) (xy 12.64505 -163.768497)
			(xy 12.617754 -163.719862) (xy 12.597831 -163.667771) (xy 12.585705 -163.613334) (xy 12.581634 -163.557712)
			(xy 1.7399 -163.557712) (xy 1.7399 -165.564312) (xy 9.249662 -165.564312) (xy 9.253733 -165.50869)
			(xy 9.265859 -165.454253) (xy 9.285782 -165.402162) (xy 9.313078 -165.353527) (xy 9.347164 -165.309384)
			(xy 9.387313 -165.270675) (xy 9.432671 -165.238224) (xy 9.482271 -165.212723) (xy 9.535055 -165.194716)
			(xy 9.589898 -165.184586) (xy 9.645632 -165.182549) (xy 9.701069 -165.188649) (xy 9.755026 -165.202755)
			(xy 9.806355 -165.224567) (xy 9.853961 -165.253621) (xy 9.896829 -165.289296) (xy 9.934046 -165.330833)
			(xy 9.954247 -165.361366) (xy 10.956542 -165.361366) (xy 10.960613 -165.305744) (xy 10.972739 -165.251307)
			(xy 10.992662 -165.199216) (xy 11.019958 -165.150581) (xy 11.054044 -165.106438) (xy 11.094193 -165.067729)
			(xy 11.139551 -165.035278) (xy 11.189151 -165.009777) (xy 11.241935 -164.99177) (xy 11.296778 -164.98164)
			(xy 11.352512 -164.979603) (xy 11.407949 -164.985703) (xy 11.461906 -164.999809) (xy 11.513235 -165.021621)
			(xy 11.560841 -165.050675) (xy 11.603709 -165.08635) (xy 11.640926 -165.127887) (xy 11.671699 -165.1744)
			(xy 11.695371 -165.224897) (xy 11.711439 -165.278304) (xy 11.719559 -165.33348) (xy 11.720068 -165.361366)
			(xy 11.719559 -165.389252) (xy 11.711439 -165.444428) (xy 11.695371 -165.497835) (xy 11.671699 -165.548332)
			(xy 11.640926 -165.594845) (xy 11.622539 -165.615366) (xy 13.270736 -165.615366) (xy 13.274807 -165.559744)
			(xy 13.286933 -165.505307) (xy 13.306856 -165.453216) (xy 13.334152 -165.404581) (xy 13.368238 -165.360438)
			(xy 13.408387 -165.321729) (xy 13.453745 -165.289278) (xy 13.503345 -165.263777) (xy 13.556129 -165.24577)
			(xy 13.610972 -165.23564) (xy 13.666706 -165.233603) (xy 13.722143 -165.239703) (xy 13.7761 -165.253809)
			(xy 13.827429 -165.275621) (xy 13.875035 -165.304675) (xy 13.917903 -165.34035) (xy 13.95512 -165.381887)
			(xy 13.985893 -165.4284) (xy 14.009565 -165.478897) (xy 14.025633 -165.532304) (xy 14.033753 -165.58748)
			(xy 14.034262 -165.615366) (xy 14.033753 -165.643252) (xy 14.025633 -165.698428) (xy 14.009565 -165.751835)
			(xy 13.985893 -165.802332) (xy 13.95512 -165.848845) (xy 13.917903 -165.890382) (xy 13.875035 -165.926057)
			(xy 13.827429 -165.955111) (xy 13.7761 -165.976923) (xy 13.722143 -165.991029) (xy 13.666706 -165.997129)
			(xy 13.610972 -165.995092) (xy 13.556129 -165.984962) (xy 13.503345 -165.966955) (xy 13.453745 -165.941454)
			(xy 13.408387 -165.909003) (xy 13.368238 -165.870294) (xy 13.334152 -165.826151) (xy 13.306856 -165.777516)
			(xy 13.286933 -165.725425) (xy 13.274807 -165.670988) (xy 13.270736 -165.615366) (xy 11.622539 -165.615366)
			(xy 11.603709 -165.636382) (xy 11.560841 -165.672057) (xy 11.513235 -165.701111) (xy 11.461906 -165.722923)
			(xy 11.407949 -165.737029) (xy 11.352512 -165.743129) (xy 11.296778 -165.741092) (xy 11.241935 -165.730962)
			(xy 11.189151 -165.712955) (xy 11.139551 -165.687454) (xy 11.094193 -165.655003) (xy 11.054044 -165.616294)
			(xy 11.019958 -165.572151) (xy 10.992662 -165.523516) (xy 10.972739 -165.471425) (xy 10.960613 -165.416988)
			(xy 10.956542 -165.361366) (xy 9.954247 -165.361366) (xy 9.964819 -165.377346) (xy 9.988491 -165.427843)
			(xy 10.004559 -165.48125) (xy 10.012679 -165.536426) (xy 10.013188 -165.564312) (xy 10.012679 -165.592198)
			(xy 10.004559 -165.647374) (xy 9.988491 -165.700781) (xy 9.964819 -165.751278) (xy 9.934046 -165.797791)
			(xy 9.896829 -165.839328) (xy 9.853961 -165.875003) (xy 9.806355 -165.904057) (xy 9.755026 -165.925869)
			(xy 9.701069 -165.939975) (xy 9.645632 -165.946075) (xy 9.589898 -165.944038) (xy 9.535055 -165.933908)
			(xy 9.482271 -165.915901) (xy 9.432671 -165.8904) (xy 9.387313 -165.857949) (xy 9.347164 -165.81924)
			(xy 9.313078 -165.775097) (xy 9.285782 -165.726462) (xy 9.265859 -165.674371) (xy 9.253733 -165.619934)
			(xy 9.249662 -165.564312) (xy 1.7399 -165.564312) (xy 1.7399 -166.017194) (xy 15.264382 -166.017194)
			(xy 15.268453 -165.961572) (xy 15.280579 -165.907135) (xy 15.300502 -165.855044) (xy 15.327798 -165.806409)
			(xy 15.361884 -165.762266) (xy 15.402033 -165.723557) (xy 15.447391 -165.691106) (xy 15.496991 -165.665605)
			(xy 15.549775 -165.647598) (xy 15.604618 -165.637468) (xy 15.660352 -165.635431) (xy 15.715789 -165.641531)
			(xy 15.769746 -165.655637) (xy 15.821075 -165.677449) (xy 15.868681 -165.706503) (xy 15.911549 -165.742178)
			(xy 15.948766 -165.783715) (xy 15.979539 -165.830228) (xy 16.003211 -165.880725) (xy 16.019279 -165.934132)
			(xy 16.027399 -165.989308) (xy 16.027908 -166.017194) (xy 16.027399 -166.04508) (xy 16.019279 -166.100256)
			(xy 16.003211 -166.153663) (xy 15.979539 -166.20416) (xy 15.948766 -166.250673) (xy 15.911549 -166.29221)
			(xy 15.868681 -166.327885) (xy 15.821075 -166.356939) (xy 15.769746 -166.378751) (xy 15.715789 -166.392857)
			(xy 15.660352 -166.398957) (xy 15.604618 -166.39692) (xy 15.549775 -166.38679) (xy 15.496991 -166.368783)
			(xy 15.447391 -166.343282) (xy 15.402033 -166.310831) (xy 15.361884 -166.272122) (xy 15.327798 -166.227979)
			(xy 15.300502 -166.179344) (xy 15.280579 -166.127253) (xy 15.268453 -166.072816) (xy 15.264382 -166.017194)
			(xy 1.7399 -166.017194) (xy 1.7399 -166.5605) (xy 5.756654 -166.5605) (xy 5.760725 -166.504878) (xy 5.772851 -166.450441)
			(xy 5.792774 -166.39835) (xy 5.82007 -166.349715) (xy 5.854156 -166.305572) (xy 5.894305 -166.266863)
			(xy 5.939663 -166.234412) (xy 5.989263 -166.208911) (xy 6.042047 -166.190904) (xy 6.09689 -166.180774)
			(xy 6.152624 -166.178737) (xy 6.208061 -166.184837) (xy 6.262018 -166.198943) (xy 6.313347 -166.220755)
			(xy 6.360953 -166.249809) (xy 6.403821 -166.285484) (xy 6.441038 -166.327021) (xy 6.471811 -166.373534)
			(xy 6.495483 -166.424031) (xy 6.511551 -166.477438) (xy 6.519671 -166.532614) (xy 6.52018 -166.5605)
			(xy 6.519671 -166.588386) (xy 6.511551 -166.643562) (xy 6.495483 -166.696969) (xy 6.482538 -166.724584)
			(xy 10.026902 -166.724584) (xy 10.030973 -166.668962) (xy 10.043099 -166.614525) (xy 10.063022 -166.562434)
			(xy 10.090318 -166.513799) (xy 10.124404 -166.469656) (xy 10.164553 -166.430947) (xy 10.209911 -166.398496)
			(xy 10.259511 -166.372995) (xy 10.312295 -166.354988) (xy 10.367138 -166.344858) (xy 10.422872 -166.342821)
			(xy 10.478309 -166.348921) (xy 10.532266 -166.363027) (xy 10.583595 -166.384839) (xy 10.631201 -166.413893)
			(xy 10.674069 -166.449568) (xy 10.711286 -166.491105) (xy 10.742059 -166.537618) (xy 10.765731 -166.588115)
			(xy 10.781799 -166.641522) (xy 10.789919 -166.696698) (xy 10.790428 -166.724584) (xy 10.789919 -166.75247)
			(xy 10.781799 -166.807646) (xy 10.765731 -166.861053) (xy 10.742059 -166.91155) (xy 10.711286 -166.958063)
			(xy 10.674069 -166.9996) (xy 10.631201 -167.035275) (xy 10.583595 -167.064329) (xy 10.532266 -167.086141)
			(xy 10.478309 -167.100247) (xy 10.422872 -167.106347) (xy 10.367138 -167.10431) (xy 10.312295 -167.09418)
			(xy 10.259511 -167.076173) (xy 10.209911 -167.050672) (xy 10.164553 -167.018221) (xy 10.124404 -166.979512)
			(xy 10.090318 -166.935369) (xy 10.063022 -166.886734) (xy 10.043099 -166.834643) (xy 10.030973 -166.780206)
			(xy 10.026902 -166.724584) (xy 6.482538 -166.724584) (xy 6.471811 -166.747466) (xy 6.441038 -166.793979)
			(xy 6.403821 -166.835516) (xy 6.360953 -166.871191) (xy 6.313347 -166.900245) (xy 6.262018 -166.922057)
			(xy 6.208061 -166.936163) (xy 6.152624 -166.942263) (xy 6.09689 -166.940226) (xy 6.042047 -166.930096)
			(xy 5.989263 -166.912089) (xy 5.939663 -166.886588) (xy 5.894305 -166.854137) (xy 5.854156 -166.815428)
			(xy 5.82007 -166.771285) (xy 5.792774 -166.72265) (xy 5.772851 -166.670559) (xy 5.760725 -166.616122)
			(xy 5.756654 -166.5605) (xy 1.7399 -166.5605) (xy 1.7399 -167.28694) (xy 1.826514 -167.373554) (xy 3.954016 -167.373554)
			(xy 3.958087 -167.317932) (xy 3.970213 -167.263495) (xy 3.990136 -167.211404) (xy 4.017432 -167.162769)
			(xy 4.051518 -167.118626) (xy 4.091667 -167.079917) (xy 4.137025 -167.047466) (xy 4.186625 -167.021965)
			(xy 4.239409 -167.003958) (xy 4.294252 -166.993828) (xy 4.349986 -166.991791) (xy 4.405423 -166.997891)
			(xy 4.45938 -167.011997) (xy 4.510709 -167.033809) (xy 4.558315 -167.062863) (xy 4.601183 -167.098538)
			(xy 4.6384 -167.140075) (xy 4.669173 -167.186588) (xy 4.692845 -167.237085) (xy 4.708913 -167.290492)
			(xy 4.717033 -167.345668) (xy 4.717542 -167.373554) (xy 7.228838 -167.373554) (xy 7.232909 -167.317932)
			(xy 7.245035 -167.263495) (xy 7.264958 -167.211404) (xy 7.292254 -167.162769) (xy 7.32634 -167.118626)
			(xy 7.366489 -167.079917) (xy 7.411847 -167.047466) (xy 7.461447 -167.021965) (xy 7.514231 -167.003958)
			(xy 7.569074 -166.993828) (xy 7.624808 -166.991791) (xy 7.680245 -166.997891) (xy 7.734202 -167.011997)
			(xy 7.785531 -167.033809) (xy 7.833137 -167.062863) (xy 7.876005 -167.098538) (xy 7.913222 -167.140075)
			(xy 7.943995 -167.186588) (xy 7.967667 -167.237085) (xy 7.983735 -167.290492) (xy 7.991855 -167.345668)
			(xy 7.992364 -167.373554) (xy 7.991855 -167.40144) (xy 7.983735 -167.456616) (xy 7.967667 -167.510023)
			(xy 7.943995 -167.56052) (xy 7.913222 -167.607033) (xy 7.876005 -167.64857) (xy 7.833137 -167.684245)
			(xy 7.785531 -167.713299) (xy 7.734202 -167.735111) (xy 7.680245 -167.749217) (xy 7.624808 -167.755317)
			(xy 7.569074 -167.75328) (xy 7.514231 -167.74315) (xy 7.461447 -167.725143) (xy 7.411847 -167.699642)
			(xy 7.366489 -167.667191) (xy 7.32634 -167.628482) (xy 7.292254 -167.584339) (xy 7.264958 -167.535704)
			(xy 7.245035 -167.483613) (xy 7.232909 -167.429176) (xy 7.228838 -167.373554) (xy 4.717542 -167.373554)
			(xy 4.717033 -167.40144) (xy 4.708913 -167.456616) (xy 4.692845 -167.510023) (xy 4.669173 -167.56052)
			(xy 4.6384 -167.607033) (xy 4.601183 -167.64857) (xy 4.558315 -167.684245) (xy 4.510709 -167.713299)
			(xy 4.45938 -167.735111) (xy 4.405423 -167.749217) (xy 4.349986 -167.755317) (xy 4.294252 -167.75328)
			(xy 4.239409 -167.74315) (xy 4.186625 -167.725143) (xy 4.137025 -167.699642) (xy 4.091667 -167.667191)
			(xy 4.051518 -167.628482) (xy 4.017432 -167.584339) (xy 3.990136 -167.535704) (xy 3.970213 -167.483613)
			(xy 3.958087 -167.429176) (xy 3.954016 -167.373554) (xy 1.826514 -167.373554) (xy 2.76098 -168.30802)
			(xy 10.78484 -168.30802) (xy 14.86408 -172.38726) (xy 14.86408 -172.857414) (xy 24.614122 -172.857414)
			(xy 24.618193 -172.801792) (xy 24.630319 -172.747355) (xy 24.650242 -172.695264) (xy 24.677538 -172.646629)
			(xy 24.711624 -172.602486) (xy 24.751773 -172.563777) (xy 24.797131 -172.531326) (xy 24.846731 -172.505825)
			(xy 24.899515 -172.487818) (xy 24.954358 -172.477688) (xy 25.010092 -172.475651) (xy 25.065529 -172.481751)
			(xy 25.119486 -172.495857) (xy 25.170815 -172.517669) (xy 25.218421 -172.546723) (xy 25.261289 -172.582398)
			(xy 25.298506 -172.623935) (xy 25.329279 -172.670448) (xy 25.352951 -172.720945) (xy 25.369019 -172.774352)
			(xy 25.377139 -172.829528) (xy 25.377648 -172.857414) (xy 25.377139 -172.8853) (xy 25.369019 -172.940476)
			(xy 25.352951 -172.993883) (xy 25.329279 -173.04438) (xy 25.298506 -173.090893) (xy 25.261289 -173.13243)
			(xy 25.218421 -173.168105) (xy 25.170815 -173.197159) (xy 25.119486 -173.218971) (xy 25.065529 -173.233077)
			(xy 25.010092 -173.239177) (xy 24.954358 -173.23714) (xy 24.899515 -173.22701) (xy 24.846731 -173.209003)
			(xy 24.797131 -173.183502) (xy 24.751773 -173.151051) (xy 24.711624 -173.112342) (xy 24.677538 -173.068199)
			(xy 24.650242 -173.019564) (xy 24.630319 -172.967473) (xy 24.618193 -172.913036) (xy 24.614122 -172.857414)
			(xy 14.86408 -172.857414) (xy 14.86408 -175.179228) (xy 20.098002 -175.179228) (xy 20.102073 -175.123606)
			(xy 20.114199 -175.069169) (xy 20.134122 -175.017078) (xy 20.161418 -174.968443) (xy 20.195504 -174.9243)
			(xy 20.235653 -174.885591) (xy 20.281011 -174.85314) (xy 20.330611 -174.827639) (xy 20.383395 -174.809632)
			(xy 20.438238 -174.799502) (xy 20.493972 -174.797465) (xy 20.549409 -174.803565) (xy 20.603366 -174.817671)
			(xy 20.654695 -174.839483) (xy 20.702301 -174.868537) (xy 20.745169 -174.904212) (xy 20.782386 -174.945749)
			(xy 20.813159 -174.992262) (xy 20.836831 -175.042759) (xy 20.852899 -175.096166) (xy 20.861019 -175.151342)
			(xy 20.861528 -175.179228) (xy 20.861019 -175.207114) (xy 20.852899 -175.26229) (xy 20.836831 -175.315697)
			(xy 20.813159 -175.366194) (xy 20.782386 -175.412707) (xy 20.745169 -175.454244) (xy 20.702301 -175.489919)
			(xy 20.654695 -175.518973) (xy 20.603366 -175.540785) (xy 20.549409 -175.554891) (xy 20.493972 -175.560991)
			(xy 20.438238 -175.558954) (xy 20.383395 -175.548824) (xy 20.330611 -175.530817) (xy 20.281011 -175.505316)
			(xy 20.235653 -175.472865) (xy 20.195504 -175.434156) (xy 20.161418 -175.390013) (xy 20.134122 -175.341378)
			(xy 20.114199 -175.289287) (xy 20.102073 -175.23485) (xy 20.098002 -175.179228) (xy 14.86408 -175.179228)
			(xy 14.86408 -177.712961) (xy 20.992058 -177.712961) (xy 20.999867 -177.535341) (xy 21.015543 -177.358242)
			(xy 21.039055 -177.182012) (xy 21.070358 -177.006998) (xy 21.109389 -176.833543) (xy 21.156072 -176.66199)
			(xy 21.210314 -176.492675) (xy 21.27201 -176.325931) (xy 21.341038 -176.162086) (xy 21.417262 -176.001463)
			(xy 21.500532 -175.844378) (xy 21.590685 -175.691138) (xy 21.687543 -175.542046) (xy 21.790916 -175.397395)
			(xy 21.9006 -175.25747) (xy 22.01638 -175.122544) (xy 22.138029 -174.992885) (xy 22.265306 -174.868746)
			(xy 22.397961 -174.750372) (xy 22.535735 -174.637996) (xy 22.678355 -174.531839) (xy 22.825541 -174.432109)
			(xy 22.977004 -174.339003) (xy 23.132446 -174.252703) (xy 23.291561 -174.17338) (xy 23.454037 -174.101189)
			(xy 23.619553 -174.036272) (xy 23.787785 -173.978758) (xy 23.958401 -173.928758) (xy 24.131067 -173.886372)
			(xy 24.305441 -173.851683) (xy 24.481182 -173.824759) (xy 24.657945 -173.805653) (xy 24.83538 -173.794402)
			(xy 25.013139 -173.791029) (xy 25.190874 -173.795541) (xy 25.368233 -173.807927) (xy 25.544869 -173.828165)
			(xy 25.720435 -173.856215) (xy 25.894583 -173.89202) (xy 25.980898 -173.913292) (xy 26.068383 -173.935873)
			(xy 26.241428 -173.987915) (xy 26.411952 -174.047702) (xy 26.579609 -174.115111) (xy 26.744058 -174.190006)
			(xy 26.904966 -174.272235) (xy 27.062006 -174.36163) (xy 27.214858 -174.45801) (xy 27.363212 -174.56118)
			(xy 27.506766 -174.67093) (xy 27.64523 -174.787036) (xy 27.778322 -174.909264) (xy 27.905771 -175.037364)
			(xy 28.027319 -175.171076) (xy 28.142718 -175.31013) (xy 28.251735 -175.454242) (xy 28.354148 -175.603119)
			(xy 28.449748 -175.75646) (xy 28.538342 -175.913953) (xy 28.61975 -176.075278) (xy 28.693806 -176.240107)
			(xy 28.76036 -176.408105) (xy 28.819277 -176.578932) (xy 28.870437 -176.75224) (xy 28.913736 -176.927677)
			(xy 28.949086 -177.104886) (xy 28.976416 -177.283509) (xy 28.995669 -177.463182) (xy 29.006807 -177.643539)
			(xy 29.009808 -177.824215) (xy 29.004664 -178.004843) (xy 28.991387 -178.185056) (xy 28.970003 -178.364488)
			(xy 28.940556 -178.542773) (xy 28.903106 -178.719551) (xy 28.857728 -178.894462) (xy 28.804516 -179.067151)
			(xy 28.743576 -179.237266) (xy 28.675034 -179.404463) (xy 28.599027 -179.568402) (xy 28.515711 -179.728749)
			(xy 28.425254 -179.88518) (xy 28.327841 -180.037376) (xy 28.223669 -180.185028) (xy 28.11295 -180.327836)
			(xy 27.995909 -180.465511) (xy 27.872784 -180.597772) (xy 27.743824 -180.724351) (xy 27.609291 -180.844991)
			(xy 27.539696 -180.90261) (xy 27.515946 -180.922625) (xy 27.473217 -180.967703) (xy 27.436503 -181.017803)
			(xy 27.406389 -181.072126) (xy 27.383354 -181.129808) (xy 27.367764 -181.189931) (xy 27.359868 -181.251539)
			(xy 27.359356 -181.282594) (xy 27.359356 -181.93385) (xy 29.017974 -181.93385) (xy 29.022045 -181.878228)
			(xy 29.034171 -181.823791) (xy 29.054094 -181.7717) (xy 29.08139 -181.723065) (xy 29.115476 -181.678922)
			(xy 29.155625 -181.640213) (xy 29.200983 -181.607762) (xy 29.250583 -181.582261) (xy 29.303367 -181.564254)
			(xy 29.35821 -181.554124) (xy 29.413944 -181.552087) (xy 29.469381 -181.558187) (xy 29.523338 -181.572293)
			(xy 29.574667 -181.594105) (xy 29.622273 -181.623159) (xy 29.665141 -181.658834) (xy 29.702358 -181.700371)
			(xy 29.733131 -181.746884) (xy 29.756803 -181.797381) (xy 29.772871 -181.850788) (xy 29.780991 -181.905964)
			(xy 29.7815 -181.93385) (xy 29.780991 -181.961736) (xy 29.772871 -182.016912) (xy 29.756803 -182.070319)
			(xy 29.733131 -182.120816) (xy 29.702358 -182.167329) (xy 29.665141 -182.208866) (xy 29.622273 -182.244541)
			(xy 29.574667 -182.273595) (xy 29.523338 -182.295407) (xy 29.469381 -182.309513) (xy 29.413944 -182.315613)
			(xy 29.35821 -182.313576) (xy 29.303367 -182.303446) (xy 29.250583 -182.285439) (xy 29.200983 -182.259938)
			(xy 29.155625 -182.227487) (xy 29.115476 -182.188778) (xy 29.08139 -182.144635) (xy 29.054094 -182.096)
			(xy 29.034171 -182.043909) (xy 29.022045 -181.989472) (xy 29.017974 -181.93385) (xy 27.359356 -181.93385)
			(xy 27.359356 -182.800244) (xy 27.358857 -182.868859) (xy 27.350878 -183.005857) (xy 27.334946 -183.142159)
			(xy 27.311117 -183.277304) (xy 27.279469 -183.410835) (xy 27.240111 -183.5423) (xy 27.193176 -183.671254)
			(xy 27.138822 -183.797261) (xy 27.077233 -183.919894) (xy 27.008618 -184.038739) (xy 26.933209 -184.153393)
			(xy 26.851261 -184.263468) (xy 26.763051 -184.368593) (xy 26.695746 -184.439932) (xy 33.845223 -184.439932)
			(xy 33.850056 -184.384021) (xy 33.863027 -184.329422) (xy 33.883855 -184.277311) (xy 33.912092 -184.228813)
			(xy 33.947127 -184.184973) (xy 33.988206 -184.146738) (xy 34.034441 -184.114933) (xy 34.084837 -184.090242)
			(xy 34.138306 -184.073199) (xy 34.193694 -184.064172) (xy 34.249808 -184.063355) (xy 34.305435 -184.070766)
			(xy 34.359378 -184.086244) (xy 34.410471 -184.109457) (xy 34.457614 -184.139903) (xy 34.499788 -184.176925)
			(xy 34.536085 -184.219726) (xy 34.565722 -184.267381) (xy 34.588059 -184.318863) (xy 34.595816 -184.345834)
			(xy 34.602289 -184.367945) (xy 34.622071 -184.409548) (xy 34.649023 -184.446908) (xy 34.682262 -184.478804)
			(xy 34.720701 -184.504192) (xy 34.763085 -184.522242) (xy 34.808026 -184.532364) (xy 34.83102 -184.533794)
			(xy 34.859044 -184.535379) (xy 34.914197 -184.545809) (xy 34.963768 -184.563004) (xy 37.682422 -184.563004)
			(xy 37.686493 -184.507382) (xy 37.698619 -184.452945) (xy 37.718542 -184.400854) (xy 37.745838 -184.352219)
			(xy 37.779924 -184.308076) (xy 37.820073 -184.269367) (xy 37.865431 -184.236916) (xy 37.915031 -184.211415)
			(xy 37.967815 -184.193408) (xy 38.022658 -184.183278) (xy 38.078392 -184.181241) (xy 38.133829 -184.187341)
			(xy 38.187786 -184.201447) (xy 38.239115 -184.223259) (xy 38.286721 -184.252313) (xy 38.329589 -184.287988)
			(xy 38.366806 -184.329525) (xy 38.397579 -184.376038) (xy 38.421251 -184.426535) (xy 38.437319 -184.479942)
			(xy 38.445439 -184.535118) (xy 38.445948 -184.563004) (xy 38.445439 -184.59089) (xy 38.437319 -184.646066)
			(xy 38.421251 -184.699473) (xy 38.397579 -184.74997) (xy 38.366806 -184.796483) (xy 38.329589 -184.83802)
			(xy 38.286721 -184.873695) (xy 38.239115 -184.902749) (xy 38.187786 -184.924561) (xy 38.133829 -184.938667)
			(xy 38.078392 -184.944767) (xy 38.022658 -184.94273) (xy 37.967815 -184.9326) (xy 37.915031 -184.914593)
			(xy 37.865431 -184.889092) (xy 37.820073 -184.856641) (xy 37.779924 -184.817932) (xy 37.745838 -184.773789)
			(xy 37.718542 -184.725154) (xy 37.698619 -184.673063) (xy 37.686493 -184.618626) (xy 37.682422 -184.563004)
			(xy 34.963768 -184.563004) (xy 34.967227 -184.564204) (xy 35.01699 -184.590169) (xy 35.062414 -184.623142)
			(xy 35.102519 -184.662413) (xy 35.136438 -184.707135) (xy 35.163441 -184.756343) (xy 35.182945 -184.808976)
			(xy 35.19453 -184.863897) (xy 35.197945 -184.919923) (xy 35.193117 -184.975845) (xy 35.18015 -185.030457)
			(xy 35.159323 -185.08258) (xy 35.135592 -185.123351) (xy 43.227629 -185.123351) (xy 43.234713 -185.069128)
			(xy 43.249467 -185.016471) (xy 43.271587 -184.966461) (xy 43.300621 -184.920121) (xy 43.335974 -184.878401)
			(xy 43.376922 -184.842156) (xy 43.422625 -184.812129) (xy 43.472147 -184.788935) (xy 43.524473 -184.77305)
			(xy 43.578531 -184.764798) (xy 43.633213 -184.764349) (xy 43.6874 -184.771712) (xy 43.73998 -184.786737)
			(xy 43.789876 -184.809114) (xy 43.813222 -184.823354) (xy 43.832844 -184.835239) (xy 43.875347 -184.85249)
			(xy 43.920258 -184.861822) (xy 43.966115 -184.862929) (xy 44.011425 -184.855777) (xy 44.054711 -184.840599)
			(xy 44.094565 -184.817888) (xy 44.129688 -184.788383) (xy 44.144692 -184.77103) (xy 44.162557 -184.750327)
			(xy 44.203128 -184.713666) (xy 44.248518 -184.683174) (xy 44.297796 -184.659474) (xy 44.349954 -184.643053)
			(xy 44.403921 -184.634246) (xy 44.458593 -184.633236) (xy 44.512849 -184.640041) (xy 44.565577 -184.654523)
			(xy 44.615698 -184.676385) (xy 44.662183 -184.705179) (xy 44.704082 -184.740315) (xy 44.740534 -184.781074)
			(xy 44.770794 -184.826619) (xy 44.794241 -184.876018) (xy 44.810395 -184.928258) (xy 44.818925 -184.98227)
			(xy 44.819656 -185.036946) (xy 44.812572 -185.091167) (xy 44.79782 -185.14382) (xy 44.775702 -185.193828)
			(xy 44.74667 -185.240166) (xy 44.71132 -185.281884) (xy 44.670375 -185.318127) (xy 44.624675 -185.348153)
			(xy 44.575157 -185.371347) (xy 44.522834 -185.387233) (xy 44.46878 -185.395486) (xy 44.4141 -185.395937)
			(xy 44.359917 -185.388576) (xy 44.30734 -185.373554) (xy 44.257446 -185.35118) (xy 44.2341 -185.336942)
			(xy 44.214464 -185.325081) (xy 44.171965 -185.307828) (xy 44.127057 -185.298495) (xy 44.081202 -185.297384)
			(xy 44.035895 -185.304532) (xy 43.99261 -185.319707) (xy 43.952757 -185.342415) (xy 43.917635 -185.371915)
			(xy 43.90263 -185.389266) (xy 43.884765 -185.409971) (xy 43.844193 -185.446636) (xy 43.798802 -185.477132)
			(xy 43.749522 -185.500835) (xy 43.697362 -185.517259) (xy 43.643392 -185.526068) (xy 43.588717 -185.52708)
			(xy 43.534457 -185.520276) (xy 43.481726 -185.505794) (xy 43.431602 -185.483932) (xy 43.385113 -185.455137)
			(xy 43.343211 -185.419999) (xy 43.306756 -185.379239) (xy 43.276494 -185.333691) (xy 43.253045 -185.284289)
			(xy 43.23689 -185.232046) (xy 43.22836 -185.178031) (xy 43.227629 -185.123351) (xy 35.135592 -185.123351)
			(xy 35.131087 -185.131091) (xy 35.09605 -185.174943) (xy 35.054967 -185.213189) (xy 35.008725 -185.245006)
			(xy 34.958322 -185.269706) (xy 34.904845 -185.286757) (xy 34.849447 -185.295791) (xy 34.793323 -185.296614)
			(xy 34.737683 -185.289207) (xy 34.683729 -185.27373) (xy 34.632624 -185.250517) (xy 34.58547 -185.220069)
			(xy 34.543284 -185.183043) (xy 34.506977 -185.140236) (xy 34.477331 -185.092574) (xy 34.454987 -185.041083)
			(xy 34.447226 -185.014108) (xy 34.440776 -184.991989) (xy 34.420995 -184.950381) (xy 34.394041 -184.913018)
			(xy 34.360799 -184.881121) (xy 34.322354 -184.855734) (xy 34.279965 -184.837688) (xy 34.235019 -184.827573)
			(xy 34.212022 -184.826148) (xy 34.184008 -184.824448) (xy 34.128868 -184.814013) (xy 34.07585 -184.795613)
			(xy 34.0261 -184.769647) (xy 33.980689 -184.736673) (xy 33.940598 -184.697404) (xy 33.906691 -184.652687)
			(xy 33.8797 -184.603485) (xy 33.860206 -184.55086) (xy 33.84863 -184.495948) (xy 33.845223 -184.439932)
			(xy 26.695746 -184.439932) (xy 26.668878 -184.46841) (xy 26.569061 -184.562583) (xy 26.463936 -184.650793)
			(xy 26.353861 -184.732741) (xy 26.239207 -184.80815) (xy 26.120362 -184.876765) (xy 25.997729 -184.938354)
			(xy 25.871722 -184.992708) (xy 25.742768 -185.039643) (xy 25.611303 -185.079001) (xy 25.477772 -185.110649)
			(xy 25.342627 -185.134478) (xy 25.206325 -185.15041) (xy 25.069327 -185.158389) (xy 24.932097 -185.158389)
			(xy 24.795099 -185.15041) (xy 24.658797 -185.134478) (xy 24.523652 -185.110649) (xy 24.390121 -185.079001)
			(xy 24.258656 -185.039643) (xy 24.129702 -184.992708) (xy 24.003695 -184.938354) (xy 23.881062 -184.876765)
			(xy 23.762217 -184.80815) (xy 23.647563 -184.732741) (xy 23.537488 -184.650793) (xy 23.432363 -184.562583)
			(xy 23.332546 -184.46841) (xy 23.238373 -184.368593) (xy 23.150163 -184.263468) (xy 23.068215 -184.153393)
			(xy 22.992806 -184.038739) (xy 22.924191 -183.919894) (xy 22.862602 -183.797261) (xy 22.808248 -183.671254)
			(xy 22.761313 -183.5423) (xy 22.721955 -183.410835) (xy 22.690307 -183.277304) (xy 22.666478 -183.142159)
			(xy 22.650546 -183.005857) (xy 22.642567 -182.868859) (xy 22.642068 -182.800244) (xy 22.642068 -181.282594)
			(xy 22.641619 -181.252219) (xy 22.63408 -181.191938) (xy 22.619168 -181.133045) (xy 22.59711 -181.076441)
			(xy 22.568242 -181.022987) (xy 22.533006 -180.973499) (xy 22.491937 -180.928732) (xy 22.469094 -180.908706)
			(xy 22.400484 -180.852178) (xy 22.26773 -180.733914) (xy 22.140351 -180.609881) (xy 22.018596 -180.480322)
			(xy 21.902704 -180.345492) (xy 21.792904 -180.205657) (xy 21.689411 -180.061092) (xy 21.59243 -179.91208)
			(xy 21.502151 -179.758915) (xy 21.41875 -179.601899) (xy 21.342394 -179.441339) (xy 21.27323 -179.277551)
			(xy 21.211397 -179.110859) (xy 21.157014 -178.941588) (xy 21.110189 -178.770074) (xy 21.071015 -178.596652)
			(xy 21.039568 -178.421663) (xy 21.01591 -178.245453) (xy 21.000087 -178.068366) (xy 20.992131 -177.890753)
			(xy 20.992058 -177.712961) (xy 14.86408 -177.712961) (xy 14.86408 -181.881272) (xy 20.66112 -181.881272)
			(xy 20.665191 -181.82565) (xy 20.677317 -181.771213) (xy 20.69724 -181.719122) (xy 20.724536 -181.670487)
			(xy 20.758622 -181.626344) (xy 20.798771 -181.587635) (xy 20.844129 -181.555184) (xy 20.893729 -181.529683)
			(xy 20.946513 -181.511676) (xy 21.001356 -181.501546) (xy 21.05709 -181.499509) (xy 21.112527 -181.505609)
			(xy 21.166484 -181.519715) (xy 21.217813 -181.541527) (xy 21.265419 -181.570581) (xy 21.308287 -181.606256)
			(xy 21.345504 -181.647793) (xy 21.376277 -181.694306) (xy 21.399949 -181.744803) (xy 21.416017 -181.79821)
			(xy 21.424137 -181.853386) (xy 21.424646 -181.881272) (xy 21.424137 -181.909158) (xy 21.416017 -181.964334)
			(xy 21.399949 -182.017741) (xy 21.376277 -182.068238) (xy 21.345504 -182.114751) (xy 21.308287 -182.156288)
			(xy 21.265419 -182.191963) (xy 21.217813 -182.221017) (xy 21.166484 -182.242829) (xy 21.112527 -182.256935)
			(xy 21.05709 -182.263035) (xy 21.001356 -182.260998) (xy 20.946513 -182.250868) (xy 20.893729 -182.232861)
			(xy 20.844129 -182.20736) (xy 20.798771 -182.174909) (xy 20.758622 -182.1362) (xy 20.724536 -182.092057)
			(xy 20.69724 -182.043422) (xy 20.677317 -181.991331) (xy 20.665191 -181.936894) (xy 20.66112 -181.881272)
			(xy 14.86408 -181.881272) (xy 14.86408 -186.234578) (xy 25.074624 -186.234578) (xy 25.078695 -186.178956)
			(xy 25.090821 -186.124519) (xy 25.110744 -186.072428) (xy 25.13804 -186.023793) (xy 25.172126 -185.97965)
			(xy 25.212275 -185.940941) (xy 25.257633 -185.90849) (xy 25.307233 -185.882989) (xy 25.360017 -185.864982)
			(xy 25.41486 -185.854852) (xy 25.470594 -185.852815) (xy 25.526031 -185.858915) (xy 25.579988 -185.873021)
			(xy 25.631317 -185.894833) (xy 25.678923 -185.923887) (xy 25.721791 -185.959562) (xy 25.759008 -186.001099)
			(xy 25.789781 -186.047612) (xy 25.813453 -186.098109) (xy 25.829521 -186.151516) (xy 25.830601 -186.158855)
			(xy 33.231067 -186.158855) (xy 33.237595 -186.1047) (xy 33.251766 -186.052026) (xy 33.273292 -186.001906)
			(xy 33.301733 -185.955361) (xy 33.336511 -185.913338) (xy 33.376917 -185.876695) (xy 33.422128 -185.846177)
			(xy 33.471223 -185.822407) (xy 33.523202 -185.805867) (xy 33.577007 -185.796896) (xy 33.63154 -185.795676)
			(xy 33.685692 -185.802232) (xy 33.738358 -185.81643) (xy 33.788468 -185.837981) (xy 33.834998 -185.866447)
			(xy 33.877003 -185.901246) (xy 33.913625 -185.941671) (xy 33.94412 -185.986897) (xy 33.967865 -186.036005)
			(xy 33.976564 -186.061858) (xy 33.984151 -186.083948) (xy 34.006187 -186.125122) (xy 34.035374 -186.161579)
			(xy 34.070728 -186.192091) (xy 34.111061 -186.215633) (xy 34.155015 -186.231412) (xy 34.201112 -186.238897)
			(xy 34.224468 -186.238896) (xy 34.252772 -186.238815) (xy 34.308926 -186.245878) (xy 34.36342 -186.261158)
			(xy 34.41506 -186.284321) (xy 34.462711 -186.314857) (xy 34.505329 -186.352098) (xy 34.541978 -186.395225)
			(xy 34.571855 -186.443293) (xy 34.594303 -186.495248) (xy 34.60883 -186.549948) (xy 34.615117 -186.606194)
			(xy 34.613027 -186.662751) (xy 34.602605 -186.71838) (xy 34.58408 -186.771858) (xy 34.557858 -186.822014)
			(xy 34.524515 -186.867746) (xy 34.484782 -186.90805) (xy 34.462466 -186.925458) (xy 34.443963 -186.940008)
			(xy 34.412199 -186.974742) (xy 34.387375 -187.01473) (xy 34.370338 -187.058606) (xy 34.361672 -187.104869)
			(xy 34.361672 -187.151936) (xy 34.37034 -187.198198) (xy 34.387377 -187.242074) (xy 34.412202 -187.282062)
			(xy 34.443966 -187.316795) (xy 34.462466 -187.33135) (xy 34.484603 -187.348519) (xy 34.523978 -187.38837)
			(xy 34.557104 -187.433551) (xy 34.583268 -187.483089) (xy 34.601907 -187.53592) (xy 34.612622 -187.590908)
			(xy 34.615181 -187.646873) (xy 34.60953 -187.70261) (xy 34.59579 -187.756922) (xy 34.585054 -187.782708)
			(xy 44.809662 -187.782708) (xy 44.813733 -187.727086) (xy 44.825859 -187.672649) (xy 44.845782 -187.620558)
			(xy 44.873078 -187.571923) (xy 44.907164 -187.52778) (xy 44.947313 -187.489071) (xy 44.992671 -187.45662)
			(xy 45.042271 -187.431119) (xy 45.095055 -187.413112) (xy 45.149898 -187.402982) (xy 45.205632 -187.400945)
			(xy 45.261069 -187.407045) (xy 45.315026 -187.421151) (xy 45.366355 -187.442963) (xy 45.413961 -187.472017)
			(xy 45.456829 -187.507692) (xy 45.494046 -187.549229) (xy 45.524819 -187.595742) (xy 45.548491 -187.646239)
			(xy 45.564559 -187.699646) (xy 45.572679 -187.754822) (xy 45.573188 -187.782708) (xy 45.572679 -187.810594)
			(xy 45.564559 -187.86577) (xy 45.548491 -187.919177) (xy 45.524819 -187.969674) (xy 45.494046 -188.016187)
			(xy 45.456829 -188.057724) (xy 45.413961 -188.093399) (xy 45.366355 -188.122453) (xy 45.315026 -188.144265)
			(xy 45.261069 -188.158371) (xy 45.205632 -188.164471) (xy 45.149898 -188.162434) (xy 45.095055 -188.152304)
			(xy 45.042271 -188.134297) (xy 44.992671 -188.108796) (xy 44.947313 -188.076345) (xy 44.907164 -188.037636)
			(xy 44.873078 -187.993493) (xy 44.845782 -187.944858) (xy 44.825859 -187.892767) (xy 44.813733 -187.83833)
			(xy 44.809662 -187.782708) (xy 34.585054 -187.782708) (xy 34.574257 -187.808641) (xy 34.545393 -187.856656)
			(xy 34.509819 -187.899935) (xy 34.48939 -187.919106) (xy 34.472561 -187.935015) (xy 34.444431 -187.971799)
			(xy 34.423426 -188.013067) (xy 34.41024 -188.057457) (xy 34.405307 -188.1035) (xy 34.408791 -188.149675)
			(xy 34.420578 -188.194457) (xy 34.440276 -188.236365) (xy 34.467237 -188.274014) (xy 34.483548 -188.290454)
			(xy 34.503106 -188.309987) (xy 34.536946 -188.35369) (xy 34.564123 -188.401821) (xy 34.584067 -188.453371)
			(xy 34.596362 -188.50726) (xy 34.600748 -188.562359) (xy 34.597136 -188.617514) (xy 34.585599 -188.67157)
			(xy 34.56638 -188.723395) (xy 34.539882 -188.771903) (xy 34.506659 -188.816077) (xy 34.467407 -188.854993)
			(xy 34.422949 -188.887836) (xy 34.374216 -188.913917) (xy 34.322228 -188.93269) (xy 34.268075 -188.943762)
			(xy 34.21289 -188.946901) (xy 34.157831 -188.942042) (xy 34.10405 -188.929285) (xy 34.052673 -188.908899)
			(xy 34.004777 -188.88131) (xy 33.961366 -188.847096) (xy 33.923348 -188.806974) (xy 33.891519 -188.761784)
			(xy 33.866548 -188.712473) (xy 33.848955 -188.660074) (xy 33.839111 -188.605684) (xy 33.837221 -188.550443)
			(xy 33.843325 -188.495507) (xy 33.857295 -188.442028) (xy 33.878839 -188.391126) (xy 33.907505 -188.343867)
			(xy 33.942692 -188.301241) (xy 33.962848 -188.282326) (xy 33.979648 -188.266386) (xy 34.007785 -188.22961)
			(xy 34.028796 -188.188348) (xy 34.041989 -188.143962) (xy 34.046927 -188.097921) (xy 34.043446 -188.051748)
			(xy 34.031661 -188.006968) (xy 34.011963 -187.965062) (xy 33.985002 -187.927416) (xy 33.96869 -187.910978)
			(xy 33.949205 -187.891542) (xy 33.915462 -187.848065) (xy 33.88832 -187.80019) (xy 33.868343 -187.748909)
			(xy 33.855944 -187.69529) (xy 33.851382 -187.640445) (xy 33.854752 -187.585514) (xy 33.865984 -187.531638)
			(xy 33.884844 -187.479936) (xy 33.91094 -187.431482) (xy 33.943731 -187.387283) (xy 33.982534 -187.348257)
			(xy 34.00425 -187.33135) (xy 34.022745 -187.31679) (xy 34.054506 -187.282057) (xy 34.079329 -187.24207)
			(xy 34.096365 -187.198196) (xy 34.105031 -187.151935) (xy 34.105031 -187.10487) (xy 34.096366 -187.058609)
			(xy 34.079331 -187.014735) (xy 34.054509 -186.974747) (xy 34.022748 -186.940014) (xy 34.00425 -186.925458)
			(xy 33.980964 -186.907276) (xy 33.939747 -186.864955) (xy 33.905531 -186.816797) (xy 33.879131 -186.763948)
			(xy 33.86963 -186.735974) (xy 33.862088 -186.713868) (xy 33.840041 -186.672695) (xy 33.810845 -186.636241)
			(xy 33.775483 -186.605732) (xy 33.735144 -186.582193) (xy 33.691185 -186.566417) (xy 33.645084 -186.558934)
			(xy 33.621726 -186.558936) (xy 33.59445 -186.559143) (xy 33.540292 -186.552642) (xy 33.48761 -186.538498)
			(xy 33.437479 -186.516998) (xy 33.390919 -186.48858) (xy 33.348879 -186.453824) (xy 33.312216 -186.413436)
			(xy 33.281675 -186.368241) (xy 33.257879 -186.319158) (xy 33.241313 -186.267187) (xy 33.232315 -186.213388)
			(xy 33.231067 -186.158855) (xy 25.830601 -186.158855) (xy 25.837641 -186.206692) (xy 25.83815 -186.234578)
			(xy 25.837641 -186.262464) (xy 25.829521 -186.31764) (xy 25.813453 -186.371047) (xy 25.789781 -186.421544)
			(xy 25.759008 -186.468057) (xy 25.721791 -186.509594) (xy 25.678923 -186.545269) (xy 25.631317 -186.574323)
			(xy 25.579988 -186.596135) (xy 25.526031 -186.610241) (xy 25.470594 -186.616341) (xy 25.41486 -186.614304)
			(xy 25.360017 -186.604174) (xy 25.307233 -186.586167) (xy 25.257633 -186.560666) (xy 25.212275 -186.528215)
			(xy 25.172126 -186.489506) (xy 25.13804 -186.445363) (xy 25.110744 -186.396728) (xy 25.090821 -186.344637)
			(xy 25.078695 -186.2902) (xy 25.074624 -186.234578) (xy 14.86408 -186.234578) (xy 14.86408 -188.541035)
			(xy 30.180587 -188.541035) (xy 30.180896 -188.48571) (xy 30.189194 -188.431009) (xy 30.205308 -188.378081)
			(xy 30.228899 -188.328036) (xy 30.259472 -188.281925) (xy 30.277562 -188.26099) (xy 30.292474 -188.243651)
			(xy 30.316383 -188.20467) (xy 30.332932 -188.16204) (xy 30.341587 -188.117137) (xy 30.34207 -188.071411)
			(xy 30.334363 -188.026335) (xy 30.318717 -187.983366) (xy 30.295636 -187.943889) (xy 30.281118 -187.926218)
			(xy 30.263304 -187.904709) (xy 30.233505 -187.857476) (xy 30.210912 -187.806402) (xy 30.196009 -187.75258)
			(xy 30.189112 -187.69716) (xy 30.190371 -187.641326) (xy 30.199758 -187.586273) (xy 30.217073 -187.533177)
			(xy 30.241945 -187.483174) (xy 30.273842 -187.437331) (xy 30.312083 -187.396631) (xy 30.355851 -187.361941)
			(xy 30.404209 -187.334004) (xy 30.456124 -187.313418) (xy 30.510486 -187.300621) (xy 30.566132 -187.295889)
			(xy 30.621874 -187.299321) (xy 30.67652 -187.310846) (xy 30.728901 -187.330215) (xy 30.777898 -187.357015)
			(xy 30.822463 -187.390674) (xy 30.861644 -187.430471) (xy 30.894603 -187.475557) (xy 30.920635 -187.524966)
			(xy 30.939184 -187.577643) (xy 30.949853 -187.632462) (xy 30.952415 -187.688251) (xy 30.946814 -187.743817)
			(xy 30.93317 -187.797973) (xy 30.911776 -187.84956) (xy 30.883087 -187.897476) (xy 30.847719 -187.940696)
			(xy 30.806425 -187.978297) (xy 30.78353 -187.99429) (xy 30.770964 -188.003201) (xy 30.750292 -188.026036)
			(xy 30.735697 -188.05316) (xy 30.728028 -188.082991) (xy 30.727734 -188.113792) (xy 30.734832 -188.143764)
			(xy 30.748907 -188.171162) (xy 30.769139 -188.194387) (xy 30.781498 -188.203586) (xy 30.79115 -188.210444)
			(xy 30.809063 -188.223284) (xy 30.848312 -188.243319) (xy 30.89043 -188.25628) (xy 30.934153 -188.261777)
			(xy 30.978168 -188.259644) (xy 31.021155 -188.249948) (xy 31.061823 -188.232977) (xy 31.098952 -188.209242)
			(xy 31.115508 -188.194696) (xy 31.136442 -188.176276) (xy 31.182571 -188.144956) (xy 31.232768 -188.120686)
			(xy 31.285964 -188.103982) (xy 31.341025 -188.095199) (xy 31.396777 -188.094526) (xy 31.452034 -188.101977)
			(xy 31.505617 -188.117392) (xy 31.556386 -188.140443) (xy 31.603258 -188.17064) (xy 31.645234 -188.207338)
			(xy 31.681421 -188.249756) (xy 31.711048 -188.29699) (xy 31.733482 -188.348034) (xy 31.748247 -188.401801)
			(xy 31.755028 -188.457144) (xy 31.753679 -188.512884) (xy 31.744231 -188.567834) (xy 31.726883 -188.620823)
			(xy 31.702006 -188.670723) (xy 31.670131 -188.716469) (xy 31.631935 -188.757088) (xy 31.588232 -188.791714)
			(xy 31.539955 -188.819608) (xy 31.488131 -188.840178) (xy 31.433865 -188.852984) (xy 31.378313 -188.857753)
			(xy 31.322658 -188.854385) (xy 31.268087 -188.84295) (xy 31.215761 -188.823693) (xy 31.166796 -188.797024)
			(xy 31.14421 -188.780674) (xy 31.126325 -188.767792) (xy 31.08707 -188.747758) (xy 31.044946 -188.734801)
			(xy 31.001218 -188.729309) (xy 30.957198 -188.731446) (xy 30.914207 -188.74115) (xy 30.873537 -188.758128)
			(xy 30.836408 -188.781871) (xy 30.819852 -188.796422) (xy 30.799105 -188.814729) (xy 30.753387 -188.845887)
			(xy 30.703646 -188.870113) (xy 30.650928 -188.886899) (xy 30.596337 -188.895894) (xy 30.54102 -188.896907)
			(xy 30.486137 -188.889919) (xy 30.432839 -188.875075) (xy 30.382245 -188.852687) (xy 30.335415 -188.823224)
			(xy 30.293334 -188.787306) (xy 30.256882 -188.745685) (xy 30.226826 -188.699235) (xy 30.203795 -188.64893)
			(xy 30.188274 -188.595825) (xy 30.180587 -188.541035) (xy 14.86408 -188.541035) (xy 14.86408 -191.507373)
			(xy 30.072583 -191.507373) (xy 30.078686 -191.451899) (xy 30.092802 -191.397906) (xy 30.114629 -191.346543)
			(xy 30.143702 -191.298905) (xy 30.179401 -191.256009) (xy 30.220965 -191.218767) (xy 30.267509 -191.187973)
			(xy 30.31804 -191.164285) (xy 30.371482 -191.148207) (xy 30.426696 -191.140081) (xy 30.4546 -191.139572)
			(xy 30.482504 -191.140081) (xy 30.537718 -191.148207) (xy 30.59116 -191.164285) (xy 30.641691 -191.187973)
			(xy 30.688235 -191.218767) (xy 30.729799 -191.256009) (xy 30.765498 -191.298905) (xy 30.794571 -191.346543)
			(xy 30.816398 -191.397906) (xy 30.830514 -191.451899) (xy 30.836617 -191.507373) (xy 30.834579 -191.563144)
			(xy 30.824442 -191.618023) (xy 30.806423 -191.670843) (xy 30.780905 -191.720475) (xy 30.748433 -191.765863)
			(xy 30.709698 -191.80604) (xy 30.665526 -191.840148) (xy 30.616858 -191.867462) (xy 30.564732 -191.887398)
			(xy 30.510259 -191.899533) (xy 30.4546 -191.903607) (xy 30.398941 -191.899533) (xy 30.344468 -191.887398)
			(xy 30.292342 -191.867462) (xy 30.243674 -191.840148) (xy 30.199502 -191.80604) (xy 30.160767 -191.765863)
			(xy 30.128295 -191.720475) (xy 30.102777 -191.670843) (xy 30.084758 -191.618023) (xy 30.074621 -191.563144)
			(xy 30.072583 -191.507373) (xy 14.86408 -191.507373) (xy 14.86408 -192.786) (xy 31.520128 -192.786)
			(xy 31.524201 -192.730341) (xy 31.536336 -192.675868) (xy 31.556272 -192.623742) (xy 31.583586 -192.575074)
			(xy 31.617694 -192.530902) (xy 31.657871 -192.492167) (xy 31.703259 -192.459695) (xy 31.752891 -192.434177)
			(xy 31.805711 -192.416158) (xy 31.86059 -192.406021) (xy 31.916361 -192.403983) (xy 31.971835 -192.410086)
			(xy 32.025828 -192.424202) (xy 32.077191 -192.446029) (xy 32.124829 -192.475102) (xy 32.167725 -192.510801)
			(xy 32.204967 -192.552365) (xy 32.235761 -192.598909) (xy 32.259449 -192.64944) (xy 32.275527 -192.702882)
			(xy 32.283653 -192.758096) (xy 32.284162 -192.786) (xy 32.283653 -192.813904) (xy 32.275527 -192.869118)
			(xy 32.259449 -192.92256) (xy 32.235761 -192.973091) (xy 32.204967 -193.019635) (xy 32.167725 -193.061199)
			(xy 32.124829 -193.096898) (xy 32.077191 -193.125971) (xy 32.025828 -193.147798) (xy 31.971835 -193.161914)
			(xy 31.916361 -193.168017) (xy 31.86059 -193.165979) (xy 31.805711 -193.155842) (xy 31.752891 -193.137823)
			(xy 31.703259 -193.112305) (xy 31.657871 -193.079833) (xy 31.617694 -193.041098) (xy 31.583586 -192.996926)
			(xy 31.556272 -192.948258) (xy 31.536336 -192.896132) (xy 31.524201 -192.841659) (xy 31.520128 -192.786)
			(xy 14.86408 -192.786) (xy 14.86408 -193.45275) (xy 16.605502 -193.45275) (xy 16.609573 -193.397128)
			(xy 16.621699 -193.342691) (xy 16.641622 -193.2906) (xy 16.668918 -193.241965) (xy 16.703004 -193.197822)
			(xy 16.743153 -193.159113) (xy 16.788511 -193.126662) (xy 16.838111 -193.101161) (xy 16.890895 -193.083154)
			(xy 16.945738 -193.073024) (xy 17.001472 -193.070987) (xy 17.056909 -193.077087) (xy 17.110866 -193.091193)
			(xy 17.162195 -193.113005) (xy 17.209801 -193.142059) (xy 17.252669 -193.177734) (xy 17.289886 -193.219271)
			(xy 17.320659 -193.265784) (xy 17.344331 -193.316281) (xy 17.360399 -193.369688) (xy 17.368519 -193.424864)
			(xy 17.369028 -193.45275) (xy 17.368519 -193.480636) (xy 17.360399 -193.535812) (xy 17.344331 -193.589219)
			(xy 17.320659 -193.639716) (xy 17.289886 -193.686229) (xy 17.252669 -193.727766) (xy 17.209801 -193.763441)
			(xy 17.162195 -193.792495) (xy 17.110866 -193.814307) (xy 17.056909 -193.828413) (xy 17.001472 -193.834513)
			(xy 16.945738 -193.832476) (xy 16.890895 -193.822346) (xy 16.838111 -193.804339) (xy 16.788511 -193.778838)
			(xy 16.743153 -193.746387) (xy 16.703004 -193.707678) (xy 16.668918 -193.663535) (xy 16.641622 -193.6149)
			(xy 16.621699 -193.562809) (xy 16.609573 -193.508372) (xy 16.605502 -193.45275) (xy 14.86408 -193.45275)
			(xy 14.86408 -194.525918) (xy 22.429977 -194.525918) (xy 22.436077 -194.470481) (xy 22.450183 -194.416524)
			(xy 22.471995 -194.365195) (xy 22.501049 -194.317589) (xy 22.536724 -194.274721) (xy 22.578261 -194.237504)
			(xy 22.624774 -194.206731) (xy 22.675271 -194.183059) (xy 22.728678 -194.166991) (xy 22.783854 -194.158871)
			(xy 22.81174 -194.158362) (xy 22.839626 -194.158871) (xy 22.894802 -194.166991) (xy 22.948209 -194.183059)
			(xy 22.998706 -194.206731) (xy 23.045219 -194.237504) (xy 23.086756 -194.274721) (xy 23.122431 -194.317589)
			(xy 23.151485 -194.365195) (xy 23.173297 -194.416524) (xy 23.187403 -194.470481) (xy 23.193503 -194.525918)
			(xy 23.191466 -194.581652) (xy 23.181336 -194.636495) (xy 23.173137 -194.660529) (xy 24.355043 -194.660529)
			(xy 24.361146 -194.605055) (xy 24.375262 -194.551062) (xy 24.397089 -194.499699) (xy 24.426162 -194.452061)
			(xy 24.461861 -194.409165) (xy 24.503425 -194.371923) (xy 24.549969 -194.341129) (xy 24.6005 -194.317441)
			(xy 24.653942 -194.301363) (xy 24.709156 -194.293237) (xy 24.73706 -194.292728) (xy 24.764964 -194.293237)
			(xy 24.820178 -194.301363) (xy 24.87362 -194.317441) (xy 24.924151 -194.341129) (xy 24.970695 -194.371923)
			(xy 25.012259 -194.409165) (xy 25.047958 -194.452061) (xy 25.077031 -194.499699) (xy 25.098858 -194.551062)
			(xy 25.112974 -194.605055) (xy 25.119077 -194.660529) (xy 25.117039 -194.7163) (xy 25.106902 -194.771179)
			(xy 25.088883 -194.823999) (xy 25.063365 -194.873631) (xy 25.030893 -194.919019) (xy 24.992158 -194.959196)
			(xy 24.947986 -194.993304) (xy 24.899318 -195.020618) (xy 24.847192 -195.040554) (xy 24.792719 -195.052689)
			(xy 24.73706 -195.056763) (xy 24.681401 -195.052689) (xy 24.626928 -195.040554) (xy 24.574802 -195.020618)
			(xy 24.526134 -194.993304) (xy 24.481962 -194.959196) (xy 24.443227 -194.919019) (xy 24.410755 -194.873631)
			(xy 24.385237 -194.823999) (xy 24.367218 -194.771179) (xy 24.357081 -194.7163) (xy 24.355043 -194.660529)
			(xy 23.173137 -194.660529) (xy 23.163329 -194.689279) (xy 23.137828 -194.738879) (xy 23.105377 -194.784237)
			(xy 23.066668 -194.824386) (xy 23.022525 -194.858472) (xy 22.97389 -194.885768) (xy 22.921799 -194.905691)
			(xy 22.867362 -194.917817) (xy 22.81174 -194.921888) (xy 22.756118 -194.917817) (xy 22.701681 -194.905691)
			(xy 22.64959 -194.885768) (xy 22.600955 -194.858472) (xy 22.556812 -194.824386) (xy 22.518103 -194.784237)
			(xy 22.485652 -194.738879) (xy 22.460151 -194.689279) (xy 22.442144 -194.636495) (xy 22.432014 -194.581652)
			(xy 22.429977 -194.525918) (xy 14.86408 -194.525918) (xy 14.86408 -196.3674) (xy 26.109928 -196.3674)
			(xy 26.114001 -196.311741) (xy 26.126136 -196.257268) (xy 26.146072 -196.205142) (xy 26.173386 -196.156474)
			(xy 26.207494 -196.112302) (xy 26.247671 -196.073567) (xy 26.293059 -196.041095) (xy 26.342691 -196.015577)
			(xy 26.395511 -195.997558) (xy 26.45039 -195.987421) (xy 26.506161 -195.985383) (xy 26.561635 -195.991486)
			(xy 26.615628 -196.005602) (xy 26.666991 -196.027429) (xy 26.714629 -196.056502) (xy 26.757525 -196.092201)
			(xy 26.794767 -196.133765) (xy 26.825561 -196.180309) (xy 26.849249 -196.23084) (xy 26.865327 -196.284282)
			(xy 26.873453 -196.339496) (xy 26.873962 -196.3674) (xy 26.873453 -196.395304) (xy 26.865327 -196.450518)
			(xy 26.849249 -196.50396) (xy 26.825561 -196.554491) (xy 26.794767 -196.601035) (xy 26.757525 -196.642599)
			(xy 26.714629 -196.678298) (xy 26.666991 -196.707371) (xy 26.615628 -196.729198) (xy 26.561635 -196.743314)
			(xy 26.506161 -196.749417) (xy 26.45039 -196.747379) (xy 26.395511 -196.737242) (xy 26.342691 -196.719223)
			(xy 26.293059 -196.693705) (xy 26.247671 -196.661233) (xy 26.207494 -196.622498) (xy 26.173386 -196.578326)
			(xy 26.146072 -196.529658) (xy 26.126136 -196.477532) (xy 26.114001 -196.423059) (xy 26.109928 -196.3674)
			(xy 14.86408 -196.3674) (xy 14.86408 -199.694292) (xy 15.182088 -200.0123) (xy 17.79905 -200.0123)
		)
		(stroke
			(width 0)
			(type solid)
		)
		(fill yes)
		(layer "In6.Cu")
		(net "P12V_PDB")
	)
	(gr_poly
		(pts
			(xy 40.792146 -103.650288) (xy 40.814463 -103.649817) (xy 40.858409 -103.642015) (xy 40.900318 -103.626658)
			(xy 40.938901 -103.604218) (xy 40.972972 -103.575385) (xy 41.001484 -103.541045) (xy 41.023562 -103.502254)
			(xy 41.038525 -103.460204) (xy 41.045916 -103.416186) (xy 41.045506 -103.371554) (xy 41.037308 -103.32768)
			(xy 41.02989 -103.306626) (xy 41.019781 -103.278366) (xy 41.007574 -103.219604) (xy 41.00473 -103.159656)
			(xy 41.011319 -103.100002) (xy 41.018714 -103.070914) (xy 41.024075 -103.049698) (xy 41.028275 -103.006143)
			(xy 41.024946 -102.962513) (xy 41.014187 -102.920099) (xy 40.996316 -102.880158) (xy 40.971862 -102.843872)
			(xy 40.941549 -102.812316) (xy 40.906275 -102.786424) (xy 40.886888 -102.776274) (xy 40.862203 -102.763442)
			(xy 40.81651 -102.731709) (xy 40.77591 -102.693675) (xy 40.741265 -102.650147) (xy 40.71331 -102.602049)
			(xy 40.692637 -102.5504) (xy 40.679685 -102.496297) (xy 40.674729 -102.440886) (xy 40.677873 -102.385343)
			(xy 40.689052 -102.330846) (xy 40.708028 -102.27855) (xy 40.734398 -102.229565) (xy 40.767604 -102.184929)
			(xy 40.80694 -102.14559) (xy 40.851573 -102.112382) (xy 40.900557 -102.086008) (xy 40.952851 -102.067029)
			(xy 41.007348 -102.055847) (xy 41.062891 -102.052698) (xy 41.118302 -102.057651) (xy 41.172406 -102.070599)
			(xy 41.224056 -102.091268) (xy 41.272156 -102.119221) (xy 41.315686 -102.153863) (xy 41.353723 -102.19446)
			(xy 41.38546 -102.240152) (xy 41.410223 -102.289968) (xy 41.427489 -102.342853) (xy 41.43689 -102.397685)
			(xy 41.438227 -102.453301) (xy 41.431471 -102.508522) (xy 41.424606 -102.535482) (xy 41.419245 -102.556698)
			(xy 41.415043 -102.600253) (xy 41.418371 -102.643883) (xy 41.429131 -102.686297) (xy 41.447002 -102.726237)
			(xy 41.471457 -102.762523) (xy 41.501771 -102.794078) (xy 41.537047 -102.819968) (xy 41.556432 -102.830122)
			(xy 41.581352 -102.843057) (xy 41.627431 -102.875135) (xy 41.668311 -102.913621) (xy 41.703109 -102.957682)
			(xy 41.731074 -103.006368) (xy 41.751601 -103.058626) (xy 41.764248 -103.113329) (xy 41.768741 -103.169294)
			(xy 41.764982 -103.225314) (xy 41.753055 -103.280177) (xy 41.74363 -103.306626) (xy 41.736187 -103.327677)
			(xy 41.727967 -103.371559) (xy 41.727541 -103.416203) (xy 41.734922 -103.460235) (xy 41.749883 -103.502299)
			(xy 41.771964 -103.541103) (xy 41.800484 -103.575451) (xy 41.834568 -103.604288) (xy 41.873165 -103.626727)
			(xy 41.91509 -103.642076) (xy 41.959051 -103.649864) (xy 41.981374 -103.650288) (xy 43.102022 -103.650288)
			(xy 43.496992 -103.255318) (xy 43.50258 -103.212392) (xy 43.506243 -103.187206) (xy 43.519396 -103.138039)
			(xy 43.538982 -103.091064) (xy 43.564651 -103.047116) (xy 43.595948 -103.00698) (xy 43.613832 -102.988872)
			(xy 43.625429 -102.976765) (xy 43.642405 -102.947866) (xy 43.651289 -102.91555) (xy 43.651472 -102.882035)
			(xy 43.642941 -102.849623) (xy 43.626282 -102.820541) (xy 43.614848 -102.808278) (xy 43.04538 -102.23881)
			(xy 43.04538 -97.412048) (xy 44.2595 -96.197928) (xy 44.2595 -85.90407) (xy 44.259049 -85.888577)
			(xy 44.251566 -85.858507) (xy 44.237073 -85.831119) (xy 44.216418 -85.80802) (xy 44.203874 -85.798914)
			(xy 44.181317 -85.782972) (xy 44.140611 -85.745638) (xy 44.105712 -85.702825) (xy 44.077349 -85.655429)
			(xy 44.056115 -85.60444) (xy 44.042452 -85.550922) (xy 44.036648 -85.495993) (xy 44.038822 -85.440801)
			(xy 44.048929 -85.3865) (xy 44.066759 -85.334222) (xy 44.091938 -85.285061) (xy 44.123942 -85.240043)
			(xy 44.1621 -85.200108) (xy 44.183554 -85.18271) (xy 44.20489 -85.1662) (xy 44.2595 -85.063076) (xy 44.2595 -81.2292)
			(xy 43.66768 -80.63738) (xy 43.66768 -78.2701) (xy 43.667185 -78.253446) (xy 43.658564 -78.221274)
			(xy 43.641909 -78.192429) (xy 43.618355 -78.168879) (xy 43.589508 -78.152228) (xy 43.557334 -78.143612)
			(xy 43.54068 -78.1431) (xy 43.394122 -78.1431) (xy 43.172126 -78.365096) (xy 41.667938 -78.365096)
			(xy 41.645882 -78.365566) (xy 41.602431 -78.37318) (xy 41.560949 -78.388186) (xy 41.522683 -78.410132)
			(xy 41.488784 -78.438359) (xy 41.46027 -78.472018) (xy 41.438 -78.510096) (xy 41.422644 -78.55145)
			(xy 41.414661 -78.594834) (xy 41.414294 -78.638945) (xy 41.421553 -78.682457) (xy 41.428416 -78.703424)
			(xy 41.437262 -78.730033) (xy 41.447946 -78.785079) (xy 41.45046 -78.841097) (xy 41.444748 -78.896878)
			(xy 41.430934 -78.951224) (xy 41.409316 -79.002962) (xy 41.380358 -79.05098) (xy 41.344685 -79.094243)
			(xy 41.303065 -79.131819) (xy 41.256394 -79.1629) (xy 41.205676 -79.186816) (xy 41.152005 -79.203052)
			(xy 41.096535 -79.211258) (xy 41.040461 -79.211258) (xy 40.984991 -79.203052) (xy 40.93132 -79.186816)
			(xy 40.880602 -79.1629) (xy 40.833931 -79.131819) (xy 40.792311 -79.094243) (xy 40.756638 -79.05098)
			(xy 40.72768 -79.002962) (xy 40.706062 -78.951224) (xy 40.692248 -78.896878) (xy 40.686536 -78.841097)
			(xy 40.68905 -78.785079) (xy 40.699734 -78.730033) (xy 40.70858 -78.703424) (xy 40.715456 -78.682465)
			(xy 40.722696 -78.638956) (xy 40.722313 -78.594851) (xy 40.714321 -78.551474) (xy 40.698959 -78.510129)
			(xy 40.676688 -78.472058) (xy 40.648178 -78.438404) (xy 40.614285 -78.410179) (xy 40.576027 -78.38823)
			(xy 40.534554 -78.373217) (xy 40.491111 -78.365591) (xy 40.469058 -78.365096) (xy 40.044116 -78.365096)
			(xy 39.622984 -78.786228) (xy 39.60004 -78.808463) (xy 39.549554 -78.847624) (xy 39.494558 -78.880149)
			(xy 39.435919 -78.905524) (xy 39.374562 -78.92335) (xy 39.311455 -78.933345) (xy 39.247593 -78.935352)
			(xy 39.183982 -78.929339) (xy 39.121628 -78.915401) (xy 39.061511 -78.893758) (xy 39.004581 -78.864751)
			(xy 38.951736 -78.828837) (xy 38.903809 -78.786583) (xy 38.861555 -78.738656) (xy 38.825641 -78.685811)
			(xy 38.796634 -78.628881) (xy 38.774991 -78.568764) (xy 38.761053 -78.50641) (xy 38.75504 -78.442799)
			(xy 38.757047 -78.378937) (xy 38.767042 -78.31583) (xy 38.784868 -78.254473) (xy 38.810243 -78.195834)
			(xy 38.842768 -78.140838) (xy 38.881929 -78.090352) (xy 38.904164 -78.067408) (xy 39.622984 -77.348588)
			(xy 40.568626 -77.348588) (xy 40.590879 -77.348125) (xy 40.634703 -77.34037) (xy 40.676508 -77.325103)
			(xy 40.715016 -77.302789) (xy 40.749049 -77.274111) (xy 40.777569 -77.239944) (xy 40.799703 -77.201333)
			(xy 40.814776 -77.159457) (xy 40.822326 -77.115597) (xy 40.822123 -77.071092) (xy 40.818562 -77.049122)
			(xy 40.814092 -77.021643) (xy 40.812226 -76.966003) (xy 40.818466 -76.910683) (xy 40.832679 -76.856857)
			(xy 40.854564 -76.805668) (xy 40.883656 -76.758204) (xy 40.919337 -76.715471) (xy 40.96085 -76.678377)
			(xy 41.007313 -76.64771) (xy 41.057739 -76.624122) (xy 41.111059 -76.608112) (xy 41.166139 -76.600021)
			(xy 41.221809 -76.600021) (xy 41.276889 -76.608112) (xy 41.330209 -76.624122) (xy 41.380635 -76.64771)
			(xy 41.427098 -76.678377) (xy 41.468611 -76.715471) (xy 41.504292 -76.758204) (xy 41.533384 -76.805668)
			(xy 41.555269 -76.856857) (xy 41.569482 -76.910683) (xy 41.575722 -76.966003) (xy 41.573856 -77.021643)
			(xy 41.569386 -77.049122) (xy 41.565855 -77.071099) (xy 41.565637 -77.115608) (xy 41.573174 -77.159473)
			(xy 41.588238 -77.201356) (xy 41.610367 -77.239973) (xy 41.638885 -77.274146) (xy 41.672919 -77.302828)
			(xy 41.71143 -77.325144) (xy 41.753239 -77.340409) (xy 41.797068 -77.348159) (xy 41.819322 -77.348588)
			(xy 42.750994 -77.348588) (xy 42.97299 -77.126592) (xy 43.54068 -77.126592) (xy 43.557336 -77.1261)
			(xy 43.589514 -77.117482) (xy 43.618365 -77.100828) (xy 43.641921 -77.077274) (xy 43.658577 -77.048425)
			(xy 43.667198 -77.016248) (xy 43.66768 -76.999592) (xy 43.66768 -73.255632) (xy 45.254164 -71.669148)
			(xy 45.269753 -71.652869) (xy 45.295496 -71.615879) (xy 45.31431 -71.574926) (xy 45.325604 -71.531297)
			(xy 45.329023 -71.48636) (xy 45.32446 -71.441525) (xy 45.31206 -71.398197) (xy 45.292209 -71.357737)
			(xy 45.265532 -71.321414) (xy 45.232865 -71.290367) (xy 45.195233 -71.26557) (xy 45.153816 -71.247802)
			(xy 45.13199 -71.242174) (xy 45.10225 -71.234641) (xy 45.045486 -71.211376) (xy 44.993185 -71.179315)
			(xy 44.946697 -71.139286) (xy 44.926504 -71.11619) (xy 44.915895 -71.104369) (xy 44.890057 -71.085912)
			(xy 44.860458 -71.074418) (xy 44.828936 -71.070601) (xy 44.797448 -71.074697) (xy 44.767952 -71.086453)
			(xy 44.7548 -71.095362) (xy 44.732112 -71.111219) (xy 44.683087 -71.136917) (xy 44.630864 -71.155262)
			(xy 44.576537 -71.165867) (xy 44.521249 -71.168509) (xy 44.466158 -71.163135) (xy 44.412423 -71.149856)
			(xy 44.361171 -71.128951) (xy 44.313477 -71.100859) (xy 44.270344 -71.066169) (xy 44.232677 -71.025611)
			(xy 44.201266 -70.980035) (xy 44.17677 -70.930399) (xy 44.159705 -70.877743) (xy 44.150428 -70.823174)
			(xy 44.149135 -70.767838) (xy 44.155851 -70.712895) (xy 44.170437 -70.659499) (xy 44.192585 -70.608772)
			(xy 44.221832 -70.561778) (xy 44.257563 -70.519504) (xy 44.299028 -70.482837) (xy 44.345356 -70.452546)
			(xy 44.395576 -70.429269) (xy 44.448632 -70.413493) (xy 44.50341 -70.40555) (xy 44.558762 -70.405606)
			(xy 44.613525 -70.41366) (xy 44.666549 -70.429544) (xy 44.716721 -70.452923) (xy 44.762987 -70.483307)
			(xy 44.804378 -70.520058) (xy 44.822618 -70.54088) (xy 44.833225 -70.552713) (xy 44.859065 -70.571192)
			(xy 44.888672 -70.582706) (xy 44.920207 -70.58654) (xy 44.951711 -70.582455) (xy 44.981226 -70.570706)
			(xy 44.994322 -70.561708) (xy 45.016329 -70.546312) (xy 45.063797 -70.521187) (xy 45.114321 -70.502969)
			(xy 45.1669 -70.492018) (xy 45.220495 -70.48855) (xy 45.274047 -70.492634) (xy 45.326497 -70.504189)
			(xy 45.376808 -70.522986) (xy 45.423985 -70.548655) (xy 45.467094 -70.580687) (xy 45.505285 -70.618449)
			(xy 45.537802 -70.661194) (xy 45.564001 -70.708078) (xy 45.583366 -70.758173) (xy 45.589952 -70.784212)
			(xy 45.595521 -70.806051) (xy 45.613295 -70.847464) (xy 45.638097 -70.885091) (xy 45.669148 -70.917753)
			(xy 45.705475 -70.944424) (xy 45.745936 -70.964267) (xy 45.789265 -70.976661) (xy 45.8341 -70.981216)
			(xy 45.879035 -70.97779) (xy 45.922661 -70.96649) (xy 45.96361 -70.947671) (xy 46.000595 -70.921922)
			(xy 46.016926 -70.906386) (xy 46.12132 -70.801992) (xy 46.133954 -70.788413) (xy 46.151482 -70.755746)
			(xy 46.158895 -70.719421) (xy 46.157896 -70.7009) (xy 46.15688 -70.689216) (xy 46.156118 -70.68439)
			(xy 46.152366 -70.659673) (xy 46.150559 -70.609711) (xy 46.155285 -70.559941) (xy 46.166463 -70.511213)
			(xy 46.183903 -70.46436) (xy 46.195234 -70.442074) (xy 46.20503 -70.422604) (xy 46.218547 -70.381173)
			(xy 46.224801 -70.338044) (xy 46.223609 -70.294479) (xy 46.215006 -70.251756) (xy 46.199244 -70.211126)
			(xy 46.176784 -70.173779) (xy 46.148284 -70.140808) (xy 46.11458 -70.113181) (xy 46.076659 -70.091705)
			(xy 46.056296 -70.083934) (xy 46.029265 -70.073734) (xy 45.978489 -70.046174) (xy 45.955204 -70.02907)
			(xy 45.936038 -70.015063) (xy 45.893649 -69.993702) (xy 45.848032 -69.980581) (xy 45.800772 -69.976156)
			(xy 45.753512 -69.980581) (xy 45.707895 -69.993702) (xy 45.665506 -70.015063) (xy 45.64634 -70.02907)
			(xy 45.625103 -70.044758) (xy 45.579074 -70.070623) (xy 45.529854 -70.089731) (xy 45.47843 -70.101699)
			(xy 45.425831 -70.106286) (xy 45.373112 -70.103402) (xy 45.321327 -70.093103) (xy 45.271516 -70.075597)
			(xy 45.224675 -70.051233) (xy 45.181743 -70.0205) (xy 45.143579 -69.984014) (xy 45.12691 -69.963538)
			(xy 45.111772 -69.945169) (xy 45.075897 -69.913895) (xy 45.034832 -69.889837) (xy 44.99001 -69.873834)
			(xy 44.942994 -69.866443) (xy 44.895424 -69.867923) (xy 44.848958 -69.878223) (xy 44.805218 -69.896981)
			(xy 44.765728 -69.923546) (xy 44.74845 -69.939916) (xy 44.72811 -69.959357) (xy 44.682754 -69.992651)
			(xy 44.632999 -70.018921) (xy 44.579926 -70.037598) (xy 44.524685 -70.048277) (xy 44.468474 -70.050725)
			(xy 44.412513 -70.044891) (xy 44.358017 -70.030899) (xy 44.306166 -70.009055) (xy 44.258087 -69.979831)
			(xy 44.214822 -69.943862) (xy 44.17731 -69.901928) (xy 44.146364 -69.854939) (xy 44.122656 -69.803913)
			(xy 44.1067 -69.749959) (xy 44.098842 -69.694247) (xy 44.099254 -69.637984) (xy 44.107925 -69.582392)
			(xy 44.115736 -69.55536) (xy 44.122294 -69.5326) (xy 44.127791 -69.485561) (xy 44.124468 -69.438318)
			(xy 44.112442 -69.392511) (xy 44.092129 -69.349729) (xy 44.064234 -69.311456) (xy 44.029726 -69.279021)
			(xy 44.010072 -69.2658) (xy 43.999555 -69.258891) (xy 43.979345 -69.243893) (xy 43.969686 -69.235828)
			(xy 43.952212 -69.221719) (xy 43.913329 -69.199249) (xy 43.871106 -69.183956) (xy 43.826852 -69.176315)
			(xy 43.781945 -69.176563) (xy 43.737779 -69.184693) (xy 43.695727 -69.200451) (xy 43.657095 -69.223349)
			(xy 43.63974 -69.237606) (xy 43.618189 -69.255543) (xy 43.570829 -69.285557) (xy 43.519585 -69.308315)
			(xy 43.465562 -69.323325) (xy 43.409924 -69.330264) (xy 43.353869 -69.328983) (xy 43.298605 -69.319509)
			(xy 43.245324 -69.302046) (xy 43.195174 -69.276972) (xy 43.149235 -69.244825) (xy 43.108497 -69.206299)
			(xy 43.073838 -69.162225) (xy 43.046006 -69.113551) (xy 43.025599 -69.061327) (xy 43.013058 -69.006678)
			(xy 43.008652 -68.950781) (xy 43.012477 -68.894842) (xy 43.024451 -68.840066) (xy 43.044315 -68.787633)
			(xy 43.071641 -68.738673) (xy 43.105841 -68.694241) (xy 43.146177 -68.655295) (xy 43.19178 -68.622673)
			(xy 43.241667 -68.59708) (xy 43.294764 -68.579066) (xy 43.349926 -68.569019) (xy 43.405965 -68.567156)
			(xy 43.461673 -68.573518) (xy 43.515849 -68.587966) (xy 43.567326 -68.610191) (xy 43.614994 -68.639712)
			(xy 43.636692 -68.65747) (xy 43.654166 -68.671581) (xy 43.693049 -68.694055) (xy 43.735274 -68.709351)
			(xy 43.77953 -68.716996) (xy 43.824439 -68.716751) (xy 43.868609 -68.708624) (xy 43.910664 -68.692867)
			(xy 43.9493 -68.669971) (xy 43.966638 -68.655692) (xy 43.987697 -68.638156) (xy 44.033891 -68.608671)
			(xy 44.083828 -68.5861) (xy 44.136481 -68.570906) (xy 44.190766 -68.563402) (xy 44.245566 -68.563742)
			(xy 44.299754 -68.57192) (xy 44.352214 -68.587766) (xy 44.401867 -68.610956) (xy 44.416631 -68.62064)
			(xy 45.068996 -68.62064) (xy 45.073067 -68.565018) (xy 45.085193 -68.510581) (xy 45.105116 -68.45849)
			(xy 45.132412 -68.409855) (xy 45.166498 -68.365712) (xy 45.206647 -68.327003) (xy 45.252005 -68.294552)
			(xy 45.301605 -68.269051) (xy 45.354389 -68.251044) (xy 45.409232 -68.240914) (xy 45.464966 -68.238877)
			(xy 45.520403 -68.244977) (xy 45.57436 -68.259083) (xy 45.625689 -68.280895) (xy 45.673295 -68.309949)
			(xy 45.716163 -68.345624) (xy 45.75338 -68.387161) (xy 45.784153 -68.433674) (xy 45.807825 -68.484171)
			(xy 45.8156 -68.510012) (xy 46.212573 -68.510012) (xy 46.21981 -68.455861) (xy 46.234699 -68.403296)
			(xy 46.256935 -68.353393) (xy 46.286063 -68.307173) (xy 46.321487 -68.265582) (xy 46.362483 -68.22947)
			(xy 46.408212 -68.199577) (xy 46.457738 -68.176514) (xy 46.510047 -68.160752) (xy 46.564071 -68.152615)
			(xy 46.618702 -68.152269) (xy 46.672824 -68.159721) (xy 46.72533 -68.174818) (xy 46.775144 -68.197252)
			(xy 46.821247 -68.226564) (xy 46.862698 -68.262153) (xy 46.898646 -68.303292) (xy 46.928358 -68.349139)
			(xy 46.940216 -68.373752) (xy 46.947682 -68.388796) (xy 46.969207 -68.414562) (xy 46.996709 -68.433821)
			(xy 47.028282 -68.445238) (xy 47.061741 -68.448023) (xy 47.094768 -68.441982) (xy 47.110142 -68.43522)
			(xy 47.134993 -68.423855) (xy 47.187186 -68.407663) (xy 47.241156 -68.399083) (xy 47.295797 -68.398291)
			(xy 47.349992 -68.405303) (xy 47.402633 -68.419975) (xy 47.452641 -68.442009) (xy 47.498994 -68.470951)
			(xy 47.540744 -68.506212) (xy 47.577035 -68.547068) (xy 47.605619 -68.590399) (xy 48.351262 -68.590399)
			(xy 48.359192 -68.53561) (xy 48.374956 -68.482543) (xy 48.398223 -68.43231) (xy 48.428505 -68.385967)
			(xy 48.465165 -68.344485) (xy 48.507434 -68.308736) (xy 48.554426 -68.279471) (xy 48.605153 -68.257302)
			(xy 48.658551 -68.242696) (xy 48.713499 -68.23596) (xy 48.768844 -68.237234) (xy 48.823423 -68.246492)
			(xy 48.876093 -68.26354) (xy 48.925746 -68.288019) (xy 48.971341 -68.319416) (xy 49.01192 -68.357072)
			(xy 49.046633 -68.400197) (xy 49.061116 -68.42379) (xy 49.070303 -68.438336) (xy 49.095062 -68.462208)
			(xy 49.125304 -68.478588) (xy 49.158826 -68.486281) (xy 49.193184 -68.484726) (xy 49.209706 -68.479924)
			(xy 49.236187 -68.471858) (xy 49.290739 -68.462468) (xy 49.346075 -68.46106) (xy 49.401033 -68.467663)
			(xy 49.454461 -68.482138) (xy 49.505236 -68.504182) (xy 49.552293 -68.533331) (xy 49.594644 -68.568974)
			(xy 49.6314 -68.610362) (xy 49.66179 -68.656628) (xy 49.685175 -68.706799) (xy 49.701066 -68.759823)
			(xy 49.709127 -68.814587) (xy 49.70919 -68.869941) (xy 49.701254 -68.924723) (xy 49.685486 -68.977783)
			(xy 49.662215 -69.028008) (xy 49.631931 -69.074343) (xy 49.59527 -69.115815) (xy 49.553001 -69.151555)
			(xy 49.50601 -69.180812) (xy 49.455286 -69.202972) (xy 49.401891 -69.217569) (xy 49.346948 -69.224297)
			(xy 49.291609 -69.223016) (xy 49.237036 -69.213752) (xy 49.184375 -69.196698) (xy 49.13473 -69.172215)
			(xy 49.089145 -69.140814) (xy 49.048575 -69.103156) (xy 49.013872 -69.060031) (xy 48.999394 -69.036438)
			(xy 48.99019 -69.021903) (xy 48.965437 -68.998028) (xy 48.935199 -68.981645) (xy 48.901681 -68.97395)
			(xy 48.867325 -68.975502) (xy 48.850804 -68.980304) (xy 48.824355 -68.988478) (xy 48.769799 -68.997873)
			(xy 48.714457 -68.999286) (xy 48.659492 -68.992688) (xy 48.606058 -68.978216) (xy 48.555275 -68.956175)
			(xy 48.50821 -68.927028) (xy 48.465851 -68.891385) (xy 48.429087 -68.849996) (xy 48.39869 -68.803729)
			(xy 48.375297 -68.753554) (xy 48.359399 -68.700527) (xy 48.351331 -68.645758) (xy 48.351262 -68.590399)
			(xy 47.605619 -68.590399) (xy 47.607126 -68.592684) (xy 47.630401 -68.642127) (xy 47.646384 -68.694384)
			(xy 47.654746 -68.748388) (xy 47.655319 -68.803032) (xy 47.648088 -68.857199) (xy 47.633204 -68.90978)
			(xy 47.61097 -68.959699) (xy 47.581841 -69.005935) (xy 47.546413 -69.047543) (xy 47.505411 -69.083669)
			(xy 47.459674 -69.113576) (xy 47.410138 -69.136652) (xy 47.357816 -69.152424) (xy 47.303779 -69.160569)
			(xy 47.249133 -69.160922) (xy 47.194996 -69.153474) (xy 47.142476 -69.138378) (xy 47.092646 -69.115943)
			(xy 47.046528 -69.086628) (xy 47.005063 -69.051032) (xy 46.969102 -69.009885) (xy 46.939379 -68.964028)
			(xy 46.927516 -68.93941) (xy 46.920027 -68.92438) (xy 46.898504 -68.898619) (xy 46.871007 -68.879364)
			(xy 46.839439 -68.867946) (xy 46.805986 -68.865156) (xy 46.772964 -68.871187) (xy 46.75759 -68.877942)
			(xy 46.732693 -68.889194) (xy 46.68051 -68.905371) (xy 46.626553 -68.913937) (xy 46.571926 -68.914717)
			(xy 46.517747 -68.907695) (xy 46.465123 -68.893015) (xy 46.415133 -68.870978) (xy 46.368797 -68.842034)
			(xy 46.327066 -68.806775) (xy 46.290791 -68.765922) (xy 46.260717 -68.720313) (xy 46.237457 -68.670879)
			(xy 46.221488 -68.618632) (xy 46.213136 -68.564642) (xy 46.212573 -68.510012) (xy 45.8156 -68.510012)
			(xy 45.823893 -68.537578) (xy 45.832013 -68.592754) (xy 45.832522 -68.62064) (xy 45.832013 -68.648526)
			(xy 45.823893 -68.703702) (xy 45.807825 -68.757109) (xy 45.784153 -68.807606) (xy 45.75338 -68.854119)
			(xy 45.716163 -68.895656) (xy 45.673295 -68.931331) (xy 45.625689 -68.960385) (xy 45.57436 -68.982197)
			(xy 45.520403 -68.996303) (xy 45.464966 -69.002403) (xy 45.409232 -69.000366) (xy 45.354389 -68.990236)
			(xy 45.301605 -68.972229) (xy 45.252005 -68.946728) (xy 45.206647 -68.914277) (xy 45.166498 -68.875568)
			(xy 45.132412 -68.831425) (xy 45.105116 -68.78279) (xy 45.085193 -68.730699) (xy 45.073067 -68.676262)
			(xy 45.068996 -68.62064) (xy 44.416631 -68.62064) (xy 44.447691 -68.641012) (xy 44.488743 -68.677315)
			(xy 44.524178 -68.719118) (xy 44.553267 -68.765562) (xy 44.575412 -68.815689) (xy 44.590157 -68.86847)
			(xy 44.597198 -68.922817) (xy 44.59639 -68.977612) (xy 44.587751 -69.031728) (xy 44.580048 -69.058028)
			(xy 44.573489 -69.080788) (xy 44.56799 -69.127829) (xy 44.571311 -69.175073) (xy 44.583336 -69.220883)
			(xy 44.603647 -69.263667) (xy 44.63154 -69.301943) (xy 44.666048 -69.334382) (xy 44.685712 -69.347588)
			(xy 44.713247 -69.366104) (xy 44.762034 -69.411068) (xy 44.78274 -69.436996) (xy 44.79764 -69.455572)
			(xy 44.833121 -69.487327) (xy 44.873894 -69.511919) (xy 44.918534 -69.528487) (xy 44.965479 -69.536451)
			(xy 45.013085 -69.535534) (xy 45.059688 -69.525767) (xy 45.103657 -69.507492) (xy 45.143453 -69.481348)
			(xy 45.160946 -69.46519) (xy 45.180329 -69.447123) (xy 45.223275 -69.416087) (xy 45.270183 -69.391444)
			(xy 45.320107 -69.373691) (xy 45.372042 -69.363186) (xy 45.424941 -69.360139) (xy 45.477739 -69.364613)
			(xy 45.529371 -69.376518) (xy 45.578797 -69.395612) (xy 45.625022 -69.421513) (xy 45.64634 -69.43725)
			(xy 45.665506 -69.451257) (xy 45.707895 -69.472618) (xy 45.753512 -69.485739) (xy 45.800772 -69.490164)
			(xy 45.848032 -69.485739) (xy 45.893649 -69.472618) (xy 45.936038 -69.451257) (xy 45.955204 -69.43725)
			(xy 45.976833 -69.421283) (xy 46.023771 -69.395072) (xy 46.073988 -69.375876) (xy 46.126441 -69.364094)
			(xy 46.180043 -69.35997) (xy 46.233682 -69.363589) (xy 46.286244 -69.374877) (xy 46.336639 -69.393599)
			(xy 46.383822 -69.419367) (xy 46.426813 -69.451646) (xy 46.464721 -69.489767) (xy 46.496759 -69.532938)
			(xy 46.522262 -69.580264) (xy 46.540702 -69.630763) (xy 46.551696 -69.683388) (xy 46.555015 -69.737046)
			(xy 46.550591 -69.790624) (xy 46.538515 -69.843011) (xy 46.519039 -69.893119) (xy 46.492565 -69.93991)
			(xy 46.459645 -69.982412) (xy 46.440598 -70.001384) (xy 46.423326 -70.018148) (xy 46.404276 -70.059296)
			(xy 46.39786 -70.074656) (xy 46.392333 -70.107469) (xy 46.395468 -70.140596) (xy 46.407052 -70.17179)
			(xy 46.426298 -70.198934) (xy 46.451902 -70.220187) (xy 46.46676 -70.227698) (xy 46.49343 -70.23989)
			(xy 46.522894 -70.239128) (xy 46.542423 -70.238908) (xy 46.581362 -70.241963) (xy 46.600618 -70.245224)
			(xy 46.600872 -70.245224) (xy 46.616015 -70.247503) (xy 46.646569 -70.245617) (xy 46.675792 -70.236499)
			(xy 46.701996 -70.220674) (xy 46.71314 -70.210172) (xy 46.791372 -70.13194) (xy 46.933612 -70.13194)
			(xy 46.933612 -70.10908) (xy 50.599594 -70.10908) (xy 50.621768 -70.108624) (xy 50.665452 -70.100977)
			(xy 50.707144 -70.085862) (xy 50.745579 -70.063739) (xy 50.77959 -70.035278) (xy 50.808142 -70.001345)
			(xy 50.83037 -69.96297) (xy 50.845598 -69.921319) (xy 50.853363 -69.877657) (xy 50.85343 -69.833309)
			(xy 50.850038 -69.811392) (xy 50.84498 -69.784758) (xy 50.841559 -69.730655) (xy 50.845834 -69.676612)
			(xy 50.857718 -69.623719) (xy 50.876972 -69.573042) (xy 50.903209 -69.525602) (xy 50.935898 -69.482356)
			(xy 50.974383 -69.444174) (xy 51.017886 -69.411827) (xy 51.065531 -69.385965) (xy 51.116358 -69.367112)
			(xy 51.169343 -69.355645) (xy 51.223418 -69.351797) (xy 51.277493 -69.355645) (xy 51.330478 -69.367112)
			(xy 51.381305 -69.385965) (xy 51.42895 -69.411827) (xy 51.472453 -69.444174) (xy 51.510938 -69.482356)
			(xy 51.543627 -69.525602) (xy 51.569864 -69.573042) (xy 51.589118 -69.623719) (xy 51.601002 -69.676612)
			(xy 51.605277 -69.730655) (xy 51.601856 -69.784758) (xy 51.596798 -69.811392) (xy 51.593458 -69.833315)
			(xy 51.593526 -69.877657) (xy 51.601289 -69.921314) (xy 51.616513 -69.962961) (xy 51.638736 -70.001333)
			(xy 51.667281 -70.035264) (xy 51.701284 -70.063726) (xy 51.73971 -70.085853) (xy 51.781394 -70.100974)
			(xy 51.825071 -70.108629) (xy 51.847242 -70.10908) (xy 54.19344 -70.10908) (xy 54.482746 -69.819774)
			(xy 54.493445 -69.80845) (xy 54.509477 -69.781748) (xy 54.518541 -69.75195) (xy 54.520094 -69.720844)
			(xy 54.517544 -69.705474) (xy 54.51271 -69.678715) (xy 54.509784 -69.624419) (xy 54.51461 -69.570259)
			(xy 54.527089 -69.517335) (xy 54.546968 -69.466724) (xy 54.559962 -69.442838) (xy 54.567836 -69.42963)
			(xy 54.58714 -69.398642) (xy 54.58714 -69.10197) (xy 54.567836 -69.070982) (xy 54.554179 -69.048183)
			(xy 54.532619 -68.999607) (xy 54.518009 -68.948509) (xy 54.510632 -68.895878) (xy 54.510631 -68.842732)
			(xy 54.518006 -68.790101) (xy 54.532615 -68.739003) (xy 54.554174 -68.690426) (xy 54.567836 -68.66763)
			(xy 54.58714 -68.636642) (xy 54.58714 -68.408042) (xy 54.574694 -68.382134) (xy 54.563155 -68.356873)
			(xy 54.546853 -68.303785) (xy 54.53861 -68.248865) (xy 54.538611 -68.193331) (xy 54.546854 -68.138412)
			(xy 54.563156 -68.085324) (xy 54.574694 -68.060062) (xy 54.58714 -68.034154) (xy 54.58714 -67.57797)
			(xy 54.567836 -67.546982) (xy 54.554179 -67.524183) (xy 54.532619 -67.475607) (xy 54.518009 -67.424509)
			(xy 54.510632 -67.371878) (xy 54.510631 -67.318732) (xy 54.518006 -67.266101) (xy 54.532615 -67.215003)
			(xy 54.554174 -67.166426) (xy 54.567836 -67.14363) (xy 54.58714 -67.112642) (xy 54.58714 -66.81597)
			(xy 54.567836 -66.784982) (xy 54.554179 -66.762183) (xy 54.532619 -66.713607) (xy 54.518009 -66.662509)
			(xy 54.510632 -66.609878) (xy 54.510631 -66.556732) (xy 54.518006 -66.504101) (xy 54.532615 -66.453003)
			(xy 54.554174 -66.404426) (xy 54.567836 -66.38163) (xy 54.58714 -66.350642) (xy 54.58714 -64.59474)
			(xy 54.586572 -64.577127) (xy 54.576928 -64.543246) (xy 54.558367 -64.513306) (xy 54.545738 -64.501014)
			(xy 54.524856 -64.481191) (xy 54.488707 -64.436377) (xy 54.459704 -64.38664) (xy 54.438504 -64.333109)
			(xy 54.425589 -64.277) (xy 54.421252 -64.219588) (xy 54.425592 -64.162176) (xy 54.438511 -64.106068)
			(xy 54.459714 -64.052538) (xy 54.488721 -64.002803) (xy 54.524873 -63.957992) (xy 54.545738 -63.93815)
			(xy 54.558351 -63.92585) (xy 54.576874 -63.895898) (xy 54.586532 -63.862031) (xy 54.58714 -63.844424)
			(xy 54.58714 -63.552324) (xy 53.36794 -62.333124) (xy 50.649632 -62.333124) (xy 50.624486 -62.344554)
			(xy 50.599502 -62.355457) (xy 50.547201 -62.370818) (xy 50.493245 -62.378577) (xy 50.438735 -62.378577)
			(xy 50.384779 -62.370818) (xy 50.332478 -62.355457) (xy 50.307494 -62.344554) (xy 50.282348 -62.333124)
			(xy 47.37354 -62.333124) (xy 47.351576 -62.333585) (xy 47.308302 -62.341133) (xy 47.266971 -62.356011)
			(xy 47.228815 -62.377776) (xy 47.19497 -62.405779) (xy 47.166446 -62.439185) (xy 47.144092 -62.476999)
			(xy 47.128574 -62.518094) (xy 47.120356 -62.561246) (xy 47.119681 -62.605168) (xy 47.126571 -62.648552)
			(xy 47.140819 -62.690105) (xy 47.151036 -62.709552) (xy 47.163784 -62.733691) (xy 47.183011 -62.784782)
			(xy 47.19476 -62.838092) (xy 47.198791 -62.892532) (xy 47.195022 -62.946991) (xy 47.183528 -63.000356)
			(xy 47.164546 -63.051539) (xy 47.138463 -63.099493) (xy 47.105811 -63.14324) (xy 47.067257 -63.181887)
			(xy 47.023588 -63.214644) (xy 46.975696 -63.240842) (xy 46.924559 -63.259947) (xy 46.871222 -63.271568)
			(xy 46.816772 -63.275468) (xy 46.762322 -63.271568) (xy 46.708985 -63.259947) (xy 46.657848 -63.240842)
			(xy 46.609956 -63.214644) (xy 46.566287 -63.181887) (xy 46.527733 -63.14324) (xy 46.495081 -63.099493)
			(xy 46.468998 -63.051539) (xy 46.450016 -63.000356) (xy 46.438522 -62.946991) (xy 46.434753 -62.892532)
			(xy 46.438784 -62.838092) (xy 46.450533 -62.784782) (xy 46.46976 -62.733691) (xy 46.482508 -62.709552)
			(xy 46.492689 -62.690088) (xy 46.506933 -62.64854) (xy 46.51382 -62.605161) (xy 46.513145 -62.561244)
			(xy 46.504928 -62.518097) (xy 46.489413 -62.477007) (xy 46.467063 -62.439196) (xy 46.438545 -62.405792)
			(xy 46.404706 -62.377789) (xy 46.366557 -62.356023) (xy 46.325233 -62.341142) (xy 46.281965 -62.333588)
			(xy 46.260004 -62.333124) (xy 41.660064 -62.333124) (xy 41.642284 -62.338458) (xy 41.615716 -62.345848)
			(xy 41.561145 -62.353786) (xy 41.505999 -62.353786) (xy 41.451428 -62.345848) (xy 41.42486 -62.338458)
			(xy 41.40708 -62.333124) (xy 37.241226 -62.333124) (xy 37.219499 -62.333565) (xy 37.176678 -62.340951)
			(xy 37.135738 -62.355512) (xy 37.09787 -62.376824) (xy 37.064178 -62.404266) (xy 37.035645 -62.437038)
			(xy 37.0131 -62.474186) (xy 36.997203 -62.514627) (xy 36.988415 -62.557182) (xy 36.986992 -62.600612)
			(xy 36.992977 -62.643651) (xy 37.006194 -62.685045) (xy 37.015928 -62.704472) (xy 37.021016 -62.714392)
			(xy 37.030165 -62.734725) (xy 37.034216 -62.745112) (xy 37.042385 -62.765373) (xy 37.064632 -62.802965)
			(xy 37.092983 -62.836196) (xy 37.126601 -62.864086) (xy 37.164496 -62.885813) (xy 37.20555 -62.900736)
			(xy 37.248551 -62.908415) (xy 37.292232 -62.908623) (xy 37.335305 -62.901355) (xy 37.356034 -62.894464)
			(xy 37.382571 -62.885627) (xy 37.437468 -62.87493) (xy 37.493339 -62.872362) (xy 37.548986 -62.877978)
			(xy 37.603217 -62.891658) (xy 37.65487 -62.913109) (xy 37.702839 -62.94187) (xy 37.746094 -62.977326)
			(xy 37.781589 -63.016384) (xy 38.477442 -63.016384) (xy 38.481513 -62.960762) (xy 38.493639 -62.906325)
			(xy 38.513562 -62.854234) (xy 38.540858 -62.805599) (xy 38.574944 -62.761456) (xy 38.615093 -62.722747)
			(xy 38.660451 -62.690296) (xy 38.710051 -62.664795) (xy 38.762835 -62.646788) (xy 38.817678 -62.636658)
			(xy 38.873412 -62.634621) (xy 38.928849 -62.640721) (xy 38.982806 -62.654827) (xy 39.034135 -62.676639)
			(xy 39.081741 -62.705693) (xy 39.124609 -62.741368) (xy 39.161826 -62.782905) (xy 39.192599 -62.829418)
			(xy 39.216271 -62.879915) (xy 39.232339 -62.933322) (xy 39.240459 -62.988498) (xy 39.240968 -63.016384)
			(xy 39.240459 -63.04427) (xy 39.232339 -63.099446) (xy 39.216271 -63.152853) (xy 39.192599 -63.20335)
			(xy 39.161826 -63.249863) (xy 39.124609 -63.2914) (xy 39.081741 -63.327075) (xy 39.034135 -63.356129)
			(xy 38.982806 -63.377941) (xy 38.928849 -63.392047) (xy 38.873412 -63.398147) (xy 38.817678 -63.39611)
			(xy 38.762835 -63.38598) (xy 38.710051 -63.367973) (xy 38.660451 -63.342472) (xy 38.615093 -63.310021)
			(xy 38.574944 -63.271312) (xy 38.540858 -63.227169) (xy 38.513562 -63.178534) (xy 38.493639 -63.126443)
			(xy 38.481513 -63.072006) (xy 38.477442 -63.016384) (xy 37.781589 -63.016384) (xy 37.783709 -63.018717)
			(xy 37.814879 -63.065156) (xy 37.838935 -63.115649) (xy 37.855363 -63.169112) (xy 37.863809 -63.2244)
			(xy 37.864093 -63.280329) (xy 37.856209 -63.335701) (xy 37.840325 -63.389328) (xy 37.816783 -63.440062)
			(xy 37.791105 -63.479172) (xy 39.671242 -63.479172) (xy 39.675313 -63.42355) (xy 39.687439 -63.369113)
			(xy 39.707362 -63.317022) (xy 39.734658 -63.268387) (xy 39.768744 -63.224244) (xy 39.808893 -63.185535)
			(xy 39.854251 -63.153084) (xy 39.903851 -63.127583) (xy 39.956635 -63.109576) (xy 40.011478 -63.099446)
			(xy 40.067212 -63.097409) (xy 40.122649 -63.103509) (xy 40.176606 -63.117615) (xy 40.227935 -63.139427)
			(xy 40.275541 -63.168481) (xy 40.318409 -63.204156) (xy 40.355626 -63.245693) (xy 40.386399 -63.292206)
			(xy 40.410071 -63.342703) (xy 40.426139 -63.39611) (xy 40.434259 -63.451286) (xy 40.434578 -63.468758)
			(xy 40.8465 -63.468758) (xy 40.850571 -63.413136) (xy 40.862697 -63.358699) (xy 40.88262 -63.306608)
			(xy 40.909916 -63.257973) (xy 40.944002 -63.21383) (xy 40.984151 -63.175121) (xy 41.029509 -63.14267)
			(xy 41.079109 -63.117169) (xy 41.131893 -63.099162) (xy 41.186736 -63.089032) (xy 41.24247 -63.086995)
			(xy 41.297907 -63.093095) (xy 41.351864 -63.107201) (xy 41.403193 -63.129013) (xy 41.450799 -63.158067)
			(xy 41.493667 -63.193742) (xy 41.530884 -63.235279) (xy 41.561657 -63.281792) (xy 41.583457 -63.328296)
			(xy 44.802296 -63.328296) (xy 44.806367 -63.272674) (xy 44.818493 -63.218237) (xy 44.838416 -63.166146)
			(xy 44.865712 -63.117511) (xy 44.899798 -63.073368) (xy 44.939947 -63.034659) (xy 44.985305 -63.002208)
			(xy 45.034905 -62.976707) (xy 45.087689 -62.9587) (xy 45.142532 -62.94857) (xy 45.198266 -62.946533)
			(xy 45.253703 -62.952633) (xy 45.30766 -62.966739) (xy 45.358989 -62.988551) (xy 45.406595 -63.017605)
			(xy 45.449463 -63.05328) (xy 45.48668 -63.094817) (xy 45.517453 -63.14133) (xy 45.541125 -63.191827)
			(xy 45.557193 -63.245234) (xy 45.565313 -63.30041) (xy 45.565822 -63.328296) (xy 45.565313 -63.356182)
			(xy 45.557193 -63.411358) (xy 45.541125 -63.464765) (xy 45.529966 -63.48857) (xy 49.179986 -63.48857)
			(xy 49.184057 -63.432948) (xy 49.196183 -63.378511) (xy 49.216106 -63.32642) (xy 49.243402 -63.277785)
			(xy 49.277488 -63.233642) (xy 49.317637 -63.194933) (xy 49.362995 -63.162482) (xy 49.412595 -63.136981)
			(xy 49.465379 -63.118974) (xy 49.520222 -63.108844) (xy 49.575956 -63.106807) (xy 49.631393 -63.112907)
			(xy 49.68535 -63.127013) (xy 49.736679 -63.148825) (xy 49.784285 -63.177879) (xy 49.827153 -63.213554)
			(xy 49.86437 -63.255091) (xy 49.895143 -63.301604) (xy 49.918815 -63.352101) (xy 49.934883 -63.405508)
			(xy 49.943003 -63.460684) (xy 49.943512 -63.48857) (xy 49.943003 -63.516456) (xy 49.934883 -63.571632)
			(xy 49.918815 -63.625039) (xy 49.895143 -63.675536) (xy 49.86437 -63.722049) (xy 49.827153 -63.763586)
			(xy 49.784285 -63.799261) (xy 49.736679 -63.828315) (xy 49.68535 -63.850127) (xy 49.631393 -63.864233)
			(xy 49.575956 -63.870333) (xy 49.520222 -63.868296) (xy 49.465379 -63.858166) (xy 49.412595 -63.840159)
			(xy 49.362995 -63.814658) (xy 49.317637 -63.782207) (xy 49.277488 -63.743498) (xy 49.243402 -63.699355)
			(xy 49.216106 -63.65072) (xy 49.196183 -63.598629) (xy 49.184057 -63.544192) (xy 49.179986 -63.48857)
			(xy 45.529966 -63.48857) (xy 45.517453 -63.515262) (xy 45.48668 -63.561775) (xy 45.449463 -63.603312)
			(xy 45.406595 -63.638987) (xy 45.358989 -63.668041) (xy 45.30766 -63.689853) (xy 45.253703 -63.703959)
			(xy 45.198266 -63.710059) (xy 45.142532 -63.708022) (xy 45.087689 -63.697892) (xy 45.034905 -63.679885)
			(xy 44.985305 -63.654384) (xy 44.939947 -63.621933) (xy 44.899798 -63.583224) (xy 44.865712 -63.539081)
			(xy 44.838416 -63.490446) (xy 44.818493 -63.438355) (xy 44.806367 -63.383918) (xy 44.802296 -63.328296)
			(xy 41.583457 -63.328296) (xy 41.585329 -63.332289) (xy 41.601397 -63.385696) (xy 41.609517 -63.440872)
			(xy 41.610026 -63.468758) (xy 41.609517 -63.496644) (xy 41.601397 -63.55182) (xy 41.585329 -63.605227)
			(xy 41.561657 -63.655724) (xy 41.530884 -63.702237) (xy 41.493667 -63.743774) (xy 41.450799 -63.779449)
			(xy 41.403193 -63.808503) (xy 41.351864 -63.830315) (xy 41.297907 -63.844421) (xy 41.24247 -63.850521)
			(xy 41.186736 -63.848484) (xy 41.131893 -63.838354) (xy 41.079109 -63.820347) (xy 41.029509 -63.794846)
			(xy 40.984151 -63.762395) (xy 40.944002 -63.723686) (xy 40.909916 -63.679543) (xy 40.88262 -63.630908)
			(xy 40.862697 -63.578817) (xy 40.850571 -63.52438) (xy 40.8465 -63.468758) (xy 40.434578 -63.468758)
			(xy 40.434768 -63.479172) (xy 40.434259 -63.507058) (xy 40.426139 -63.562234) (xy 40.410071 -63.615641)
			(xy 40.386399 -63.666138) (xy 40.355626 -63.712651) (xy 40.318409 -63.754188) (xy 40.275541 -63.789863)
			(xy 40.227935 -63.818917) (xy 40.176606 -63.840729) (xy 40.122649 -63.854835) (xy 40.067212 -63.860935)
			(xy 40.011478 -63.858898) (xy 39.956635 -63.848768) (xy 39.903851 -63.830761) (xy 39.854251 -63.80526)
			(xy 39.808893 -63.772809) (xy 39.768744 -63.7341) (xy 39.734658 -63.689957) (xy 39.707362 -63.641322)
			(xy 39.687439 -63.589231) (xy 39.675313 -63.534794) (xy 39.671242 -63.479172) (xy 37.791105 -63.479172)
			(xy 37.786087 -63.486815) (xy 37.748893 -63.528586) (xy 37.706 -63.56448) (xy 37.658327 -63.593727)
			(xy 37.606895 -63.615701) (xy 37.552805 -63.629931) (xy 37.497218 -63.636112) (xy 37.441324 -63.634112)
			(xy 37.38632 -63.623973) (xy 37.333387 -63.605912) (xy 37.283657 -63.580318) (xy 37.238196 -63.547737)
			(xy 37.197979 -63.508869) (xy 37.163867 -63.464546) (xy 37.136591 -63.415718) (xy 37.126164 -63.389764)
			(xy 37.117994 -63.369506) (xy 37.095745 -63.33192) (xy 37.067393 -63.298694) (xy 37.033774 -63.270809)
			(xy 36.995881 -63.249087) (xy 36.95483 -63.234169) (xy 36.911832 -63.226494) (xy 36.868155 -63.226288)
			(xy 36.825086 -63.233558) (xy 36.804346 -63.240412) (xy 36.779172 -63.248797) (xy 36.727167 -63.259323)
			(xy 36.674205 -63.262539) (xy 36.621309 -63.258382) (xy 36.569499 -63.246933) (xy 36.519777 -63.228413)
			(xy 36.473102 -63.203179) (xy 36.430375 -63.171719) (xy 36.392422 -63.134641) (xy 36.375848 -63.11392)
			(xy 36.362286 -63.097136) (xy 36.330497 -63.067962) (xy 36.294234 -63.044579) (xy 36.254542 -63.027661)
			(xy 36.212562 -63.017695) (xy 36.169501 -63.014966) (xy 36.126599 -63.019553) (xy 36.085088 -63.031325)
			(xy 36.046164 -63.049943) (xy 36.010947 -63.074871) (xy 35.995356 -63.08979) (xy 34.913824 -64.171322)
			(xy 47.48225 -64.171322) (xy 47.486321 -64.1157) (xy 47.498447 -64.061263) (xy 47.51837 -64.009172)
			(xy 47.545666 -63.960537) (xy 47.579752 -63.916394) (xy 47.619901 -63.877685) (xy 47.665259 -63.845234)
			(xy 47.714859 -63.819733) (xy 47.767643 -63.801726) (xy 47.822486 -63.791596) (xy 47.87822 -63.789559)
			(xy 47.933657 -63.795659) (xy 47.987614 -63.809765) (xy 48.038943 -63.831577) (xy 48.086549 -63.860631)
			(xy 48.129417 -63.896306) (xy 48.166634 -63.937843) (xy 48.197407 -63.984356) (xy 48.221079 -64.034853)
			(xy 48.237147 -64.08826) (xy 48.243166 -64.129158) (xy 51.978558 -64.129158) (xy 51.982629 -64.073536)
			(xy 51.994755 -64.019099) (xy 52.014678 -63.967008) (xy 52.041974 -63.918373) (xy 52.07606 -63.87423)
			(xy 52.116209 -63.835521) (xy 52.161567 -63.80307) (xy 52.211167 -63.777569) (xy 52.263951 -63.759562)
			(xy 52.318794 -63.749432) (xy 52.374528 -63.747395) (xy 52.429965 -63.753495) (xy 52.483922 -63.767601)
			(xy 52.535251 -63.789413) (xy 52.582857 -63.818467) (xy 52.625725 -63.854142) (xy 52.662942 -63.895679)
			(xy 52.693715 -63.942192) (xy 52.717387 -63.992689) (xy 52.733455 -64.046096) (xy 52.741575 -64.101272)
			(xy 52.742084 -64.129158) (xy 52.741575 -64.157044) (xy 52.733455 -64.21222) (xy 52.717387 -64.265627)
			(xy 52.693715 -64.316124) (xy 52.662942 -64.362637) (xy 52.625725 -64.404174) (xy 52.582857 -64.439849)
			(xy 52.535251 -64.468903) (xy 52.483922 -64.490715) (xy 52.429965 -64.504821) (xy 52.374528 -64.510921)
			(xy 52.318794 -64.508884) (xy 52.263951 -64.498754) (xy 52.211167 -64.480747) (xy 52.161567 -64.455246)
			(xy 52.116209 -64.422795) (xy 52.07606 -64.384086) (xy 52.041974 -64.339943) (xy 52.014678 -64.291308)
			(xy 51.994755 -64.239217) (xy 51.982629 -64.18478) (xy 51.978558 -64.129158) (xy 48.243166 -64.129158)
			(xy 48.245267 -64.143436) (xy 48.245776 -64.171322) (xy 48.245267 -64.199208) (xy 48.237147 -64.254384)
			(xy 48.221079 -64.307791) (xy 48.197407 -64.358288) (xy 48.166634 -64.404801) (xy 48.129417 -64.446338)
			(xy 48.086549 -64.482013) (xy 48.038943 -64.511067) (xy 47.987614 -64.532879) (xy 47.933657 -64.546985)
			(xy 47.87822 -64.553085) (xy 47.822486 -64.551048) (xy 47.767643 -64.540918) (xy 47.714859 -64.522911)
			(xy 47.665259 -64.49741) (xy 47.619901 -64.464959) (xy 47.579752 -64.42625) (xy 47.545666 -64.382107)
			(xy 47.51837 -64.333472) (xy 47.498447 -64.281381) (xy 47.486321 -64.226944) (xy 47.48225 -64.171322)
			(xy 34.913824 -64.171322) (xy 34.496248 -64.588898) (xy 40.745154 -64.588898) (xy 40.749225 -64.533276)
			(xy 40.761351 -64.478839) (xy 40.781274 -64.426748) (xy 40.80857 -64.378113) (xy 40.842656 -64.33397)
			(xy 40.882805 -64.295261) (xy 40.928163 -64.26281) (xy 40.977763 -64.237309) (xy 41.030547 -64.219302)
			(xy 41.08539 -64.209172) (xy 41.141124 -64.207135) (xy 41.196561 -64.213235) (xy 41.250518 -64.227341)
			(xy 41.301847 -64.249153) (xy 41.349453 -64.278207) (xy 41.392321 -64.313882) (xy 41.429538 -64.355419)
			(xy 41.460311 -64.401932) (xy 41.483983 -64.452429) (xy 41.500051 -64.505836) (xy 41.508171 -64.561012)
			(xy 41.50868 -64.588898) (xy 41.508171 -64.616784) (xy 41.500051 -64.67196) (xy 41.483983 -64.725367)
			(xy 41.460311 -64.775864) (xy 41.429538 -64.822377) (xy 41.392321 -64.863914) (xy 41.349453 -64.899589)
			(xy 41.301847 -64.928643) (xy 41.250518 -64.950455) (xy 41.196561 -64.964561) (xy 41.141124 -64.970661)
			(xy 41.08539 -64.968624) (xy 41.030547 -64.958494) (xy 40.977763 -64.940487) (xy 40.928163 -64.914986)
			(xy 40.882805 -64.882535) (xy 40.842656 -64.843826) (xy 40.80857 -64.799683) (xy 40.781274 -64.751048)
			(xy 40.761351 -64.698957) (xy 40.749225 -64.64452) (xy 40.745154 -64.588898) (xy 34.496248 -64.588898)
			(xy 33.810702 -65.274444) (xy 38.872666 -65.274444) (xy 38.876737 -65.218822) (xy 38.888863 -65.164385)
			(xy 38.908786 -65.112294) (xy 38.936082 -65.063659) (xy 38.970168 -65.019516) (xy 39.010317 -64.980807)
			(xy 39.055675 -64.948356) (xy 39.105275 -64.922855) (xy 39.158059 -64.904848) (xy 39.212902 -64.894718)
			(xy 39.268636 -64.892681) (xy 39.324073 -64.898781) (xy 39.37803 -64.912887) (xy 39.429359 -64.934699)
			(xy 39.476965 -64.963753) (xy 39.505103 -64.98717) (xy 42.11777 -64.98717) (xy 42.121841 -64.931548)
			(xy 42.133967 -64.877111) (xy 42.15389 -64.82502) (xy 42.181186 -64.776385) (xy 42.215272 -64.732242)
			(xy 42.255421 -64.693533) (xy 42.300779 -64.661082) (xy 42.350379 -64.635581) (xy 42.403163 -64.617574)
			(xy 42.458006 -64.607444) (xy 42.51374 -64.605407) (xy 42.569177 -64.611507) (xy 42.623134 -64.625613)
			(xy 42.674463 -64.647425) (xy 42.722069 -64.676479) (xy 42.764937 -64.712154) (xy 42.802154 -64.753691)
			(xy 42.832927 -64.800204) (xy 42.856599 -64.850701) (xy 42.872667 -64.904108) (xy 42.880787 -64.959284)
			(xy 42.881296 -64.98717) (xy 42.880787 -65.015056) (xy 42.872667 -65.070232) (xy 42.864644 -65.096898)
			(xy 43.221654 -65.096898) (xy 43.225725 -65.041276) (xy 43.237851 -64.986839) (xy 43.257774 -64.934748)
			(xy 43.28507 -64.886113) (xy 43.319156 -64.84197) (xy 43.359305 -64.803261) (xy 43.404663 -64.77081)
			(xy 43.454263 -64.745309) (xy 43.507047 -64.727302) (xy 43.56189 -64.717172) (xy 43.617624 -64.715135)
			(xy 43.673061 -64.721235) (xy 43.727018 -64.735341) (xy 43.778347 -64.757153) (xy 43.825953 -64.786207)
			(xy 43.868821 -64.821882) (xy 43.906038 -64.863419) (xy 43.936811 -64.909932) (xy 43.960483 -64.960429)
			(xy 43.976551 -65.013836) (xy 43.984671 -65.069012) (xy 43.98518 -65.096898) (xy 43.984671 -65.124784)
			(xy 43.976551 -65.17996) (xy 43.960483 -65.233367) (xy 43.936811 -65.283864) (xy 43.906038 -65.330377)
			(xy 43.868821 -65.371914) (xy 43.825953 -65.407589) (xy 43.778347 -65.436643) (xy 43.727018 -65.458455)
			(xy 43.673061 -65.472561) (xy 43.617624 -65.478661) (xy 43.56189 -65.476624) (xy 43.507047 -65.466494)
			(xy 43.454263 -65.448487) (xy 43.404663 -65.422986) (xy 43.359305 -65.390535) (xy 43.319156 -65.351826)
			(xy 43.28507 -65.307683) (xy 43.257774 -65.259048) (xy 43.237851 -65.206957) (xy 43.225725 -65.15252)
			(xy 43.221654 -65.096898) (xy 42.864644 -65.096898) (xy 42.856599 -65.123639) (xy 42.832927 -65.174136)
			(xy 42.802154 -65.220649) (xy 42.764937 -65.262186) (xy 42.722069 -65.297861) (xy 42.674463 -65.326915)
			(xy 42.623134 -65.348727) (xy 42.569177 -65.362833) (xy 42.51374 -65.368933) (xy 42.458006 -65.366896)
			(xy 42.403163 -65.356766) (xy 42.350379 -65.338759) (xy 42.300779 -65.313258) (xy 42.255421 -65.280807)
			(xy 42.215272 -65.242098) (xy 42.181186 -65.197955) (xy 42.15389 -65.14932) (xy 42.133967 -65.097229)
			(xy 42.121841 -65.042792) (xy 42.11777 -64.98717) (xy 39.505103 -64.98717) (xy 39.519833 -64.999428)
			(xy 39.55705 -65.040965) (xy 39.587823 -65.087478) (xy 39.611495 -65.137975) (xy 39.627563 -65.191382)
			(xy 39.635683 -65.246558) (xy 39.636192 -65.274444) (xy 39.635683 -65.30233) (xy 39.627563 -65.357506)
			(xy 39.611495 -65.410913) (xy 39.587823 -65.46141) (xy 39.55705 -65.507923) (xy 39.519833 -65.54946)
			(xy 39.476965 -65.585135) (xy 39.429359 -65.614189) (xy 39.37803 -65.636001) (xy 39.324073 -65.650107)
			(xy 39.268636 -65.656207) (xy 39.212902 -65.65417) (xy 39.158059 -65.64404) (xy 39.105275 -65.626033)
			(xy 39.055675 -65.600532) (xy 39.010317 -65.568081) (xy 38.970168 -65.529372) (xy 38.936082 -65.485229)
			(xy 38.908786 -65.436594) (xy 38.888863 -65.384503) (xy 38.876737 -65.330066) (xy 38.872666 -65.274444)
			(xy 33.810702 -65.274444) (xy 33.348422 -65.736724) (xy 37.293802 -65.736724) (xy 37.297873 -65.681102)
			(xy 37.309999 -65.626665) (xy 37.329922 -65.574574) (xy 37.357218 -65.525939) (xy 37.391304 -65.481796)
			(xy 37.431453 -65.443087) (xy 37.476811 -65.410636) (xy 37.526411 -65.385135) (xy 37.579195 -65.367128)
			(xy 37.634038 -65.356998) (xy 37.689772 -65.354961) (xy 37.745209 -65.361061) (xy 37.799166 -65.375167)
			(xy 37.850495 -65.396979) (xy 37.898101 -65.426033) (xy 37.940969 -65.461708) (xy 37.978186 -65.503245)
			(xy 38.008959 -65.549758) (xy 38.032631 -65.600255) (xy 38.048699 -65.653662) (xy 38.056819 -65.708838)
			(xy 38.057328 -65.736724) (xy 38.056819 -65.76461) (xy 38.048699 -65.819786) (xy 38.032631 -65.873193)
			(xy 38.008959 -65.92369) (xy 37.998387 -65.93967) (xy 40.372028 -65.93967) (xy 40.376099 -65.884048)
			(xy 40.388225 -65.829611) (xy 40.408148 -65.77752) (xy 40.435444 -65.728885) (xy 40.46953 -65.684742)
			(xy 40.509679 -65.646033) (xy 40.555037 -65.613582) (xy 40.604637 -65.588081) (xy 40.657421 -65.570074)
			(xy 40.712264 -65.559944) (xy 40.767998 -65.557907) (xy 40.823435 -65.564007) (xy 40.877392 -65.578113)
			(xy 40.928721 -65.599925) (xy 40.976327 -65.628979) (xy 41.019195 -65.664654) (xy 41.056412 -65.706191)
			(xy 41.087185 -65.752704) (xy 41.110857 -65.803201) (xy 41.126925 -65.856608) (xy 41.135045 -65.911784)
			(xy 41.135554 -65.93967) (xy 41.135045 -65.967556) (xy 41.126925 -66.022732) (xy 41.110857 -66.076139)
			(xy 41.087185 -66.126636) (xy 41.056412 -66.173149) (xy 41.035294 -66.196718) (xy 42.213274 -66.196718)
			(xy 42.217345 -66.141096) (xy 42.229471 -66.086659) (xy 42.249394 -66.034568) (xy 42.27669 -65.985933)
			(xy 42.310776 -65.94179) (xy 42.350925 -65.903081) (xy 42.396283 -65.87063) (xy 42.445883 -65.845129)
			(xy 42.498667 -65.827122) (xy 42.55351 -65.816992) (xy 42.609244 -65.814955) (xy 42.664681 -65.821055)
			(xy 42.718638 -65.835161) (xy 42.769967 -65.856973) (xy 42.817573 -65.886027) (xy 42.860441 -65.921702)
			(xy 42.897658 -65.963239) (xy 42.928431 -66.009752) (xy 42.952103 -66.060249) (xy 42.968171 -66.113656)
			(xy 42.976291 -66.168832) (xy 42.9768 -66.196718) (xy 42.976291 -66.224604) (xy 42.968171 -66.27978)
			(xy 42.952103 -66.333187) (xy 42.928431 -66.383684) (xy 42.897658 -66.430197) (xy 42.860441 -66.471734)
			(xy 42.817573 -66.507409) (xy 42.769967 -66.536463) (xy 42.718638 -66.558275) (xy 42.664681 -66.572381)
			(xy 42.609244 -66.578481) (xy 42.55351 -66.576444) (xy 42.498667 -66.566314) (xy 42.445883 -66.548307)
			(xy 42.396283 -66.522806) (xy 42.350925 -66.490355) (xy 42.310776 -66.451646) (xy 42.27669 -66.407503)
			(xy 42.249394 -66.358868) (xy 42.229471 -66.306777) (xy 42.217345 -66.25234) (xy 42.213274 -66.196718)
			(xy 41.035294 -66.196718) (xy 41.019195 -66.214686) (xy 40.976327 -66.250361) (xy 40.928721 -66.279415)
			(xy 40.877392 -66.301227) (xy 40.823435 -66.315333) (xy 40.767998 -66.321433) (xy 40.712264 -66.319396)
			(xy 40.657421 -66.309266) (xy 40.604637 -66.291259) (xy 40.555037 -66.265758) (xy 40.509679 -66.233307)
			(xy 40.46953 -66.194598) (xy 40.435444 -66.150455) (xy 40.408148 -66.10182) (xy 40.388225 -66.049729)
			(xy 40.376099 -65.995292) (xy 40.372028 -65.93967) (xy 37.998387 -65.93967) (xy 37.978186 -65.970203)
			(xy 37.940969 -66.01174) (xy 37.898101 -66.047415) (xy 37.850495 -66.076469) (xy 37.799166 -66.098281)
			(xy 37.745209 -66.112387) (xy 37.689772 -66.118487) (xy 37.634038 -66.11645) (xy 37.579195 -66.10632)
			(xy 37.526411 -66.088313) (xy 37.476811 -66.062812) (xy 37.431453 -66.030361) (xy 37.391304 -65.991652)
			(xy 37.357218 -65.947509) (xy 37.329922 -65.898874) (xy 37.309999 -65.846783) (xy 37.297873 -65.792346)
			(xy 37.293802 -65.736724) (xy 33.348422 -65.736724) (xy 33.26384 -65.821306) (xy 33.26384 -66.697759)
			(xy 43.626802 -66.697759) (xy 43.63066 -66.643447) (xy 43.642201 -66.590235) (xy 43.661189 -66.539204)
			(xy 43.687241 -66.491392) (xy 43.719825 -66.447768) (xy 43.75828 -66.409221) (xy 43.801826 -66.376533)
			(xy 43.849576 -66.350368) (xy 43.900562 -66.331258) (xy 43.953746 -66.31959) (xy 43.980862 -66.317114)
			(xy 43.997601 -66.315326) (xy 44.029334 -66.304122) (xy 44.05704 -66.28502) (xy 44.078798 -66.259347)
			(xy 44.093097 -66.228883) (xy 44.098947 -66.195743) (xy 44.097956 -66.178938) (xy 44.095969 -66.152709)
			(xy 44.098477 -66.100166) (xy 44.10818 -66.048466) (xy 44.124896 -65.99859) (xy 44.148306 -65.951484)
			(xy 44.177966 -65.908041) (xy 44.213315 -65.869086) (xy 44.253681 -65.835357) (xy 44.275756 -65.821052)
			(xy 44.289497 -65.811822) (xy 44.312076 -65.787633) (xy 44.327675 -65.758451) (xy 44.335246 -65.726239)
			(xy 44.334278 -65.693163) (xy 44.324838 -65.661449) (xy 44.31665 -65.647062) (xy 44.30243 -65.622871)
			(xy 44.280436 -65.57125) (xy 44.26624 -65.516963) (xy 44.260148 -65.461183) (xy 44.262291 -65.405112)
			(xy 44.272622 -65.34996) (xy 44.29092 -65.296915) (xy 44.31679 -65.247123) (xy 44.349673 -65.201656)
			(xy 44.38886 -65.161495) (xy 44.433507 -65.127507) (xy 44.48265 -65.100424) (xy 44.53523 -65.080831)
			(xy 44.590112 -65.069149) (xy 44.646114 -65.065632) (xy 44.702027 -65.070354) (xy 44.756645 -65.083215)
			(xy 44.808791 -65.103936) (xy 44.857339 -65.132071) (xy 44.901244 -65.167012) (xy 44.939557 -65.208007)
			(xy 44.971454 -65.254172) (xy 44.996245 -65.30451) (xy 45.013396 -65.357936) (xy 45.022538 -65.413298)
			(xy 45.023473 -65.469402) (xy 45.016181 -65.525038) (xy 45.00082 -65.579006) (xy 44.97772 -65.630143)
			(xy 44.947379 -65.677344) (xy 44.910453 -65.719593) (xy 44.867737 -65.755979) (xy 44.844208 -65.771268)
			(xy 44.830447 -65.780469) (xy 44.807872 -65.804668) (xy 44.792278 -65.833856) (xy 44.784711 -65.866073)
			(xy 44.785682 -65.899152) (xy 44.795125 -65.93087) (xy 44.803314 -65.945258) (xy 44.817561 -65.96939)
			(xy 44.839531 -66.020944) (xy 44.853726 -66.075156) (xy 44.859841 -66.130861) (xy 44.857745 -66.186862)
			(xy 44.853098 -66.214498) (xy 44.850429 -66.231572) (xy 44.853355 -66.265994) (xy 44.865424 -66.298362)
			(xy 44.88575 -66.326296) (xy 44.912835 -66.347738) (xy 44.928536 -66.35496) (xy 44.944538 -66.361903)
			(xy 44.975322 -66.378308) (xy 44.990004 -66.387726) (xy 45.00306 -66.395842) (xy 45.032036 -66.406092)
			(xy 45.062624 -66.4091) (xy 45.093042 -66.40469) (xy 45.121517 -66.393121) (xy 45.146391 -66.375065)
			(xy 45.156628 -66.363596) (xy 45.175154 -66.342548) (xy 45.217255 -66.305518) (xy 45.264322 -66.275047)
			(xy 45.315342 -66.251792) (xy 45.369215 -66.236252) (xy 45.424782 -66.228764) (xy 45.480846 -66.229487)
			(xy 45.536202 -66.238406) (xy 45.589656 -66.255329) (xy 45.640059 -66.279892) (xy 45.686324 -66.311566)
			(xy 45.727457 -66.34967) (xy 45.7454 -66.371216) (xy 45.755616 -66.383191) (xy 45.780698 -66.402189)
			(xy 45.809671 -66.414461) (xy 45.840768 -66.419259) (xy 45.872093 -66.41629) (xy 45.901735 -66.405735)
			(xy 45.915072 -66.397378) (xy 45.938405 -66.382312) (xy 45.988572 -66.358474) (xy 46.041665 -66.342163)
			(xy 46.096562 -66.333724) (xy 46.152103 -66.333335) (xy 46.207113 -66.341005) (xy 46.26043 -66.356571)
			(xy 46.310925 -66.379704) (xy 46.357532 -66.409916) (xy 46.399265 -66.446566) (xy 46.435242 -66.488882)
			(xy 46.464702 -66.535967) (xy 46.487023 -66.586827) (xy 46.501732 -66.640386) (xy 46.505622 -66.667888)
			(xy 46.508962 -66.690869) (xy 46.522866 -66.73517) (xy 46.544594 -66.776204) (xy 46.573421 -66.812603)
			(xy 46.608387 -66.843153) (xy 46.648326 -66.866835) (xy 46.691905 -66.882859) (xy 46.737671 -66.890692)
			(xy 46.760892 -66.8909) (xy 46.785324 -66.890982) (xy 46.833859 -66.896585) (xy 46.857666 -66.902076)
			(xy 46.880331 -66.907133) (xy 46.926683 -66.909894) (xy 46.972767 -66.904201) (xy 47.017053 -66.890243)
			(xy 47.058073 -66.868483) (xy 47.094466 -66.839644) (xy 47.125023 -66.804682) (xy 47.13732 -66.784982)
			(xy 47.142681 -66.776074) (xy 47.154246 -66.758793) (xy 47.160434 -66.750438) (xy 47.173993 -66.731401)
			(xy 47.194725 -66.689524) (xy 47.207454 -66.644562) (xy 47.211748 -66.59803) (xy 47.207465 -66.551498)
			(xy 47.194747 -66.506533) (xy 47.174024 -66.464651) (xy 47.160434 -66.445638) (xy 47.144762 -66.42401)
			(xy 47.118986 -66.377228) (xy 47.099991 -66.327308) (xy 47.093632 -66.301366) (xy 47.089977 -66.287046)
			(xy 47.077039 -66.260484) (xy 47.058333 -66.237615) (xy 47.034864 -66.219668) (xy 47.007893 -66.207607)
			(xy 46.978869 -66.20208) (xy 46.964092 -66.202306) (xy 46.935612 -66.203035) (xy 46.878948 -66.197169)
			(xy 46.823787 -66.182938) (xy 46.771356 -66.16066) (xy 46.722823 -66.130831) (xy 46.679267 -66.094114)
			(xy 46.641658 -66.051326) (xy 46.610832 -66.00342) (xy 46.587475 -65.951461) (xy 46.579282 -65.924176)
			(xy 46.572577 -65.90206) (xy 46.552271 -65.860549) (xy 46.524795 -65.823393) (xy 46.491055 -65.791817)
			(xy 46.452163 -65.766861) (xy 46.4094 -65.749346) (xy 46.364175 -65.739852) (xy 46.317978 -65.738689)
			(xy 46.272333 -65.745898) (xy 46.228743 -65.761239) (xy 46.208442 -65.772284) (xy 46.184053 -65.785706)
			(xy 46.132249 -65.806084) (xy 46.078033 -65.818716) (xy 46.022556 -65.823334) (xy 45.966998 -65.819838)
			(xy 45.912538 -65.808303) (xy 45.860333 -65.788974) (xy 45.811492 -65.762263) (xy 45.767052 -65.728735)
			(xy 45.727958 -65.689104) (xy 45.69504 -65.644212) (xy 45.668998 -65.595011) (xy 45.650383 -65.542547)
			(xy 45.639592 -65.487935) (xy 45.636855 -65.432334) (xy 45.642228 -65.376925) (xy 45.655599 -65.322887)
			(xy 45.676682 -65.271365) (xy 45.705031 -65.223456) (xy 45.740042 -65.180176) (xy 45.780973 -65.142445)
			(xy 45.826953 -65.111065) (xy 45.877007 -65.086701) (xy 45.930071 -65.069872) (xy 45.985017 -65.060935)
			(xy 46.040678 -65.06008) (xy 46.095873 -65.067325) (xy 46.149429 -65.082515) (xy 46.200207 -65.10533)
			(xy 46.24713 -65.135283) (xy 46.289201 -65.171738) (xy 46.325526 -65.213922) (xy 46.355333 -65.260938)
			(xy 46.377989 -65.311787) (xy 46.385988 -65.338452) (xy 46.39272 -65.360559) (xy 46.413026 -65.402065)
			(xy 46.4405 -65.439216) (xy 46.474238 -65.470789) (xy 46.513126 -65.495744) (xy 46.555885 -65.513259)
			(xy 46.601105 -65.522755) (xy 46.647297 -65.523922) (xy 46.692939 -65.516719) (xy 46.736527 -65.501385)
			(xy 46.756828 -65.490344) (xy 46.76775 -65.484248) (xy 46.780587 -65.476964) (xy 46.802766 -65.4575)
			(xy 46.819878 -65.433461) (xy 46.83101 -65.406133) (xy 46.835564 -65.376978) (xy 46.833297 -65.347557)
			(xy 46.829218 -65.333372) (xy 46.821037 -65.30619) (xy 46.811955 -65.250157) (xy 46.811273 -65.193397)
			(xy 46.819006 -65.137162) (xy 46.834984 -65.082693) (xy 46.858853 -65.031191) (xy 46.890088 -64.983793)
			(xy 46.927999 -64.941544) (xy 46.971749 -64.905377) (xy 47.020374 -64.876089) (xy 47.072801 -64.854326)
			(xy 47.127873 -64.84057) (xy 47.184376 -64.835122) (xy 47.241062 -64.838103) (xy 47.296681 -64.849449)
			(xy 47.350006 -64.868907) (xy 47.39986 -64.896049) (xy 47.422816 -64.912748) (xy 47.440743 -64.925692)
			(xy 47.480094 -64.945846) (xy 47.52234 -64.958887) (xy 47.566204 -64.964419) (xy 47.610365 -64.962277)
			(xy 47.653488 -64.952525) (xy 47.694273 -64.935457) (xy 47.713138 -64.923924) (xy 47.736737 -64.909356)
			(xy 47.787261 -64.886487) (xy 47.840565 -64.871175) (xy 47.895523 -64.863742) (xy 47.950979 -64.864347)
			(xy 48.005763 -64.872975) (xy 48.05872 -64.889445) (xy 48.108734 -64.91341) (xy 48.15475 -64.944364)
			(xy 48.1958 -64.981655) (xy 48.231016 -65.024498) (xy 48.259658 -65.071988) (xy 48.281122 -65.123125)
			(xy 48.294954 -65.176831) (xy 48.300864 -65.231975) (xy 48.298726 -65.287392) (xy 48.288587 -65.341916)
			(xy 48.270659 -65.394398) (xy 48.24532 -65.44373) (xy 48.213105 -65.488873) (xy 48.174693 -65.528875)
			(xy 48.130893 -65.562894) (xy 48.082629 -65.590212) (xy 48.030918 -65.610253) (xy 47.97685 -65.622595)
			(xy 47.921564 -65.626978) (xy 47.866227 -65.623309) (xy 47.812004 -65.611665) (xy 47.760038 -65.592293)
			(xy 47.711426 -65.5656) (xy 47.689008 -65.549272) (xy 47.671066 -65.536349) (xy 47.631719 -65.516191)
			(xy 47.589477 -65.503148) (xy 47.545615 -65.497611) (xy 47.501457 -65.49975) (xy 47.458335 -65.509499)
			(xy 47.417551 -65.526564) (xy 47.398686 -65.538096) (xy 47.371508 -65.554098) (xy 47.358695 -65.561419)
			(xy 47.336521 -65.580878) (xy 47.31941 -65.60491) (xy 47.308276 -65.632229) (xy 47.303714 -65.661376)
			(xy 47.305968 -65.69079) (xy 47.31004 -65.704974) (xy 47.318676 -65.736978) (xy 47.32236 -65.75129)
			(xy 47.335288 -65.777854) (xy 47.353987 -65.800726) (xy 47.377451 -65.818676) (xy 47.404419 -65.830738)
			(xy 47.43344 -65.836265) (xy 47.448216 -65.836038) (xy 47.47515 -65.835167) (xy 47.528796 -65.840298)
			(xy 47.581185 -65.852927) (xy 47.631276 -65.872805) (xy 47.678071 -65.899535) (xy 47.720638 -65.932584)
			(xy 47.758129 -65.971295) (xy 47.7898 -66.014898) (xy 47.815018 -66.062524) (xy 47.833282 -66.113226)
			(xy 47.844229 -66.165993) (xy 47.84764 -66.219775) (xy 47.843447 -66.273503) (xy 47.831735 -66.326105)
			(xy 47.812736 -66.376536) (xy 47.786828 -66.423791) (xy 47.77105 -66.445638) (xy 47.757422 -66.464627)
			(xy 47.736696 -66.506517) (xy 47.723977 -66.55149) (xy 47.719693 -66.59803) (xy 47.723988 -66.64457)
			(xy 47.736718 -66.689539) (xy 47.757453 -66.731425) (xy 47.77105 -66.750438) (xy 47.787182 -66.772817)
			(xy 47.813561 -66.821268) (xy 47.832685 -66.873013) (xy 47.844155 -66.926974) (xy 47.847732 -66.982024)
			(xy 47.843342 -67.037015) (xy 47.831075 -67.0908) (xy 47.811188 -67.142257) (xy 47.784096 -67.190312)
			(xy 47.750363 -67.233963) (xy 47.710694 -67.272299) (xy 47.665916 -67.304521) (xy 47.616964 -67.329956)
			(xy 47.564857 -67.348074) (xy 47.510685 -67.358496) (xy 47.455576 -67.361006) (xy 47.40068 -67.35555)
			(xy 47.373794 -67.34937) (xy 47.35114 -67.344251) (xy 47.304782 -67.341496) (xy 47.258692 -67.347197)
			(xy 47.214402 -67.361164) (xy 47.17338 -67.382934) (xy 47.136988 -67.411785) (xy 47.106434 -67.446759)
			(xy 47.09414 -67.466464) (xy 47.07948 -67.490211) (xy 47.062206 -67.511592) (xy 48.826996 -67.511592)
			(xy 48.833178 -67.457404) (xy 48.84701 -67.404649) (xy 48.868212 -67.354399) (xy 48.896351 -67.30768)
			(xy 48.930854 -67.265442) (xy 48.971018 -67.228546) (xy 49.016026 -67.197743) (xy 49.040288 -67.185286)
			(xy 49.059591 -67.175216) (xy 49.094759 -67.14956) (xy 49.125041 -67.118286) (xy 49.149551 -67.08231)
			(xy 49.167573 -67.042684) (xy 49.17858 -67.000567) (xy 49.18225 -66.95719) (xy 49.178474 -66.913822)
			(xy 49.167365 -66.871731) (xy 49.149246 -66.832149) (xy 49.137316 -66.813938) (xy 49.122804 -66.791905)
			(xy 49.099248 -66.7447) (xy 49.082422 -66.694699) (xy 49.072648 -66.642856) (xy 49.070113 -66.59016)
			(xy 49.074865 -66.537618) (xy 49.086812 -66.486233) (xy 49.105728 -66.436984) (xy 49.13125 -66.390813)
			(xy 49.146714 -66.369438) (xy 49.160273 -66.350402) (xy 49.181008 -66.308524) (xy 49.193737 -66.263562)
			(xy 49.198032 -66.21703) (xy 49.193748 -66.170498) (xy 49.18103 -66.125533) (xy 49.160305 -66.08365)
			(xy 49.146714 -66.064638) (xy 49.131411 -66.04352) (xy 49.106115 -65.997913) (xy 49.087272 -65.949283)
			(xy 49.075233 -65.898539) (xy 49.070223 -65.846628) (xy 49.072336 -65.794518) (xy 49.081532 -65.743183)
			(xy 49.097639 -65.69358) (xy 49.108614 -65.669922) (xy 49.114811 -65.656408) (xy 49.121248 -65.627387)
			(xy 49.120784 -65.597665) (xy 49.113445 -65.568859) (xy 49.09963 -65.542537) (xy 49.080092 -65.520134)
			(xy 49.068228 -65.511172) (xy 49.045812 -65.494459) (xy 49.005591 -65.455624) (xy 48.97147 -65.411333)
			(xy 48.94418 -65.362535) (xy 48.924307 -65.310277) (xy 48.912275 -65.255677) (xy 48.908343 -65.199905)
			(xy 48.912595 -65.144157) (xy 48.924939 -65.089627) (xy 48.945112 -65.037483) (xy 48.972681 -64.988843)
			(xy 49.007055 -64.944748) (xy 49.047499 -64.906144) (xy 49.093144 -64.873858) (xy 49.143014 -64.848581)
			(xy 49.19604 -64.830855) (xy 49.251085 -64.82106) (xy 49.306971 -64.819405) (xy 49.362499 -64.825927)
			(xy 49.41648 -64.840485) (xy 49.467758 -64.862768) (xy 49.515234 -64.892297) (xy 49.55789 -64.928441)
			(xy 49.594812 -64.970425) (xy 49.62521 -65.01735) (xy 49.648433 -65.068209) (xy 49.663981 -65.121913)
			(xy 49.671523 -65.177312) (xy 49.670897 -65.233219) (xy 49.662117 -65.288435) (xy 49.645369 -65.341778)
			(xy 49.633632 -65.367154) (xy 49.627479 -65.380685) (xy 49.621042 -65.409699) (xy 49.621501 -65.439414)
			(xy 49.628832 -65.468215) (xy 49.642636 -65.494534) (xy 49.66216 -65.516939) (xy 49.674018 -65.525904)
			(xy 49.696228 -65.542327) (xy 49.736033 -65.580625) (xy 49.769898 -65.624264) (xy 49.797114 -65.672331)
			(xy 49.817113 -65.723822) (xy 49.829475 -65.777658) (xy 49.832663 -65.816945) (xy 50.537204 -65.816945)
			(xy 50.541639 -65.763096) (xy 50.553627 -65.71041) (xy 50.572929 -65.659943) (xy 50.599157 -65.612703)
			(xy 50.631788 -65.569637) (xy 50.650648 -65.550288) (xy 50.666116 -65.534266) (xy 50.691813 -65.497899)
			(xy 50.710782 -65.457611) (xy 50.722442 -65.414635) (xy 50.726437 -65.370285) (xy 50.722646 -65.325917)
			(xy 50.711183 -65.282888) (xy 50.70221 -65.262506) (xy 50.690961 -65.237099) (xy 50.675068 -65.183858)
			(xy 50.667067 -65.128876) (xy 50.667126 -65.073314) (xy 50.675245 -65.018348) (xy 50.69125 -64.965141)
			(xy 50.714805 -64.914819) (xy 50.74541 -64.868446) (xy 50.782418 -64.827003) (xy 50.825047 -64.791367)
			(xy 50.872394 -64.762291) (xy 50.923458 -64.740391) (xy 50.977158 -64.72613) (xy 51.032359 -64.719809)
			(xy 51.087894 -64.721563) (xy 51.142586 -64.731354) (xy 51.19528 -64.748976) (xy 51.24486 -64.774054)
			(xy 51.290278 -64.806059) (xy 51.330573 -64.844314) (xy 51.364893 -64.88801) (xy 51.392511 -64.936222)
			(xy 51.412843 -64.98793) (xy 51.425459 -65.042041) (xy 51.430093 -65.097409) (xy 51.426646 -65.152864)
			(xy 51.415191 -65.207233) (xy 51.395971 -65.259364) (xy 51.369392 -65.308157) (xy 51.336016 -65.352577)
			(xy 51.316636 -65.372488) (xy 51.301107 -65.388454) (xy 51.280325 -65.41788) (xy 52.482903 -65.41788)
			(xy 52.485651 -65.363483) (xy 52.496107 -65.31003) (xy 52.514059 -65.258608) (xy 52.539142 -65.210262)
			(xy 52.570846 -65.165974) (xy 52.608527 -65.126646) (xy 52.651418 -65.093077) (xy 52.698647 -65.065949)
			(xy 52.749255 -65.045815) (xy 52.802211 -65.033083) (xy 52.856441 -65.028011) (xy 52.91084 -65.030705)
			(xy 52.937664 -65.03543) (xy 52.961286 -65.039467) (xy 53.009201 -65.039648) (xy 53.056302 -65.030851)
			(xy 53.100923 -65.013387) (xy 53.141482 -64.987875) (xy 53.176545 -64.955218) (xy 53.204871 -64.916572)
			(xy 53.225458 -64.873304) (xy 53.23205 -64.850264) (xy 53.239604 -64.823629) (xy 53.261204 -64.772658)
			(xy 53.289944 -64.725344) (xy 53.325221 -64.682681) (xy 53.366295 -64.645565) (xy 53.412301 -64.614776)
			(xy 53.462275 -64.590959) (xy 53.515167 -64.574616) (xy 53.569865 -64.566089) (xy 53.625221 -64.565557)
			(xy 53.680073 -64.573033) (xy 53.733269 -64.588358) (xy 53.78369 -64.611211) (xy 53.83028 -64.641111)
			(xy 53.872058 -64.677432) (xy 53.908148 -64.71941) (xy 53.937791 -64.766163) (xy 53.960365 -64.816711)
			(xy 53.975397 -64.86999) (xy 53.982569 -64.924882) (xy 53.981733 -64.980235) (xy 53.972904 -65.034885)
			(xy 53.956269 -65.087686) (xy 53.932177 -65.137527) (xy 53.901135 -65.183363) (xy 53.863793 -65.224231)
			(xy 53.820936 -65.259273) (xy 53.797454 -65.273936) (xy 53.777493 -65.286435) (xy 53.74227 -65.317696)
			(xy 53.71341 -65.354912) (xy 53.691901 -65.396808) (xy 53.67848 -65.441949) (xy 53.673605 -65.488791)
			(xy 53.677445 -65.535729) (xy 53.689867 -65.581156) (xy 53.710445 -65.623516) (xy 53.724048 -65.642744)
			(xy 53.739737 -65.664637) (xy 53.765361 -65.712014) (xy 53.78407 -65.762523) (xy 53.795493 -65.81516)
			(xy 53.799404 -65.868881) (xy 53.795724 -65.922617) (xy 53.784526 -65.975303) (xy 53.766033 -66.025891)
			(xy 53.740613 -66.073378) (xy 53.725064 -66.095372) (xy 53.711881 -66.114199) (xy 53.691844 -66.155557)
			(xy 53.679556 -66.199841) (xy 53.675416 -66.245611) (xy 53.679559 -66.29138) (xy 53.691851 -66.335662)
			(xy 53.711892 -66.377019) (xy 53.725064 -66.395854) (xy 53.740326 -66.417351) (xy 53.765379 -66.463739)
			(xy 53.783802 -66.513136) (xy 53.795242 -66.564601) (xy 53.799482 -66.617151) (xy 53.79644 -66.669785)
			(xy 53.786176 -66.721497) (xy 53.768883 -66.771301) (xy 53.744894 -66.818248) (xy 53.730144 -66.8401)
			(xy 53.717599 -66.858805) (xy 53.698666 -66.899667) (xy 53.687239 -66.943229) (xy 53.683678 -66.988123)
			(xy 53.688094 -67.032942) (xy 53.700349 -67.076277) (xy 53.720058 -67.116771) (xy 53.732938 -67.135248)
			(xy 53.748669 -67.15764) (xy 53.774261 -67.206009) (xy 53.792674 -67.25754) (xy 53.803531 -67.311174)
			(xy 53.806607 -67.365809) (xy 53.801841 -67.420323) (xy 53.789329 -67.473596) (xy 53.769329 -67.524532)
			(xy 53.742252 -67.572086) (xy 53.725826 -67.593972) (xy 53.711766 -67.612962) (xy 53.690159 -67.654976)
			(xy 53.676695 -67.700261) (xy 53.671838 -67.747255) (xy 53.675754 -67.794337) (xy 53.68831 -67.839882)
			(xy 53.709071 -67.88232) (xy 53.722778 -67.901566) (xy 53.73862 -67.923694) (xy 53.764603 -67.971508)
			(xy 53.783531 -68.022527) (xy 53.795021 -68.075719) (xy 53.798838 -68.130002) (xy 53.794906 -68.184278)
			(xy 53.783305 -68.237445) (xy 53.764269 -68.288425) (xy 53.738185 -68.336184) (xy 53.72227 -68.358258)
			(xy 53.708715 -68.377297) (xy 53.687981 -68.419174) (xy 53.675253 -68.464136) (xy 53.670957 -68.510666)
			(xy 53.67524 -68.557198) (xy 53.687957 -68.602163) (xy 53.70868 -68.644045) (xy 53.72227 -68.663058)
			(xy 53.738091 -68.685049) (xy 53.764113 -68.732559) (xy 53.783152 -68.783273) (xy 53.794824 -68.836171)
			(xy 53.798894 -68.890188) (xy 53.79528 -68.944238) (xy 53.784055 -68.997232) (xy 53.765445 -69.048105)
			(xy 53.739825 -69.095833) (xy 53.707709 -69.139457) (xy 53.669744 -69.178097) (xy 53.626694 -69.210977)
			(xy 53.579424 -69.237435) (xy 53.528887 -69.256939) (xy 53.476099 -69.269097) (xy 53.422122 -69.273663)
			(xy 53.368041 -69.270546) (xy 53.314946 -69.259809) (xy 53.263904 -69.241667) (xy 53.215942 -69.216486)
			(xy 53.172026 -69.184772) (xy 53.133038 -69.147164) (xy 53.099764 -69.104418) (xy 53.072872 -69.057394)
			(xy 53.052905 -69.007038) (xy 53.046122 -68.980812) (xy 53.042247 -68.966477) (xy 53.02883 -68.939993)
			(xy 53.009647 -68.917336) (xy 52.98574 -68.899735) (xy 52.958407 -68.888147) (xy 52.929134 -68.883202)
			(xy 52.914296 -68.883784) (xy 52.887112 -68.885141) (xy 52.832845 -68.880938) (xy 52.779726 -68.869067)
			(xy 52.728833 -68.849768) (xy 52.681199 -68.823432) (xy 52.637791 -68.790595) (xy 52.59949 -68.751922)
			(xy 52.567073 -68.708199) (xy 52.541198 -68.660313) (xy 52.522391 -68.609236) (xy 52.511033 -68.556005)
			(xy 52.507355 -68.5017) (xy 52.511431 -68.447423) (xy 52.523179 -68.394277) (xy 52.54236 -68.343339)
			(xy 52.568585 -68.295644) (xy 52.601321 -68.25216) (xy 52.639905 -68.213769) (xy 52.683552 -68.181251)
			(xy 52.731378 -68.155265) (xy 52.782411 -68.136339) (xy 52.835616 -68.124857) (xy 52.889912 -68.121053)
			(xy 52.91709 -68.122546) (xy 52.934609 -68.123244) (xy 52.968935 -68.116172) (xy 53.000054 -68.100048)
			(xy 53.025629 -68.076084) (xy 53.04374 -68.046079) (xy 53.048916 -68.029328) (xy 53.055903 -68.00525)
			(xy 53.075327 -67.959031) (xy 53.100645 -67.915758) (xy 53.115718 -67.895724) (xy 53.129784 -67.876737)
			(xy 53.151395 -67.834723) (xy 53.164862 -67.789437) (xy 53.16972 -67.742442) (xy 53.165802 -67.695358)
			(xy 53.153243 -67.649812) (xy 53.132476 -67.607375) (xy 53.118766 -67.58813) (xy 53.103226 -67.566548)
			(xy 53.077642 -67.519926) (xy 53.058795 -67.470198) (xy 53.052472 -67.444366) (xy 53.048874 -67.430029)
			(xy 53.035928 -67.403462) (xy 53.017212 -67.380591) (xy 52.99373 -67.362645) (xy 52.966747 -67.35059)
			(xy 52.937713 -67.345073) (xy 52.922932 -67.345306) (xy 52.894767 -67.346128) (xy 52.838712 -67.34041)
			(xy 52.784107 -67.326507) (xy 52.732142 -67.304723) (xy 52.683948 -67.275531) (xy 52.640572 -67.239567)
			(xy 52.602958 -67.197613) (xy 52.571926 -67.150582) (xy 52.54815 -67.099498) (xy 52.532148 -67.045471)
			(xy 52.524268 -66.989679) (xy 52.524681 -66.933334) (xy 52.533379 -66.877663) (xy 52.550171 -66.823877)
			(xy 52.574694 -66.773147) (xy 52.606413 -66.726577) (xy 52.644637 -66.685179) (xy 52.688536 -66.649855)
			(xy 52.737154 -66.621373) (xy 52.789433 -66.600353) (xy 52.844235 -66.587253) (xy 52.900368 -66.582357)
			(xy 52.92852 -66.58356) (xy 52.945091 -66.584044) (xy 52.977578 -66.57751) (xy 53.007285 -66.562827)
			(xy 53.032207 -66.540987) (xy 53.050661 -66.513464) (xy 53.056536 -66.497962) (xy 53.066414 -66.470771)
			(xy 53.093203 -66.419497) (xy 53.109876 -66.395854) (xy 53.123069 -66.377025) (xy 53.143169 -66.33568)
			(xy 53.155498 -66.291393) (xy 53.159654 -66.245611) (xy 53.155502 -66.199827) (xy 53.143176 -66.155539)
			(xy 53.12308 -66.114193) (xy 53.109876 -66.095372) (xy 53.094943 -66.074294) (xy 53.07026 -66.028917)
			(xy 53.051929 -65.980623) (xy 53.040285 -65.930297) (xy 53.037486 -65.904618) (xy 53.0354 -65.888111)
			(xy 53.023885 -65.856911) (xy 53.004695 -65.829748) (xy 52.979136 -65.808469) (xy 52.948945 -65.794521)
			(xy 52.916174 -65.788851) (xy 52.899564 -65.78981) (xy 52.8724 -65.791804) (xy 52.818006 -65.789003)
			(xy 52.764564 -65.778494) (xy 52.713159 -65.760491) (xy 52.664838 -65.73536) (xy 52.620582 -65.703611)
			(xy 52.581292 -65.665892) (xy 52.547765 -65.622967) (xy 52.520684 -65.575711) (xy 52.5006 -65.525083)
			(xy 52.48792 -65.472114) (xy 52.482903 -65.41788) (xy 51.280325 -65.41788) (xy 51.275414 -65.424834)
			(xy 51.256453 -65.465133) (xy 51.244801 -65.508119) (xy 51.240816 -65.552478) (xy 51.244619 -65.596853)
			(xy 51.256095 -65.639887) (xy 51.265074 -65.66027) (xy 51.275136 -65.682794) (xy 51.290003 -65.729834)
			(xy 51.298673 -65.7784) (xy 51.301002 -65.827679) (xy 51.299364 -65.852294) (xy 51.298545 -65.867286)
			(xy 51.303131 -65.896951) (xy 51.314534 -65.924718) (xy 51.33212 -65.949044) (xy 51.354912 -65.968578)
			(xy 51.381644 -65.982233) (xy 51.396138 -65.986152) (xy 51.422319 -65.993012) (xy 51.472599 -66.013034)
			(xy 51.519545 -66.039961) (xy 51.562213 -66.073253) (xy 51.599748 -66.112241) (xy 51.631397 -66.156143)
			(xy 51.656523 -66.204076) (xy 51.674622 -66.25508) (xy 51.685331 -66.30813) (xy 51.688436 -66.36216)
			(xy 51.683873 -66.416088) (xy 51.671734 -66.468829) (xy 51.652263 -66.519325) (xy 51.63947 -66.543174)
			(xy 51.63151 -66.558392) (xy 51.623313 -66.591732) (xy 51.624317 -66.62605) (xy 51.634448 -66.658853)
			(xy 51.652971 -66.687761) (xy 51.665378 -66.699638) (xy 51.685366 -66.718335) (xy 51.720399 -66.760385)
			(xy 51.749061 -66.807009) (xy 51.770765 -66.857252) (xy 51.785065 -66.910081) (xy 51.791667 -66.964412)
			(xy 51.790436 -67.019128) (xy 51.781396 -67.073107) (xy 51.764735 -67.125239) (xy 51.740793 -67.174455)
			(xy 51.710062 -67.219743) (xy 51.673174 -67.260174) (xy 51.630886 -67.294917) (xy 51.60772 -67.309492)
			(xy 51.593683 -67.318564) (xy 51.570563 -67.342687) (xy 51.554495 -67.371983) (xy 51.546579 -67.404444)
			(xy 51.547357 -67.437848) (xy 51.551586 -67.454018) (xy 51.559218 -67.481719) (xy 51.566968 -67.538653)
			(xy 51.566097 -67.596104) (xy 51.556624 -67.652777) (xy 51.538764 -67.707389) (xy 51.51292 -67.758707)
			(xy 51.496722 -67.78244) (xy 51.484178 -67.801002) (xy 51.465083 -67.841522) (xy 51.453383 -67.884762)
			(xy 51.44944 -67.929383) (xy 51.453376 -67.974004) (xy 51.465071 -68.017245) (xy 51.484161 -68.057769)
			(xy 51.496722 -68.076318) (xy 51.512436 -68.099318) (xy 51.537745 -68.148938) (xy 51.555571 -68.20171)
			(xy 51.565536 -68.256513) (xy 51.567429 -68.312183) (xy 51.561209 -68.367536) (xy 51.547008 -68.421397)
			(xy 51.525128 -68.472621) (xy 51.496034 -68.520121) (xy 51.460343 -68.562886) (xy 51.418815 -68.600009)
			(xy 51.372332 -68.630701) (xy 51.32188 -68.654308) (xy 51.268533 -68.670331) (xy 51.213423 -68.678429)
			(xy 51.157721 -68.678429) (xy 51.102611 -68.670331) (xy 51.049264 -68.654308) (xy 50.998812 -68.630701)
			(xy 50.952329 -68.600009) (xy 50.910801 -68.562886) (xy 50.87511 -68.520121) (xy 50.846016 -68.472621)
			(xy 50.824136 -68.421397) (xy 50.809935 -68.367536) (xy 50.803715 -68.312183) (xy 50.805608 -68.256513)
			(xy 50.815573 -68.20171) (xy 50.833399 -68.148938) (xy 50.858708 -68.099318) (xy 50.874422 -68.076318)
			(xy 50.887038 -68.057794) (xy 50.906186 -68.017276) (xy 50.917918 -67.974023) (xy 50.921867 -67.929383)
			(xy 50.917912 -67.884743) (xy 50.906174 -67.841492) (xy 50.88702 -67.800977) (xy 50.874422 -67.78244)
			(xy 50.8584 -67.758835) (xy 50.832674 -67.707919) (xy 50.814812 -67.653742) (xy 50.805214 -67.597509)
			(xy 50.804093 -67.540474) (xy 50.811473 -67.483908) (xy 50.827191 -67.42907) (xy 50.850896 -67.377183)
			(xy 50.882061 -67.329402) (xy 50.91999 -67.286792) (xy 50.963839 -67.250302) (xy 50.98796 -67.23507)
			(xy 51.002017 -67.226025) (xy 51.025138 -67.201896) (xy 51.041205 -67.172593) (xy 51.049116 -67.140125)
			(xy 51.048329 -67.106715) (xy 51.044094 -67.090544) (xy 51.036095 -67.061251) (xy 51.028416 -67.00102)
			(xy 51.030382 -66.940333) (xy 51.041943 -66.880725) (xy 51.062808 -66.823704) (xy 51.077114 -66.79692)
			(xy 51.08506 -66.781697) (xy 51.093249 -66.74836) (xy 51.092244 -66.714047) (xy 51.082119 -66.681246)
			(xy 51.063607 -66.652336) (xy 51.051206 -66.640456) (xy 51.029864 -66.620475) (xy 50.992888 -66.575195)
			(xy 50.963257 -66.524802) (xy 50.941664 -66.470476) (xy 50.928617 -66.413491) (xy 50.924419 -66.355182)
			(xy 50.926238 -66.326004) (xy 50.927058 -66.311012) (xy 50.922471 -66.281347) (xy 50.911068 -66.25358)
			(xy 50.893482 -66.229254) (xy 50.870689 -66.20972) (xy 50.843958 -66.196065) (xy 50.829464 -66.192146)
			(xy 50.80332 -66.185321) (xy 50.753121 -66.165332) (xy 50.706245 -66.138459) (xy 50.663629 -66.105243)
			(xy 50.626126 -66.066346) (xy 50.594485 -66.022547) (xy 50.56934 -65.974722) (xy 50.551195 -65.923828)
			(xy 50.54041 -65.870882) (xy 50.537204 -65.816945) (xy 49.832663 -65.816945) (xy 49.833943 -65.832715)
			(xy 49.830423 -65.88784) (xy 49.818988 -65.941882) (xy 49.799878 -65.993708) (xy 49.773493 -66.042237)
			(xy 49.75733 -66.064638) (xy 49.743698 -66.083625) (xy 49.722966 -66.125515) (xy 49.710243 -66.170489)
			(xy 49.705957 -66.21703) (xy 49.710254 -66.263571) (xy 49.722988 -66.308542) (xy 49.74373 -66.350426)
			(xy 49.75733 -66.369438) (xy 49.77368 -66.392095) (xy 49.800313 -66.441209) (xy 49.819494 -66.493684)
			(xy 49.830814 -66.548397) (xy 49.834028 -66.604175) (xy 49.82907 -66.659826) (xy 49.816044 -66.714157)
			(xy 49.79523 -66.766006) (xy 49.767073 -66.814263) (xy 49.732177 -66.857896) (xy 49.691287 -66.895969)
			(xy 49.645279 -66.927668) (xy 49.620424 -66.94043) (xy 49.601112 -66.950483) (xy 49.565942 -66.976141)
			(xy 49.535659 -67.007416) (xy 49.511147 -67.043394) (xy 49.493125 -67.083023) (xy 49.482119 -67.125143)
			(xy 49.478451 -67.168522) (xy 49.482229 -67.211892) (xy 49.493341 -67.253984) (xy 49.511464 -67.293567)
			(xy 49.523396 -67.311778) (xy 49.5385 -67.334486) (xy 49.562647 -67.383388) (xy 49.579587 -67.43523)
			(xy 49.588974 -67.488955) (xy 49.590618 -67.543469) (xy 49.584485 -67.597662) (xy 49.570699 -67.65043)
			(xy 49.549542 -67.700698) (xy 49.521445 -67.747443) (xy 49.486979 -67.789711) (xy 49.446848 -67.826643)
			(xy 49.401867 -67.857486) (xy 49.352955 -67.881611) (xy 49.301106 -67.898528) (xy 49.247376 -67.907891)
			(xy 49.192861 -67.909511) (xy 49.138671 -67.903353) (xy 49.085909 -67.889544) (xy 49.035651 -67.868365)
			(xy 48.988919 -67.840247) (xy 48.946665 -67.805763) (xy 48.909751 -67.765615) (xy 48.878929 -67.720621)
			(xy 48.854825 -67.671697) (xy 48.837931 -67.619841) (xy 48.828592 -67.566107) (xy 48.826996 -67.511592)
			(xy 47.062206 -67.511592) (xy 47.044411 -67.533619) (xy 47.003392 -67.571455) (xy 46.957298 -67.60291)
			(xy 46.907113 -67.627314) (xy 46.853907 -67.644146) (xy 46.798817 -67.653047) (xy 46.743019 -67.653825)
			(xy 46.687702 -67.646466) (xy 46.634047 -67.631126) (xy 46.5832 -67.608133) (xy 46.536246 -67.577976)
			(xy 46.494187 -67.541301) (xy 46.457919 -67.498888) (xy 46.428219 -67.451645) (xy 46.405718 -67.400578)
			(xy 46.390898 -67.346777) (xy 46.387004 -67.319144) (xy 46.383613 -67.296172) (xy 46.369717 -67.251873)
			(xy 46.347997 -67.21084) (xy 46.319177 -67.174441) (xy 46.284218 -67.143891) (xy 46.244286 -67.120206)
			(xy 46.200713 -67.104179) (xy 46.154952 -67.096342) (xy 46.131734 -67.096132) (xy 46.10288 -67.095935)
			(xy 46.045734 -67.087964) (xy 45.990443 -67.071473) (xy 45.938267 -67.046838) (xy 45.890401 -67.014621)
			(xy 45.847935 -66.97556) (xy 45.829474 -66.953384) (xy 45.819282 -66.941387) (xy 45.794194 -66.92239)
			(xy 45.765215 -66.91012) (xy 45.734113 -66.905326) (xy 45.702784 -66.9083) (xy 45.67314 -66.918861)
			(xy 45.659802 -66.927222) (xy 45.636339 -66.942357) (xy 45.585878 -66.966262) (xy 45.532472 -66.982555)
			(xy 45.477262 -66.990889) (xy 45.421426 -66.991086) (xy 45.366158 -66.983142) (xy 45.312638 -66.967226)
			(xy 45.26201 -66.943678) (xy 45.238416 -66.928746) (xy 45.225345 -66.920657) (xy 45.196374 -66.910408)
			(xy 45.165791 -66.907397) (xy 45.135377 -66.911802) (xy 45.106904 -66.923364) (xy 45.082031 -66.941411)
			(xy 45.071792 -66.952876) (xy 45.054232 -66.97286) (xy 45.014582 -67.008324) (xy 44.970388 -67.037935)
			(xy 44.92251 -67.061118) (xy 44.871875 -67.077424) (xy 44.819465 -67.086537) (xy 44.766297 -67.08828)
			(xy 44.713403 -67.082618) (xy 44.661809 -67.069663) (xy 44.612515 -67.049664) (xy 44.566478 -67.02301)
			(xy 44.54525 -67.006978) (xy 44.52624 -66.992829) (xy 44.484171 -66.971033) (xy 44.43879 -66.957417)
			(xy 44.391671 -66.952454) (xy 44.344448 -66.956315) (xy 44.298761 -66.968867) (xy 44.256195 -66.989675)
			(xy 44.236894 -67.003422) (xy 44.214779 -67.019307) (xy 44.166947 -67.045324) (xy 44.115903 -67.064276)
			(xy 44.062683 -67.075779) (xy 44.008368 -67.079598) (xy 43.954061 -67.075656) (xy 43.900867 -67.064033)
			(xy 43.849866 -67.044965) (xy 43.802094 -67.01884) (xy 43.758521 -66.986188) (xy 43.720034 -66.947673)
			(xy 43.687413 -66.904077) (xy 43.661322 -66.856286) (xy 43.64229 -66.805271) (xy 43.630705 -66.752068)
			(xy 43.626802 -66.697759) (xy 33.26384 -66.697759) (xy 33.26384 -67.985132) (xy 33.28077 -68.017644)
			(xy 33.791142 -68.017644) (xy 33.795213 -67.962022) (xy 33.807339 -67.907585) (xy 33.827262 -67.855494)
			(xy 33.854558 -67.806859) (xy 33.888644 -67.762716) (xy 33.928793 -67.724007) (xy 33.974151 -67.691556)
			(xy 34.023751 -67.666055) (xy 34.076535 -67.648048) (xy 34.131378 -67.637918) (xy 34.187112 -67.635881)
			(xy 34.242549 -67.641981) (xy 34.296506 -67.656087) (xy 34.347835 -67.677899) (xy 34.395441 -67.706953)
			(xy 34.438309 -67.742628) (xy 34.475526 -67.784165) (xy 34.506299 -67.830678) (xy 34.529971 -67.881175)
			(xy 34.535877 -67.900804) (xy 42.9547 -67.900804) (xy 42.958771 -67.845182) (xy 42.970897 -67.790745)
			(xy 42.99082 -67.738654) (xy 43.018116 -67.690019) (xy 43.052202 -67.645876) (xy 43.092351 -67.607167)
			(xy 43.137709 -67.574716) (xy 43.187309 -67.549215) (xy 43.240093 -67.531208) (xy 43.294936 -67.521078)
			(xy 43.35067 -67.519041) (xy 43.406107 -67.525141) (xy 43.460064 -67.539247) (xy 43.511393 -67.561059)
			(xy 43.558999 -67.590113) (xy 43.601867 -67.625788) (xy 43.639084 -67.667325) (xy 43.669857 -67.713838)
			(xy 43.693529 -67.764335) (xy 43.709597 -67.817742) (xy 43.717717 -67.872918) (xy 43.718226 -67.900804)
			(xy 43.717717 -67.92869) (xy 43.709597 -67.983866) (xy 43.693529 -68.037273) (xy 43.669857 -68.08777)
			(xy 43.639084 -68.134283) (xy 43.601867 -68.17582) (xy 43.558999 -68.211495) (xy 43.511393 -68.240549)
			(xy 43.460064 -68.262361) (xy 43.406107 -68.276467) (xy 43.35067 -68.282567) (xy 43.294936 -68.28053)
			(xy 43.240093 -68.2704) (xy 43.187309 -68.252393) (xy 43.137709 -68.226892) (xy 43.092351 -68.194441)
			(xy 43.052202 -68.155732) (xy 43.018116 -68.111589) (xy 42.99082 -68.062954) (xy 42.970897 -68.010863)
			(xy 42.958771 -67.956426) (xy 42.9547 -67.900804) (xy 34.535877 -67.900804) (xy 34.546039 -67.934582)
			(xy 34.554159 -67.989758) (xy 34.554668 -68.017644) (xy 34.554159 -68.04553) (xy 34.546039 -68.100706)
			(xy 34.529971 -68.154113) (xy 34.506299 -68.20461) (xy 34.475526 -68.251123) (xy 34.438309 -68.29266)
			(xy 34.395441 -68.328335) (xy 34.347835 -68.357389) (xy 34.296506 -68.379201) (xy 34.242549 -68.393307)
			(xy 34.187112 -68.399407) (xy 34.131378 -68.39737) (xy 34.076535 -68.38724) (xy 34.023751 -68.369233)
			(xy 33.974151 -68.343732) (xy 33.928793 -68.311281) (xy 33.888644 -68.272572) (xy 33.854558 -68.228429)
			(xy 33.827262 -68.179794) (xy 33.807339 -68.127703) (xy 33.795213 -68.073266) (xy 33.791142 -68.017644)
			(xy 33.28077 -68.017644) (xy 33.292542 -68.04025) (xy 33.317942 -68.05803) (xy 33.340054 -68.074143)
			(xy 33.379868 -68.111671) (xy 33.413916 -68.154499) (xy 33.441499 -68.20175) (xy 33.462052 -68.252455)
			(xy 33.475154 -68.305576) (xy 33.480536 -68.360023) (xy 33.478089 -68.414681) (xy 33.467862 -68.468429)
			(xy 33.450064 -68.520166) (xy 33.441639 -68.536566) (xy 35.60521 -68.536566) (xy 35.609281 -68.480944)
			(xy 35.621407 -68.426507) (xy 35.64133 -68.374416) (xy 35.668626 -68.325781) (xy 35.702712 -68.281638)
			(xy 35.742861 -68.242929) (xy 35.788219 -68.210478) (xy 35.837819 -68.184977) (xy 35.890603 -68.16697)
			(xy 35.945446 -68.15684) (xy 36.00118 -68.154803) (xy 36.056617 -68.160903) (xy 36.110574 -68.175009)
			(xy 36.161903 -68.196821) (xy 36.209509 -68.225875) (xy 36.252377 -68.26155) (xy 36.289594 -68.303087)
			(xy 36.320367 -68.3496) (xy 36.344039 -68.400097) (xy 36.360107 -68.453504) (xy 36.368227 -68.50868)
			(xy 36.368736 -68.536566) (xy 36.368227 -68.564452) (xy 36.360107 -68.619628) (xy 36.344039 -68.673035)
			(xy 36.320367 -68.723532) (xy 36.289594 -68.770045) (xy 36.252377 -68.811582) (xy 36.209509 -68.847257)
			(xy 36.161903 -68.876311) (xy 36.110574 -68.898123) (xy 36.056617 -68.912229) (xy 36.00118 -68.918329)
			(xy 35.945446 -68.916292) (xy 35.890603 -68.906162) (xy 35.837819 -68.888155) (xy 35.788219 -68.862654)
			(xy 35.742861 -68.830203) (xy 35.702712 -68.791494) (xy 35.668626 -68.747351) (xy 35.64133 -68.698716)
			(xy 35.621407 -68.646625) (xy 35.609281 -68.592188) (xy 35.60521 -68.536566) (xy 33.441639 -68.536566)
			(xy 33.425062 -68.568832) (xy 33.409636 -68.59143) (xy 33.396872 -68.610149) (xy 33.377495 -68.651098)
			(xy 33.365696 -68.694837) (xy 33.361849 -68.739976) (xy 33.366078 -68.785081) (xy 33.378247 -68.828718)
			(xy 33.39797 -68.869502) (xy 33.410906 -68.888102) (xy 33.426786 -68.910793) (xy 33.452527 -68.959831)
			(xy 33.470907 -69.012075) (xy 33.48154 -69.066427) (xy 33.484202 -69.121747) (xy 33.478837 -69.176869)
			(xy 33.465559 -69.230637) (xy 33.444645 -69.281919) (xy 33.416536 -69.329639) (xy 33.381822 -69.372792)
			(xy 33.341233 -69.410473) (xy 33.318704 -69.426582) (xy 33.306273 -69.435661) (xy 33.285857 -69.458689)
			(xy 33.271572 -69.485948) (xy 33.264255 -69.515841) (xy 33.26384 -69.53123) (xy 33.26384 -69.796406)
			(xy 33.228026 -69.832474) (xy 33.216708 -69.844677) (xy 33.200202 -69.873563) (xy 33.19171 -69.90573)
			(xy 33.191805 -69.938999) (xy 33.200483 -69.971116) (xy 33.217154 -69.999907) (xy 33.228534 -70.012052)
			(xy 33.244282 -70.027546) (xy 33.264094 -70.036944) (xy 33.288306 -70.048797) (xy 33.333419 -70.078306)
			(xy 33.373928 -70.113872) (xy 33.409027 -70.154787) (xy 33.438016 -70.200236) (xy 33.448302 -70.222872)
			(xy 36.498782 -70.222872) (xy 36.502853 -70.16725) (xy 36.514979 -70.112813) (xy 36.534902 -70.060722)
			(xy 36.562198 -70.012087) (xy 36.596284 -69.967944) (xy 36.636433 -69.929235) (xy 36.681791 -69.896784)
			(xy 36.731391 -69.871283) (xy 36.784175 -69.853276) (xy 36.839018 -69.843146) (xy 36.894752 -69.841109)
			(xy 36.950189 -69.847209) (xy 37.004146 -69.861315) (xy 37.055475 -69.883127) (xy 37.103081 -69.912181)
			(xy 37.145949 -69.947856) (xy 37.183166 -69.989393) (xy 37.213939 -70.035906) (xy 37.237611 -70.086403)
			(xy 37.253679 -70.13981) (xy 37.261799 -70.194986) (xy 37.262308 -70.222872) (xy 37.261799 -70.250758)
			(xy 37.253679 -70.305934) (xy 37.25261 -70.309486) (xy 38.387018 -70.309486) (xy 38.391089 -70.253864)
			(xy 38.403215 -70.199427) (xy 38.423138 -70.147336) (xy 38.450434 -70.098701) (xy 38.48452 -70.054558)
			(xy 38.524669 -70.015849) (xy 38.570027 -69.983398) (xy 38.619627 -69.957897) (xy 38.672411 -69.93989)
			(xy 38.727254 -69.92976) (xy 38.782988 -69.927723) (xy 38.838425 -69.933823) (xy 38.892382 -69.947929)
			(xy 38.943711 -69.969741) (xy 38.991317 -69.998795) (xy 39.034185 -70.03447) (xy 39.071402 -70.076007)
			(xy 39.102175 -70.12252) (xy 39.125847 -70.173017) (xy 39.141915 -70.226424) (xy 39.146289 -70.256146)
			(xy 40.888918 -70.256146) (xy 40.892989 -70.200524) (xy 40.905115 -70.146087) (xy 40.925038 -70.093996)
			(xy 40.952334 -70.045361) (xy 40.98642 -70.001218) (xy 41.026569 -69.962509) (xy 41.071927 -69.930058)
			(xy 41.121527 -69.904557) (xy 41.174311 -69.88655) (xy 41.229154 -69.87642) (xy 41.284888 -69.874383)
			(xy 41.340325 -69.880483) (xy 41.394282 -69.894589) (xy 41.445611 -69.916401) (xy 41.493217 -69.945455)
			(xy 41.536085 -69.98113) (xy 41.537391 -69.982588) (xy 42.927522 -69.982588) (xy 42.931593 -69.926966)
			(xy 42.943719 -69.872529) (xy 42.963642 -69.820438) (xy 42.990938 -69.771803) (xy 43.025024 -69.72766)
			(xy 43.065173 -69.688951) (xy 43.110531 -69.6565) (xy 43.160131 -69.630999) (xy 43.212915 -69.612992)
			(xy 43.267758 -69.602862) (xy 43.323492 -69.600825) (xy 43.378929 -69.606925) (xy 43.432886 -69.621031)
			(xy 43.484215 -69.642843) (xy 43.531821 -69.671897) (xy 43.574689 -69.707572) (xy 43.611906 -69.749109)
			(xy 43.642679 -69.795622) (xy 43.666351 -69.846119) (xy 43.682419 -69.899526) (xy 43.690539 -69.954702)
			(xy 43.691048 -69.982588) (xy 43.690539 -70.010474) (xy 43.682419 -70.06565) (xy 43.666351 -70.119057)
			(xy 43.642679 -70.169554) (xy 43.611906 -70.216067) (xy 43.574689 -70.257604) (xy 43.531821 -70.293279)
			(xy 43.484215 -70.322333) (xy 43.432886 -70.344145) (xy 43.378929 -70.358251) (xy 43.323492 -70.364351)
			(xy 43.267758 -70.362314) (xy 43.212915 -70.352184) (xy 43.160131 -70.334177) (xy 43.110531 -70.308676)
			(xy 43.065173 -70.276225) (xy 43.025024 -70.237516) (xy 42.990938 -70.193373) (xy 42.963642 -70.144738)
			(xy 42.943719 -70.092647) (xy 42.931593 -70.03821) (xy 42.927522 -69.982588) (xy 41.537391 -69.982588)
			(xy 41.573302 -70.022667) (xy 41.604075 -70.06918) (xy 41.627747 -70.119677) (xy 41.643815 -70.173084)
			(xy 41.651935 -70.22826) (xy 41.652444 -70.256146) (xy 41.651935 -70.284032) (xy 41.643815 -70.339208)
			(xy 41.627747 -70.392615) (xy 41.604075 -70.443112) (xy 41.573302 -70.489625) (xy 41.536085 -70.531162)
			(xy 41.493217 -70.566837) (xy 41.445611 -70.595891) (xy 41.394282 -70.617703) (xy 41.340325 -70.631809)
			(xy 41.284888 -70.637909) (xy 41.229154 -70.635872) (xy 41.174311 -70.625742) (xy 41.121527 -70.607735)
			(xy 41.071927 -70.582234) (xy 41.026569 -70.549783) (xy 40.98642 -70.511074) (xy 40.952334 -70.466931)
			(xy 40.925038 -70.418296) (xy 40.905115 -70.366205) (xy 40.892989 -70.311768) (xy 40.888918 -70.256146)
			(xy 39.146289 -70.256146) (xy 39.150035 -70.2816) (xy 39.150544 -70.309486) (xy 39.150035 -70.337372)
			(xy 39.141915 -70.392548) (xy 39.125847 -70.445955) (xy 39.102175 -70.496452) (xy 39.071402 -70.542965)
			(xy 39.034185 -70.584502) (xy 38.991317 -70.620177) (xy 38.943711 -70.649231) (xy 38.892382 -70.671043)
			(xy 38.838425 -70.685149) (xy 38.782988 -70.691249) (xy 38.727254 -70.689212) (xy 38.672411 -70.679082)
			(xy 38.619627 -70.661075) (xy 38.570027 -70.635574) (xy 38.524669 -70.603123) (xy 38.48452 -70.564414)
			(xy 38.450434 -70.520271) (xy 38.423138 -70.471636) (xy 38.403215 -70.419545) (xy 38.391089 -70.365108)
			(xy 38.387018 -70.309486) (xy 37.25261 -70.309486) (xy 37.237611 -70.359341) (xy 37.213939 -70.409838)
			(xy 37.183166 -70.456351) (xy 37.145949 -70.497888) (xy 37.103081 -70.533563) (xy 37.055475 -70.562617)
			(xy 37.004146 -70.584429) (xy 36.950189 -70.598535) (xy 36.894752 -70.604635) (xy 36.839018 -70.602598)
			(xy 36.784175 -70.592468) (xy 36.731391 -70.574461) (xy 36.681791 -70.54896) (xy 36.636433 -70.516509)
			(xy 36.596284 -70.4778) (xy 36.562198 -70.433657) (xy 36.534902 -70.385022) (xy 36.514979 -70.332931)
			(xy 36.502853 -70.278494) (xy 36.498782 -70.222872) (xy 33.448302 -70.222872) (xy 33.460318 -70.249314)
			(xy 33.475489 -70.301042) (xy 33.483226 -70.354391) (xy 33.483375 -70.408298) (xy 33.475934 -70.461689)
			(xy 33.46105 -70.5135) (xy 33.43902 -70.5627) (xy 33.410284 -70.608309) (xy 33.375412 -70.649418)
			(xy 33.355534 -70.667626) (xy 33.339223 -70.682702) (xy 33.311629 -70.717502) (xy 33.290514 -70.756575)
			(xy 33.276524 -70.798727) (xy 33.270086 -70.84267) (xy 33.270512 -70.85711) (xy 34.906202 -70.85711)
			(xy 34.910273 -70.801488) (xy 34.922399 -70.747051) (xy 34.942322 -70.69496) (xy 34.969618 -70.646325)
			(xy 35.003704 -70.602182) (xy 35.043853 -70.563473) (xy 35.089211 -70.531022) (xy 35.138811 -70.505521)
			(xy 35.191595 -70.487514) (xy 35.246438 -70.477384) (xy 35.302172 -70.475347) (xy 35.357609 -70.481447)
			(xy 35.411566 -70.495553) (xy 35.462895 -70.517365) (xy 35.510501 -70.546419) (xy 35.553369 -70.582094)
			(xy 35.590586 -70.623631) (xy 35.621359 -70.670144) (xy 35.645031 -70.720641) (xy 35.661099 -70.774048)
			(xy 35.669219 -70.829224) (xy 35.669728 -70.85711) (xy 35.669219 -70.884996) (xy 35.661099 -70.940172)
			(xy 35.645031 -70.993579) (xy 35.621359 -71.044076) (xy 35.590586 -71.090589) (xy 35.553369 -71.132126)
			(xy 35.510501 -71.167801) (xy 35.462895 -71.196855) (xy 35.411566 -71.218667) (xy 35.357609 -71.232773)
			(xy 35.302172 -71.238873) (xy 35.246438 -71.236836) (xy 35.191595 -71.226706) (xy 35.138811 -71.208699)
			(xy 35.089211 -71.183198) (xy 35.043853 -71.150747) (xy 35.003704 -71.112038) (xy 34.969618 -71.067895)
			(xy 34.942322 -71.01926) (xy 34.922399 -70.967169) (xy 34.910273 -70.912732) (xy 34.906202 -70.85711)
			(xy 33.270512 -70.85711) (xy 33.271396 -70.887064) (xy 33.280414 -70.930551) (xy 33.288224 -70.951344)
			(xy 33.298081 -70.977511) (xy 33.310899 -71.031936) (xy 33.315639 -71.08765) (xy 33.312198 -71.143459)
			(xy 33.300651 -71.198168) (xy 33.281244 -71.250607) (xy 33.254393 -71.299652) (xy 33.220672 -71.344255)
			(xy 33.180804 -71.38346) (xy 33.150966 -71.405242) (xy 35.978082 -71.405242) (xy 35.982153 -71.34962)
			(xy 35.994279 -71.295183) (xy 36.014202 -71.243092) (xy 36.041498 -71.194457) (xy 36.075584 -71.150314)
			(xy 36.115733 -71.111605) (xy 36.161091 -71.079154) (xy 36.210691 -71.053653) (xy 36.263475 -71.035646)
			(xy 36.318318 -71.025516) (xy 36.374052 -71.023479) (xy 36.429489 -71.029579) (xy 36.483446 -71.043685)
			(xy 36.534775 -71.065497) (xy 36.582381 -71.094551) (xy 36.625249 -71.130226) (xy 36.662466 -71.171763)
			(xy 36.693239 -71.218276) (xy 36.716911 -71.268773) (xy 36.732979 -71.32218) (xy 36.741099 -71.377356)
			(xy 36.741608 -71.405242) (xy 36.741099 -71.433128) (xy 36.732979 -71.488304) (xy 36.716911 -71.541711)
			(xy 36.703966 -71.569326) (xy 37.298882 -71.569326) (xy 37.302953 -71.513704) (xy 37.315079 -71.459267)
			(xy 37.335002 -71.407176) (xy 37.362298 -71.358541) (xy 37.396384 -71.314398) (xy 37.436533 -71.275689)
			(xy 37.481891 -71.243238) (xy 37.531491 -71.217737) (xy 37.584275 -71.19973) (xy 37.639118 -71.1896)
			(xy 37.694852 -71.187563) (xy 37.750289 -71.193663) (xy 37.804246 -71.207769) (xy 37.855575 -71.229581)
			(xy 37.903181 -71.258635) (xy 37.946049 -71.29431) (xy 37.983266 -71.335847) (xy 38.014039 -71.38236)
			(xy 38.037711 -71.432857) (xy 38.053779 -71.486264) (xy 38.061899 -71.54144) (xy 38.062408 -71.569326)
			(xy 38.061899 -71.597212) (xy 38.053779 -71.652388) (xy 38.037711 -71.705795) (xy 38.014039 -71.756292)
			(xy 37.983266 -71.802805) (xy 37.946049 -71.844342) (xy 37.903181 -71.880017) (xy 37.855575 -71.909071)
			(xy 37.804246 -71.930883) (xy 37.750289 -71.944989) (xy 37.694852 -71.951089) (xy 37.639118 -71.949052)
			(xy 37.584275 -71.938922) (xy 37.531491 -71.920915) (xy 37.481891 -71.895414) (xy 37.436533 -71.862963)
			(xy 37.396384 -71.824254) (xy 37.362298 -71.780111) (xy 37.335002 -71.731476) (xy 37.315079 -71.679385)
			(xy 37.302953 -71.624948) (xy 37.298882 -71.569326) (xy 36.703966 -71.569326) (xy 36.693239 -71.592208)
			(xy 36.662466 -71.638721) (xy 36.625249 -71.680258) (xy 36.582381 -71.715933) (xy 36.534775 -71.744987)
			(xy 36.483446 -71.766799) (xy 36.429489 -71.780905) (xy 36.374052 -71.787005) (xy 36.318318 -71.784968)
			(xy 36.263475 -71.774838) (xy 36.210691 -71.756831) (xy 36.161091 -71.73133) (xy 36.115733 -71.698879)
			(xy 36.075584 -71.66017) (xy 36.041498 -71.616027) (xy 36.014202 -71.567392) (xy 35.994279 -71.515301)
			(xy 35.982153 -71.460864) (xy 35.978082 -71.405242) (xy 33.150966 -71.405242) (xy 33.135643 -71.416428)
			(xy 33.086154 -71.442453) (xy 33.033397 -71.460978) (xy 33.00603 -71.46671) (xy 32.988892 -71.47059)
			(xy 32.957523 -71.486396) (xy 32.931651 -71.510153) (xy 32.913233 -71.540064) (xy 32.903666 -71.573861)
			(xy 32.90316 -71.591424) (xy 32.90316 -71.63054) (xy 32.903654 -71.646446) (xy 32.91153 -71.677267)
			(xy 32.926783 -71.705183) (xy 32.948465 -71.728461) (xy 32.96158 -71.737474) (xy 32.984448 -71.752684)
			(xy 33.025974 -71.788626) (xy 33.061916 -71.830152) (xy 33.091531 -71.876404) (xy 33.114206 -71.926425)
			(xy 33.129472 -71.979181) (xy 33.137015 -72.033581) (xy 33.136678 -72.0885) (xy 33.128467 -72.142803)
			(xy 33.112554 -72.195367) (xy 33.089266 -72.245106) (xy 33.07461 -72.268334) (xy 33.063057 -72.286725)
			(xy 33.045732 -72.326548) (xy 33.035437 -72.368738) (xy 33.032471 -72.412065) (xy 33.036923 -72.455265)
			(xy 33.04866 -72.497077) (xy 33.053617 -72.50748) (xy 39.898635 -72.50748) (xy 39.905698 -72.452972)
			(xy 39.92051 -72.400041) (xy 39.942762 -72.349783) (xy 39.971996 -72.303237) (xy 40.007605 -72.261368)
			(xy 40.048853 -72.225042) (xy 40.094887 -72.195009) (xy 40.144753 -72.171892) (xy 40.19742 -72.15617)
			(xy 40.251799 -72.148167) (xy 40.306763 -72.148048) (xy 40.361175 -72.155818) (xy 40.413909 -72.171314)
			(xy 40.463875 -72.194216) (xy 40.510037 -72.22405) (xy 40.551441 -72.260199) (xy 40.58723 -72.301915)
			(xy 40.616663 -72.348334) (xy 40.639132 -72.398496) (xy 40.647112 -72.424798) (xy 40.65381 -72.446511)
			(xy 40.673836 -72.487293) (xy 40.70079 -72.523867) (xy 40.733815 -72.55507) (xy 40.771859 -72.579908)
			(xy 40.81371 -72.59759) (xy 40.858038 -72.607554) (xy 40.903431 -72.609482) (xy 40.948444 -72.603313)
			(xy 40.9702 -72.596756) (xy 40.996456 -72.588627) (xy 41.05061 -72.579214) (xy 41.105553 -72.577668)
			(xy 41.16015 -72.584021) (xy 41.21327 -72.598142) (xy 41.263815 -72.619739) (xy 41.310738 -72.648364)
			(xy 41.353069 -72.683425) (xy 41.389931 -72.724197) (xy 41.420562 -72.769837) (xy 41.444327 -72.819398)
			(xy 41.460736 -72.871857) (xy 41.469448 -72.926128) (xy 41.470284 -72.981087) (xy 41.463225 -73.035597)
			(xy 41.448418 -73.08853) (xy 41.42617 -73.138791) (xy 41.396941 -73.18534) (xy 41.361335 -73.227214)
			(xy 41.32009 -73.263546) (xy 41.274059 -73.293584) (xy 41.224194 -73.316707) (xy 41.171527 -73.332436)
			(xy 41.117149 -73.340446) (xy 41.062184 -73.340571) (xy 41.007769 -73.332809) (xy 40.955032 -73.317319)
			(xy 40.905062 -73.294423) (xy 40.858895 -73.264594) (xy 40.817485 -73.22845) (xy 40.781689 -73.186739)
			(xy 40.752249 -73.140323) (xy 40.729772 -73.090164) (xy 40.721788 -73.063862) (xy 40.715056 -73.04216)
			(xy 40.695039 -73.001375) (xy 40.668091 -72.964798) (xy 40.635072 -72.933592) (xy 40.597032 -72.908752)
			(xy 40.555183 -72.891068) (xy 40.510857 -72.881103) (xy 40.465466 -72.879175) (xy 40.420454 -72.885345)
			(xy 40.3987 -72.891904) (xy 40.372421 -72.899962) (xy 40.318268 -72.909372) (xy 40.263326 -72.910915)
			(xy 40.208731 -72.904558) (xy 40.155612 -72.890434) (xy 40.10507 -72.868835) (xy 40.05815 -72.840207)
			(xy 40.015823 -72.805144) (xy 39.978964 -72.76437) (xy 39.948338 -72.718729) (xy 39.924577 -72.669167)
			(xy 39.908173 -72.616708) (xy 39.899465 -72.562438) (xy 39.898635 -72.50748) (xy 33.053617 -72.50748)
			(xy 33.067342 -72.536282) (xy 33.092423 -72.571736) (xy 33.123172 -72.602404) (xy 33.14065 -72.615298)
			(xy 33.162701 -72.631405) (xy 33.202401 -72.668898) (xy 33.23635 -72.711668) (xy 33.263855 -72.758841)
			(xy 33.284354 -72.809454) (xy 33.297428 -72.862472) (xy 33.302809 -72.916812) (xy 33.300389 -72.971364)
			(xy 33.290217 -73.025014) (xy 33.2725 -73.076666) (xy 33.2476 -73.125265) (xy 33.216026 -73.169817)
			(xy 33.178423 -73.209413) (xy 33.13556 -73.243244) (xy 33.088311 -73.270619) (xy 33.056706 -73.283318)
			(xy 38.412164 -73.283318) (xy 38.416235 -73.227696) (xy 38.428361 -73.173259) (xy 38.448284 -73.121168)
			(xy 38.47558 -73.072533) (xy 38.509666 -73.02839) (xy 38.549815 -72.989681) (xy 38.595173 -72.95723)
			(xy 38.644773 -72.931729) (xy 38.697557 -72.913722) (xy 38.7524 -72.903592) (xy 38.808134 -72.901555)
			(xy 38.863571 -72.907655) (xy 38.917528 -72.921761) (xy 38.968857 -72.943573) (xy 39.016463 -72.972627)
			(xy 39.059331 -73.008302) (xy 39.096548 -73.049839) (xy 39.127321 -73.096352) (xy 39.150993 -73.146849)
			(xy 39.167061 -73.200256) (xy 39.175181 -73.255432) (xy 39.17569 -73.283318) (xy 39.175181 -73.311204)
			(xy 39.167061 -73.36638) (xy 39.150993 -73.419787) (xy 39.127321 -73.470284) (xy 39.096548 -73.516797)
			(xy 39.059331 -73.558334) (xy 39.016463 -73.594009) (xy 38.968857 -73.623063) (xy 38.917528 -73.644875)
			(xy 38.863571 -73.658981) (xy 38.808134 -73.665081) (xy 38.7524 -73.663044) (xy 38.697557 -73.652914)
			(xy 38.644773 -73.634907) (xy 38.595173 -73.609406) (xy 38.549815 -73.576955) (xy 38.509666 -73.538246)
			(xy 38.47558 -73.494103) (xy 38.448284 -73.445468) (xy 38.428361 -73.393377) (xy 38.416235 -73.33894)
			(xy 38.412164 -73.283318) (xy 33.056706 -73.283318) (xy 33.037642 -73.290978) (xy 32.984588 -73.303905)
			(xy 32.930233 -73.309137) (xy 32.875687 -73.306566) (xy 32.822066 -73.296245) (xy 32.770463 -73.278386)
			(xy 32.721933 -73.253352) (xy 32.699452 -73.237852) (xy 32.681009 -73.225259) (xy 32.640692 -73.206064)
			(xy 32.597639 -73.194213) (xy 32.553178 -73.190071) (xy 32.508677 -73.193766) (xy 32.465508 -73.205184)
			(xy 32.425 -73.223973) (xy 32.3884 -73.249555) (xy 32.3723 -73.26503) (xy 31.80842 -73.82891) (xy 31.80842 -73.910601)
			(xy 34.650801 -73.910601) (xy 34.654909 -73.854822) (xy 34.667116 -73.800241) (xy 34.68716 -73.748026)
			(xy 34.714611 -73.699296) (xy 34.748882 -73.655097) (xy 34.789238 -73.616373) (xy 34.834815 -73.583956)
			(xy 34.884636 -73.558539) (xy 34.937634 -73.540668) (xy 34.992673 -73.530725) (xy 35.048573 -73.528923)
			(xy 35.104138 -73.535301) (xy 35.158177 -73.549722) (xy 35.209531 -73.571877) (xy 35.257101 -73.601292)
			(xy 35.299867 -73.637336) (xy 35.336914 -73.679237) (xy 35.367446 -73.726098) (xy 35.390811 -73.776913)
			(xy 35.403786 -73.82129) (xy 39.769286 -73.82129) (xy 39.773357 -73.765668) (xy 39.785483 -73.711231)
			(xy 39.805406 -73.65914) (xy 39.832702 -73.610505) (xy 39.866788 -73.566362) (xy 39.906937 -73.527653)
			(xy 39.952295 -73.495202) (xy 40.001895 -73.469701) (xy 40.054679 -73.451694) (xy 40.109522 -73.441564)
			(xy 40.165256 -73.439527) (xy 40.220693 -73.445627) (xy 40.27465 -73.459733) (xy 40.325979 -73.481545)
			(xy 40.373585 -73.510599) (xy 40.416453 -73.546274) (xy 40.45367 -73.587811) (xy 40.484443 -73.634324)
			(xy 40.508115 -73.684821) (xy 40.524183 -73.738228) (xy 40.532303 -73.793404) (xy 40.532812 -73.82129)
			(xy 40.532303 -73.849176) (xy 40.524183 -73.904352) (xy 40.508115 -73.957759) (xy 40.484443 -74.008256)
			(xy 40.45367 -74.054769) (xy 40.416453 -74.096306) (xy 40.373585 -74.131981) (xy 40.325979 -74.161035)
			(xy 40.27465 -74.182847) (xy 40.220693 -74.196953) (xy 40.165256 -74.203053) (xy 40.109522 -74.201016)
			(xy 40.054679 -74.190886) (xy 40.001895 -74.172879) (xy 39.952295 -74.147378) (xy 39.906937 -74.114927)
			(xy 39.866788 -74.076218) (xy 39.832702 -74.032075) (xy 39.805406 -73.98344) (xy 39.785483 -73.931349)
			(xy 39.773357 -73.876912) (xy 39.769286 -73.82129) (xy 35.403786 -73.82129) (xy 35.406507 -73.830595)
			(xy 35.414199 -73.885993) (xy 35.413721 -73.941921) (xy 35.409886 -73.969626) (xy 35.406947 -73.991257)
			(xy 35.407684 -74.034903) (xy 35.415869 -74.077781) (xy 35.431263 -74.118628) (xy 35.453412 -74.156244)
			(xy 35.481665 -74.18952) (xy 35.515188 -74.217478) (xy 35.552997 -74.239295) (xy 35.593979 -74.254329)
			(xy 35.615372 -74.258678) (xy 35.642591 -74.264042) (xy 35.695174 -74.281726) (xy 35.744643 -74.306839)
			(xy 35.789953 -74.33885) (xy 35.830151 -74.377085) (xy 35.862788 -74.418698) (xy 37.647116 -74.418698)
			(xy 37.651187 -74.363076) (xy 37.663313 -74.308639) (xy 37.683236 -74.256548) (xy 37.710532 -74.207913)
			(xy 37.744618 -74.16377) (xy 37.784767 -74.125061) (xy 37.830125 -74.09261) (xy 37.879725 -74.067109)
			(xy 37.932509 -74.049102) (xy 37.987352 -74.038972) (xy 38.043086 -74.036935) (xy 38.098523 -74.043035)
			(xy 38.15248 -74.057141) (xy 38.203809 -74.078953) (xy 38.251415 -74.108007) (xy 38.294283 -74.143682)
			(xy 38.3315 -74.185219) (xy 38.362273 -74.231732) (xy 38.385945 -74.282229) (xy 38.402013 -74.335636)
			(xy 38.410133 -74.390812) (xy 38.410642 -74.418698) (xy 38.410133 -74.446584) (xy 38.402013 -74.50176)
			(xy 38.385945 -74.555167) (xy 38.362273 -74.605664) (xy 38.337753 -74.642726) (xy 40.745154 -74.642726)
			(xy 40.749225 -74.587104) (xy 40.761351 -74.532667) (xy 40.781274 -74.480576) (xy 40.80857 -74.431941)
			(xy 40.842656 -74.387798) (xy 40.882805 -74.349089) (xy 40.928163 -74.316638) (xy 40.977763 -74.291137)
			(xy 41.030547 -74.27313) (xy 41.08539 -74.263) (xy 41.141124 -74.260963) (xy 41.196561 -74.267063)
			(xy 41.250518 -74.281169) (xy 41.301847 -74.302981) (xy 41.349453 -74.332035) (xy 41.392321 -74.36771)
			(xy 41.429538 -74.409247) (xy 41.460311 -74.45576) (xy 41.483983 -74.506257) (xy 41.500051 -74.559664)
			(xy 41.508171 -74.61484) (xy 41.50868 -74.642726) (xy 41.508171 -74.670612) (xy 41.500051 -74.725788)
			(xy 41.483983 -74.779195) (xy 41.460311 -74.829692) (xy 41.429538 -74.876205) (xy 41.392321 -74.917742)
			(xy 41.349453 -74.953417) (xy 41.301847 -74.982471) (xy 41.250518 -75.004283) (xy 41.196561 -75.018389)
			(xy 41.141124 -75.024489) (xy 41.08539 -75.022452) (xy 41.030547 -75.012322) (xy 40.977763 -74.994315)
			(xy 40.928163 -74.968814) (xy 40.882805 -74.936363) (xy 40.842656 -74.897654) (xy 40.80857 -74.853511)
			(xy 40.781274 -74.804876) (xy 40.761351 -74.752785) (xy 40.749225 -74.698348) (xy 40.745154 -74.642726)
			(xy 38.337753 -74.642726) (xy 38.3315 -74.652177) (xy 38.294283 -74.693714) (xy 38.251415 -74.729389)
			(xy 38.203809 -74.758443) (xy 38.15248 -74.780255) (xy 38.098523 -74.794361) (xy 38.043086 -74.800461)
			(xy 37.987352 -74.798424) (xy 37.932509 -74.788294) (xy 37.879725 -74.770287) (xy 37.830125 -74.744786)
			(xy 37.784767 -74.712335) (xy 37.744618 -74.673626) (xy 37.710532 -74.629483) (xy 37.683236 -74.580848)
			(xy 37.663313 -74.528757) (xy 37.651187 -74.47432) (xy 37.647116 -74.418698) (xy 35.862788 -74.418698)
			(xy 35.864388 -74.420738) (xy 35.891943 -74.468889) (xy 35.912235 -74.520522) (xy 35.924837 -74.57455)
			(xy 35.929482 -74.629833) (xy 35.926072 -74.685205) (xy 35.914681 -74.739501) (xy 35.895547 -74.791574)
			(xy 35.869074 -74.840329) (xy 35.835821 -74.884735) (xy 35.796487 -74.923859) (xy 35.751903 -74.956874)
			(xy 35.703008 -74.983085) (xy 35.650832 -75.00194) (xy 35.623754 -75.007978) (xy 35.6024 -75.012763)
			(xy 35.561661 -75.028736) (xy 35.524263 -75.051458) (xy 35.491315 -75.080254) (xy 35.463792 -75.114274)
			(xy 35.442509 -75.152509) (xy 35.428098 -75.193827) (xy 35.420984 -75.237003) (xy 35.421378 -75.28076)
			(xy 35.424872 -75.302364) (xy 35.429383 -75.329988) (xy 35.431254 -75.385927) (xy 35.424935 -75.441539)
			(xy 35.41056 -75.495632) (xy 35.388438 -75.547045) (xy 35.359044 -75.594676) (xy 35.323008 -75.637502)
			(xy 35.281103 -75.674605) (xy 35.234228 -75.705189) (xy 35.183388 -75.728599) (xy 35.129675 -75.744331)
			(xy 35.074239 -75.752049) (xy 35.018271 -75.751588) (xy 34.96297 -75.742956) (xy 34.909523 -75.726339)
			(xy 34.859077 -75.702093) (xy 34.812713 -75.67074) (xy 34.771426 -75.63295) (xy 34.736102 -75.589535)
			(xy 34.707498 -75.541426) (xy 34.686228 -75.489655) (xy 34.672748 -75.435332) (xy 34.667347 -75.379623)
			(xy 34.670141 -75.323722) (xy 34.68107 -75.26883) (xy 34.6999 -75.216122) (xy 34.726227 -75.16673)
			(xy 34.759486 -75.121713) (xy 34.798964 -75.082037) (xy 34.843814 -75.048553) (xy 34.893073 -75.021979)
			(xy 34.945686 -75.002885) (xy 34.973006 -74.996802) (xy 34.994331 -74.991901) (xy 35.035064 -74.975941)
			(xy 35.072457 -74.953234) (xy 35.105404 -74.924453) (xy 35.132928 -74.890448) (xy 35.154215 -74.852229)
			(xy 35.168634 -74.810925) (xy 35.175758 -74.767761) (xy 35.175376 -74.724015) (xy 35.171888 -74.702416)
			(xy 35.166809 -74.670829) (xy 35.166044 -74.606862) (xy 35.170364 -74.575162) (xy 35.173357 -74.553536)
			(xy 35.172618 -74.509884) (xy 35.164429 -74.467002) (xy 35.149029 -74.42615) (xy 35.126874 -74.388532)
			(xy 35.098614 -74.355255) (xy 35.065082 -74.327298) (xy 35.027264 -74.305484) (xy 34.986275 -74.290456)
			(xy 34.964878 -74.28611) (xy 34.937441 -74.280682) (xy 34.884453 -74.262783) (xy 34.834645 -74.237341)
			(xy 34.789085 -74.2049) (xy 34.748749 -74.166156) (xy 34.714501 -74.121938) (xy 34.687075 -74.073194)
			(xy 34.667058 -74.020969) (xy 34.65488 -73.966381) (xy 34.650801 -73.910601) (xy 31.80842 -73.910601)
			(xy 31.80842 -77.608738) (xy 34.195587 -77.608738) (xy 34.203115 -77.553484) (xy 34.218607 -77.499914)
			(xy 34.241733 -77.44917) (xy 34.272 -77.402334) (xy 34.308762 -77.360402) (xy 34.351237 -77.324269)
			(xy 34.39852 -77.294705) (xy 34.423858 -77.283056) (xy 34.444951 -77.273359) (xy 34.483405 -77.247356)
			(xy 34.516497 -77.2148) (xy 34.543125 -77.176775) (xy 34.562404 -77.134546) (xy 34.573692 -77.089518)
			(xy 34.576614 -77.043188) (xy 34.571073 -76.997099) (xy 34.557252 -76.952783) (xy 34.535612 -76.911714)
			(xy 34.521648 -76.893166) (xy 34.504789 -76.870953) (xy 34.477007 -76.822602) (xy 34.456561 -76.770721)
			(xy 34.443885 -76.716417) (xy 34.43925 -76.660846) (xy 34.442754 -76.605192) (xy 34.454322 -76.550641)
			(xy 34.473709 -76.498356) (xy 34.500501 -76.44945) (xy 34.534127 -76.404965) (xy 34.573871 -76.365849)
			(xy 34.618886 -76.332936) (xy 34.668213 -76.306926) (xy 34.720801 -76.288375) (xy 34.775529 -76.277677)
			(xy 34.831231 -76.27506) (xy 34.886722 -76.28058) (xy 34.940817 -76.29412) (xy 34.992365 -76.31539)
			(xy 35.040267 -76.343938) (xy 35.083503 -76.379155) (xy 35.121152 -76.420292) (xy 35.152411 -76.466471)
			(xy 35.176614 -76.516709) (xy 35.193246 -76.569935) (xy 35.201952 -76.625015) (xy 35.202547 -76.680776)
			(xy 35.195018 -76.736029) (xy 35.179525 -76.789598) (xy 35.1564 -76.840341) (xy 35.126133 -76.887176)
			(xy 35.089371 -76.929106) (xy 35.046896 -76.965238) (xy 34.999613 -76.994802) (xy 34.974276 -77.00645)
			(xy 34.95325 -77.016282) (xy 34.9148 -77.042268) (xy 34.88171 -77.074806) (xy 34.872121 -77.088492)
			(xy 37.469062 -77.088492) (xy 37.473133 -77.03287) (xy 37.485259 -76.978433) (xy 37.505182 -76.926342)
			(xy 37.532478 -76.877707) (xy 37.566564 -76.833564) (xy 37.606713 -76.794855) (xy 37.652071 -76.762404)
			(xy 37.701671 -76.736903) (xy 37.754455 -76.718896) (xy 37.809298 -76.708766) (xy 37.865032 -76.706729)
			(xy 37.920469 -76.712829) (xy 37.974426 -76.726935) (xy 38.025755 -76.748747) (xy 38.073361 -76.777801)
			(xy 38.116229 -76.813476) (xy 38.153446 -76.855013) (xy 38.184219 -76.901526) (xy 38.207891 -76.952023)
			(xy 38.223959 -77.00543) (xy 38.232079 -77.060606) (xy 38.232588 -77.088492) (xy 38.232079 -77.116378)
			(xy 38.223959 -77.171554) (xy 38.207891 -77.224961) (xy 38.184219 -77.275458) (xy 38.153446 -77.321971)
			(xy 38.116229 -77.363508) (xy 38.073361 -77.399183) (xy 38.025755 -77.428237) (xy 37.974426 -77.450049)
			(xy 37.920469 -77.464155) (xy 37.865032 -77.470255) (xy 37.809298 -77.468218) (xy 37.754455 -77.458088)
			(xy 37.701671 -77.440081) (xy 37.652071 -77.41458) (xy 37.606713 -77.382129) (xy 37.566564 -77.34342)
			(xy 37.532478 -77.299277) (xy 37.505182 -77.250642) (xy 37.485259 -77.198551) (xy 37.473133 -77.144114)
			(xy 37.469062 -77.088492) (xy 34.872121 -77.088492) (xy 34.85508 -77.112812) (xy 34.835796 -77.155024)
			(xy 34.824501 -77.200036) (xy 34.821569 -77.246351) (xy 34.827098 -77.292428) (xy 34.840905 -77.336734)
			(xy 34.86253 -77.377795) (xy 34.876486 -77.39634) (xy 34.893353 -77.418548) (xy 34.921135 -77.4669)
			(xy 34.941583 -77.518781) (xy 34.95426 -77.573086) (xy 34.958896 -77.628657) (xy 34.955393 -77.684312)
			(xy 34.943825 -77.738864) (xy 34.924439 -77.791151) (xy 34.897647 -77.840059) (xy 34.864021 -77.884545)
			(xy 34.824277 -77.923662) (xy 34.779262 -77.956576) (xy 34.729935 -77.982587) (xy 34.677346 -78.001139)
			(xy 34.622617 -78.011838) (xy 34.566914 -78.014456) (xy 34.511423 -78.008937) (xy 34.457326 -77.995398)
			(xy 34.405777 -77.974128) (xy 34.357873 -77.94558) (xy 34.314636 -77.910362) (xy 34.276986 -77.869226)
			(xy 34.245726 -77.823046) (xy 34.221522 -77.772808) (xy 34.204889 -77.719581) (xy 34.196182 -77.6645)
			(xy 34.195587 -77.608738) (xy 31.80842 -77.608738) (xy 31.80842 -79.079344) (xy 36.630862 -79.079344)
			(xy 36.634933 -79.023722) (xy 36.647059 -78.969285) (xy 36.666982 -78.917194) (xy 36.694278 -78.868559)
			(xy 36.728364 -78.824416) (xy 36.768513 -78.785707) (xy 36.813871 -78.753256) (xy 36.863471 -78.727755)
			(xy 36.916255 -78.709748) (xy 36.971098 -78.699618) (xy 37.026832 -78.697581) (xy 37.082269 -78.703681)
			(xy 37.136226 -78.717787) (xy 37.187555 -78.739599) (xy 37.235161 -78.768653) (xy 37.278029 -78.804328)
			(xy 37.315246 -78.845865) (xy 37.346019 -78.892378) (xy 37.369691 -78.942875) (xy 37.385759 -78.996282)
			(xy 37.393879 -79.051458) (xy 37.394388 -79.079344) (xy 37.393879 -79.10723) (xy 37.385759 -79.162406)
			(xy 37.369691 -79.215813) (xy 37.346019 -79.26631) (xy 37.315246 -79.312823) (xy 37.278029 -79.35436)
			(xy 37.235161 -79.390035) (xy 37.187555 -79.419089) (xy 37.136226 -79.440901) (xy 37.082269 -79.455007)
			(xy 37.026832 -79.461107) (xy 36.971098 -79.45907) (xy 36.916255 -79.44894) (xy 36.863471 -79.430933)
			(xy 36.813871 -79.405432) (xy 36.768513 -79.372981) (xy 36.728364 -79.334272) (xy 36.694278 -79.290129)
			(xy 36.666982 -79.241494) (xy 36.647059 -79.189403) (xy 36.634933 -79.134966) (xy 36.630862 -79.079344)
			(xy 31.80842 -79.079344) (xy 31.80842 -79.893922) (xy 34.093402 -79.893922) (xy 34.097473 -79.8383)
			(xy 34.109599 -79.783863) (xy 34.129522 -79.731772) (xy 34.156818 -79.683137) (xy 34.190904 -79.638994)
			(xy 34.231053 -79.600285) (xy 34.276411 -79.567834) (xy 34.326011 -79.542333) (xy 34.378795 -79.524326)
			(xy 34.433638 -79.514196) (xy 34.489372 -79.512159) (xy 34.544809 -79.518259) (xy 34.598766 -79.532365)
			(xy 34.650095 -79.554177) (xy 34.697701 -79.583231) (xy 34.740569 -79.618906) (xy 34.777786 -79.660443)
			(xy 34.808559 -79.706956) (xy 34.832231 -79.757453) (xy 34.848299 -79.81086) (xy 34.856419 -79.866036)
			(xy 34.856928 -79.893922) (xy 34.856419 -79.921808) (xy 34.848299 -79.976984) (xy 34.832231 -80.030391)
			(xy 34.808559 -80.080888) (xy 34.777786 -80.127401) (xy 34.740569 -80.168938) (xy 34.697701 -80.204613)
			(xy 34.650095 -80.233667) (xy 34.598766 -80.255479) (xy 34.544809 -80.269585) (xy 34.489372 -80.275685)
			(xy 34.433638 -80.273648) (xy 34.378795 -80.263518) (xy 34.326011 -80.245511) (xy 34.276411 -80.22001)
			(xy 34.231053 -80.187559) (xy 34.190904 -80.14885) (xy 34.156818 -80.104707) (xy 34.129522 -80.056072)
			(xy 34.109599 -80.003981) (xy 34.097473 -79.949544) (xy 34.093402 -79.893922) (xy 31.80842 -79.893922)
			(xy 31.80842 -80.476344) (xy 36.595302 -80.476344) (xy 36.599373 -80.420722) (xy 36.611499 -80.366285)
			(xy 36.631422 -80.314194) (xy 36.658718 -80.265559) (xy 36.692804 -80.221416) (xy 36.732953 -80.182707)
			(xy 36.778311 -80.150256) (xy 36.827911 -80.124755) (xy 36.880695 -80.106748) (xy 36.935538 -80.096618)
			(xy 36.991272 -80.094581) (xy 37.046709 -80.100681) (xy 37.100666 -80.114787) (xy 37.151995 -80.136599)
			(xy 37.199601 -80.165653) (xy 37.242469 -80.201328) (xy 37.279686 -80.242865) (xy 37.310459 -80.289378)
			(xy 37.334131 -80.339875) (xy 37.350199 -80.393282) (xy 37.358319 -80.448458) (xy 37.358828 -80.476344)
			(xy 37.358319 -80.50423) (xy 37.350199 -80.559406) (xy 37.334131 -80.612813) (xy 37.310459 -80.66331)
			(xy 37.279686 -80.709823) (xy 37.242469 -80.75136) (xy 37.199601 -80.787035) (xy 37.168467 -80.806036)
			(xy 37.951154 -80.806036) (xy 37.955225 -80.750414) (xy 37.967351 -80.695977) (xy 37.987274 -80.643886)
			(xy 38.01457 -80.595251) (xy 38.048656 -80.551108) (xy 38.088805 -80.512399) (xy 38.134163 -80.479948)
			(xy 38.183763 -80.454447) (xy 38.236547 -80.43644) (xy 38.29139 -80.42631) (xy 38.347124 -80.424273)
			(xy 38.402561 -80.430373) (xy 38.456518 -80.444479) (xy 38.507847 -80.466291) (xy 38.555453 -80.495345)
			(xy 38.598321 -80.53102) (xy 38.6192 -80.554322) (xy 40.642284 -80.554322) (xy 40.646355 -80.4987)
			(xy 40.658481 -80.444263) (xy 40.678404 -80.392172) (xy 40.7057 -80.343537) (xy 40.739786 -80.299394)
			(xy 40.779935 -80.260685) (xy 40.825293 -80.228234) (xy 40.874893 -80.202733) (xy 40.927677 -80.184726)
			(xy 40.98252 -80.174596) (xy 41.038254 -80.172559) (xy 41.093691 -80.178659) (xy 41.147648 -80.192765)
			(xy 41.198977 -80.214577) (xy 41.246583 -80.243631) (xy 41.289451 -80.279306) (xy 41.326668 -80.320843)
			(xy 41.357441 -80.367356) (xy 41.381113 -80.417853) (xy 41.397181 -80.47126) (xy 41.405301 -80.526436)
			(xy 41.40581 -80.554322) (xy 41.405301 -80.582208) (xy 41.397181 -80.637384) (xy 41.381113 -80.690791)
			(xy 41.357441 -80.741288) (xy 41.326668 -80.787801) (xy 41.289451 -80.829338) (xy 41.246583 -80.865013)
			(xy 41.198977 -80.894067) (xy 41.147648 -80.915879) (xy 41.093691 -80.929985) (xy 41.038254 -80.936085)
			(xy 40.98252 -80.934048) (xy 40.927677 -80.923918) (xy 40.874893 -80.905911) (xy 40.825293 -80.88041)
			(xy 40.779935 -80.847959) (xy 40.739786 -80.80925) (xy 40.7057 -80.765107) (xy 40.678404 -80.716472)
			(xy 40.658481 -80.664381) (xy 40.646355 -80.609944) (xy 40.642284 -80.554322) (xy 38.6192 -80.554322)
			(xy 38.635538 -80.572557) (xy 38.666311 -80.61907) (xy 38.689983 -80.669567) (xy 38.706051 -80.722974)
			(xy 38.714171 -80.77815) (xy 38.71468 -80.806036) (xy 38.714171 -80.833922) (xy 38.706051 -80.889098)
			(xy 38.689983 -80.942505) (xy 38.666311 -80.993002) (xy 38.635538 -81.039515) (xy 38.598321 -81.081052)
			(xy 38.555453 -81.116727) (xy 38.507847 -81.145781) (xy 38.456518 -81.167593) (xy 38.402561 -81.181699)
			(xy 38.347124 -81.187799) (xy 38.29139 -81.185762) (xy 38.236547 -81.175632) (xy 38.183763 -81.157625)
			(xy 38.134163 -81.132124) (xy 38.088805 -81.099673) (xy 38.048656 -81.060964) (xy 38.01457 -81.016821)
			(xy 37.987274 -80.968186) (xy 37.967351 -80.916095) (xy 37.955225 -80.861658) (xy 37.951154 -80.806036)
			(xy 37.168467 -80.806036) (xy 37.151995 -80.816089) (xy 37.100666 -80.837901) (xy 37.046709 -80.852007)
			(xy 36.991272 -80.858107) (xy 36.935538 -80.85607) (xy 36.880695 -80.84594) (xy 36.827911 -80.827933)
			(xy 36.778311 -80.802432) (xy 36.732953 -80.769981) (xy 36.692804 -80.731272) (xy 36.658718 -80.687129)
			(xy 36.631422 -80.638494) (xy 36.611499 -80.586403) (xy 36.599373 -80.531966) (xy 36.595302 -80.476344)
			(xy 31.80842 -80.476344) (xy 31.80842 -81.036922) (xy 33.849054 -81.036922) (xy 33.853125 -80.9813)
			(xy 33.865251 -80.926863) (xy 33.885174 -80.874772) (xy 33.91247 -80.826137) (xy 33.946556 -80.781994)
			(xy 33.986705 -80.743285) (xy 34.032063 -80.710834) (xy 34.081663 -80.685333) (xy 34.134447 -80.667326)
			(xy 34.18929 -80.657196) (xy 34.245024 -80.655159) (xy 34.300461 -80.661259) (xy 34.354418 -80.675365)
			(xy 34.405747 -80.697177) (xy 34.453353 -80.726231) (xy 34.496221 -80.761906) (xy 34.533438 -80.803443)
			(xy 34.564211 -80.849956) (xy 34.587883 -80.900453) (xy 34.603951 -80.95386) (xy 34.612071 -81.009036)
			(xy 34.61258 -81.036922) (xy 34.612071 -81.064808) (xy 34.603951 -81.119984) (xy 34.587883 -81.173391)
			(xy 34.564211 -81.223888) (xy 34.533438 -81.270401) (xy 34.496221 -81.311938) (xy 34.453353 -81.347613)
			(xy 34.405747 -81.376667) (xy 34.354418 -81.398479) (xy 34.300461 -81.412585) (xy 34.245024 -81.418685)
			(xy 34.18929 -81.416648) (xy 34.134447 -81.406518) (xy 34.081663 -81.388511) (xy 34.032063 -81.36301)
			(xy 33.986705 -81.330559) (xy 33.946556 -81.29185) (xy 33.91247 -81.247707) (xy 33.885174 -81.199072)
			(xy 33.865251 -81.146981) (xy 33.853125 -81.092544) (xy 33.849054 -81.036922) (xy 31.80842 -81.036922)
			(xy 31.80842 -81.346548) (xy 32.641794 -82.179922) (xy 33.964878 -82.179922) (xy 33.968949 -82.1243)
			(xy 33.981075 -82.069863) (xy 34.000998 -82.017772) (xy 34.028294 -81.969137) (xy 34.06238 -81.924994)
			(xy 34.102529 -81.886285) (xy 34.147887 -81.853834) (xy 34.197487 -81.828333) (xy 34.250271 -81.810326)
			(xy 34.305114 -81.800196) (xy 34.360848 -81.798159) (xy 34.416285 -81.804259) (xy 34.470242 -81.818365)
			(xy 34.521571 -81.840177) (xy 34.569177 -81.869231) (xy 34.612045 -81.904906) (xy 34.649262 -81.946443)
			(xy 34.680035 -81.992956) (xy 34.703707 -82.043453) (xy 34.719775 -82.09686) (xy 34.727895 -82.152036)
			(xy 34.728404 -82.179922) (xy 36.727382 -82.179922) (xy 36.731453 -82.1243) (xy 36.743579 -82.069863)
			(xy 36.763502 -82.017772) (xy 36.790798 -81.969137) (xy 36.824884 -81.924994) (xy 36.865033 -81.886285)
			(xy 36.910391 -81.853834) (xy 36.959991 -81.828333) (xy 37.012775 -81.810326) (xy 37.067618 -81.800196)
			(xy 37.123352 -81.798159) (xy 37.178789 -81.804259) (xy 37.232746 -81.818365) (xy 37.284075 -81.840177)
			(xy 37.331681 -81.869231) (xy 37.374549 -81.904906) (xy 37.411766 -81.946443) (xy 37.442539 -81.992956)
			(xy 37.466211 -82.043453) (xy 37.482279 -82.09686) (xy 37.490399 -82.152036) (xy 37.490908 -82.179922)
			(xy 37.490399 -82.207808) (xy 37.482279 -82.262984) (xy 37.466211 -82.316391) (xy 37.442539 -82.366888)
			(xy 37.411766 -82.413401) (xy 37.374549 -82.454938) (xy 37.331681 -82.490613) (xy 37.284075 -82.519667)
			(xy 37.232746 -82.541479) (xy 37.178789 -82.555585) (xy 37.123352 -82.561685) (xy 37.067618 -82.559648)
			(xy 37.012775 -82.549518) (xy 36.959991 -82.531511) (xy 36.910391 -82.50601) (xy 36.865033 -82.473559)
			(xy 36.824884 -82.43485) (xy 36.790798 -82.390707) (xy 36.763502 -82.342072) (xy 36.743579 -82.289981)
			(xy 36.731453 -82.235544) (xy 36.727382 -82.179922) (xy 34.728404 -82.179922) (xy 34.727895 -82.207808)
			(xy 34.719775 -82.262984) (xy 34.703707 -82.316391) (xy 34.680035 -82.366888) (xy 34.649262 -82.413401)
			(xy 34.612045 -82.454938) (xy 34.569177 -82.490613) (xy 34.521571 -82.519667) (xy 34.470242 -82.541479)
			(xy 34.416285 -82.555585) (xy 34.360848 -82.561685) (xy 34.305114 -82.559648) (xy 34.250271 -82.549518)
			(xy 34.197487 -82.531511) (xy 34.147887 -82.50601) (xy 34.102529 -82.473559) (xy 34.06238 -82.43485)
			(xy 34.028294 -82.390707) (xy 34.000998 -82.342072) (xy 33.981075 -82.289981) (xy 33.968949 -82.235544)
			(xy 33.964878 -82.179922) (xy 32.641794 -82.179922) (xy 33.26384 -82.801968) (xy 33.26384 -83.326519)
			(xy 40.147525 -83.326519) (xy 40.149904 -83.271295) (xy 40.160229 -83.216992) (xy 40.178284 -83.164748)
			(xy 40.203692 -83.115657) (xy 40.235919 -83.070748) (xy 40.274291 -83.030961) (xy 40.318005 -82.99713)
			(xy 40.366144 -82.969963) (xy 40.4177 -82.950028) (xy 40.471594 -82.937745) (xy 40.526696 -82.933369)
			(xy 40.581853 -82.936993) (xy 40.635909 -82.948541) (xy 40.687732 -82.96777) (xy 40.736237 -82.994278)
			(xy 40.758618 -83.010502) (xy 40.77267 -83.020342) (xy 40.804583 -83.032892) (xy 40.838683 -83.03651)
			(xy 40.872519 -83.030935) (xy 40.903655 -83.016567) (xy 40.917114 -83.00593) (xy 40.932611 -82.993122)
			(xy 40.965824 -82.970465) (xy 40.983408 -82.960718) (xy 40.996767 -82.953034) (xy 41.019599 -82.932343)
			(xy 41.036807 -82.906785) (xy 41.047389 -82.877847) (xy 41.050729 -82.847217) (xy 41.046631 -82.816679)
			(xy 41.035334 -82.788013) (xy 41.017497 -82.762889) (xy 40.99416 -82.742771) (xy 40.980614 -82.73542)
			(xy 40.956403 -82.722632) (xy 40.911544 -82.691241) (xy 40.871634 -82.653758) (xy 40.837494 -82.610954)
			(xy 40.809824 -82.563709) (xy 40.789193 -82.512993) (xy 40.776026 -82.459848) (xy 40.770592 -82.405367)
			(xy 40.773004 -82.350668) (xy 40.783212 -82.296877) (xy 40.801006 -82.245097) (xy 40.82602 -82.196394)
			(xy 40.857741 -82.151767) (xy 40.895517 -82.112134) (xy 40.938571 -82.07831) (xy 40.986019 -82.050989)
			(xy 41.036886 -82.030732) (xy 41.090126 -82.017957) (xy 41.144646 -82.012925) (xy 41.199325 -82.01574)
			(xy 41.25304 -82.026343) (xy 41.304687 -82.044518) (xy 41.353205 -82.069891) (xy 41.397597 -82.101939)
			(xy 41.43695 -82.140006) (xy 41.470456 -82.183308) (xy 41.497427 -82.230956) (xy 41.517309 -82.28197)
			(xy 41.529692 -82.335303) (xy 41.534322 -82.389859) (xy 41.531104 -82.444516) (xy 41.520105 -82.498151)
			(xy 41.501551 -82.549663) (xy 41.475821 -82.597993) (xy 41.443447 -82.642147) (xy 41.424606 -82.662014)
			(xy 41.409395 -82.67829) (xy 41.384234 -82.715046) (xy 41.365861 -82.755623) (xy 41.354837 -82.79878)
			(xy 41.3515 -82.843197) (xy 41.355951 -82.887517) (xy 41.368055 -82.930384) (xy 41.387441 -82.970487)
			(xy 41.413516 -83.006599) (xy 41.429178 -83.02244) (xy 41.448572 -83.04184) (xy 41.48214 -83.085224)
			(xy 41.509148 -83.132968) (xy 41.529039 -83.184089) (xy 41.541404 -83.237531) (xy 41.545988 -83.292194)
			(xy 41.542695 -83.346949) (xy 41.531594 -83.400668) (xy 41.512914 -83.452244) (xy 41.48704 -83.500612)
			(xy 41.454505 -83.544776) (xy 41.41598 -83.583825) (xy 41.37226 -83.616954) (xy 41.324246 -83.64348)
			(xy 41.272927 -83.662856) (xy 41.219363 -83.674681) (xy 41.164657 -83.678714) (xy 41.109938 -83.67487)
			(xy 41.056333 -83.663228) (xy 41.004948 -83.644029) (xy 40.956843 -83.617669) (xy 40.93464 -83.60156)
			(xy 40.920612 -83.591683) (xy 40.88869 -83.579143) (xy 40.854583 -83.575534) (xy 40.820743 -83.581118)
			(xy 40.789604 -83.595491) (xy 40.776144 -83.606132) (xy 40.754732 -83.623615) (xy 40.707868 -83.652926)
			(xy 40.657263 -83.675166) (xy 40.603978 -83.689868) (xy 40.549129 -83.696725) (xy 40.493865 -83.695592)
			(xy 40.439343 -83.686495) (xy 40.386705 -83.669623) (xy 40.337054 -83.645329) (xy 40.291429 -83.614123)
			(xy 40.250787 -83.576658) (xy 40.215978 -83.533719) (xy 40.187731 -83.486206) (xy 40.166639 -83.435112)
			(xy 40.153143 -83.381509) (xy 40.147525 -83.326519) (xy 33.26384 -83.326519) (xy 33.26384 -83.861656)
			(xy 38.030402 -83.861656) (xy 38.034473 -83.806034) (xy 38.046599 -83.751597) (xy 38.066522 -83.699506)
			(xy 38.093818 -83.650871) (xy 38.127904 -83.606728) (xy 38.168053 -83.568019) (xy 38.213411 -83.535568)
			(xy 38.263011 -83.510067) (xy 38.315795 -83.49206) (xy 38.370638 -83.48193) (xy 38.426372 -83.479893)
			(xy 38.481809 -83.485993) (xy 38.535766 -83.500099) (xy 38.587095 -83.521911) (xy 38.634701 -83.550965)
			(xy 38.677569 -83.58664) (xy 38.714786 -83.628177) (xy 38.745559 -83.67469) (xy 38.769231 -83.725187)
			(xy 38.785299 -83.778594) (xy 38.793419 -83.83377) (xy 38.793928 -83.861656) (xy 38.793419 -83.889542)
			(xy 38.785299 -83.944718) (xy 38.769231 -83.998125) (xy 38.745559 -84.048622) (xy 38.714786 -84.095135)
			(xy 38.677569 -84.136672) (xy 38.634701 -84.172347) (xy 38.587095 -84.201401) (xy 38.535766 -84.223213)
			(xy 38.481809 -84.237319) (xy 38.426372 -84.243419) (xy 38.370638 -84.241382) (xy 38.315795 -84.231252)
			(xy 38.263011 -84.213245) (xy 38.213411 -84.187744) (xy 38.168053 -84.155293) (xy 38.127904 -84.116584)
			(xy 38.093818 -84.072441) (xy 38.066522 -84.023806) (xy 38.046599 -83.971715) (xy 38.034473 -83.917278)
			(xy 38.030402 -83.861656) (xy 33.26384 -83.861656) (xy 33.26384 -84.377022) (xy 34.290506 -84.377022)
			(xy 34.294577 -84.3214) (xy 34.306703 -84.266963) (xy 34.326626 -84.214872) (xy 34.353922 -84.166237)
			(xy 34.388008 -84.122094) (xy 34.428157 -84.083385) (xy 34.473515 -84.050934) (xy 34.523115 -84.025433)
			(xy 34.575899 -84.007426) (xy 34.630742 -83.997296) (xy 34.686476 -83.995259) (xy 34.741913 -84.001359)
			(xy 34.79587 -84.015465) (xy 34.847199 -84.037277) (xy 34.894805 -84.066331) (xy 34.937673 -84.102006)
			(xy 34.97489 -84.143543) (xy 35.005663 -84.190056) (xy 35.029335 -84.240553) (xy 35.045403 -84.29396)
			(xy 35.053523 -84.349136) (xy 35.054032 -84.377022) (xy 35.053523 -84.404908) (xy 35.045403 -84.460084)
			(xy 35.029335 -84.513491) (xy 35.005663 -84.563988) (xy 34.97489 -84.610501) (xy 34.937673 -84.652038)
			(xy 34.894805 -84.687713) (xy 34.847199 -84.716767) (xy 34.79587 -84.738579) (xy 34.741913 -84.752685)
			(xy 34.686476 -84.758785) (xy 34.630742 -84.756748) (xy 34.575899 -84.746618) (xy 34.523115 -84.728611)
			(xy 34.473515 -84.70311) (xy 34.428157 -84.670659) (xy 34.388008 -84.63195) (xy 34.353922 -84.587807)
			(xy 34.326626 -84.539172) (xy 34.306703 -84.487081) (xy 34.294577 -84.432644) (xy 34.290506 -84.377022)
			(xy 33.26384 -84.377022) (xy 33.26384 -85.421724) (xy 37.847522 -85.421724) (xy 37.851593 -85.366102)
			(xy 37.863719 -85.311665) (xy 37.883642 -85.259574) (xy 37.910938 -85.210939) (xy 37.945024 -85.166796)
			(xy 37.985173 -85.128087) (xy 38.030531 -85.095636) (xy 38.080131 -85.070135) (xy 38.132915 -85.052128)
			(xy 38.187758 -85.041998) (xy 38.243492 -85.039961) (xy 38.298929 -85.046061) (xy 38.352886 -85.060167)
			(xy 38.404215 -85.081979) (xy 38.451821 -85.111033) (xy 38.494689 -85.146708) (xy 38.531906 -85.188245)
			(xy 38.562679 -85.234758) (xy 38.586351 -85.285255) (xy 38.602419 -85.338662) (xy 38.610539 -85.393838)
			(xy 38.611048 -85.421724) (xy 38.610539 -85.44961) (xy 38.602419 -85.504786) (xy 38.594637 -85.530652)
			(xy 39.356763 -85.530652) (xy 39.356893 -85.475168) (xy 39.365059 -85.420289) (xy 39.381089 -85.367171)
			(xy 39.404645 -85.316936) (xy 39.435231 -85.270644) (xy 39.4722 -85.229271) (xy 39.514772 -85.19369)
			(xy 39.56205 -85.164651) (xy 39.613036 -85.142768) (xy 39.666655 -85.128502) (xy 39.721774 -85.122155)
			(xy 39.777232 -85.123859) (xy 39.831857 -85.13358) (xy 39.884498 -85.151111) (xy 39.909496 -85.163152)
			(xy 39.929502 -85.172665) (xy 39.971924 -85.18541) (xy 40.015913 -85.190611) (xy 40.060137 -85.188109)
			(xy 40.103259 -85.177981) (xy 40.143973 -85.160534) (xy 40.181048 -85.136295) (xy 40.197532 -85.121496)
			(xy 40.218427 -85.102672) (xy 40.264682 -85.070685) (xy 40.31513 -85.045833) (xy 40.368681 -85.028656)
			(xy 40.424172 -85.019525) (xy 40.480402 -85.018637) (xy 40.536154 -85.026013) (xy 40.59022 -85.041492)
			(xy 40.641427 -85.064739) (xy 40.688668 -85.095251) (xy 40.730919 -85.132366) (xy 40.749474 -85.1535)
			(xy 40.75734 -85.16239) (xy 41.829988 -85.16239) (xy 41.834059 -85.106768) (xy 41.846185 -85.052331)
			(xy 41.866108 -85.00024) (xy 41.893404 -84.951605) (xy 41.92749 -84.907462) (xy 41.967639 -84.868753)
			(xy 42.012997 -84.836302) (xy 42.062597 -84.810801) (xy 42.115381 -84.792794) (xy 42.170224 -84.782664)
			(xy 42.225958 -84.780627) (xy 42.281395 -84.786727) (xy 42.335352 -84.800833) (xy 42.386681 -84.822645)
			(xy 42.434287 -84.851699) (xy 42.477155 -84.887374) (xy 42.514372 -84.928911) (xy 42.545145 -84.975424)
			(xy 42.568817 -85.025921) (xy 42.584885 -85.079328) (xy 42.593005 -85.134504) (xy 42.593514 -85.16239)
			(xy 42.593005 -85.190276) (xy 42.584885 -85.245452) (xy 42.568817 -85.298859) (xy 42.545145 -85.349356)
			(xy 42.514372 -85.395869) (xy 42.477155 -85.437406) (xy 42.434287 -85.473081) (xy 42.386681 -85.502135)
			(xy 42.335352 -85.523947) (xy 42.281395 -85.538053) (xy 42.225958 -85.544153) (xy 42.170224 -85.542116)
			(xy 42.115381 -85.531986) (xy 42.062597 -85.513979) (xy 42.012997 -85.488478) (xy 41.967639 -85.456027)
			(xy 41.92749 -85.417318) (xy 41.893404 -85.373175) (xy 41.866108 -85.32454) (xy 41.846185 -85.272449)
			(xy 41.834059 -85.218012) (xy 41.829988 -85.16239) (xy 40.75734 -85.16239) (xy 40.764234 -85.170182)
			(xy 40.798507 -85.198626) (xy 40.837212 -85.220661) (xy 40.879167 -85.235612) (xy 40.923085 -85.24302)
			(xy 40.967622 -85.24266) (xy 41.011414 -85.234541) (xy 41.03243 -85.22716) (xy 41.058614 -85.217878)
			(xy 41.11292 -85.206176) (xy 41.16835 -85.202477) (xy 41.22373 -85.206858) (xy 41.277888 -85.219227)
			(xy 41.329679 -85.239321) (xy 41.378008 -85.266716) (xy 41.421851 -85.300832) (xy 41.460281 -85.340947)
			(xy 41.492485 -85.386213) (xy 41.517782 -85.435672) (xy 41.535636 -85.488278) (xy 41.54567 -85.542917)
			(xy 41.547672 -85.598434) (xy 41.541599 -85.653653) (xy 41.527579 -85.707408) (xy 41.50591 -85.75856)
			(xy 41.477049 -85.806028) (xy 41.441608 -85.848807) (xy 41.400335 -85.885992) (xy 41.354105 -85.916796)
			(xy 41.303896 -85.940568) (xy 41.250768 -85.956804) (xy 41.195848 -85.965162) (xy 41.140296 -85.965464)
			(xy 41.085288 -85.957704) (xy 41.031987 -85.942047) (xy 40.981522 -85.918822) (xy 40.934959 -85.888523)
			(xy 40.893285 -85.851789) (xy 40.87495 -85.830918) (xy 40.860168 -85.814256) (xy 40.825901 -85.785809)
			(xy 40.787199 -85.763772) (xy 40.745249 -85.748818) (xy 40.701334 -85.741406) (xy 40.656799 -85.741764)
			(xy 40.613009 -85.749879) (xy 40.591994 -85.757258) (xy 40.567262 -85.765996) (xy 40.516072 -85.777431)
			(xy 40.463798 -85.781753) (xy 40.411424 -85.778881) (xy 40.359937 -85.768869) (xy 40.310304 -85.751905)
			(xy 40.286686 -85.740494) (xy 40.266691 -85.730955) (xy 40.224266 -85.718209) (xy 40.180273 -85.71301)
			(xy 40.136046 -85.715515) (xy 40.092922 -85.725647) (xy 40.052207 -85.743101) (xy 40.015133 -85.767347)
			(xy 39.99865 -85.78215) (xy 39.978066 -85.800755) (xy 39.932512 -85.832429) (xy 39.882849 -85.85717)
			(xy 39.830127 -85.874456) (xy 39.775457 -85.883921) (xy 39.719992 -85.885366) (xy 39.664902 -85.878761)
			(xy 39.611351 -85.864245) (xy 39.560468 -85.842124) (xy 39.513326 -85.812865) (xy 39.47092 -85.777086)
			(xy 39.434145 -85.73554) (xy 39.403776 -85.689105) (xy 39.380455 -85.638761) (xy 39.364673 -85.585569)
			(xy 39.356763 -85.530652) (xy 38.594637 -85.530652) (xy 38.586351 -85.558193) (xy 38.562679 -85.60869)
			(xy 38.531906 -85.655203) (xy 38.494689 -85.69674) (xy 38.451821 -85.732415) (xy 38.404215 -85.761469)
			(xy 38.352886 -85.783281) (xy 38.298929 -85.797387) (xy 38.243492 -85.803487) (xy 38.187758 -85.80145)
			(xy 38.132915 -85.79132) (xy 38.080131 -85.773313) (xy 38.030531 -85.747812) (xy 37.985173 -85.715361)
			(xy 37.945024 -85.676652) (xy 37.910938 -85.632509) (xy 37.883642 -85.583874) (xy 37.863719 -85.531783)
			(xy 37.851593 -85.477346) (xy 37.847522 -85.421724) (xy 33.26384 -85.421724) (xy 33.26384 -86.691724)
			(xy 42.133264 -86.691724) (xy 42.137335 -86.636102) (xy 42.149461 -86.581665) (xy 42.169384 -86.529574)
			(xy 42.19668 -86.480939) (xy 42.230766 -86.436796) (xy 42.270915 -86.398087) (xy 42.316273 -86.365636)
			(xy 42.365873 -86.340135) (xy 42.418657 -86.322128) (xy 42.4735 -86.311998) (xy 42.529234 -86.309961)
			(xy 42.584671 -86.316061) (xy 42.638628 -86.330167) (xy 42.689957 -86.351979) (xy 42.737563 -86.381033)
			(xy 42.780431 -86.416708) (xy 42.817648 -86.458245) (xy 42.848421 -86.504758) (xy 42.872093 -86.555255)
			(xy 42.888161 -86.608662) (xy 42.896281 -86.663838) (xy 42.89679 -86.691724) (xy 42.896281 -86.71961)
			(xy 42.888161 -86.774786) (xy 42.872093 -86.828193) (xy 42.848421 -86.87869) (xy 42.817648 -86.925203)
			(xy 42.780431 -86.96674) (xy 42.737563 -87.002415) (xy 42.689957 -87.031469) (xy 42.638628 -87.053281)
			(xy 42.584671 -87.067387) (xy 42.529234 -87.073487) (xy 42.4735 -87.07145) (xy 42.418657 -87.06132)
			(xy 42.365873 -87.043313) (xy 42.316273 -87.017812) (xy 42.270915 -86.985361) (xy 42.230766 -86.946652)
			(xy 42.19668 -86.902509) (xy 42.169384 -86.853874) (xy 42.149461 -86.801783) (xy 42.137335 -86.747346)
			(xy 42.133264 -86.691724) (xy 33.26384 -86.691724) (xy 33.26384 -88.439498) (xy 41.380154 -88.439498)
			(xy 41.384225 -88.383876) (xy 41.396351 -88.329439) (xy 41.416274 -88.277348) (xy 41.44357 -88.228713)
			(xy 41.477656 -88.18457) (xy 41.517805 -88.145861) (xy 41.563163 -88.11341) (xy 41.612763 -88.087909)
			(xy 41.665547 -88.069902) (xy 41.72039 -88.059772) (xy 41.776124 -88.057735) (xy 41.831561 -88.063835)
			(xy 41.885518 -88.077941) (xy 41.936847 -88.099753) (xy 41.984453 -88.128807) (xy 42.027321 -88.164482)
			(xy 42.064538 -88.206019) (xy 42.095311 -88.252532) (xy 42.118983 -88.303029) (xy 42.135051 -88.356436)
			(xy 42.143171 -88.411612) (xy 42.14368 -88.439498) (xy 42.143171 -88.467384) (xy 42.135051 -88.52256)
			(xy 42.118983 -88.575967) (xy 42.095311 -88.626464) (xy 42.064538 -88.672977) (xy 42.027321 -88.714514)
			(xy 41.984453 -88.750189) (xy 41.936847 -88.779243) (xy 41.885518 -88.801055) (xy 41.831561 -88.815161)
			(xy 41.776124 -88.821261) (xy 41.72039 -88.819224) (xy 41.665547 -88.809094) (xy 41.612763 -88.791087)
			(xy 41.563163 -88.765586) (xy 41.517805 -88.733135) (xy 41.477656 -88.694426) (xy 41.44357 -88.650283)
			(xy 41.416274 -88.601648) (xy 41.396351 -88.549557) (xy 41.384225 -88.49512) (xy 41.380154 -88.439498)
			(xy 33.26384 -88.439498) (xy 33.26384 -89.063068) (xy 42.317922 -89.063068) (xy 42.321993 -89.007446)
			(xy 42.334119 -88.953009) (xy 42.354042 -88.900918) (xy 42.381338 -88.852283) (xy 42.415424 -88.80814)
			(xy 42.455573 -88.769431) (xy 42.500931 -88.73698) (xy 42.550531 -88.711479) (xy 42.603315 -88.693472)
			(xy 42.658158 -88.683342) (xy 42.713892 -88.681305) (xy 42.769329 -88.687405) (xy 42.823286 -88.701511)
			(xy 42.874615 -88.723323) (xy 42.922221 -88.752377) (xy 42.965089 -88.788052) (xy 43.002306 -88.829589)
			(xy 43.033079 -88.876102) (xy 43.056751 -88.926599) (xy 43.072819 -88.980006) (xy 43.080939 -89.035182)
			(xy 43.081448 -89.063068) (xy 43.080939 -89.090954) (xy 43.072819 -89.14613) (xy 43.056751 -89.199537)
			(xy 43.033079 -89.250034) (xy 43.002306 -89.296547) (xy 42.965089 -89.338084) (xy 42.922221 -89.373759)
			(xy 42.874615 -89.402813) (xy 42.823286 -89.424625) (xy 42.769329 -89.438731) (xy 42.713892 -89.444831)
			(xy 42.658158 -89.442794) (xy 42.603315 -89.432664) (xy 42.550531 -89.414657) (xy 42.500931 -89.389156)
			(xy 42.455573 -89.356705) (xy 42.415424 -89.317996) (xy 42.381338 -89.273853) (xy 42.354042 -89.225218)
			(xy 42.334119 -89.173127) (xy 42.321993 -89.11869) (xy 42.317922 -89.063068) (xy 33.26384 -89.063068)
			(xy 33.26384 -95.51035) (xy 36.208714 -95.51035) (xy 36.212785 -95.454728) (xy 36.224911 -95.400291)
			(xy 36.244834 -95.3482) (xy 36.27213 -95.299565) (xy 36.306216 -95.255422) (xy 36.346365 -95.216713)
			(xy 36.391723 -95.184262) (xy 36.441323 -95.158761) (xy 36.494107 -95.140754) (xy 36.54895 -95.130624)
			(xy 36.604684 -95.128587) (xy 36.660121 -95.134687) (xy 36.714078 -95.148793) (xy 36.765407 -95.170605)
			(xy 36.813013 -95.199659) (xy 36.855881 -95.235334) (xy 36.893098 -95.276871) (xy 36.923871 -95.323384)
			(xy 36.947543 -95.373881) (xy 36.963611 -95.427288) (xy 36.971731 -95.482464) (xy 36.97224 -95.51035)
			(xy 36.971731 -95.538236) (xy 36.963611 -95.593412) (xy 36.947543 -95.646819) (xy 36.923871 -95.697316)
			(xy 36.893098 -95.743829) (xy 36.855881 -95.785366) (xy 36.813013 -95.821041) (xy 36.765407 -95.850095)
			(xy 36.714078 -95.871907) (xy 36.660121 -95.886013) (xy 36.604684 -95.892113) (xy 36.54895 -95.890076)
			(xy 36.494107 -95.879946) (xy 36.441323 -95.861939) (xy 36.391723 -95.836438) (xy 36.346365 -95.803987)
			(xy 36.306216 -95.765278) (xy 36.27213 -95.721135) (xy 36.244834 -95.6725) (xy 36.224911 -95.620409)
			(xy 36.212785 -95.565972) (xy 36.208714 -95.51035) (xy 33.26384 -95.51035) (xy 33.26384 -97.234929)
			(xy 37.851077 -97.234929) (xy 37.854857 -97.179659) (xy 37.866589 -97.125517) (xy 37.886027 -97.073639)
			(xy 37.912761 -97.025118) (xy 37.94623 -96.980972) (xy 37.965634 -96.961198) (xy 37.980534 -96.94587)
			(xy 38.005594 -96.911245) (xy 38.0245 -96.872912) (xy 38.036718 -96.831954) (xy 38.041904 -96.789528)
			(xy 38.03991 -96.746832) (xy 38.030793 -96.705074) (xy 38.014811 -96.665433) (xy 38.003988 -96.647)
			(xy 37.989902 -96.623179) (xy 37.968047 -96.572337) (xy 37.953768 -96.51887) (xy 37.947365 -96.463902)
			(xy 37.948971 -96.408584) (xy 37.958553 -96.35408) (xy 37.97591 -96.301532) (xy 38.000677 -96.252043)
			(xy 38.032336 -96.206652) (xy 38.07022 -96.166312) (xy 38.113536 -96.13187) (xy 38.161374 -96.104047)
			(xy 38.186868 -96.09328) (xy 38.207579 -96.084455) (xy 38.245725 -96.060554) (xy 38.279066 -96.030308)
			(xy 38.306559 -95.994663) (xy 38.327344 -95.954734) (xy 38.340773 -95.911767) (xy 38.346424 -95.867108)
			(xy 38.344121 -95.822151) (xy 38.333937 -95.778302) (xy 38.31619 -95.736933) (xy 38.304216 -95.717868)
			(xy 38.289498 -95.694544) (xy 38.266126 -95.644593) (xy 38.25019 -95.591796) (xy 38.242022 -95.537256)
			(xy 38.241793 -95.482107) (xy 38.249508 -95.427501) (xy 38.265005 -95.374574) (xy 38.287962 -95.32443)
			(xy 38.3179 -95.278115) (xy 38.354195 -95.236593) (xy 38.396091 -95.200731) (xy 38.442715 -95.171274)
			(xy 38.493094 -95.148839) (xy 38.546178 -95.133892) (xy 38.600862 -95.126744) (xy 38.656005 -95.127545)
			(xy 38.710458 -95.136278) (xy 38.763086 -95.152761) (xy 38.812793 -95.17665) (xy 38.858541 -95.207448)
			(xy 38.899377 -95.244512) (xy 38.934451 -95.287071) (xy 38.963032 -95.334236) (xy 38.984522 -95.385025)
			(xy 38.998476 -95.43838) (xy 39.000643 -95.457772) (xy 40.272714 -95.457772) (xy 40.276785 -95.40215)
			(xy 40.288911 -95.347713) (xy 40.308834 -95.295622) (xy 40.33613 -95.246987) (xy 40.370216 -95.202844)
			(xy 40.410365 -95.164135) (xy 40.455723 -95.131684) (xy 40.505323 -95.106183) (xy 40.558107 -95.088176)
			(xy 40.61295 -95.078046) (xy 40.668684 -95.076009) (xy 40.724121 -95.082109) (xy 40.778078 -95.096215)
			(xy 40.829407 -95.118027) (xy 40.877013 -95.147081) (xy 40.919881 -95.182756) (xy 40.957098 -95.224293)
			(xy 40.987871 -95.270806) (xy 41.011543 -95.321303) (xy 41.027611 -95.37471) (xy 41.035731 -95.429886)
			(xy 41.03624 -95.457772) (xy 41.035731 -95.485658) (xy 41.031723 -95.51289) (xy 42.304714 -95.51289)
			(xy 42.308785 -95.457268) (xy 42.320911 -95.402831) (xy 42.340834 -95.35074) (xy 42.36813 -95.302105)
			(xy 42.402216 -95.257962) (xy 42.442365 -95.219253) (xy 42.487723 -95.186802) (xy 42.537323 -95.161301)
			(xy 42.590107 -95.143294) (xy 42.64495 -95.133164) (xy 42.700684 -95.131127) (xy 42.756121 -95.137227)
			(xy 42.810078 -95.151333) (xy 42.861407 -95.173145) (xy 42.909013 -95.202199) (xy 42.951881 -95.237874)
			(xy 42.989098 -95.279411) (xy 43.019871 -95.325924) (xy 43.043543 -95.376421) (xy 43.059611 -95.429828)
			(xy 43.067731 -95.485004) (xy 43.06824 -95.51289) (xy 43.067731 -95.540776) (xy 43.059611 -95.595952)
			(xy 43.043543 -95.649359) (xy 43.019871 -95.699856) (xy 42.989098 -95.746369) (xy 42.951881 -95.787906)
			(xy 42.909013 -95.823581) (xy 42.861407 -95.852635) (xy 42.810078 -95.874447) (xy 42.756121 -95.888553)
			(xy 42.700684 -95.894653) (xy 42.64495 -95.892616) (xy 42.590107 -95.882486) (xy 42.537323 -95.864479)
			(xy 42.487723 -95.838978) (xy 42.442365 -95.806527) (xy 42.402216 -95.767818) (xy 42.36813 -95.723675)
			(xy 42.340834 -95.67504) (xy 42.320911 -95.622949) (xy 42.308785 -95.568512) (xy 42.304714 -95.51289)
			(xy 41.031723 -95.51289) (xy 41.027611 -95.540834) (xy 41.011543 -95.594241) (xy 40.987871 -95.644738)
			(xy 40.957098 -95.691251) (xy 40.919881 -95.732788) (xy 40.877013 -95.768463) (xy 40.829407 -95.797517)
			(xy 40.778078 -95.819329) (xy 40.724121 -95.833435) (xy 40.668684 -95.839535) (xy 40.61295 -95.837498)
			(xy 40.558107 -95.827368) (xy 40.505323 -95.809361) (xy 40.455723 -95.78386) (xy 40.410365 -95.751409)
			(xy 40.370216 -95.7127) (xy 40.33613 -95.668557) (xy 40.308834 -95.619922) (xy 40.288911 -95.567831)
			(xy 40.276785 -95.513394) (xy 40.272714 -95.457772) (xy 39.000643 -95.457772) (xy 39.004601 -95.493188)
			(xy 39.002771 -95.548306) (xy 38.993022 -95.602587) (xy 38.975559 -95.654898) (xy 38.950746 -95.704149)
			(xy 38.919099 -95.749314) (xy 38.881278 -95.789452) (xy 38.838073 -95.823725) (xy 38.790382 -95.851419)
			(xy 38.764972 -95.86214) (xy 38.744255 -95.870953) (xy 38.706104 -95.894852) (xy 38.672759 -95.925098)
			(xy 38.645263 -95.960744) (xy 38.624476 -96.000676) (xy 38.611048 -96.043645) (xy 38.605398 -96.088308)
			(xy 38.607704 -96.133267) (xy 38.617893 -96.177118) (xy 38.635646 -96.218488) (xy 38.647624 -96.237552)
			(xy 38.661764 -96.25969) (xy 38.684382 -96.307102) (xy 38.700279 -96.35717) (xy 38.709153 -96.408946)
			(xy 38.710836 -96.46145) (xy 38.705296 -96.513688) (xy 38.692638 -96.564671) (xy 38.673102 -96.613435)
			(xy 38.647057 -96.659054) (xy 38.614997 -96.700668) (xy 38.59657 -96.71939) (xy 38.581594 -96.734648)
			(xy 38.556537 -96.769286) (xy 38.537637 -96.807632) (xy 38.525426 -96.848603) (xy 38.520251 -96.89104)
			(xy 38.522257 -96.933744) (xy 38.531388 -96.975509) (xy 38.547385 -97.015154) (xy 38.558216 -97.033588)
			(xy 38.573015 -97.058638) (xy 38.59561 -97.112253) (xy 38.60979 -97.168679) (xy 38.615228 -97.226605)
			(xy 38.611795 -97.284685) (xy 38.606222 -97.313242) (xy 38.601746 -97.336491) (xy 38.600598 -97.383818)
			(xy 38.608232 -97.43054) (xy 38.624384 -97.47504) (xy 38.648496 -97.515781) (xy 38.679733 -97.551354)
			(xy 38.702579 -97.569232) (xy 40.439029 -97.569232) (xy 40.439896 -97.513281) (xy 40.448928 -97.458057)
			(xy 40.46593 -97.404745) (xy 40.490538 -97.354489) (xy 40.522224 -97.308367) (xy 40.560309 -97.267369)
			(xy 40.581834 -97.249488) (xy 40.598414 -97.235678) (xy 40.627067 -97.203416) (xy 40.649852 -97.166774)
			(xy 40.666114 -97.126808) (xy 40.675385 -97.084667) (xy 40.677397 -97.041566) (xy 40.672093 -96.998745)
			(xy 40.659626 -96.957437) (xy 40.640354 -96.918832) (xy 40.614832 -96.884041) (xy 40.599614 -96.868742)
			(xy 40.579875 -96.848909) (xy 40.545797 -96.804528) (xy 40.518568 -96.755645) (xy 40.498772 -96.703308)
			(xy 40.486835 -96.648641) (xy 40.483012 -96.592817) (xy 40.487385 -96.537033) (xy 40.499861 -96.482487)
			(xy 40.520171 -96.430348) (xy 40.547881 -96.381736) (xy 40.582394 -96.337693) (xy 40.622972 -96.299165)
			(xy 40.668743 -96.266978) (xy 40.718725 -96.241823) (xy 40.771845 -96.22424) (xy 40.826965 -96.214606)
			(xy 40.8829 -96.213127) (xy 40.938452 -96.219836) (xy 40.992427 -96.234588) (xy 41.043668 -96.257067)
			(xy 41.091076 -96.286791) (xy 41.133632 -96.323121) (xy 41.170425 -96.365279) (xy 41.200664 -96.412359)
			(xy 41.223701 -96.463352) (xy 41.239041 -96.517163) (xy 41.246355 -96.572638) (xy 41.245487 -96.628586)
			(xy 41.240356 -96.659954) (xy 42.277536 -96.659954) (xy 42.281607 -96.604332) (xy 42.293733 -96.549895)
			(xy 42.313656 -96.497804) (xy 42.340952 -96.449169) (xy 42.375038 -96.405026) (xy 42.415187 -96.366317)
			(xy 42.460545 -96.333866) (xy 42.510145 -96.308365) (xy 42.562929 -96.290358) (xy 42.617772 -96.280228)
			(xy 42.673506 -96.278191) (xy 42.728943 -96.284291) (xy 42.7829 -96.298397) (xy 42.834229 -96.320209)
			(xy 42.881835 -96.349263) (xy 42.924703 -96.384938) (xy 42.96192 -96.426475) (xy 42.992693 -96.472988)
			(xy 43.016365 -96.523485) (xy 43.032433 -96.576892) (xy 43.040553 -96.632068) (xy 43.041062 -96.659954)
			(xy 43.040553 -96.68784) (xy 43.032433 -96.743016) (xy 43.016365 -96.796423) (xy 42.992693 -96.84692)
			(xy 42.96192 -96.893433) (xy 42.924703 -96.93497) (xy 42.881835 -96.970645) (xy 42.834229 -96.999699)
			(xy 42.7829 -97.021511) (xy 42.728943 -97.035617) (xy 42.673506 -97.041717) (xy 42.617772 -97.03968)
			(xy 42.562929 -97.02955) (xy 42.510145 -97.011543) (xy 42.460545 -96.986042) (xy 42.415187 -96.953591)
			(xy 42.375038 -96.914882) (xy 42.340952 -96.870739) (xy 42.313656 -96.822104) (xy 42.293733 -96.770013)
			(xy 42.281607 -96.715576) (xy 42.277536 -96.659954) (xy 41.240356 -96.659954) (xy 41.236454 -96.683807)
			(xy 41.219452 -96.737117) (xy 41.194843 -96.78737) (xy 41.163158 -96.833489) (xy 41.125075 -96.874485)
			(xy 41.10355 -96.892364) (xy 41.087015 -96.906226) (xy 41.058365 -96.938481) (xy 41.03558 -96.975114)
			(xy 41.019316 -97.015073) (xy 41.010042 -97.057206) (xy 41.008025 -97.100301) (xy 41.013322 -97.143116)
			(xy 41.025782 -97.184419) (xy 41.045045 -97.223021) (xy 41.070557 -97.257811) (xy 41.08577 -97.27311)
			(xy 41.105526 -97.292928) (xy 41.139608 -97.337309) (xy 41.16684 -97.386194) (xy 41.186639 -97.438532)
			(xy 41.198579 -97.493201) (xy 41.202404 -97.549027) (xy 41.198033 -97.604814) (xy 41.185559 -97.659364)
			(xy 41.16525 -97.711506) (xy 41.137541 -97.760121) (xy 41.103027 -97.804167) (xy 41.062449 -97.842699)
			(xy 41.016677 -97.874889) (xy 40.966693 -97.900047) (xy 40.913571 -97.917633) (xy 40.858449 -97.927269)
			(xy 40.802511 -97.92875) (xy 40.746957 -97.922043) (xy 40.692979 -97.907291) (xy 40.641734 -97.884813)
			(xy 40.594324 -97.855089) (xy 40.551764 -97.818758) (xy 40.514969 -97.7766) (xy 40.484727 -97.729518)
			(xy 40.461688 -97.678523) (xy 40.446345 -97.62471) (xy 40.439029 -97.569232) (xy 38.702579 -97.569232)
			(xy 38.717016 -97.580529) (xy 38.737794 -97.59188) (xy 38.761911 -97.604844) (xy 38.806432 -97.636717)
			(xy 38.845942 -97.674625) (xy 38.879627 -97.717791) (xy 38.906798 -97.765328) (xy 38.926896 -97.816261)
			(xy 38.939509 -97.869543) (xy 38.944377 -97.92408) (xy 38.941401 -97.978754) (xy 38.930972 -98.030792)
			(xy 41.601642 -98.030792) (xy 41.605713 -97.97517) (xy 41.617839 -97.920733) (xy 41.637762 -97.868642)
			(xy 41.665058 -97.820007) (xy 41.699144 -97.775864) (xy 41.739293 -97.737155) (xy 41.784651 -97.704704)
			(xy 41.834251 -97.679203) (xy 41.887035 -97.661196) (xy 41.941878 -97.651066) (xy 41.997612 -97.649029)
			(xy 42.053049 -97.655129) (xy 42.107006 -97.669235) (xy 42.158335 -97.691047) (xy 42.205941 -97.720101)
			(xy 42.248809 -97.755776) (xy 42.286026 -97.797313) (xy 42.316799 -97.843826) (xy 42.340471 -97.894323)
			(xy 42.356539 -97.94773) (xy 42.364659 -98.002906) (xy 42.365168 -98.030792) (xy 42.364659 -98.058678)
			(xy 42.356539 -98.113854) (xy 42.340471 -98.167261) (xy 42.316799 -98.217758) (xy 42.286026 -98.264271)
			(xy 42.248809 -98.305808) (xy 42.205941 -98.341483) (xy 42.158335 -98.370537) (xy 42.107006 -98.392349)
			(xy 42.053049 -98.406455) (xy 41.997612 -98.412555) (xy 41.941878 -98.410518) (xy 41.887035 -98.400388)
			(xy 41.834251 -98.382381) (xy 41.784651 -98.35688) (xy 41.739293 -98.324429) (xy 41.699144 -98.28572)
			(xy 41.665058 -98.241577) (xy 41.637762 -98.192942) (xy 41.617839 -98.140851) (xy 41.605713 -98.086414)
			(xy 41.601642 -98.030792) (xy 38.930972 -98.030792) (xy 38.930642 -98.032441) (xy 38.91232 -98.084039)
			(xy 38.886812 -98.132488) (xy 38.854642 -98.176795) (xy 38.81647 -98.21605) (xy 38.773079 -98.249446)
			(xy 38.725361 -98.276298) (xy 38.674295 -98.296055) (xy 38.62093 -98.30831) (xy 38.566361 -98.312813)
			(xy 38.511709 -98.309471) (xy 38.458095 -98.298352) (xy 38.406621 -98.279686) (xy 38.358343 -98.253854)
			(xy 38.314253 -98.221388) (xy 38.275255 -98.182953) (xy 38.24215 -98.13934) (xy 38.215618 -98.091443)
			(xy 38.196204 -98.040246) (xy 38.184306 -97.9868) (xy 38.180168 -97.932202) (xy 38.183876 -97.877574)
			(xy 38.189154 -97.850706) (xy 38.193542 -97.827444) (xy 38.194697 -97.780126) (xy 38.187073 -97.733413)
			(xy 38.170935 -97.688918) (xy 38.146839 -97.648179) (xy 38.115618 -97.612604) (xy 38.078352 -97.583423)
			(xy 38.057582 -97.572068) (xy 38.033203 -97.55891) (xy 37.988223 -97.52657) (xy 37.948392 -97.488066)
			(xy 37.914548 -97.444207) (xy 37.8874 -97.395915) (xy 37.867521 -97.344205) (xy 37.855328 -97.290165)
			(xy 37.851077 -97.234929) (xy 33.26384 -97.234929) (xy 33.26384 -102.893368) (xy 34.02076 -103.650288)
		)
		(stroke
			(width 0)
			(type solid)
		)
		(fill yes)
		(layer "In6.Cu")
		(net "P1V5_SUS_NODE1")
	)
	(gr_poly
		(pts
			(xy 29.338016 -115.148868) (xy 29.359611 -115.148434) (xy 29.40218 -115.141129) (xy 29.442902 -115.126733)
			(xy 29.480603 -115.105659) (xy 29.514198 -115.078515) (xy 29.542721 -115.046082) (xy 29.565351 -115.009294)
			(xy 29.581435 -114.96921) (xy 29.59051 -114.926983) (xy 29.592316 -114.883829) (xy 29.589984 -114.862356)
			(xy 29.586196 -114.835153) (xy 29.585545 -114.780233) (xy 29.592775 -114.725788) (xy 29.607737 -114.672942)
			(xy 29.630121 -114.622787) (xy 29.659465 -114.57636) (xy 29.695163 -114.53462) (xy 29.736476 -114.49843)
			(xy 29.782552 -114.468538) (xy 29.832438 -114.44556) (xy 29.885103 -114.429973) (xy 29.939458 -114.422098)
			(xy 29.994382 -114.422098) (xy 30.048737 -114.429973) (xy 30.101402 -114.44556) (xy 30.151288 -114.468538)
			(xy 30.197364 -114.49843) (xy 30.238677 -114.53462) (xy 30.274375 -114.57636) (xy 30.303719 -114.622787)
			(xy 30.326103 -114.672942) (xy 30.341065 -114.725788) (xy 30.348295 -114.780233) (xy 30.347644 -114.835153)
			(xy 30.343856 -114.862356) (xy 30.341518 -114.883831) (xy 30.343309 -114.926988) (xy 30.352374 -114.969221)
			(xy 30.368453 -115.009311) (xy 30.391082 -115.046104) (xy 30.419609 -115.078538) (xy 30.453212 -115.10568)
			(xy 30.490921 -115.126746) (xy 30.531651 -115.141129) (xy 30.574226 -115.148415) (xy 30.595824 -115.148868)
			(xy 43.587162 -115.148868) (xy 44.483782 -114.252248) (xy 45.46727 -114.252248) (xy 45.69968 -114.019838)
			(xy 45.69968 -111.76635) (xy 45.739812 -111.726218) (xy 46.072552 -111.726218) (xy 46.081188 -111.725964)
			(xy 47.415704 -111.725964) (xy 47.438056 -111.724795) (xy 47.481852 -111.715584) (xy 47.523356 -111.698841)
			(xy 47.561285 -111.675084) (xy 47.594463 -111.645048) (xy 47.621864 -111.609662) (xy 47.642641 -111.570023)
			(xy 47.656149 -111.527356) (xy 47.661971 -111.482982) (xy 47.659928 -111.438274) (xy 47.65548 -111.416338)
			(xy 47.649066 -111.388705) (xy 47.643529 -111.332249) (xy 47.646415 -111.275596) (xy 47.657659 -111.219995)
			(xy 47.677014 -111.166672) (xy 47.704052 -111.116804) (xy 47.738177 -111.071489) (xy 47.778638 -111.031729)
			(xy 47.82454 -110.998399) (xy 47.874872 -110.972235) (xy 47.928524 -110.953813) (xy 47.984313 -110.943541)
			(xy 48.041008 -110.941643) (xy 48.097359 -110.948164) (xy 48.124872 -110.955074) (xy 48.150786 -110.96255)
			(xy 48.20036 -110.983795) (xy 48.246449 -111.011806) (xy 48.288137 -111.046025) (xy 48.324593 -111.085772)
			(xy 48.355091 -111.130255) (xy 48.379024 -111.178588) (xy 48.395915 -111.229809) (xy 48.405429 -111.282897)
			(xy 48.407374 -111.336795) (xy 48.401714 -111.390431) (xy 48.38856 -111.442737) (xy 48.368174 -111.492669)
			(xy 48.340963 -111.539236) (xy 48.324516 -111.56061) (xy 48.31207 -111.576104) (xy 48.295292 -111.620701)
			(xy 58.513255 -111.620701) (xy 58.519463 -111.565601) (xy 58.533583 -111.51198) (xy 58.555319 -111.460968)
			(xy 58.584212 -111.413642) (xy 58.619653 -111.370997) (xy 58.660895 -111.333934) (xy 58.707069 -111.303233)
			(xy 58.757202 -111.279541) (xy 58.810237 -111.263358) (xy 58.865056 -111.255024) (xy 58.920505 -111.254715)
			(xy 58.975413 -111.262439) (xy 59.028625 -111.278031) (xy 59.079018 -111.301163) (xy 59.125531 -111.331349)
			(xy 59.167183 -111.367951) (xy 59.203097 -111.410198) (xy 59.232514 -111.457201) (xy 59.254817 -111.507967)
			(xy 59.269533 -111.561428) (xy 59.276354 -111.616456) (xy 59.275135 -111.671891) (xy 59.265902 -111.726566)
			(xy 59.250746 -111.773462) (xy 60.730128 -111.773462) (xy 60.734199 -111.71784) (xy 60.746325 -111.663403)
			(xy 60.766248 -111.611312) (xy 60.793544 -111.562677) (xy 60.82763 -111.518534) (xy 60.867779 -111.479825)
			(xy 60.913137 -111.447374) (xy 60.962737 -111.421873) (xy 61.015521 -111.403866) (xy 61.070364 -111.393736)
			(xy 61.126098 -111.391699) (xy 61.181535 -111.397799) (xy 61.235492 -111.411905) (xy 61.286821 -111.433717)
			(xy 61.334427 -111.462771) (xy 61.377295 -111.498446) (xy 61.414512 -111.539983) (xy 61.445285 -111.586496)
			(xy 61.468957 -111.636993) (xy 61.485025 -111.6904) (xy 61.493145 -111.745576) (xy 61.493654 -111.773462)
			(xy 61.493145 -111.801348) (xy 61.485025 -111.856524) (xy 61.468957 -111.909931) (xy 61.445285 -111.960428)
			(xy 61.414512 -112.006941) (xy 61.377295 -112.048478) (xy 61.334427 -112.084153) (xy 61.286821 -112.113207)
			(xy 61.235492 -112.135019) (xy 61.181535 -112.149125) (xy 61.126098 -112.155225) (xy 61.070364 -112.153188)
			(xy 61.015521 -112.143058) (xy 60.962737 -112.125051) (xy 60.913137 -112.09955) (xy 60.867779 -112.067099)
			(xy 60.82763 -112.02839) (xy 60.793544 -111.984247) (xy 60.766248 -111.935612) (xy 60.746325 -111.883521)
			(xy 60.734199 -111.829084) (xy 60.730128 -111.773462) (xy 59.250746 -111.773462) (xy 59.24885 -111.779329)
			(xy 59.224338 -111.829066) (xy 59.192883 -111.874729) (xy 59.17438 -111.895382) (xy 59.163788 -111.907385)
			(xy 59.148526 -111.935517) (xy 59.140747 -111.966563) (xy 59.140941 -111.998568) (xy 59.149095 -112.029518)
			(xy 59.164696 -112.057464) (xy 59.175396 -112.069372) (xy 59.194097 -112.089841) (xy 59.226048 -112.13515)
			(xy 59.251102 -112.184608) (xy 59.268731 -112.237172) (xy 59.278563 -112.291734) (xy 59.280391 -112.347146)
			(xy 59.274177 -112.402238) (xy 59.260051 -112.455849) (xy 59.238312 -112.506851) (xy 59.209417 -112.554167)
			(xy 59.173975 -112.596801) (xy 59.132734 -112.633854) (xy 59.086563 -112.664545) (xy 59.036434 -112.688227)
			(xy 58.983404 -112.704402) (xy 58.928592 -112.712728) (xy 58.873151 -112.713029) (xy 58.818251 -112.7053)
			(xy 58.765049 -112.689703) (xy 58.714665 -112.666567) (xy 58.668163 -112.63638) (xy 58.626521 -112.599778)
			(xy 58.590618 -112.557532) (xy 58.56121 -112.510533) (xy 58.538917 -112.459771) (xy 58.524209 -112.406316)
			(xy 58.517396 -112.351295) (xy 58.518622 -112.295867) (xy 58.52786 -112.241201) (xy 58.544916 -112.188448)
			(xy 58.569431 -112.138721) (xy 58.600887 -112.093067) (xy 58.61939 -112.07242) (xy 58.629983 -112.060417)
			(xy 58.645248 -112.032285) (xy 58.653029 -112.001239) (xy 58.652836 -111.969233) (xy 58.64468 -111.938283)
			(xy 58.629076 -111.910337) (xy 58.618374 -111.89843) (xy 58.599594 -111.87803) (xy 58.567633 -111.832719)
			(xy 58.542569 -111.783258) (xy 58.524931 -111.730689) (xy 58.51509 -111.67612) (xy 58.513255 -111.620701)
			(xy 48.295292 -111.620701) (xy 48.282352 -111.655098) (xy 48.2981 -111.727996) (xy 48.32477 -111.754666)
			(xy 48.978647 -112.408543) (xy 55.112747 -112.408543) (xy 55.116627 -112.353496) (xy 55.128398 -112.299582)
			(xy 55.147815 -112.247927) (xy 55.174473 -112.19961) (xy 55.207815 -112.155638) (xy 55.247146 -112.11693)
			(xy 55.291644 -112.084293) (xy 55.340381 -112.058409) (xy 55.392339 -112.039818) (xy 55.446433 -112.028908)
			(xy 55.501535 -112.025908) (xy 55.556495 -112.030878) (xy 55.610164 -112.043717) (xy 55.661424 -112.064155)
			(xy 55.709203 -112.091767) (xy 55.731156 -112.108488) (xy 55.749969 -112.122752) (xy 55.791782 -112.144667)
			(xy 55.836922 -112.158489) (xy 55.883837 -112.163743) (xy 55.930916 -112.160248) (xy 55.976541 -112.148123)
			(xy 56.019144 -112.127787) (xy 56.057263 -112.099937) (xy 56.073802 -112.083088) (xy 56.092663 -112.063764)
			(xy 56.134791 -112.029991) (xy 56.181262 -112.002497) (xy 56.231146 -111.981831) (xy 56.283446 -111.968408)
			(xy 56.337116 -111.962495) (xy 56.391084 -111.96421) (xy 56.44427 -111.973519) (xy 56.495612 -111.990236)
			(xy 56.544083 -112.014027) (xy 56.588715 -112.044416) (xy 56.60898 -112.06226) (xy 56.62542 -112.076568)
			(xy 56.662195 -112.099949) (xy 56.702418 -112.116715) (xy 56.744912 -112.126376) (xy 56.788431 -112.128649)
			(xy 56.8317 -112.123466) (xy 56.873451 -112.110981) (xy 56.912461 -112.091558) (xy 56.93029 -112.079024)
			(xy 56.953362 -112.062659) (xy 57.003412 -112.036298) (xy 57.056803 -112.017614) (xy 57.112368 -112.007015)
			(xy 57.168889 -112.004733) (xy 57.225127 -112.01082) (xy 57.279851 -112.02514) (xy 57.331862 -112.047382)
			(xy 57.380021 -112.077056) (xy 57.423271 -112.113514) (xy 57.442354 -112.134396) (xy 57.453562 -112.146395)
			(xy 57.480819 -112.164683) (xy 57.511844 -112.175402) (xy 57.544577 -112.177841) (xy 57.576847 -112.171838)
			(xy 57.606514 -112.157791) (xy 57.619392 -112.147604) (xy 57.641116 -112.129976) (xy 57.688706 -112.100569)
			(xy 57.74008 -112.078427) (xy 57.794137 -112.064025) (xy 57.849718 -112.057671) (xy 57.90563 -112.059503)
			(xy 57.960676 -112.06948) (xy 58.013675 -112.087389) (xy 58.06349 -112.112845) (xy 58.109053 -112.145304)
			(xy 58.149388 -112.184069) (xy 58.183629 -112.228308) (xy 58.211042 -112.277074) (xy 58.23104 -112.32932)
			(xy 58.243194 -112.383926) (xy 58.247243 -112.439722) (xy 58.2431 -112.495511) (xy 58.230854 -112.550097)
			(xy 58.210768 -112.60231) (xy 58.183272 -112.651029) (xy 58.148956 -112.695211) (xy 58.108556 -112.733907)
			(xy 58.062938 -112.766289) (xy 58.01308 -112.791661) (xy 57.960052 -112.809481) (xy 57.904989 -112.819365)
			(xy 57.849073 -112.821102) (xy 57.793503 -112.814655) (xy 57.739471 -112.800161) (xy 57.688134 -112.777933)
			(xy 57.640594 -112.748445) (xy 57.59787 -112.712331) (xy 57.579006 -112.691672) (xy 57.567743 -112.679729)
			(xy 57.5405 -112.661442) (xy 57.50949 -112.650719) (xy 57.476769 -112.648271) (xy 57.444508 -112.654259)
			(xy 57.414847 -112.668287) (xy 57.401968 -112.678464) (xy 57.380674 -112.69583) (xy 57.333997 -112.724822)
			(xy 57.283645 -112.746822) (xy 57.230658 -112.761373) (xy 57.176133 -112.768176) (xy 57.121195 -112.76709)
			(xy 57.066981 -112.758137) (xy 57.014611 -112.741502) (xy 56.965168 -112.717529) (xy 56.919673 -112.686715)
			(xy 56.899048 -112.668558) (xy 56.882587 -112.654276) (xy 56.845817 -112.630892) (xy 56.805597 -112.614123)
			(xy 56.763107 -112.604458) (xy 56.719591 -112.602182) (xy 56.676325 -112.60736) (xy 56.634575 -112.619842)
			(xy 56.595566 -112.639262) (xy 56.577738 -112.651794) (xy 56.555197 -112.667747) (xy 56.506436 -112.693667)
			(xy 56.454446 -112.71228) (xy 56.400315 -112.723198) (xy 56.345174 -112.726192) (xy 56.290179 -112.7212)
			(xy 56.236479 -112.708325) (xy 56.185198 -112.687838) (xy 56.13741 -112.660166) (xy 56.115458 -112.643412)
			(xy 56.096635 -112.629163) (xy 56.054824 -112.607246) (xy 56.009687 -112.593423) (xy 55.962773 -112.588168)
			(xy 55.915696 -112.591661) (xy 55.870072 -112.603783) (xy 55.827469 -112.624117) (xy 55.789351 -112.651965)
			(xy 55.772812 -112.668812) (xy 55.753599 -112.68862) (xy 55.71043 -112.722997) (xy 55.662759 -112.750794)
			(xy 55.61158 -112.771431) (xy 55.55796 -112.784478) (xy 55.503021 -112.789663) (xy 55.447908 -112.786876)
			(xy 55.393771 -112.776177) (xy 55.341741 -112.757789) (xy 55.292904 -112.732094) (xy 55.248279 -112.699631)
			(xy 55.208798 -112.661076) (xy 55.175285 -112.617234) (xy 55.14844 -112.569021) (xy 55.128821 -112.517442)
			(xy 55.116841 -112.463574) (xy 55.112747 -112.408543) (xy 48.978647 -112.408543) (xy 49.15154 -112.581436)
			(xy 50.072798 -112.581436) (xy 50.183542 -112.470692) (xy 52.140866 -112.470692) (xy 52.25161 -112.581436)
			(xy 52.972462 -112.581436) (xy 53.899816 -113.50879) (xy 64.977772 -113.50879) (xy 65.42532 -113.061242)
			(xy 65.42532 -109.544612) (xy 64.727328 -108.84662) (xy 64.682624 -108.842048) (xy 64.675258 -108.841032)
			(xy 62.389766 -108.841032) (xy 62.300612 -108.878624) (xy 62.284102 -108.89361) (xy 62.262858 -108.912453)
			(xy 62.215839 -108.944288) (xy 62.164619 -108.968801) (xy 62.110331 -108.985451) (xy 62.054176 -108.993868)
			(xy 61.997392 -108.993868) (xy 61.941237 -108.985451) (xy 61.886949 -108.968801) (xy 61.835729 -108.944288)
			(xy 61.78871 -108.912453) (xy 61.767466 -108.89361) (xy 61.750956 -108.878624) (xy 61.661802 -108.841032)
			(xy 58.493152 -108.841032) (xy 58.477011 -108.841514) (xy 58.445762 -108.84962) (xy 58.417545 -108.865303)
			(xy 58.405522 -108.876084) (xy 58.386086 -108.894019) (xy 58.343157 -108.924908) (xy 58.296373 -108.949569)
			(xy 58.24663 -108.96753) (xy 58.194883 -108.978446) (xy 58.142124 -108.982108) (xy 58.089365 -108.978446)
			(xy 58.037618 -108.96753) (xy 57.987875 -108.949569) (xy 57.941091 -108.924908) (xy 57.898162 -108.894019)
			(xy 57.878726 -108.876084) (xy 57.841896 -108.841032) (xy 49.526698 -108.841032) (xy 49.50467 -108.841502)
			(xy 49.461274 -108.849102) (xy 49.41984 -108.864073) (xy 49.381609 -108.885967) (xy 49.347728 -108.914126)
			(xy 49.319211 -108.947708) (xy 49.296915 -108.985706) (xy 49.281507 -109.02698) (xy 49.277016 -109.04855)
			(xy 49.271402 -109.075837) (xy 49.253317 -109.128528) (xy 49.227763 -109.17803) (xy 49.195284 -109.223291)
			(xy 49.15657 -109.263349) (xy 49.112443 -109.297353) (xy 49.063842 -109.324581) (xy 49.011798 -109.344453)
			(xy 48.957418 -109.356548) (xy 48.901858 -109.360608) (xy 48.846298 -109.356548) (xy 48.791918 -109.344453)
			(xy 48.739874 -109.324581) (xy 48.691273 -109.297353) (xy 48.647146 -109.263349) (xy 48.608432 -109.223291)
			(xy 48.575953 -109.17803) (xy 48.550399 -109.128528) (xy 48.532314 -109.075837) (xy 48.5267 -109.04855)
			(xy 48.522202 -109.026985) (xy 48.506783 -108.985724) (xy 48.484481 -108.947739) (xy 48.455963 -108.914169)
			(xy 48.422083 -108.88602) (xy 48.383857 -108.864134) (xy 48.34243 -108.849168) (xy 48.299042 -108.841569)
			(xy 48.277018 -108.841032) (xy 47.014638 -108.841032) (xy 46.99293 -108.841472) (xy 46.950146 -108.848849)
			(xy 46.909239 -108.863395) (xy 46.871403 -108.884686) (xy 46.837738 -108.912102) (xy 46.809226 -108.944843)
			(xy 46.786698 -108.981956) (xy 46.77081 -109.022361) (xy 46.762025 -109.064878) (xy 46.760599 -109.10827)
			(xy 46.766573 -109.151273) (xy 46.779773 -109.192633) (xy 46.78934 -109.212126) (xy 46.801801 -109.237156)
			(xy 46.820077 -109.289997) (xy 46.830446 -109.344939) (xy 46.832687 -109.400806) (xy 46.826752 -109.456402)
			(xy 46.812768 -109.510537) (xy 46.791034 -109.562052) (xy 46.762015 -109.609844) (xy 46.726333 -109.65289)
			(xy 46.684752 -109.690269) (xy 46.638161 -109.72118) (xy 46.587559 -109.744961) (xy 46.534028 -109.761104)
			(xy 46.478714 -109.769263) (xy 46.422802 -109.769263) (xy 46.367488 -109.761104) (xy 46.313957 -109.744961)
			(xy 46.263355 -109.72118) (xy 46.216764 -109.690269) (xy 46.175183 -109.65289) (xy 46.139501 -109.609844)
			(xy 46.110482 -109.562052) (xy 46.088748 -109.510537) (xy 46.074764 -109.456402) (xy 46.068829 -109.400806)
			(xy 46.07107 -109.344939) (xy 46.081439 -109.289997) (xy 46.099715 -109.237156) (xy 46.112176 -109.212126)
			(xy 46.121794 -109.19266) (xy 46.134974 -109.151293) (xy 46.140932 -109.108288) (xy 46.139492 -109.064897)
			(xy 46.130697 -109.022381) (xy 46.114804 -108.981979) (xy 46.092274 -108.944867) (xy 46.063763 -108.912124)
			(xy 46.030102 -108.884705) (xy 45.992269 -108.863406) (xy 45.951367 -108.848849) (xy 45.908586 -108.841455)
			(xy 45.886878 -108.841032) (xy 45.837348 -108.841032) (xy 45.813766 -108.841545) (xy 45.76741 -108.850241)
			(xy 45.723456 -108.867343) (xy 45.683413 -108.892264) (xy 45.648658 -108.924147) (xy 45.620384 -108.961896)
			(xy 45.599563 -109.004216) (xy 45.58691 -109.049651) (xy 45.58286 -109.096641) (xy 45.587553 -109.143571)
			(xy 45.600826 -109.188829) (xy 45.611034 -109.210094) (xy 45.6232 -109.235129) (xy 45.640957 -109.28788)
			(xy 45.65086 -109.342652) (xy 45.652701 -109.398281) (xy 45.64644 -109.453588) (xy 45.632209 -109.507398)
			(xy 45.610312 -109.558569) (xy 45.581212 -109.606016) (xy 45.545527 -109.648732) (xy 45.504015 -109.685809)
			(xy 45.457556 -109.716462) (xy 45.407137 -109.74004) (xy 45.353827 -109.756042) (xy 45.298758 -109.764129)
			(xy 45.243098 -109.764129) (xy 45.188029 -109.756042) (xy 45.134719 -109.74004) (xy 45.0843 -109.716462)
			(xy 45.037841 -109.685809) (xy 44.996329 -109.648732) (xy 44.960644 -109.606016) (xy 44.931544 -109.558569)
			(xy 44.909647 -109.507398) (xy 44.895416 -109.453588) (xy 44.889155 -109.398281) (xy 44.890996 -109.342652)
			(xy 44.900899 -109.28788) (xy 44.918656 -109.235129) (xy 44.930822 -109.210094) (xy 44.941046 -109.18884)
			(xy 44.954294 -109.14358) (xy 44.958967 -109.096653) (xy 44.954904 -109.04967) (xy 44.942245 -109.004242)
			(xy 44.921423 -108.961928) (xy 44.893154 -108.924181) (xy 44.858408 -108.892296) (xy 44.818376 -108.867367)
			(xy 44.774433 -108.85025) (xy 44.728087 -108.841532) (xy 44.704508 -108.841032) (xy 44.32935 -108.841032)
			(xy 44.313327 -108.841498) (xy 44.282291 -108.849481) (xy 44.254216 -108.864934) (xy 44.242228 -108.875576)
			(xy 44.220401 -108.89542) (xy 44.171793 -108.928841) (xy 44.145454 -108.942124) (xy 44.120212 -108.95371)
			(xy 44.0672 -108.970269) (xy 44.012346 -108.97896) (xy 43.956811 -108.979598) (xy 43.901772 -108.972172)
			(xy 43.874944 -108.964984) (xy 43.852886 -108.95912) (xy 43.807482 -108.954508) (xy 43.761985 -108.958089)
			(xy 43.717862 -108.969748) (xy 43.676534 -108.989107) (xy 43.639334 -109.015545) (xy 43.60746 -109.048208)
			(xy 43.594274 -109.066838) (xy 43.579282 -109.089706) (xy 43.54379 -109.131302) (xy 43.502722 -109.167405)
			(xy 43.456921 -109.197273) (xy 43.407324 -109.220297) (xy 43.354948 -109.236002) (xy 43.300866 -109.244069)
			(xy 43.246186 -109.244331) (xy 43.192029 -109.236783) (xy 43.139505 -109.22158) (xy 43.08969 -109.199033)
			(xy 43.043604 -109.169605) (xy 43.002192 -109.133898) (xy 42.966303 -109.092644) (xy 42.951146 -109.069886)
			(xy 42.937485 -109.047964) (xy 42.915562 -109.001194) (xy 42.907458 -108.976668) (xy 42.896028 -108.939838)
			(xy 42.774108 -108.841032) (xy 32.04845 -108.841032) (xy 31.85668 -109.032802) (xy 28.338018 -109.032802)
			(xy 26.99512 -107.689904) (xy 26.99512 -107.019852) (xy 26.975562 -106.973116) (xy 26.966672 -106.964226)
			(xy 26.966672 -104.969056) (xy 26.842466 -104.844596) (xy 26.79827 -104.83977) (xy 26.770617 -104.836203)
			(xy 26.71668 -104.822077) (xy 26.665373 -104.800251) (xy 26.61779 -104.771189) (xy 26.574944 -104.735511)
			(xy 26.537747 -104.693977) (xy 26.506991 -104.647471) (xy 26.483333 -104.596983) (xy 26.467275 -104.54359)
			(xy 26.459159 -104.488428) (xy 26.459159 -104.432672) (xy 26.467275 -104.37751) (xy 26.483333 -104.324116)
			(xy 26.506992 -104.273629) (xy 26.537747 -104.227123) (xy 26.574944 -104.185588) (xy 26.617791 -104.14991)
			(xy 26.665374 -104.120849) (xy 26.71668 -104.099023) (xy 26.770617 -104.084897) (xy 26.79827 -104.081326)
			(xy 26.842466 -104.0765) (xy 26.966672 -103.95204) (xy 26.966672 -102.892606) (xy 27.674824 -102.184708)
			(xy 29.112972 -102.184708) (xy 29.61894 -101.67874) (xy 29.61894 -100.542344) (xy 29.551122 -100.4316)
			(xy 29.522166 -100.415344) (xy 29.497987 -100.401332) (xy 29.45364 -100.36733) (xy 29.414727 -100.327223)
			(xy 29.382079 -100.281869) (xy 29.356396 -100.232238) (xy 29.338225 -100.179393) (xy 29.327957 -100.124462)
			(xy 29.32581 -100.068621) (xy 29.33183 -100.013064) (xy 29.34589 -99.958979) (xy 29.367687 -99.907523)
			(xy 29.396756 -99.859797) (xy 29.432475 -99.81682) (xy 29.47408 -99.779513) (xy 29.520681 -99.748673)
			(xy 29.545788 -99.736402) (xy 29.579316 -99.720654) (xy 29.61894 -99.658424) (xy 29.61894 -99.470464)
			(xy 29.581856 -99.409504) (xy 29.55036 -99.393248) (xy 29.525879 -99.380019) (xy 29.480691 -99.347548)
			(xy 29.440699 -99.308856) (xy 29.406754 -99.264765) (xy 29.379574 -99.21621) (xy 29.359737 -99.164221)
			(xy 29.347664 -99.109902) (xy 29.34361 -99.054406) (xy 29.347662 -98.998909) (xy 29.359734 -98.944589)
			(xy 29.37957 -98.8926) (xy 29.406748 -98.844044) (xy 29.440692 -98.799952) (xy 29.480682 -98.761259)
			(xy 29.525869 -98.728787) (xy 29.55036 -98.715576) (xy 29.581856 -98.69932) (xy 29.61894 -98.63836)
			(xy 29.61894 -85.757766) (xy 29.16936 -85.308186) (xy 29.16936 -69.931788) (xy 30.288992 -68.812156)
			(xy 30.288992 -42.340784) (xy 28.972764 -41.024556) (xy 28.956249 -41.00878) (xy 28.918698 -40.982793)
			(xy 28.877111 -40.963928) (xy 28.832823 -40.952792) (xy 28.787259 -40.949742) (xy 28.741882 -40.954878)
			(xy 28.698152 -40.968033) (xy 28.657473 -40.988785) (xy 28.621153 -41.016467) (xy 28.59036 -41.050189)
			(xy 28.577794 -41.06926) (xy 28.56317 -41.092885) (xy 28.528157 -41.136025) (xy 28.487254 -41.173628)
			(xy 28.441329 -41.204898) (xy 28.391352 -41.229175) (xy 28.338383 -41.245944) (xy 28.28354 -41.25485)
			(xy 28.227986 -41.255706) (xy 28.172896 -41.248492) (xy 28.119435 -41.233361) (xy 28.068735 -41.210634)
			(xy 28.021869 -41.180792) (xy 27.979829 -41.144466) (xy 27.943503 -41.102425) (xy 27.913662 -41.055558)
			(xy 27.890936 -41.004858) (xy 27.875807 -40.951396) (xy 27.868594 -40.896306) (xy 27.86945 -40.840752)
			(xy 27.878358 -40.78591) (xy 27.895128 -40.73294) (xy 27.919405 -40.682965) (xy 27.950677 -40.63704)
			(xy 27.988281 -40.596138) (xy 28.031421 -40.561125) (xy 28.055062 -40.546528) (xy 28.074172 -40.534001)
			(xy 28.107945 -40.503231) (xy 28.135671 -40.466917) (xy 28.156455 -40.426229) (xy 28.169627 -40.382481)
			(xy 28.174762 -40.337082) (xy 28.171695 -40.291496) (xy 28.160524 -40.247194) (xy 28.141611 -40.205605)
			(xy 28.115563 -40.168068) (xy 28.099766 -40.151558) (xy 20.435062 -32.486854) (xy 20.422932 -32.47546)
			(xy 20.394148 -32.458781) (xy 20.362032 -32.450107) (xy 20.3454 -32.449516) (xy 19.750532 -32.449516)
			(xy 19.72056 -32.467042) (xy 19.696631 -32.480524) (xy 19.645762 -32.501233) (xy 19.592449 -32.514434)
			(xy 19.537794 -32.519856) (xy 19.482926 -32.517386) (xy 19.42898 -32.507075) (xy 19.377069 -32.489136)
			(xy 19.328266 -32.46394) (xy 19.28358 -32.432008) (xy 19.243934 -32.393999) (xy 19.210146 -32.350698)
			(xy 19.182916 -32.303) (xy 19.162805 -32.251892) (xy 19.15023 -32.198428) (xy 19.145449 -32.143713)
			(xy 19.14652 -32.116268) (xy 19.14844 -32.090358) (xy 19.158419 -32.03937) (xy 19.175231 -31.990211)
			(xy 19.198564 -31.94379) (xy 19.227986 -31.900968) (xy 19.262951 -31.86254) (xy 19.302811 -31.829216)
			(xy 19.324574 -31.815024) (xy 19.343582 -31.802438) (xy 19.37719 -31.771643) (xy 19.404771 -31.735351)
			(xy 19.425441 -31.694723) (xy 19.438539 -31.651062) (xy 19.443644 -31.605766) (xy 19.440594 -31.560285)
			(xy 19.429486 -31.516076) (xy 19.410676 -31.474554) (xy 19.384766 -31.437051) (xy 19.369024 -31.420562)
			(xy 16.683482 -28.73502) (xy 16.646144 -28.697682) (xy 16.541242 -28.697428) (xy 16.503396 -28.735274)
			(xy 16.502888 -28.735782) (xy 16.481783 -28.756486) (xy 16.434361 -28.791788) (xy 16.382071 -28.81937)
			(xy 16.354298 -28.829508) (xy 16.327335 -28.838207) (xy 16.271615 -28.848454) (xy 16.214992 -28.850344)
			(xy 16.158713 -28.843835) (xy 16.104016 -28.829072) (xy 16.052105 -28.806378) (xy 16.004124 -28.776254)
			(xy 15.961127 -28.739362) (xy 15.924062 -28.696514) (xy 15.893744 -28.648655) (xy 15.870842 -28.596836)
			(xy 15.862808 -28.569666) (xy 15.855765 -28.542033) (xy 15.84901 -28.485412) (xy 15.850759 -28.428416)
			(xy 15.860975 -28.372315) (xy 15.879428 -28.318361) (xy 15.905708 -28.267755) (xy 15.939229 -28.221625)
			(xy 15.979244 -28.181) (xy 16.024861 -28.146785) (xy 16.075063 -28.119742) (xy 16.128732 -28.100474)
			(xy 16.184671 -28.089411) (xy 16.241634 -28.086799) (xy 16.298351 -28.092697) (xy 16.326104 -28.099258)
			(xy 16.348471 -28.103905) (xy 16.3941 -28.106016) (xy 16.439373 -28.099936) (xy 16.482828 -28.085859)
			(xy 16.523066 -28.06424) (xy 16.558791 -28.035774) (xy 16.588851 -28.001381) (xy 16.612278 -27.962167)
			(xy 16.628316 -27.919396) (xy 16.636449 -27.874448) (xy 16.637 -27.851608) (xy 16.637 -19.132296)
			(xy 16.636497 -19.108672) (xy 16.627802 -19.062232) (xy 16.610676 -19.018199) (xy 16.585707 -18.978089)
			(xy 16.553757 -18.943283) (xy 16.515925 -18.914981) (xy 16.473515 -18.894157) (xy 16.427987 -18.881529)
			(xy 16.38091 -18.877531) (xy 16.357346 -18.879312) (xy 16.330349 -18.882619) (xy 16.275961 -18.882461)
			(xy 16.222146 -18.874579) (xy 16.169997 -18.859132) (xy 16.120571 -18.836434) (xy 16.074871 -18.806945)
			(xy 16.033823 -18.771263) (xy 15.998261 -18.730112) (xy 15.968904 -18.684326) (xy 15.94635 -18.634835)
			(xy 15.931054 -18.582641) (xy 15.923328 -18.528804) (xy 15.923328 -18.474415) (xy 15.931054 -18.420578)
			(xy 15.94635 -18.368384) (xy 15.968905 -18.318893) (xy 15.998261 -18.273107) (xy 16.033824 -18.231956)
			(xy 16.074872 -18.196274) (xy 16.120572 -18.166785) (xy 16.169998 -18.144087) (xy 16.222147 -18.128641)
			(xy 16.275962 -18.120758) (xy 16.33035 -18.120601) (xy 16.357346 -18.123916) (xy 16.380907 -18.125784)
			(xy 16.427996 -18.121785) (xy 16.473534 -18.109151) (xy 16.515953 -18.088319) (xy 16.553791 -18.060006)
			(xy 16.585744 -18.025187) (xy 16.610711 -17.985063) (xy 16.627833 -17.941015) (xy 16.636518 -17.894562)
			(xy 16.637 -17.870932) (xy 16.637 -15.149322) (xy 16.63573 -15.140178) (xy 16.632428 -15.108936)
			(xy 16.632174 -15.105634) (xy 16.630716 -15.089511) (xy 16.620695 -15.058739) (xy 16.603253 -15.031479)
			(xy 16.579512 -15.009486) (xy 16.551 -14.994176) (xy 16.519553 -14.986534) (xy 16.487194 -14.987052)
			(xy 16.456008 -14.995698) (xy 16.428001 -15.011913) (xy 16.404976 -15.034655) (xy 16.388416 -15.06246)
			(xy 16.379387 -15.093537) (xy 16.378428 -15.109698) (xy 16.377094 -15.137121) (xy 16.367531 -15.191185)
			(xy 16.350314 -15.243319) (xy 16.325801 -15.292446) (xy 16.294497 -15.337551) (xy 16.257049 -15.377701)
			(xy 16.214231 -15.412066) (xy 16.166928 -15.439938) (xy 16.116117 -15.460738) (xy 16.06285 -15.474039)
			(xy 16.008225 -15.479564) (xy 15.953373 -15.477201) (xy 15.899426 -15.466996) (xy 15.8475 -15.449162)
			(xy 15.798667 -15.424067) (xy 15.753938 -15.39223) (xy 15.714235 -15.354308) (xy 15.68038 -15.311086)
			(xy 15.653072 -15.263455) (xy 15.632876 -15.212402) (xy 15.620208 -15.15898) (xy 15.615332 -15.104293)
			(xy 15.618346 -15.049473) (xy 15.62919 -14.995651) (xy 15.647639 -14.94394) (xy 15.673312 -14.895409)
			(xy 15.705678 -14.85106) (xy 15.744068 -14.811811) (xy 15.78769 -14.778471) (xy 15.835641 -14.75173)
			(xy 15.88693 -14.732141) (xy 15.913608 -14.72565) (xy 15.934989 -14.719528) (xy 15.975354 -14.700867)
			(xy 16.011858 -14.675468) (xy 16.043387 -14.644108) (xy 16.068982 -14.607741) (xy 16.08786 -14.567477)
			(xy 16.099448 -14.524543) (xy 16.103391 -14.480248) (xy 16.099569 -14.435943) (xy 16.088099 -14.392977)
			(xy 16.069331 -14.352662) (xy 16.043836 -14.316225) (xy 16.028416 -14.3002) (xy 10.832592 -9.104376)
			(xy 10.823702 -9.098026) (xy 10.797639 -9.078744) (xy 10.751804 -9.032899) (xy 10.732516 -9.00684)
			(xy 10.732262 -9.006586) (xy 10.725912 -8.997696) (xy 10.36828 -8.640064) (xy 10.36828 -5.614924)
			(xy 10.360914 -5.594096) (xy 10.352489 -5.569254) (xy 10.341754 -5.517907) (xy 10.338156 -5.465574)
			(xy 10.341761 -5.413241) (xy 10.352504 -5.361896) (xy 10.360914 -5.337048) (xy 10.36828 -5.31622)
			(xy 10.36828 -5.012944) (xy 10.8204 -5.012944) (xy 11.90752 -3.925824) (xy 13.899896 -3.925824) (xy 13.904976 -3.92557)
			(xy 13.919691 -3.924572) (xy 13.949189 -3.924572) (xy 13.963904 -3.92557) (xy 13.968984 -3.925824)
			(xy 14.160754 -3.925824) (xy 15.53711 -5.30218) (xy 17.840956 -5.30218) (xy 17.840956 -5.217484)
			(xy 17.849007 -5.13317) (xy 17.865036 -5.050004) (xy 17.888897 -4.968737) (xy 17.920376 -4.890107)
			(xy 17.959187 -4.814826) (xy 18.004977 -4.743574) (xy 18.057333 -4.676998) (xy 18.115781 -4.6157)
			(xy 18.179791 -4.560235) (xy 18.248783 -4.511106) (xy 18.322133 -4.468757) (xy 18.399176 -4.433573)
			(xy 18.479215 -4.405871) (xy 18.561524 -4.385903) (xy 18.645359 -4.37385) (xy 18.72996 -4.36982)
			(xy 18.814561 -4.37385) (xy 18.898396 -4.385903) (xy 18.980705 -4.405871) (xy 19.060744 -4.433573)
			(xy 19.137787 -4.468757) (xy 19.211137 -4.511106) (xy 19.280129 -4.560235) (xy 19.344139 -4.6157)
			(xy 19.402587 -4.676998) (xy 19.454943 -4.743574) (xy 19.500733 -4.814826) (xy 19.539544 -4.890107)
			(xy 19.571023 -4.968737) (xy 19.594884 -5.050004) (xy 19.610913 -5.13317) (xy 19.618964 -5.217484)
			(xy 19.619468 -5.259832) (xy 19.618964 -5.30218) (xy 20.380956 -5.30218) (xy 20.380956 -5.217484)
			(xy 20.389007 -5.13317) (xy 20.405036 -5.050004) (xy 20.428897 -4.968737) (xy 20.460376 -4.890107)
			(xy 20.499187 -4.814826) (xy 20.544977 -4.743574) (xy 20.597333 -4.676998) (xy 20.655781 -4.6157)
			(xy 20.719791 -4.560235) (xy 20.788783 -4.511106) (xy 20.862133 -4.468757) (xy 20.939176 -4.433573)
			(xy 21.019215 -4.405871) (xy 21.101524 -4.385903) (xy 21.185359 -4.37385) (xy 21.26996 -4.36982)
			(xy 21.354561 -4.37385) (xy 21.438396 -4.385903) (xy 21.520705 -4.405871) (xy 21.600744 -4.433573)
			(xy 21.677787 -4.468757) (xy 21.751137 -4.511106) (xy 21.820129 -4.560235) (xy 21.884139 -4.6157)
			(xy 21.942587 -4.676998) (xy 21.994943 -4.743574) (xy 22.040733 -4.814826) (xy 22.079544 -4.890107)
			(xy 22.111023 -4.968737) (xy 22.134884 -5.050004) (xy 22.150913 -5.13317) (xy 22.158964 -5.217484)
			(xy 22.159468 -5.259832) (xy 22.158964 -5.30218) (xy 22.150913 -5.386494) (xy 22.134884 -5.46966)
			(xy 22.111023 -5.550927) (xy 22.079544 -5.629557) (xy 22.040733 -5.704838) (xy 21.994943 -5.77609)
			(xy 21.942587 -5.842666) (xy 21.884139 -5.903964) (xy 21.820129 -5.959429) (xy 21.751137 -6.008558)
			(xy 21.677787 -6.050907) (xy 21.600744 -6.086091) (xy 21.520705 -6.113793) (xy 21.438396 -6.133761)
			(xy 21.354561 -6.145814) (xy 21.26996 -6.149845) (xy 21.185359 -6.145814) (xy 21.101524 -6.133761)
			(xy 21.019215 -6.113793) (xy 20.939176 -6.086091) (xy 20.862133 -6.050907) (xy 20.788783 -6.008558)
			(xy 20.719791 -5.959429) (xy 20.655781 -5.903964) (xy 20.597333 -5.842666) (xy 20.544977 -5.77609)
			(xy 20.499187 -5.704838) (xy 20.460376 -5.629557) (xy 20.428897 -5.550927) (xy 20.405036 -5.46966)
			(xy 20.389007 -5.386494) (xy 20.380956 -5.30218) (xy 19.618964 -5.30218) (xy 19.610913 -5.386494)
			(xy 19.594884 -5.46966) (xy 19.571023 -5.550927) (xy 19.539544 -5.629557) (xy 19.500733 -5.704838)
			(xy 19.454943 -5.77609) (xy 19.402587 -5.842666) (xy 19.344139 -5.903964) (xy 19.280129 -5.959429)
			(xy 19.211137 -6.008558) (xy 19.137787 -6.050907) (xy 19.060744 -6.086091) (xy 18.980705 -6.113793)
			(xy 18.898396 -6.133761) (xy 18.814561 -6.145814) (xy 18.72996 -6.149845) (xy 18.645359 -6.145814)
			(xy 18.561524 -6.133761) (xy 18.479215 -6.113793) (xy 18.399176 -6.086091) (xy 18.322133 -6.050907)
			(xy 18.248783 -6.008558) (xy 18.179791 -5.959429) (xy 18.115781 -5.903964) (xy 18.057333 -5.842666)
			(xy 18.004977 -5.77609) (xy 17.959187 -5.704838) (xy 17.920376 -5.629557) (xy 17.888897 -5.550927)
			(xy 17.865036 -5.46966) (xy 17.849007 -5.386494) (xy 17.840956 -5.30218) (xy 15.53711 -5.30218) (xy 18.07711 -7.84218)
			(xy 19.110956 -7.84218) (xy 19.110956 -7.757484) (xy 19.119007 -7.67317) (xy 19.135036 -7.590004)
			(xy 19.158897 -7.508737) (xy 19.190376 -7.430107) (xy 19.229187 -7.354826) (xy 19.274977 -7.283574)
			(xy 19.327333 -7.216998) (xy 19.385781 -7.1557) (xy 19.449791 -7.100235) (xy 19.518783 -7.051106)
			(xy 19.592133 -7.008757) (xy 19.669176 -6.973573) (xy 19.749215 -6.945871) (xy 19.831524 -6.925903)
			(xy 19.915359 -6.91385) (xy 19.99996 -6.90982) (xy 20.084561 -6.91385) (xy 20.168396 -6.925903) (xy 20.250705 -6.945871)
			(xy 20.330744 -6.973573) (xy 20.407787 -7.008757) (xy 20.481137 -7.051106) (xy 20.550129 -7.100235)
			(xy 20.614139 -7.1557) (xy 20.672587 -7.216998) (xy 20.724943 -7.283574) (xy 20.770733 -7.354826)
			(xy 20.809544 -7.430107) (xy 20.841023 -7.508737) (xy 20.864884 -7.590004) (xy 20.880913 -7.67317)
			(xy 20.888964 -7.757484) (xy 20.889468 -7.799832) (xy 20.888964 -7.84218) (xy 20.880913 -7.926494)
			(xy 20.864884 -8.00966) (xy 20.841023 -8.090927) (xy 20.809544 -8.169557) (xy 20.770733 -8.244838)
			(xy 20.724943 -8.31609) (xy 20.672587 -8.382666) (xy 20.614139 -8.443964) (xy 20.550129 -8.499429)
			(xy 20.481137 -8.548558) (xy 20.407787 -8.590907) (xy 20.330744 -8.626091) (xy 20.250705 -8.653793)
			(xy 20.168396 -8.673761) (xy 20.084561 -8.685814) (xy 19.99996 -8.689845) (xy 19.915359 -8.685814)
			(xy 19.831524 -8.673761) (xy 19.749215 -8.653793) (xy 19.669176 -8.626091) (xy 19.592133 -8.590907)
			(xy 19.518783 -8.548558) (xy 19.449791 -8.499429) (xy 19.385781 -8.443964) (xy 19.327333 -8.382666)
			(xy 19.274977 -8.31609) (xy 19.229187 -8.244838) (xy 19.190376 -8.169557) (xy 19.158897 -8.090927)
			(xy 19.135036 -8.00966) (xy 19.119007 -7.926494) (xy 19.110956 -7.84218) (xy 18.07711 -7.84218) (xy 23.822152 -13.587222)
			(xy 33.920682 -13.587222) (xy 33.924753 -13.5316) (xy 33.936879 -13.477163) (xy 33.956802 -13.425072)
			(xy 33.984098 -13.376437) (xy 34.018184 -13.332294) (xy 34.058333 -13.293585) (xy 34.103691 -13.261134)
			(xy 34.153291 -13.235633) (xy 34.206075 -13.217626) (xy 34.260918 -13.207496) (xy 34.316652 -13.205459)
			(xy 34.372089 -13.211559) (xy 34.426046 -13.225665) (xy 34.477375 -13.247477) (xy 34.524981 -13.276531)
			(xy 34.567849 -13.312206) (xy 34.605066 -13.353743) (xy 34.635839 -13.400256) (xy 34.659511 -13.450753)
			(xy 34.675579 -13.50416) (xy 34.683699 -13.559336) (xy 34.684208 -13.587222) (xy 34.683699 -13.615108)
			(xy 34.675579 -13.670284) (xy 34.659511 -13.723691) (xy 34.635839 -13.774188) (xy 34.605066 -13.820701)
			(xy 34.567849 -13.862238) (xy 34.524981 -13.897913) (xy 34.477375 -13.926967) (xy 34.426046 -13.948779)
			(xy 34.372089 -13.962885) (xy 34.316652 -13.968985) (xy 34.260918 -13.966948) (xy 34.206075 -13.956818)
			(xy 34.153291 -13.938811) (xy 34.103691 -13.91331) (xy 34.058333 -13.880859) (xy 34.018184 -13.84215)
			(xy 33.984098 -13.798007) (xy 33.956802 -13.749372) (xy 33.936879 -13.697281) (xy 33.924753 -13.642844)
			(xy 33.920682 -13.587222) (xy 23.822152 -13.587222) (xy 24.70658 -14.47165) (xy 26.138632 -14.47165)
			(xy 26.463752 -14.79677) (xy 34.553142 -14.79677) (xy 34.557213 -14.741148) (xy 34.569339 -14.686711)
			(xy 34.589262 -14.63462) (xy 34.616558 -14.585985) (xy 34.650644 -14.541842) (xy 34.690793 -14.503133)
			(xy 34.736151 -14.470682) (xy 34.785751 -14.445181) (xy 34.838535 -14.427174) (xy 34.893378 -14.417044)
			(xy 34.949112 -14.415007) (xy 35.004549 -14.421107) (xy 35.058506 -14.435213) (xy 35.109835 -14.457025)
			(xy 35.157441 -14.486079) (xy 35.200309 -14.521754) (xy 35.237526 -14.563291) (xy 35.268299 -14.609804)
			(xy 35.291971 -14.660301) (xy 35.308039 -14.713708) (xy 35.316159 -14.768884) (xy 35.316668 -14.79677)
			(xy 35.316159 -14.824656) (xy 35.308039 -14.879832) (xy 35.291971 -14.933239) (xy 35.268299 -14.983736)
			(xy 35.237526 -15.030249) (xy 35.200309 -15.071786) (xy 35.157441 -15.107461) (xy 35.109835 -15.136515)
			(xy 35.058506 -15.158327) (xy 35.004549 -15.172433) (xy 34.949112 -15.178533) (xy 34.893378 -15.176496)
			(xy 34.838535 -15.166366) (xy 34.785751 -15.148359) (xy 34.736151 -15.122858) (xy 34.690793 -15.090407)
			(xy 34.650644 -15.051698) (xy 34.616558 -15.007555) (xy 34.589262 -14.95892) (xy 34.569339 -14.906829)
			(xy 34.557213 -14.852392) (xy 34.553142 -14.79677) (xy 26.463752 -14.79677) (xy 26.580846 -14.913864)
			(xy 27.653996 -14.913864) (xy 28.005143 -15.265011) (xy 36.50158 -15.265011) (xy 36.50767 -15.20966)
			(xy 36.521744 -15.155782) (xy 36.543501 -15.104523) (xy 36.572479 -15.056973) (xy 36.608064 -15.01414)
			(xy 36.649498 -14.976937) (xy 36.6959 -14.946153) (xy 36.746286 -14.922443) (xy 36.799583 -14.906311)
			(xy 36.854659 -14.898099) (xy 36.910345 -14.897983) (xy 36.965455 -14.905964) (xy 37.018819 -14.921872)
			(xy 37.069304 -14.945371) (xy 37.115835 -14.97596) (xy 37.157424 -15.01299) (xy 37.175694 -15.034006)
			(xy 37.190968 -15.051382) (xy 37.22659 -15.080889) (xy 37.266964 -15.103463) (xy 37.310756 -15.118359)
			(xy 37.35652 -15.125085) (xy 37.402746 -15.123419) (xy 37.447907 -15.113415) (xy 37.490513 -15.095405)
			(xy 37.529156 -15.069982) (xy 37.562561 -15.037986) (xy 37.576506 -15.019528) (xy 37.59315 -14.997202)
			(xy 37.63194 -14.957246) (xy 37.676127 -14.923354) (xy 37.724772 -14.896247) (xy 37.776842 -14.8765)
			(xy 37.831229 -14.864534) (xy 37.886778 -14.860603) (xy 37.942308 -14.86479) (xy 37.99664 -14.877006)
			(xy 38.048618 -14.896991) (xy 38.097138 -14.924322) (xy 38.141169 -14.958416) (xy 38.158663 -14.976602)
			(xy 39.498522 -14.976602) (xy 39.502593 -14.92098) (xy 39.514719 -14.866543) (xy 39.534642 -14.814452)
			(xy 39.561938 -14.765817) (xy 39.596024 -14.721674) (xy 39.636173 -14.682965) (xy 39.681531 -14.650514)
			(xy 39.731131 -14.625013) (xy 39.783915 -14.607006) (xy 39.838758 -14.596876) (xy 39.894492 -14.594839)
			(xy 39.949929 -14.600939) (xy 40.003886 -14.615045) (xy 40.055215 -14.636857) (xy 40.102821 -14.665911)
			(xy 40.145689 -14.701586) (xy 40.182906 -14.743123) (xy 40.213679 -14.789636) (xy 40.237351 -14.840133)
			(xy 40.253419 -14.89354) (xy 40.261539 -14.948716) (xy 40.262048 -14.976602) (xy 40.261539 -15.004488)
			(xy 40.253419 -15.059664) (xy 40.237351 -15.113071) (xy 40.213679 -15.163568) (xy 40.182906 -15.210081)
			(xy 40.145689 -15.251618) (xy 40.102821 -15.287293) (xy 40.055215 -15.316347) (xy 40.003886 -15.338159)
			(xy 39.949929 -15.352265) (xy 39.894492 -15.358365) (xy 39.838758 -15.356328) (xy 39.783915 -15.346198)
			(xy 39.731131 -15.328191) (xy 39.681531 -15.30269) (xy 39.636173 -15.270239) (xy 39.596024 -15.23153)
			(xy 39.561938 -15.187387) (xy 39.534642 -15.138752) (xy 39.514719 -15.086661) (xy 39.502593 -15.032224)
			(xy 39.498522 -14.976602) (xy 38.158663 -14.976602) (xy 38.179775 -14.99855) (xy 38.212135 -15.043871)
			(xy 38.237562 -15.093415) (xy 38.255516 -15.146129) (xy 38.265615 -15.200894) (xy 38.267644 -15.256545)
			(xy 38.26156 -15.311899) (xy 38.247492 -15.365781) (xy 38.22574 -15.417045) (xy 38.196766 -15.464602)
			(xy 38.161185 -15.507441) (xy 38.119754 -15.544651) (xy 38.073353 -15.575442) (xy 38.022969 -15.59916)
			(xy 37.969671 -15.6153) (xy 37.914593 -15.623519) (xy 37.858905 -15.623643) (xy 37.803791 -15.615669)
			(xy 37.750422 -15.599767) (xy 37.699932 -15.576274) (xy 37.653394 -15.54569) (xy 37.611798 -15.508665)
			(xy 37.593524 -15.48765) (xy 37.578227 -15.470297) (xy 37.542606 -15.440795) (xy 37.502236 -15.418224)
			(xy 37.458449 -15.40333) (xy 37.412689 -15.396604) (xy 37.366468 -15.398268) (xy 37.321311 -15.408268)
			(xy 37.278707 -15.426272) (xy 37.240065 -15.451687) (xy 37.206658 -15.483674) (xy 37.192712 -15.502128)
			(xy 37.17601 -15.524411) (xy 37.137218 -15.564361) (xy 37.09303 -15.598247) (xy 37.044385 -15.625349)
			(xy 36.992316 -15.645089) (xy 36.93793 -15.657049) (xy 36.882383 -15.660975) (xy 36.826856 -15.656783)
			(xy 36.772529 -15.644562) (xy 36.720555 -15.624572) (xy 36.67204 -15.597237) (xy 36.628015 -15.56314)
			(xy 36.589416 -15.523003) (xy 36.557062 -15.477681) (xy 36.531641 -15.428137) (xy 36.513694 -15.375423)
			(xy 36.503603 -15.32066) (xy 36.50158 -15.265011) (xy 28.005143 -15.265011) (xy 29.998416 -17.258284)
			(xy 40.64635 -17.258284) (xy 41.57218 -16.332454) (xy 41.57218 -15.923006) (xy 41.571619 -15.905843)
			(xy 41.562476 -15.872757) (xy 41.544849 -15.843303) (xy 41.53281 -15.831058) (xy 41.512786 -15.811319)
			(xy 41.478178 -15.767005) (xy 41.450451 -15.718091) (xy 41.430205 -15.665636) (xy 41.417879 -15.610778)
			(xy 41.41374 -15.554704) (xy 41.417878 -15.49863) (xy 41.430203 -15.443772) (xy 41.450448 -15.391317)
			(xy 41.478174 -15.342402) (xy 41.512781 -15.298088) (xy 41.53281 -15.278354) (xy 41.544847 -15.266107)
			(xy 41.56248 -15.236657) (xy 41.571615 -15.203569) (xy 41.57218 -15.186406) (xy 41.57218 -15.156434)
			(xy 41.753282 -15.156434) (xy 42.054272 -14.855444) (xy 43.082972 -14.855444) (xy 43.325796 -15.098268)
			(xy 56.137556 -15.098268) (xy 56.97474 -14.261084) (xy 63.861442 -14.261084) (xy 63.884328 -14.260602)
			(xy 63.929361 -14.252415) (xy 63.9722 -14.236294) (xy 64.011459 -14.212762) (xy 64.045869 -14.182579)
			(xy 64.074316 -14.146721) (xy 64.095881 -14.106347) (xy 64.109867 -14.062765) (xy 64.11582 -14.017382)
			(xy 64.11355 -13.971667) (xy 64.103128 -13.927097) (xy 64.084893 -13.885115) (xy 64.072516 -13.86586)
			(xy 64.057373 -13.843131) (xy 64.033041 -13.794234) (xy 64.015929 -13.742368) (xy 64.006388 -13.688592)
			(xy 64.004611 -13.634005) (xy 64.010635 -13.579722) (xy 64.024338 -13.526853) (xy 64.045438 -13.476477)
			(xy 64.073505 -13.429625) (xy 64.107966 -13.387253) (xy 64.148116 -13.350227) (xy 64.193135 -13.319305)
			(xy 64.242102 -13.295116) (xy 64.294019 -13.278157) (xy 64.347822 -13.268773) (xy 64.402414 -13.267156)
			(xy 64.456679 -13.27334) (xy 64.509508 -13.287197) (xy 64.559822 -13.308445) (xy 64.606591 -13.336649)
			(xy 64.648862 -13.371234) (xy 64.68577 -13.411492) (xy 64.716561 -13.456602) (xy 64.740605 -13.50564)
			(xy 64.757412 -13.557606) (xy 64.766638 -13.611437) (xy 64.768095 -13.666033) (xy 64.761753 -13.72028)
			(xy 64.747741 -13.773068) (xy 64.726345 -13.823319) (xy 64.698004 -13.870006) (xy 64.663295 -13.912175)
			(xy 64.622929 -13.948964) (xy 64.600582 -13.964666) (xy 64.576452 -13.980922) (xy 64.512952 -14.091158)
			(xy 64.52235 -14.153134) (xy 64.525033 -14.167941) (xy 64.536401 -14.195795) (xy 64.553976 -14.220211)
			(xy 64.576781 -14.239833) (xy 64.603546 -14.253569) (xy 64.632784 -14.260654) (xy 64.647826 -14.261084)
			(xy 64.910716 -14.261084) (xy 65.031874 -14.16558) (xy 65.044066 -14.13002) (xy 65.053403 -14.104288)
			(xy 65.078394 -14.055585) (xy 65.09385 -14.032992) (xy 65.107329 -14.014532) (xy 65.13802 -13.980658)
			(xy 65.155064 -13.965428) (xy 65.174114 -13.948664) (xy 65.203324 -13.890244) (xy 65.210771 -13.873627)
			(xy 65.216978 -13.837764) (xy 65.212835 -13.801605) (xy 65.206372 -13.78458) (xy 65.195963 -13.758547)
			(xy 65.182034 -13.704241) (xy 65.176209 -13.64848) (xy 65.178613 -13.592467) (xy 65.189194 -13.53741)
			(xy 65.207725 -13.484497) (xy 65.220342 -13.45946) (xy 65.232832 -13.436611) (xy 65.263076 -13.394222)
			(xy 65.298805 -13.356342) (xy 65.339356 -13.323674) (xy 65.383973 -13.296826) (xy 65.431828 -13.276297)
			(xy 65.482031 -13.26247) (xy 65.533648 -13.255601) (xy 65.559686 -13.255244) (xy 65.586886 -13.255839)
			(xy 65.640708 -13.263789) (xy 65.692855 -13.279301) (xy 65.742271 -13.302061) (xy 65.787954 -13.331608)
			(xy 65.828978 -13.367342) (xy 65.864512 -13.40854) (xy 65.893835 -13.454367) (xy 65.916353 -13.503893)
			(xy 65.93161 -13.556116) (xy 65.939297 -13.609975) (xy 65.939257 -13.664381) (xy 65.931492 -13.718229)
			(xy 65.916159 -13.770429) (xy 65.893568 -13.819922) (xy 65.864178 -13.865706) (xy 65.828584 -13.906853)
			(xy 65.808352 -13.925042) (xy 65.789048 -13.941806) (xy 65.759838 -14.000226) (xy 65.752384 -14.016842)
			(xy 65.746165 -14.052708) (xy 65.750303 -14.088873) (xy 65.75679 -14.10589) (xy 65.765934 -14.130274)
			(xy 65.778126 -14.16558) (xy 65.899284 -14.261084) (xy 68.838572 -14.261084) (xy 68.844668 -14.254988)
			(xy 69.389244 -14.79931) (xy 88.218264 -14.79931) (xy 88.234949 -14.798815) (xy 88.267179 -14.790166)
			(xy 88.296061 -14.77345) (xy 88.30818 -14.761972) (xy 88.38692 -14.682978) (xy 88.38946 -14.634464)
			(xy 88.391624 -14.604955) (xy 88.403932 -14.547084) (xy 88.425045 -14.491813) (xy 88.454455 -14.440474)
			(xy 88.472518 -14.41704) (xy 88.492573 -14.392975) (xy 88.539168 -14.351111) (xy 88.565228 -14.333728)
			(xy 88.590628 -14.317472) (xy 88.65616 -14.207744) (xy 88.65616 -9.252966) (xy 88.334596 -8.931402)
			(xy 87.27186 -8.931402) (xy 87.04326 -9.160002) (xy 87.04326 -12.535154) (xy 86.05647 -13.521944)
			(xy 75.535028 -13.521944) (xy 75.520485 -13.522342) (xy 75.492158 -13.528938) (xy 75.466067 -13.541793)
			(xy 75.443576 -13.560234) (xy 75.425858 -13.5833) (xy 75.419458 -13.596366) (xy 75.407735 -13.621007)
			(xy 75.37829 -13.666947) (xy 75.342599 -13.708223) (xy 75.301391 -13.743992) (xy 75.255508 -13.773525)
			(xy 75.205884 -13.796218) (xy 75.153533 -13.81161) (xy 75.099523 -13.819385) (xy 75.044957 -13.819385)
			(xy 74.990947 -13.81161) (xy 74.938596 -13.796218) (xy 74.888972 -13.773525) (xy 74.843089 -13.743992)
			(xy 74.801881 -13.708223) (xy 74.76619 -13.666947) (xy 74.736745 -13.621007) (xy 74.725022 -13.596366)
			(xy 74.718634 -13.583298) (xy 74.7009 -13.560249) (xy 74.678403 -13.54182) (xy 74.652314 -13.52897)
			(xy 74.623993 -13.522367) (xy 74.609452 -13.521944) (xy 70.490334 -13.521944) (xy 70.473324 -13.522455)
			(xy 70.440498 -13.531386) (xy 70.411201 -13.548677) (xy 70.387516 -13.573096) (xy 70.378828 -13.58773)
			(xy 70.364775 -13.612234) (xy 70.330561 -13.657179) (xy 70.290092 -13.696586) (xy 70.244254 -13.729594)
			(xy 70.194049 -13.75548) (xy 70.140575 -13.773678) (xy 70.085002 -13.78379) (xy 70.028545 -13.785596)
			(xy 69.972439 -13.779054) (xy 69.917911 -13.76431) (xy 69.866155 -13.741684) (xy 69.818302 -13.711672)
			(xy 69.775398 -13.674931) (xy 69.738383 -13.632263) (xy 69.708065 -13.584603) (xy 69.685109 -13.532992)
			(xy 69.670015 -13.47856) (xy 69.663115 -13.422498) (xy 69.664559 -13.36603) (xy 69.674315 -13.310393)
			(xy 69.692171 -13.256804) (xy 69.704458 -13.231368) (xy 69.718174 -13.20419) (xy 69.718174 -13.069824)
			(xy 69.3166 -12.66825) (xy 69.3166 -11.364722) (xy 70.03542 -10.645902) (xy 70.03542 -10.108438)
			(xy 70.03493 -10.091779) (xy 70.026316 -10.059594) (xy 70.009664 -10.030736) (xy 69.98611 -10.007171)
			(xy 69.95726 -9.990507) (xy 69.925079 -9.981878) (xy 69.90842 -9.981438) (xy 68.790058 -9.981438)
			(xy 68.767617 -9.98192) (xy 68.723435 -9.989812) (xy 68.681326 -10.005343) (xy 68.642601 -10.028031)
			(xy 68.608464 -10.057169) (xy 68.579977 -10.091851) (xy 68.558027 -10.130998) (xy 68.543295 -10.173393)
			(xy 68.53624 -10.217717) (xy 68.537081 -10.262591) (xy 68.540884 -10.284714) (xy 68.545768 -10.311967)
			(xy 68.548541 -10.367263) (xy 68.543292 -10.422379) (xy 68.530132 -10.476158) (xy 68.509337 -10.52747)
			(xy 68.481344 -10.575237) (xy 68.44674 -10.618457) (xy 68.406253 -10.656221) (xy 68.360733 -10.687736)
			(xy 68.311135 -10.712341) (xy 68.258501 -10.729519) (xy 68.203938 -10.738908) (xy 68.14859 -10.740312)
			(xy 68.093621 -10.733702) (xy 68.040184 -10.719215) (xy 68.014596 -10.70864) (xy 67.991564 -10.698177)
			(xy 67.948244 -10.672051) (xy 67.928236 -10.65657) (xy 67.914488 -10.646314) (xy 67.882963 -10.632834)
			(xy 67.848988 -10.62823) (xy 67.815013 -10.632834) (xy 67.783488 -10.646314) (xy 67.76974 -10.65657)
			(xy 67.749735 -10.672054) (xy 67.706409 -10.698169) (xy 67.68338 -10.70864) (xy 67.657791 -10.719202)
			(xy 67.604356 -10.733663) (xy 67.549392 -10.740253) (xy 67.494052 -10.738833) (xy 67.439499 -10.729433)
			(xy 67.386875 -10.71225) (xy 67.337287 -10.687645) (xy 67.291773 -10.656134) (xy 67.251288 -10.618379)
			(xy 67.216683 -10.57517) (xy 67.188684 -10.527416) (xy 67.167877 -10.476117) (xy 67.1547 -10.422351)
			(xy 67.149428 -10.367245) (xy 67.152173 -10.311956) (xy 67.157092 -10.284714) (xy 67.160981 -10.2626)
			(xy 67.161823 -10.217713) (xy 67.154766 -10.173376) (xy 67.140028 -10.130968) (xy 67.11807 -10.091809)
			(xy 67.089572 -10.057117) (xy 67.055423 -10.027972) (xy 67.016685 -10.005279) (xy 66.974562 -9.989746)
			(xy 66.930366 -9.981855) (xy 66.907918 -9.981438) (xy 65.469516 -9.981438) (xy 64.994536 -10.456418)
			(xy 50.908712 -10.456418) (xy 50.327052 -11.038078) (xy 41.6814 -11.038078) (xy 41.572434 -11.102086)
			(xy 41.556178 -11.126978) (xy 41.540422 -11.15015) (xy 41.503208 -11.192041) (xy 41.460269 -11.228041)
			(xy 41.412526 -11.257373) (xy 41.361007 -11.279409) (xy 41.30682 -11.293673) (xy 41.251129 -11.299859)
			(xy 41.195132 -11.297834) (xy 41.140033 -11.287643) (xy 41.087017 -11.269502) (xy 41.037224 -11.243804)
			(xy 40.991724 -11.2111) (xy 40.951496 -11.172094) (xy 40.917406 -11.127624) (xy 40.903398 -11.103356)
			(xy 40.903398 -11.103102) (xy 40.894716 -11.088593) (xy 40.871087 -11.064425) (xy 40.84193 -11.047329)
			(xy 40.809301 -11.03851) (xy 40.7924 -11.038078) (xy 39.54399 -11.038078) (xy 39.1922 -11.389868)
			(xy 39.1922 -11.716004) (xy 41.613326 -11.716004) (xy 41.617397 -11.660382) (xy 41.629523 -11.605945)
			(xy 41.649446 -11.553854) (xy 41.676742 -11.505219) (xy 41.710828 -11.461076) (xy 41.750977 -11.422367)
			(xy 41.796335 -11.389916) (xy 41.845935 -11.364415) (xy 41.898719 -11.346408) (xy 41.953562 -11.336278)
			(xy 42.009296 -11.334241) (xy 42.064733 -11.340341) (xy 42.11869 -11.354447) (xy 42.170019 -11.376259)
			(xy 42.217625 -11.405313) (xy 42.260493 -11.440988) (xy 42.29771 -11.482525) (xy 42.328483 -11.529038)
			(xy 42.352155 -11.579535) (xy 42.354106 -11.586021) (xy 56.080728 -11.586021) (xy 56.080729 -11.529954)
			(xy 56.088938 -11.474491) (xy 56.105177 -11.420827) (xy 56.129096 -11.370118) (xy 56.16018 -11.323457)
			(xy 56.197759 -11.281848) (xy 56.241024 -11.246187) (xy 56.289043 -11.217244) (xy 56.340781 -11.195642)
			(xy 56.395124 -11.181845) (xy 56.450901 -11.176151) (xy 56.506911 -11.178683) (xy 56.561946 -11.189387)
			(xy 56.614823 -11.208031) (xy 56.664401 -11.234214) (xy 56.709612 -11.267372) (xy 56.749483 -11.30679)
			(xy 56.766714 -11.328908) (xy 56.78127 -11.347406) (xy 56.816004 -11.379167) (xy 56.855992 -11.403989)
			(xy 56.899866 -11.421025) (xy 56.946127 -11.42969) (xy 56.993193 -11.42969) (xy 57.039454 -11.421025)
			(xy 57.083328 -11.403989) (xy 57.123316 -11.379167) (xy 57.15805 -11.347406) (xy 57.172606 -11.328908)
			(xy 57.189329 -11.307444) (xy 57.227855 -11.269021) (xy 57.271448 -11.236462) (xy 57.319225 -11.210426)
			(xy 57.370216 -11.191442) (xy 57.423388 -11.179895) (xy 57.47766 -11.17602) (xy 57.531932 -11.179895)
			(xy 57.585104 -11.191442) (xy 57.636095 -11.210426) (xy 57.683872 -11.236462) (xy 57.727465 -11.269021)
			(xy 57.765991 -11.307444) (xy 57.782714 -11.328908) (xy 57.79727 -11.347406) (xy 57.832004 -11.379167)
			(xy 57.871992 -11.403989) (xy 57.915866 -11.421025) (xy 57.962127 -11.42969) (xy 58.009193 -11.42969)
			(xy 58.055454 -11.421025) (xy 58.099328 -11.403989) (xy 58.139316 -11.379167) (xy 58.17405 -11.347406)
			(xy 58.188606 -11.328908) (xy 58.205824 -11.306771) (xy 58.245701 -11.267337) (xy 58.290921 -11.234165)
			(xy 58.340509 -11.20797) (xy 58.393398 -11.189316) (xy 58.448447 -11.178605) (xy 58.504472 -11.176067)
			(xy 58.560264 -11.181758) (xy 58.614623 -11.195555) (xy 58.666376 -11.21716) (xy 58.714409 -11.246109)
			(xy 58.757687 -11.281777) (xy 58.795278 -11.323395) (xy 58.826372 -11.370069) (xy 58.850298 -11.420791)
			(xy 58.866542 -11.474469) (xy 58.874753 -11.529946) (xy 58.874755 -11.586021) (xy 61.160728 -11.586021)
			(xy 61.160729 -11.529954) (xy 61.168938 -11.474491) (xy 61.185177 -11.420827) (xy 61.209096 -11.370118)
			(xy 61.24018 -11.323457) (xy 61.277759 -11.281848) (xy 61.321024 -11.246187) (xy 61.369043 -11.217244)
			(xy 61.420781 -11.195642) (xy 61.475124 -11.181845) (xy 61.530901 -11.176151) (xy 61.586911 -11.178683)
			(xy 61.641946 -11.189387) (xy 61.694823 -11.208031) (xy 61.744401 -11.234214) (xy 61.789612 -11.267372)
			(xy 61.829483 -11.30679) (xy 61.846714 -11.328908) (xy 61.86127 -11.347406) (xy 61.896004 -11.379167)
			(xy 61.935992 -11.403989) (xy 61.979866 -11.421025) (xy 62.026127 -11.42969) (xy 62.073193 -11.42969)
			(xy 62.119454 -11.421025) (xy 62.163328 -11.403989) (xy 62.203316 -11.379167) (xy 62.23805 -11.347406)
			(xy 62.252606 -11.328908) (xy 62.269329 -11.307444) (xy 62.307855 -11.269021) (xy 62.351448 -11.236462)
			(xy 62.399225 -11.210426) (xy 62.450216 -11.191442) (xy 62.503388 -11.179895) (xy 62.55766 -11.17602)
			(xy 62.611932 -11.179895) (xy 62.665104 -11.191442) (xy 62.716095 -11.210426) (xy 62.763872 -11.236462)
			(xy 62.807465 -11.269021) (xy 62.845991 -11.307444) (xy 62.862714 -11.328908) (xy 62.87727 -11.347406)
			(xy 62.912004 -11.379167) (xy 62.951992 -11.403989) (xy 62.995866 -11.421025) (xy 63.042127 -11.42969)
			(xy 63.089193 -11.42969) (xy 63.135454 -11.421025) (xy 63.179328 -11.403989) (xy 63.219316 -11.379167)
			(xy 63.25405 -11.347406) (xy 63.268606 -11.328908) (xy 63.285824 -11.306771) (xy 63.325701 -11.267337)
			(xy 63.370921 -11.234165) (xy 63.420509 -11.20797) (xy 63.473398 -11.189316) (xy 63.528447 -11.178605)
			(xy 63.584472 -11.176067) (xy 63.640264 -11.181758) (xy 63.694623 -11.195555) (xy 63.746376 -11.21716)
			(xy 63.794409 -11.246109) (xy 63.837687 -11.281777) (xy 63.875278 -11.323395) (xy 63.906372 -11.370069)
			(xy 63.930298 -11.420791) (xy 63.946542 -11.474469) (xy 63.954753 -11.529946) (xy 63.954755 -11.586028)
			(xy 63.946548 -11.641506) (xy 63.930307 -11.695186) (xy 63.906384 -11.745909) (xy 63.875294 -11.792584)
			(xy 63.837706 -11.834206) (xy 63.79443 -11.869876) (xy 63.746399 -11.898828) (xy 63.694647 -11.920437)
			(xy 63.64029 -11.934237) (xy 63.584498 -11.939932) (xy 63.528473 -11.937398) (xy 63.473422 -11.926691)
			(xy 63.420532 -11.908041) (xy 63.370942 -11.881849) (xy 63.32572 -11.84868) (xy 63.285841 -11.809249)
			(xy 63.268606 -11.787124) (xy 63.25405 -11.768626) (xy 63.219316 -11.736865) (xy 63.179328 -11.712043)
			(xy 63.135454 -11.695007) (xy 63.089193 -11.686342) (xy 63.042127 -11.686342) (xy 62.995866 -11.695007)
			(xy 62.951992 -11.712043) (xy 62.912004 -11.736865) (xy 62.87727 -11.768626) (xy 62.862714 -11.787124)
			(xy 62.845991 -11.808588) (xy 62.807465 -11.847011) (xy 62.763872 -11.87957) (xy 62.716095 -11.905606)
			(xy 62.665104 -11.92459) (xy 62.611932 -11.936137) (xy 62.55766 -11.940012) (xy 62.503388 -11.936137)
			(xy 62.450216 -11.92459) (xy 62.399225 -11.905606) (xy 62.351448 -11.87957) (xy 62.307855 -11.847011)
			(xy 62.269329 -11.808588) (xy 62.252606 -11.787124) (xy 62.23805 -11.768626) (xy 62.203316 -11.736865)
			(xy 62.163328 -11.712043) (xy 62.119454 -11.695007) (xy 62.073193 -11.686342) (xy 62.026127 -11.686342)
			(xy 61.979866 -11.695007) (xy 61.935992 -11.712043) (xy 61.896004 -11.736865) (xy 61.86127 -11.768626)
			(xy 61.846714 -11.787124) (xy 61.829466 -11.809229) (xy 61.789592 -11.848645) (xy 61.744379 -11.8818)
			(xy 61.694799 -11.90798) (xy 61.641922 -11.92662) (xy 61.586885 -11.93732) (xy 61.530875 -11.939848)
			(xy 61.475098 -11.934151) (xy 61.420756 -11.92035) (xy 61.36902 -11.898744) (xy 61.321003 -11.869798)
			(xy 61.27774 -11.834135) (xy 61.240164 -11.792523) (xy 61.209083 -11.74586) (xy 61.185168 -11.695149)
			(xy 61.168933 -11.641484) (xy 61.160728 -11.586021) (xy 58.874755 -11.586021) (xy 58.874755 -11.586028)
			(xy 58.866548 -11.641506) (xy 58.850307 -11.695186) (xy 58.826384 -11.745909) (xy 58.795294 -11.792584)
			(xy 58.757706 -11.834206) (xy 58.71443 -11.869876) (xy 58.666399 -11.898828) (xy 58.614647 -11.920437)
			(xy 58.56029 -11.934237) (xy 58.504498 -11.939932) (xy 58.448473 -11.937398) (xy 58.393422 -11.926691)
			(xy 58.340532 -11.908041) (xy 58.290942 -11.881849) (xy 58.24572 -11.84868) (xy 58.205841 -11.809249)
			(xy 58.188606 -11.787124) (xy 58.17405 -11.768626) (xy 58.139316 -11.736865) (xy 58.099328 -11.712043)
			(xy 58.055454 -11.695007) (xy 58.009193 -11.686342) (xy 57.962127 -11.686342) (xy 57.915866 -11.695007)
			(xy 57.871992 -11.712043) (xy 57.832004 -11.736865) (xy 57.79727 -11.768626) (xy 57.782714 -11.787124)
			(xy 57.765991 -11.808588) (xy 57.727465 -11.847011) (xy 57.683872 -11.87957) (xy 57.636095 -11.905606)
			(xy 57.585104 -11.92459) (xy 57.531932 -11.936137) (xy 57.47766 -11.940012) (xy 57.423388 -11.936137)
			(xy 57.370216 -11.92459) (xy 57.319225 -11.905606) (xy 57.271448 -11.87957) (xy 57.227855 -11.847011)
			(xy 57.189329 -11.808588) (xy 57.172606 -11.787124) (xy 57.15805 -11.768626) (xy 57.123316 -11.736865)
			(xy 57.083328 -11.712043) (xy 57.039454 -11.695007) (xy 56.993193 -11.686342) (xy 56.946127 -11.686342)
			(xy 56.899866 -11.695007) (xy 56.855992 -11.712043) (xy 56.816004 -11.736865) (xy 56.78127 -11.768626)
			(xy 56.766714 -11.787124) (xy 56.749466 -11.809229) (xy 56.709592 -11.848645) (xy 56.664379 -11.8818)
			(xy 56.614799 -11.90798) (xy 56.561922 -11.92662) (xy 56.506885 -11.93732) (xy 56.450875 -11.939848)
			(xy 56.395098 -11.934151) (xy 56.340756 -11.92035) (xy 56.28902 -11.898744) (xy 56.241003 -11.869798)
			(xy 56.19774 -11.834135) (xy 56.160164 -11.792523) (xy 56.129083 -11.74586) (xy 56.105168 -11.695149)
			(xy 56.088933 -11.641484) (xy 56.080728 -11.586021) (xy 42.354106 -11.586021) (xy 42.368223 -11.632942)
			(xy 42.376343 -11.688118) (xy 42.376852 -11.716004) (xy 42.376343 -11.74389) (xy 42.368223 -11.799066)
			(xy 42.352155 -11.852473) (xy 42.328483 -11.90297) (xy 42.29771 -11.949483) (xy 42.260493 -11.99102)
			(xy 42.217625 -12.026695) (xy 42.170019 -12.055749) (xy 42.11869 -12.077561) (xy 42.064733 -12.091667)
			(xy 42.009296 -12.097767) (xy 41.953562 -12.09573) (xy 41.898719 -12.0856) (xy 41.845935 -12.067593)
			(xy 41.796335 -12.042092) (xy 41.750977 -12.009641) (xy 41.710828 -11.970932) (xy 41.676742 -11.926789)
			(xy 41.649446 -11.878154) (xy 41.629523 -11.826063) (xy 41.617397 -11.771626) (xy 41.613326 -11.716004)
			(xy 39.1922 -11.716004) (xy 39.1922 -12.540742) (xy 38.865556 -12.867386) (xy 38.487604 -12.867386)
			(xy 38.465097 -12.867895) (xy 38.420794 -12.875874) (xy 38.378589 -12.89153) (xy 38.339801 -12.914372)
			(xy 38.305641 -12.943689) (xy 38.303365 -12.946477) (xy 42.581813 -12.946477) (xy 42.58581 -12.890776)
			(xy 42.597884 -12.836252) (xy 42.617776 -12.78407) (xy 42.645062 -12.735345) (xy 42.67916 -12.691118)
			(xy 42.71934 -12.652334) (xy 42.764744 -12.619821) (xy 42.814402 -12.594274) (xy 42.867254 -12.576238)
			(xy 42.922171 -12.566098) (xy 42.977979 -12.564072) (xy 43.033486 -12.570203) (xy 43.06062 -12.57681)
			(xy 43.082652 -12.582114) (xy 43.127826 -12.585664) (xy 43.172914 -12.581147) (xy 43.216485 -12.568704)
			(xy 43.257159 -12.548731) (xy 43.293646 -12.521861) (xy 43.324789 -12.488946) (xy 43.349601 -12.451029)
			(xy 43.367294 -12.409313) (xy 43.372786 -12.387326) (xy 43.379392 -12.360556) (xy 43.399198 -12.3091)
			(xy 43.426204 -12.261031) (xy 43.459848 -12.21735) (xy 43.499429 -12.178967) (xy 43.544124 -12.146681)
			(xy 43.593 -12.121165) (xy 43.64504 -12.10295) (xy 43.69916 -12.092416) (xy 43.754233 -12.089782)
			(xy 43.809112 -12.095103) (xy 43.862653 -12.108268) (xy 43.913741 -12.129003) (xy 43.961313 -12.156876)
			(xy 43.983148 -12.173712) (xy 43.996896 -12.183968) (xy 44.028421 -12.197448) (xy 44.062396 -12.202052)
			(xy 44.096371 -12.197448) (xy 44.127896 -12.183968) (xy 44.141644 -12.173712) (xy 44.164305 -12.156245)
			(xy 44.213825 -12.127587) (xy 44.267068 -12.106645) (xy 44.322842 -12.093889) (xy 44.379896 -12.089604)
			(xy 44.43695 -12.093889) (xy 44.492724 -12.106645) (xy 44.545967 -12.127587) (xy 44.595487 -12.156245)
			(xy 44.618148 -12.173712) (xy 44.631896 -12.183968) (xy 44.663421 -12.197448) (xy 44.697396 -12.202052)
			(xy 44.731371 -12.197448) (xy 44.762896 -12.183968) (xy 44.776644 -12.173712) (xy 44.798761 -12.156767)
			(xy 44.846873 -12.128676) (xy 44.898559 -12.107882) (xy 44.95272 -12.094828) (xy 45.008204 -12.089792)
			(xy 45.06383 -12.09288) (xy 45.118416 -12.104028) (xy 45.170799 -12.122997) (xy 45.219866 -12.149384)
			(xy 45.264572 -12.182628) (xy 45.303967 -12.222022) (xy 45.337212 -12.266728) (xy 45.3636 -12.315794)
			(xy 45.38257 -12.368177) (xy 45.393719 -12.422762) (xy 45.396808 -12.478388) (xy 45.391773 -12.533872)
			(xy 45.37872 -12.588034) (xy 45.357927 -12.63972) (xy 45.329837 -12.687832) (xy 45.312838 -12.709906)
			(xy 45.302629 -12.723685) (xy 45.289148 -12.755199) (xy 45.284537 -12.789164) (xy 45.289128 -12.823131)
			(xy 45.302592 -12.854653) (xy 45.312838 -12.868402) (xy 45.330261 -12.891096) (xy 45.358922 -12.940608)
			(xy 45.363478 -12.952188) (xy 55.83163 -12.952188) (xy 55.839836 -12.896708) (xy 55.856074 -12.843026)
			(xy 55.879995 -12.7923) (xy 55.911085 -12.745621) (xy 55.948672 -12.703997) (xy 55.991948 -12.668323)
			(xy 56.039979 -12.639368) (xy 56.091732 -12.617756) (xy 56.146091 -12.603953) (xy 56.201884 -12.598255)
			(xy 56.257911 -12.600786) (xy 56.312964 -12.611492) (xy 56.365857 -12.63014) (xy 56.41545 -12.656331)
			(xy 56.460675 -12.689499) (xy 56.500557 -12.728929) (xy 56.517794 -12.751054) (xy 56.53235 -12.769552)
			(xy 56.567084 -12.801313) (xy 56.607072 -12.826135) (xy 56.650946 -12.843171) (xy 56.697207 -12.851836)
			(xy 56.744273 -12.851836) (xy 56.790534 -12.843171) (xy 56.834408 -12.826135) (xy 56.874396 -12.801313)
			(xy 56.90913 -12.769552) (xy 56.923686 -12.751054) (xy 56.940409 -12.72959) (xy 56.978935 -12.691167)
			(xy 57.022528 -12.658608) (xy 57.070305 -12.632572) (xy 57.121296 -12.613588) (xy 57.174468 -12.602041)
			(xy 57.22874 -12.598166) (xy 57.283012 -12.602041) (xy 57.336184 -12.613588) (xy 57.387175 -12.632572)
			(xy 57.434952 -12.658608) (xy 57.478545 -12.691167) (xy 57.517071 -12.72959) (xy 57.533794 -12.751054)
			(xy 57.54835 -12.769552) (xy 57.583084 -12.801313) (xy 57.623072 -12.826135) (xy 57.666946 -12.843171)
			(xy 57.713207 -12.851836) (xy 57.760273 -12.851836) (xy 57.806534 -12.843171) (xy 57.850408 -12.826135)
			(xy 57.890396 -12.801313) (xy 57.92513 -12.769552) (xy 57.939686 -12.751054) (xy 57.956156 -12.729799)
			(xy 57.99417 -12.691767) (xy 58.037148 -12.659449) (xy 58.084238 -12.633486) (xy 58.134506 -12.614391)
			(xy 58.186958 -12.602543) (xy 58.240553 -12.598177) (xy 58.29423 -12.601379) (xy 58.346927 -12.612085)
			(xy 58.397598 -12.630084) (xy 58.44524 -12.655019) (xy 58.488909 -12.686396) (xy 58.52774 -12.723594)
			(xy 58.544714 -12.74445) (xy 58.559517 -12.762561) (xy 58.594642 -12.793446) (xy 58.634823 -12.817385)
			(xy 58.678706 -12.83357) (xy 58.724809 -12.841455) (xy 58.771576 -12.840774) (xy 58.81743 -12.831549)
			(xy 58.860823 -12.814093) (xy 58.90029 -12.788994) (xy 58.9345 -12.757099) (xy 58.948828 -12.738608)
			(xy 58.965861 -12.716437) (xy 59.005303 -12.676813) (xy 59.050105 -12.64337) (xy 59.099309 -12.616825)
			(xy 59.151861 -12.597746) (xy 59.206634 -12.586542) (xy 59.262456 -12.583452) (xy 59.318132 -12.588543)
			(xy 59.372468 -12.601706) (xy 59.424301 -12.622659) (xy 59.47252 -12.650953) (xy 59.516094 -12.685983)
			(xy 59.554088 -12.726996) (xy 59.585688 -12.773117) (xy 59.610219 -12.823355) (xy 59.627154 -12.876637)
			(xy 59.63448 -12.921673) (xy 59.895643 -12.921673) (xy 59.903851 -12.866195) (xy 59.920091 -12.812516)
			(xy 59.944014 -12.761792) (xy 59.975104 -12.715116) (xy 60.012692 -12.673495) (xy 60.055968 -12.637824)
			(xy 60.103999 -12.608872) (xy 60.155751 -12.587263) (xy 60.210109 -12.573462) (xy 60.265901 -12.567767)
			(xy 60.321926 -12.5703) (xy 60.376976 -12.581007) (xy 60.429867 -12.599658) (xy 60.479457 -12.625849)
			(xy 60.524679 -12.659018) (xy 60.564559 -12.698449) (xy 60.581794 -12.720574) (xy 60.59635 -12.739072)
			(xy 60.631084 -12.770833) (xy 60.671072 -12.795655) (xy 60.714946 -12.812691) (xy 60.761207 -12.821356)
			(xy 60.808273 -12.821356) (xy 60.854534 -12.812691) (xy 60.898408 -12.795655) (xy 60.938396 -12.770833)
			(xy 60.97313 -12.739072) (xy 60.987686 -12.720574) (xy 61.00419 -12.69949) (xy 61.042033 -12.661614)
			(xy 61.084799 -12.629401) (xy 61.131648 -12.603482) (xy 61.181661 -12.584369) (xy 61.233855 -12.572435)
			(xy 61.287204 -12.567915) (xy 61.340662 -12.570898) (xy 61.393178 -12.581326) (xy 61.44372 -12.598993)
			(xy 61.491295 -12.623552) (xy 61.53497 -12.654522) (xy 61.573886 -12.691294) (xy 61.590936 -12.711938)
			(xy 61.60601 -12.730056) (xy 61.641697 -12.760837) (xy 61.682444 -12.784517) (xy 61.726856 -12.800284)
			(xy 61.773412 -12.807599) (xy 61.82052 -12.806212) (xy 61.866565 -12.796169) (xy 61.909972 -12.777816)
			(xy 61.949255 -12.751779) (xy 61.983069 -12.718951) (xy 61.997082 -12.7) (xy 62.013334 -12.677723)
			(xy 62.051309 -12.637736) (xy 62.094643 -12.603632) (xy 62.142434 -12.576119) (xy 62.193687 -12.555771)
			(xy 62.247336 -12.543012) (xy 62.302262 -12.538107) (xy 62.357323 -12.541159) (xy 62.411371 -12.552104)
			(xy 62.463281 -12.570713) (xy 62.511972 -12.5966) (xy 62.55643 -12.629226) (xy 62.59573 -12.66791)
			(xy 62.612778 -12.689586) (xy 62.627358 -12.707956) (xy 62.662091 -12.739463) (xy 62.702016 -12.764063)
			(xy 62.745775 -12.780921) (xy 62.791885 -12.789464) (xy 62.838779 -12.789402) (xy 62.884867 -12.780738)
			(xy 62.928582 -12.763766) (xy 62.968441 -12.739061) (xy 63.003092 -12.707463) (xy 63.017654 -12.689078)
			(xy 63.034926 -12.667031) (xy 63.074842 -12.627746) (xy 63.120071 -12.594718) (xy 63.169643 -12.568656)
			(xy 63.222491 -12.550119) (xy 63.277482 -12.539507) (xy 63.333432 -12.537046) (xy 63.389142 -12.542791)
			(xy 63.443414 -12.556616) (xy 63.495082 -12.578226) (xy 63.543036 -12.607157) (xy 63.586246 -12.642786)
			(xy 63.623785 -12.684348) (xy 63.654845 -12.730951) (xy 63.678759 -12.781594) (xy 63.695014 -12.835188)
			(xy 63.703261 -12.890582) (xy 63.703322 -12.946587) (xy 63.695196 -13.002) (xy 63.679057 -13.055629)
			(xy 63.655253 -13.106324) (xy 63.624295 -13.152994) (xy 63.586847 -13.194639) (xy 63.543715 -13.230362)
			(xy 63.495824 -13.259396) (xy 63.444203 -13.281119) (xy 63.389962 -13.295063) (xy 63.334264 -13.300928)
			(xy 63.278308 -13.29859) (xy 63.223295 -13.288097) (xy 63.170406 -13.269676) (xy 63.120778 -13.243722)
			(xy 63.075477 -13.210792) (xy 63.035475 -13.171594) (xy 63.018162 -13.14958) (xy 63.003537 -13.131246)
			(xy 62.968814 -13.099731) (xy 62.928898 -13.075124) (xy 62.885144 -13.058259) (xy 62.839038 -13.04971)
			(xy 62.792146 -13.049767) (xy 62.746061 -13.058428) (xy 62.702348 -13.075399) (xy 62.662492 -13.100104)
			(xy 62.627845 -13.131703) (xy 62.613286 -13.150088) (xy 62.596855 -13.17119) (xy 62.558962 -13.208935)
			(xy 62.516171 -13.241019) (xy 62.469318 -13.266815) (xy 62.419323 -13.285816) (xy 62.367165 -13.29765)
			(xy 62.313866 -13.302086) (xy 62.260469 -13.299037) (xy 62.20802 -13.288562) (xy 62.157549 -13.270866)
			(xy 62.110042 -13.246297) (xy 62.066431 -13.215336) (xy 62.02757 -13.178588) (xy 62.010544 -13.157962)
			(xy 61.995493 -13.139824) (xy 61.959803 -13.109042) (xy 61.919052 -13.085363) (xy 61.874636 -13.069597)
			(xy 61.828077 -13.062284) (xy 61.780966 -13.063674) (xy 61.734919 -13.073719) (xy 61.69151 -13.092076)
			(xy 61.652226 -13.118115) (xy 61.618412 -13.150947) (xy 61.604398 -13.1699) (xy 61.588042 -13.192179)
			(xy 61.549959 -13.232233) (xy 61.506497 -13.266375) (xy 61.458564 -13.293889) (xy 61.407163 -13.314201)
			(xy 61.353369 -13.326885) (xy 61.298309 -13.331676) (xy 61.243133 -13.328474) (xy 61.188997 -13.317346)
			(xy 61.137032 -13.298525) (xy 61.088325 -13.272404) (xy 61.043896 -13.23953) (xy 61.004675 -13.200591)
			(xy 60.987686 -13.17879) (xy 60.97313 -13.160292) (xy 60.938396 -13.128531) (xy 60.898408 -13.103709)
			(xy 60.854534 -13.086673) (xy 60.808273 -13.078008) (xy 60.761207 -13.078008) (xy 60.714946 -13.086673)
			(xy 60.671072 -13.103709) (xy 60.631084 -13.128531) (xy 60.59635 -13.160292) (xy 60.581794 -13.17879)
			(xy 60.564578 -13.200929) (xy 60.524701 -13.240363) (xy 60.479481 -13.273535) (xy 60.429893 -13.299731)
			(xy 60.377004 -13.318385) (xy 60.321954 -13.329096) (xy 60.26593 -13.331634) (xy 60.210137 -13.325943)
			(xy 60.155778 -13.312147) (xy 60.104025 -13.290541) (xy 60.055991 -13.261593) (xy 60.012713 -13.225925)
			(xy 59.975122 -13.184307) (xy 59.944028 -13.137633) (xy 59.920101 -13.086911) (xy 59.903857 -13.033233)
			(xy 59.895646 -12.977755) (xy 59.895643 -12.921673) (xy 59.63448 -12.921673) (xy 59.636131 -12.931819)
			(xy 59.636957 -12.987721) (xy 59.629615 -13.043144) (xy 59.614262 -13.096902) (xy 59.591227 -13.147844)
			(xy 59.561003 -13.194878) (xy 59.524238 -13.236997) (xy 59.481719 -13.273299) (xy 59.434356 -13.303005)
			(xy 59.383165 -13.325481) (xy 59.329242 -13.340244) (xy 59.273741 -13.346978) (xy 59.217852 -13.34554)
			(xy 59.162771 -13.335959) (xy 59.109679 -13.318441) (xy 59.059712 -13.293362) (xy 59.013941 -13.261258)
			(xy 58.973345 -13.222817) (xy 58.955686 -13.201142) (xy 58.940883 -13.183032) (xy 58.905758 -13.152148)
			(xy 58.865576 -13.128209) (xy 58.821693 -13.112025) (xy 58.775591 -13.10414) (xy 58.728824 -13.104821)
			(xy 58.682971 -13.114045) (xy 58.639578 -13.131501) (xy 58.600111 -13.156599) (xy 58.5659 -13.188494)
			(xy 58.551572 -13.206984) (xy 58.53498 -13.228694) (xy 58.496555 -13.267541) (xy 58.452982 -13.300511)
			(xy 58.405152 -13.326929) (xy 58.354043 -13.346255) (xy 58.3007 -13.358093) (xy 58.246214 -13.362201)
			(xy 58.191699 -13.358496) (xy 58.13827 -13.347053) (xy 58.087019 -13.328106) (xy 58.038994 -13.302043)
			(xy 57.995179 -13.269397) (xy 57.956467 -13.230834) (xy 57.939686 -13.20927) (xy 57.92513 -13.190772)
			(xy 57.890396 -13.159011) (xy 57.850408 -13.134189) (xy 57.806534 -13.117153) (xy 57.760273 -13.108488)
			(xy 57.713207 -13.108488) (xy 57.666946 -13.117153) (xy 57.623072 -13.134189) (xy 57.583084 -13.159011)
			(xy 57.54835 -13.190772) (xy 57.533794 -13.20927) (xy 57.517071 -13.230734) (xy 57.478545 -13.269157)
			(xy 57.434952 -13.301716) (xy 57.387175 -13.327752) (xy 57.336184 -13.346736) (xy 57.283012 -13.358283)
			(xy 57.22874 -13.362158) (xy 57.174468 -13.358283) (xy 57.121296 -13.346736) (xy 57.070305 -13.327752)
			(xy 57.022528 -13.301716) (xy 56.978935 -13.269157) (xy 56.940409 -13.230734) (xy 56.923686 -13.20927)
			(xy 56.90913 -13.190772) (xy 56.874396 -13.159011) (xy 56.834408 -13.134189) (xy 56.790534 -13.117153)
			(xy 56.744273 -13.108488) (xy 56.697207 -13.108488) (xy 56.650946 -13.117153) (xy 56.607072 -13.134189)
			(xy 56.567084 -13.159011) (xy 56.53235 -13.190772) (xy 56.517794 -13.20927) (xy 56.500597 -13.231425)
			(xy 56.460721 -13.270862) (xy 56.415501 -13.304037) (xy 56.365912 -13.330235) (xy 56.313023 -13.348892)
			(xy 56.257972 -13.359606) (xy 56.201945 -13.362147) (xy 56.146151 -13.356458) (xy 56.09179 -13.342663)
			(xy 56.040034 -13.321059) (xy 55.991997 -13.292112) (xy 55.948716 -13.256445) (xy 55.911122 -13.214827)
			(xy 55.880025 -13.168153) (xy 55.856096 -13.117431) (xy 55.839849 -13.063751) (xy 55.831635 -13.008272)
			(xy 55.83163 -12.952188) (xy 45.363478 -12.952188) (xy 45.379868 -12.993846) (xy 45.392629 -13.049615)
			(xy 45.396918 -13.106664) (xy 45.39264 -13.163714) (xy 45.37989 -13.219485) (xy 45.358954 -13.272727)
			(xy 45.330302 -13.322245) (xy 45.312838 -13.344906) (xy 45.302629 -13.358685) (xy 45.289148 -13.390199)
			(xy 45.284537 -13.424164) (xy 45.289128 -13.458131) (xy 45.302592 -13.489653) (xy 45.312838 -13.503402)
			(xy 45.329797 -13.525512) (xy 45.357898 -13.573625) (xy 45.378701 -13.625314) (xy 45.391763 -13.679479)
			(xy 45.396806 -13.734969) (xy 45.393722 -13.790602) (xy 45.382577 -13.845194) (xy 45.363608 -13.897584)
			(xy 45.33722 -13.946657) (xy 45.303972 -13.991369) (xy 45.264574 -14.030768) (xy 45.219863 -14.064016)
			(xy 45.17079 -14.090406) (xy 45.1184 -14.109375) (xy 45.063808 -14.120521) (xy 45.008175 -14.123606)
			(xy 44.952686 -14.118564) (xy 44.89852 -14.105503) (xy 44.84683 -14.084701) (xy 44.798717 -14.056601)
			(xy 44.776644 -14.039596) (xy 44.762896 -14.02934) (xy 44.731371 -14.01586) (xy 44.697396 -14.011256)
			(xy 44.663421 -14.01586) (xy 44.631896 -14.02934) (xy 44.618148 -14.039596) (xy 44.595487 -14.057063)
			(xy 44.545967 -14.085721) (xy 44.492724 -14.106663) (xy 44.43695 -14.119419) (xy 44.379896 -14.123704)
			(xy 44.322842 -14.119419) (xy 44.267068 -14.106663) (xy 44.213825 -14.085721) (xy 44.164305 -14.057063)
			(xy 44.141644 -14.039596) (xy 44.127896 -14.02934) (xy 44.096371 -14.01586) (xy 44.062396 -14.011256)
			(xy 44.028421 -14.01586) (xy 43.996896 -14.02934) (xy 43.983148 -14.039596) (xy 43.961115 -14.056658)
			(xy 43.912994 -14.084763) (xy 43.861296 -14.105568) (xy 43.807121 -14.11863) (xy 43.751622 -14.123672)
			(xy 43.69598 -14.120586) (xy 43.641379 -14.109438) (xy 43.588981 -14.090465) (xy 43.539901 -14.064071)
			(xy 43.495182 -14.030817) (xy 43.455778 -13.991412) (xy 43.422525 -13.946693) (xy 43.396132 -13.897612)
			(xy 43.37716 -13.845213) (xy 43.366013 -13.790612) (xy 43.362928 -13.73497) (xy 43.367971 -13.679472)
			(xy 43.381035 -13.625297) (xy 43.401841 -13.573599) (xy 43.429946 -13.525479) (xy 43.446954 -13.503402)
			(xy 43.45725 -13.489682) (xy 43.47072 -13.458147) (xy 43.475315 -13.424164) (xy 43.470701 -13.390184)
			(xy 43.457213 -13.358656) (xy 43.446954 -13.344906) (xy 43.434791 -13.329275) (xy 43.413412 -13.295933)
			(xy 43.404282 -13.278358) (xy 43.39645 -13.263958) (xy 43.374777 -13.239383) (xy 43.347551 -13.221152)
			(xy 43.316575 -13.210472) (xy 43.283899 -13.20805) (xy 43.251686 -13.214045) (xy 43.222069 -13.228062)
			(xy 43.20921 -13.238226) (xy 43.187467 -13.255753) (xy 43.139913 -13.285032) (xy 43.088599 -13.307066)
			(xy 43.034621 -13.321385) (xy 42.979132 -13.327684) (xy 42.923318 -13.325826) (xy 42.868371 -13.315853)
			(xy 42.815465 -13.297976) (xy 42.76573 -13.272579) (xy 42.720228 -13.240203) (xy 42.679931 -13.201541)
			(xy 42.6457 -13.157417) (xy 42.618267 -13.108775) (xy 42.598217 -13.056654) (xy 42.585978 -13.002166)
			(xy 42.581813 -12.946477) (xy 38.303365 -12.946477) (xy 38.277177 -12.978563) (xy 38.255299 -13.017904)
			(xy 38.240691 -13.060483) (xy 38.233809 -13.104969) (xy 38.233858 -13.127482) (xy 38.234046 -13.155174)
			(xy 38.227394 -13.210148) (xy 38.212867 -13.263584) (xy 38.190769 -13.31436) (xy 38.161564 -13.361408)
			(xy 38.125867 -13.403742) (xy 38.084425 -13.440471) (xy 38.03811 -13.470826) (xy 37.998993 -13.489008)
			(xy 38.426495 -13.489008) (xy 38.431084 -13.4343) (xy 38.44347 -13.380814) (xy 38.463395 -13.329656)
			(xy 38.49045 -13.281884) (xy 38.524074 -13.238484) (xy 38.563573 -13.200353) (xy 38.608131 -13.16828)
			(xy 38.656827 -13.142926) (xy 38.708655 -13.124815) (xy 38.735508 -13.1191) (xy 38.808406 -13.104876)
			(xy 38.881304 -13.1191) (xy 38.908157 -13.124815) (xy 38.959985 -13.142926) (xy 39.008681 -13.16828)
			(xy 39.053239 -13.200353) (xy 39.092738 -13.238484) (xy 39.126362 -13.281884) (xy 39.153417 -13.329656)
			(xy 39.173342 -13.380814) (xy 39.185728 -13.4343) (xy 39.190317 -13.489008) (xy 39.187014 -13.54381)
			(xy 39.175889 -13.597572) (xy 39.157171 -13.649184) (xy 39.131247 -13.697578) (xy 39.098652 -13.741756)
			(xy 39.06006 -13.780805) (xy 39.016268 -13.813917) (xy 38.968181 -13.840408) (xy 38.916793 -13.859731)
			(xy 38.863165 -13.871487) (xy 38.808406 -13.875433) (xy 38.753647 -13.871487) (xy 38.700019 -13.859731)
			(xy 38.648631 -13.840408) (xy 38.600544 -13.813917) (xy 38.556752 -13.780805) (xy 38.51816 -13.741756)
			(xy 38.485565 -13.697578) (xy 38.459641 -13.649184) (xy 38.440923 -13.597572) (xy 38.429798 -13.54381)
			(xy 38.426495 -13.489008) (xy 37.998993 -13.489008) (xy 37.987894 -13.494167) (xy 37.934832 -13.510006)
			(xy 37.880038 -13.51801) (xy 37.824662 -13.51801) (xy 37.769868 -13.510006) (xy 37.716806 -13.494167)
			(xy 37.66659 -13.470826) (xy 37.620275 -13.440471) (xy 37.578833 -13.403742) (xy 37.543136 -13.361408)
			(xy 37.513931 -13.31436) (xy 37.491833 -13.263584) (xy 37.477306 -13.210148) (xy 37.470654 -13.155174)
			(xy 37.470842 -13.127482) (xy 37.470905 -13.104964) (xy 37.46405 -13.060464) (xy 37.449458 -13.017869)
			(xy 37.427586 -12.978513) (xy 37.39912 -12.943629) (xy 37.36495 -12.914308) (xy 37.326147 -12.89147)
			(xy 37.283926 -12.87583) (xy 37.239608 -12.867876) (xy 37.217096 -12.867386) (xy 37.171122 -12.867386)
			(xy 37.147626 -12.867935) (xy 37.101437 -12.876583) (xy 37.057624 -12.893571) (xy 37.017678 -12.918321)
			(xy 36.982959 -12.949988) (xy 36.95465 -12.987496) (xy 36.933715 -13.029566) (xy 36.920866 -13.074767)
			(xy 36.916541 -13.121559) (xy 36.918138 -13.145008) (xy 36.92122 -13.173031) (xy 36.920082 -13.229395)
			(xy 36.910663 -13.284977) (xy 36.893168 -13.338569) (xy 36.867979 -13.389003) (xy 36.835642 -13.435182)
			(xy 36.796862 -13.4761) (xy 36.752484 -13.510867) (xy 36.703473 -13.538725) (xy 36.650897 -13.559069)
			(xy 36.595899 -13.571455) (xy 36.539678 -13.575614) (xy 36.483457 -13.571455) (xy 36.428459 -13.559069)
			(xy 36.375883 -13.538725) (xy 36.326872 -13.510867) (xy 36.282494 -13.4761) (xy 36.243714 -13.435182)
			(xy 36.211377 -13.389003) (xy 36.186188 -13.338569) (xy 36.168693 -13.284977) (xy 36.159274 -13.229395)
			(xy 36.158136 -13.173031) (xy 36.161218 -13.145008) (xy 36.162905 -13.121556) (xy 36.158609 -13.074737)
			(xy 36.145775 -13.029508) (xy 36.12484 -12.987411) (xy 36.09652 -12.949883) (xy 36.061779 -12.918205)
			(xy 36.021805 -12.893458) (xy 35.97796 -12.876486) (xy 35.931742 -12.867868) (xy 35.908234 -12.867386)
			(xy 34.17189 -12.867386) (xy 22.91334 -1.608836) (xy 6.15188 -1.608836) (xy 5.428234 -2.332482) (xy 8.213596 -2.332482)
			(xy 8.217667 -2.27686) (xy 8.229793 -2.222423) (xy 8.249716 -2.170332) (xy 8.277012 -2.121697) (xy 8.311098 -2.077554)
			(xy 8.351247 -2.038845) (xy 8.396605 -2.006394) (xy 8.446205 -1.980893) (xy 8.498989 -1.962886) (xy 8.553832 -1.952756)
			(xy 8.609566 -1.950719) (xy 8.665003 -1.956819) (xy 8.71896 -1.970925) (xy 8.770289 -1.992737) (xy 8.817895 -2.021791)
			(xy 8.860763 -2.057466) (xy 8.89798 -2.099003) (xy 8.928753 -2.145516) (xy 8.952425 -2.196013) (xy 8.968493 -2.24942)
			(xy 8.976613 -2.304596) (xy 8.977122 -2.332482) (xy 8.976613 -2.360368) (xy 8.968493 -2.415544) (xy 8.952425 -2.468951)
			(xy 8.928753 -2.519448) (xy 8.89798 -2.565961) (xy 8.860763 -2.607498) (xy 8.817895 -2.643173) (xy 8.770289 -2.672227)
			(xy 8.71896 -2.694039) (xy 8.665003 -2.708145) (xy 8.609566 -2.714245) (xy 8.553832 -2.712208) (xy 8.498989 -2.702078)
			(xy 8.446205 -2.684071) (xy 8.396605 -2.65857) (xy 8.351247 -2.626119) (xy 8.311098 -2.58741) (xy 8.277012 -2.543267)
			(xy 8.249716 -2.494632) (xy 8.229793 -2.442541) (xy 8.217667 -2.388104) (xy 8.213596 -2.332482) (xy 5.428234 -2.332482)
			(xy 4.61518 -3.145536) (xy 4.61518 -3.306737) (xy 5.710903 -3.306737) (xy 5.713454 -3.250794) (xy 5.724156 -3.195825)
			(xy 5.74278 -3.143012) (xy 5.768925 -3.093488) (xy 5.80203 -3.048319) (xy 5.841382 -3.008476) (xy 5.886137 -2.974814)
			(xy 5.935332 -2.948056) (xy 5.987911 -2.928779) (xy 6.042743 -2.917395) (xy 6.09865 -2.914151) (xy 6.154431 -2.919115)
			(xy 6.208886 -2.932181) (xy 6.260847 -2.953067) (xy 6.309195 -2.981326) (xy 6.352893 -3.01635) (xy 6.391 -3.057386)
			(xy 6.422698 -3.103553) (xy 6.447307 -3.153857) (xy 6.464296 -3.207219) (xy 6.473301 -3.262491) (xy 6.474129 -3.318487)
			(xy 6.466761 -3.374001) (xy 6.451357 -3.427842) (xy 6.428246 -3.478852) (xy 6.4135 -3.50266) (xy 6.401813 -3.521722)
			(xy 6.38455 -3.562964) (xy 6.374765 -3.606588) (xy 6.372759 -3.651252) (xy 6.378595 -3.695578) (xy 6.392093 -3.738201)
			(xy 6.412836 -3.777806) (xy 6.440185 -3.813174) (xy 6.456426 -3.828542) (xy 6.476852 -3.847702) (xy 6.512418 -3.890962)
			(xy 6.541277 -3.938957) (xy 6.562809 -3.990656) (xy 6.576551 -4.044947) (xy 6.582208 -4.100663) (xy 6.579658 -4.156609)
			(xy 6.568956 -4.21158) (xy 6.550333 -4.264396) (xy 6.524188 -4.313922) (xy 6.491083 -4.359093) (xy 6.45173 -4.398938)
			(xy 6.406974 -4.432603) (xy 6.357777 -4.459362) (xy 6.305197 -4.47864) (xy 6.250363 -4.490025) (xy 6.194454 -4.49327)
			(xy 6.138671 -4.488307) (xy 6.084213 -4.475241) (xy 6.032251 -4.454354) (xy 5.9839 -4.426094) (xy 5.940201 -4.391069)
			(xy 5.902092 -4.350032) (xy 5.870393 -4.303864) (xy 5.845783 -4.253557) (xy 5.828793 -4.200194) (xy 5.819788 -4.144919)
			(xy 5.81896 -4.088922) (xy 5.826328 -4.033406) (xy 5.841734 -3.979563) (xy 5.864845 -3.928551) (xy 5.879592 -3.904742)
			(xy 5.891279 -3.885679) (xy 5.908543 -3.844438) (xy 5.918328 -3.800813) (xy 5.920334 -3.756149) (xy 5.914498 -3.711823)
			(xy 5.901001 -3.6692) (xy 5.880257 -3.629595) (xy 5.852907 -3.594228) (xy 5.836666 -3.57886) (xy 5.816248 -3.559693)
			(xy 5.780685 -3.516433) (xy 5.751828 -3.468439) (xy 5.730299 -3.416742) (xy 5.716559 -3.362452) (xy 5.710903 -3.306737)
			(xy 4.61518 -3.306737) (xy 4.61518 -6.709156) (xy 6.833614 -6.709156) (xy 6.837685 -6.653534) (xy 6.849811 -6.599097)
			(xy 6.869734 -6.547006) (xy 6.89703 -6.498371) (xy 6.931116 -6.454228) (xy 6.971265 -6.415519) (xy 7.016623 -6.383068)
			(xy 7.066223 -6.357567) (xy 7.119007 -6.33956) (xy 7.17385 -6.32943) (xy 7.229584 -6.327393) (xy 7.285021 -6.333493)
			(xy 7.338978 -6.347599) (xy 7.390307 -6.369411) (xy 7.437913 -6.398465) (xy 7.440108 -6.400292) (xy 8.977374 -6.400292)
			(xy 8.981445 -6.34467) (xy 8.993571 -6.290233) (xy 9.013494 -6.238142) (xy 9.04079 -6.189507) (xy 9.074876 -6.145364)
			(xy 9.115025 -6.106655) (xy 9.160383 -6.074204) (xy 9.209983 -6.048703) (xy 9.262767 -6.030696) (xy 9.31761 -6.020566)
			(xy 9.373344 -6.018529) (xy 9.428781 -6.024629) (xy 9.482738 -6.038735) (xy 9.534067 -6.060547) (xy 9.581673 -6.089601)
			(xy 9.624541 -6.125276) (xy 9.661758 -6.166813) (xy 9.692531 -6.213326) (xy 9.716203 -6.263823) (xy 9.732271 -6.31723)
			(xy 9.740391 -6.372406) (xy 9.7409 -6.400292) (xy 9.740391 -6.428178) (xy 9.732271 -6.483354) (xy 9.716203 -6.536761)
			(xy 9.692531 -6.587258) (xy 9.661758 -6.633771) (xy 9.624541 -6.675308) (xy 9.581673 -6.710983) (xy 9.534067 -6.740037)
			(xy 9.482738 -6.761849) (xy 9.428781 -6.775955) (xy 9.373344 -6.782055) (xy 9.31761 -6.780018) (xy 9.262767 -6.769888)
			(xy 9.209983 -6.751881) (xy 9.160383 -6.72638) (xy 9.115025 -6.693929) (xy 9.074876 -6.65522) (xy 9.04079 -6.611077)
			(xy 9.013494 -6.562442) (xy 8.993571 -6.510351) (xy 8.981445 -6.455914) (xy 8.977374 -6.400292) (xy 7.440108 -6.400292)
			(xy 7.480781 -6.43414) (xy 7.517998 -6.475677) (xy 7.548771 -6.52219) (xy 7.572443 -6.572687) (xy 7.588511 -6.626094)
			(xy 7.596631 -6.68127) (xy 7.59714 -6.709156) (xy 7.596631 -6.737042) (xy 7.588511 -6.792218) (xy 7.572443 -6.845625)
			(xy 7.548771 -6.896122) (xy 7.517998 -6.942635) (xy 7.480781 -6.984172) (xy 7.437913 -7.019847) (xy 7.390307 -7.048901)
			(xy 7.338978 -7.070713) (xy 7.285021 -7.084819) (xy 7.229584 -7.090919) (xy 7.17385 -7.088882) (xy 7.119007 -7.078752)
			(xy 7.066223 -7.060745) (xy 7.016623 -7.035244) (xy 6.971265 -7.002793) (xy 6.931116 -6.964084) (xy 6.89703 -6.919941)
			(xy 6.869734 -6.871306) (xy 6.849811 -6.819215) (xy 6.837685 -6.764778) (xy 6.833614 -6.709156) (xy 4.61518 -6.709156)
			(xy 4.61518 -7.725156) (xy 6.756398 -7.725156) (xy 6.760469 -7.669534) (xy 6.772595 -7.615097) (xy 6.792518 -7.563006)
			(xy 6.819814 -7.514371) (xy 6.8539 -7.470228) (xy 6.894049 -7.431519) (xy 6.939407 -7.399068) (xy 6.989007 -7.373567)
			(xy 7.041791 -7.35556) (xy 7.096634 -7.34543) (xy 7.152368 -7.343393) (xy 7.207805 -7.349493) (xy 7.261762 -7.363599)
			(xy 7.313091 -7.385411) (xy 7.360697 -7.414465) (xy 7.403565 -7.45014) (xy 7.440782 -7.491677) (xy 7.471555 -7.53819)
			(xy 7.495227 -7.588687) (xy 7.511295 -7.642094) (xy 7.519415 -7.69727) (xy 7.519924 -7.725156) (xy 7.519415 -7.753042)
			(xy 7.511295 -7.808218) (xy 7.495227 -7.861625) (xy 7.471555 -7.912122) (xy 7.440782 -7.958635) (xy 7.403565 -8.000172)
			(xy 7.360697 -8.035847) (xy 7.313091 -8.064901) (xy 7.261762 -8.086713) (xy 7.207805 -8.100819) (xy 7.152368 -8.106919)
			(xy 7.096634 -8.104882) (xy 7.041791 -8.094752) (xy 6.989007 -8.076745) (xy 6.939407 -8.051244) (xy 6.894049 -8.018793)
			(xy 6.8539 -7.980084) (xy 6.819814 -7.935941) (xy 6.792518 -7.887306) (xy 6.772595 -7.835215) (xy 6.760469 -7.780778)
			(xy 6.756398 -7.725156) (xy 4.61518 -7.725156) (xy 4.61518 -8.198612) (xy 8.911334 -8.198612) (xy 8.915405 -8.14299)
			(xy 8.927531 -8.088553) (xy 8.947454 -8.036462) (xy 8.97475 -7.987827) (xy 9.008836 -7.943684) (xy 9.048985 -7.904975)
			(xy 9.094343 -7.872524) (xy 9.143943 -7.847023) (xy 9.196727 -7.829016) (xy 9.25157 -7.818886) (xy 9.307304 -7.816849)
			(xy 9.362741 -7.822949) (xy 9.416698 -7.837055) (xy 9.468027 -7.858867) (xy 9.515633 -7.887921) (xy 9.558501 -7.923596)
			(xy 9.595718 -7.965133) (xy 9.626491 -8.011646) (xy 9.650163 -8.062143) (xy 9.666231 -8.11555) (xy 9.674351 -8.170726)
			(xy 9.67486 -8.198612) (xy 9.674351 -8.226498) (xy 9.666231 -8.281674) (xy 9.650163 -8.335081) (xy 9.626491 -8.385578)
			(xy 9.595718 -8.432091) (xy 9.558501 -8.473628) (xy 9.515633 -8.509303) (xy 9.468027 -8.538357) (xy 9.416698 -8.560169)
			(xy 9.362741 -8.574275) (xy 9.307304 -8.580375) (xy 9.25157 -8.578338) (xy 9.196727 -8.568208) (xy 9.143943 -8.550201)
			(xy 9.094343 -8.5247) (xy 9.048985 -8.492249) (xy 9.008836 -8.45354) (xy 8.97475 -8.409397) (xy 8.947454 -8.360762)
			(xy 8.927531 -8.308671) (xy 8.915405 -8.254234) (xy 8.911334 -8.198612) (xy 4.61518 -8.198612) (xy 4.61518 -8.779256)
			(xy 7.30961 -8.779256) (xy 7.313681 -8.723634) (xy 7.325807 -8.669197) (xy 7.34573 -8.617106) (xy 7.373026 -8.568471)
			(xy 7.407112 -8.524328) (xy 7.447261 -8.485619) (xy 7.492619 -8.453168) (xy 7.542219 -8.427667) (xy 7.595003 -8.40966)
			(xy 7.649846 -8.39953) (xy 7.70558 -8.397493) (xy 7.761017 -8.403593) (xy 7.814974 -8.417699) (xy 7.866303 -8.439511)
			(xy 7.913909 -8.468565) (xy 7.956777 -8.50424) (xy 7.993994 -8.545777) (xy 8.024767 -8.59229) (xy 8.048439 -8.642787)
			(xy 8.064507 -8.696194) (xy 8.072627 -8.75137) (xy 8.073136 -8.779256) (xy 8.072627 -8.807142) (xy 8.064507 -8.862318)
			(xy 8.048439 -8.915725) (xy 8.024767 -8.966222) (xy 7.993994 -9.012735) (xy 7.956777 -9.054272) (xy 7.913909 -9.089947)
			(xy 7.866303 -9.119001) (xy 7.814974 -9.140813) (xy 7.761017 -9.154919) (xy 7.70558 -9.161019) (xy 7.649846 -9.158982)
			(xy 7.595003 -9.148852) (xy 7.542219 -9.130845) (xy 7.492619 -9.105344) (xy 7.447261 -9.072893) (xy 7.407112 -9.034184)
			(xy 7.373026 -8.990041) (xy 7.34573 -8.941406) (xy 7.325807 -8.889315) (xy 7.313681 -8.834878) (xy 7.30961 -8.779256)
			(xy 4.61518 -8.779256) (xy 4.61518 -11.213846) (xy 8.291828 -11.213846) (xy 8.295899 -11.158224)
			(xy 8.308025 -11.103787) (xy 8.327948 -11.051696) (xy 8.355244 -11.003061) (xy 8.38933 -10.958918)
			(xy 8.429479 -10.920209) (xy 8.474837 -10.887758) (xy 8.524437 -10.862257) (xy 8.577221 -10.84425)
			(xy 8.632064 -10.83412) (xy 8.687798 -10.832083) (xy 8.743235 -10.838183) (xy 8.797192 -10.852289)
			(xy 8.848521 -10.874101) (xy 8.896127 -10.903155) (xy 8.938995 -10.93883) (xy 8.976212 -10.980367)
			(xy 9.006985 -11.02688) (xy 9.030657 -11.077377) (xy 9.046725 -11.130784) (xy 9.054845 -11.18596)
			(xy 9.055354 -11.213846) (xy 9.054845 -11.241732) (xy 9.046725 -11.296908) (xy 9.030657 -11.350315)
			(xy 9.006985 -11.400812) (xy 8.976212 -11.447325) (xy 8.938995 -11.488862) (xy 8.896127 -11.524537)
			(xy 8.848521 -11.553591) (xy 8.797192 -11.575403) (xy 8.743235 -11.589509) (xy 8.687798 -11.595609)
			(xy 8.632064 -11.593572) (xy 8.577221 -11.583442) (xy 8.524437 -11.565435) (xy 8.474837 -11.539934)
			(xy 8.429479 -11.507483) (xy 8.38933 -11.468774) (xy 8.355244 -11.424631) (xy 8.327948 -11.375996)
			(xy 8.308025 -11.323905) (xy 8.295899 -11.269468) (xy 8.291828 -11.213846) (xy 4.61518 -11.213846)
			(xy 4.61518 -12.839556) (xy 11.195186 -12.839556) (xy 11.1966 -12.783638) (xy 11.206163 -12.728525)
			(xy 11.223671 -12.675398) (xy 11.248748 -12.625398) (xy 11.280856 -12.579595) (xy 11.319308 -12.53897)
			(xy 11.363279 -12.504395) (xy 11.411827 -12.476611) (xy 11.463912 -12.456212) (xy 11.518417 -12.443637)
			(xy 11.574174 -12.439155) (xy 11.629987 -12.442862) (xy 11.684662 -12.454678) (xy 11.737025 -12.47435)
			(xy 11.785955 -12.501456) (xy 11.830403 -12.535417) (xy 11.869416 -12.575503) (xy 11.886184 -12.597892)
			(xy 11.900301 -12.616551) (xy 11.934169 -12.648827) (xy 11.973372 -12.674359) (xy 12.016585 -12.692285)
			(xy 12.062349 -12.702) (xy 12.109118 -12.703175) (xy 12.155313 -12.695771) (xy 12.199372 -12.680037)
			(xy 12.239807 -12.656506) (xy 12.275253 -12.625971) (xy 12.290298 -12.608052) (xy 12.308176 -12.586539)
			(xy 12.349165 -12.548478) (xy 12.395272 -12.516809) (xy 12.445508 -12.492211) (xy 12.498798 -12.475211)
			(xy 12.553999 -12.466175) (xy 12.609927 -12.465294) (xy 12.665385 -12.472589) (xy 12.719183 -12.487903)
			(xy 12.770169 -12.510908) (xy 12.817249 -12.54111) (xy 12.859416 -12.577863) (xy 12.895764 -12.620378)
			(xy 12.925516 -12.667745) (xy 12.948033 -12.718948) (xy 12.962833 -12.77289) (xy 12.969598 -12.828414)
			(xy 12.968184 -12.884332) (xy 12.958621 -12.939444) (xy 12.941113 -12.992569) (xy 12.916037 -13.042568)
			(xy 12.88393 -13.08837) (xy 12.845479 -13.128994) (xy 12.801509 -13.163569) (xy 12.752962 -13.191353)
			(xy 12.700878 -13.211751) (xy 12.646375 -13.224326) (xy 12.590619 -13.228808) (xy 12.534807 -13.225102)
			(xy 12.480133 -13.213287) (xy 12.427771 -13.193616) (xy 12.378842 -13.16651) (xy 12.334395 -13.132551)
			(xy 12.295382 -13.092467) (xy 12.278614 -13.070078) (xy 12.264499 -13.051418) (xy 12.230629 -13.019146)
			(xy 12.191426 -12.993617) (xy 12.148213 -12.975693) (xy 12.102449 -12.965979) (xy 12.055681 -12.964804)
			(xy 12.009488 -12.972208) (xy 11.965429 -12.98794) (xy 11.924993 -13.011469) (xy 11.889546 -13.042)
			(xy 11.8745 -13.059918) (xy 11.856622 -13.081432) (xy 11.815632 -13.119494) (xy 11.769525 -13.151165)
			(xy 11.719288 -13.175764) (xy 11.665997 -13.192764) (xy 11.610795 -13.201801) (xy 11.554866 -13.202682)
			(xy 11.499407 -13.195388) (xy 11.445607 -13.180074) (xy 11.39462 -13.157069) (xy 11.347538 -13.126866)
			(xy 11.305371 -13.090113) (xy 11.269021 -13.047597) (xy 11.239269 -13.000229) (xy 11.216751 -12.949025)
			(xy 11.201951 -12.895082) (xy 11.195186 -12.839556) (xy 4.61518 -12.839556) (xy 4.61518 -14.01318)
			(xy 10.796522 -14.01318) (xy 10.800593 -13.957558) (xy 10.812719 -13.903121) (xy 10.832642 -13.85103)
			(xy 10.859938 -13.802395) (xy 10.894024 -13.758252) (xy 10.934173 -13.719543) (xy 10.979531 -13.687092)
			(xy 11.029131 -13.661591) (xy 11.081915 -13.643584) (xy 11.136758 -13.633454) (xy 11.192492 -13.631417)
			(xy 11.247929 -13.637517) (xy 11.301886 -13.651623) (xy 11.353215 -13.673435) (xy 11.400821 -13.702489)
			(xy 11.443689 -13.738164) (xy 11.480906 -13.779701) (xy 11.511679 -13.826214) (xy 11.535351 -13.876711)
			(xy 11.551419 -13.930118) (xy 11.559539 -13.985294) (xy 11.560048 -14.01318) (xy 11.559539 -14.041066)
			(xy 11.551419 -14.096242) (xy 11.535351 -14.149649) (xy 11.511679 -14.200146) (xy 11.480906 -14.246659)
			(xy 11.443689 -14.288196) (xy 11.400821 -14.323871) (xy 11.353215 -14.352925) (xy 11.301886 -14.374737)
			(xy 11.247929 -14.388843) (xy 11.192492 -14.394943) (xy 11.136758 -14.392906) (xy 11.081915 -14.382776)
			(xy 11.029131 -14.364769) (xy 10.979531 -14.339268) (xy 10.934173 -14.306817) (xy 10.894024 -14.268108)
			(xy 10.859938 -14.223965) (xy 10.832642 -14.17533) (xy 10.812719 -14.123239) (xy 10.800593 -14.068802)
			(xy 10.796522 -14.01318) (xy 4.61518 -14.01318) (xy 4.61518 -14.880106) (xy 11.55207 -14.880106)
			(xy 11.560155 -14.824616) (xy 11.576274 -14.770907) (xy 11.60008 -14.720135) (xy 11.631061 -14.673395)
			(xy 11.66855 -14.631692) (xy 11.711738 -14.595925) (xy 11.759696 -14.566865) (xy 11.811391 -14.545137)
			(xy 11.86571 -14.531209) (xy 11.921482 -14.525381) (xy 11.977506 -14.527779) (xy 12.032577 -14.53835)
			(xy 12.085507 -14.556868) (xy 12.135156 -14.582934) (xy 12.180456 -14.615986) (xy 12.220431 -14.655312)
			(xy 12.23772 -14.67739) (xy 12.25233 -14.695853) (xy 12.287128 -14.727559) (xy 12.327174 -14.75231)
			(xy 12.371095 -14.769256) (xy 12.417386 -14.777817) (xy 12.464463 -14.777701) (xy 12.510712 -14.768911)
			(xy 12.554548 -14.751749) (xy 12.594471 -14.726801) (xy 12.629113 -14.694924) (xy 12.643612 -14.676374)
			(xy 12.660801 -14.654216) (xy 12.700601 -14.614711) (xy 12.745755 -14.581456) (xy 12.79529 -14.555169)
			(xy 12.848139 -14.536415) (xy 12.903164 -14.525598) (xy 12.959179 -14.52295) (xy 13.014979 -14.52853)
			(xy 13.069361 -14.542217) (xy 13.121154 -14.563716) (xy 13.169243 -14.592565) (xy 13.212592 -14.62814)
			(xy 13.250267 -14.669678) (xy 13.281456 -14.716282) (xy 13.305489 -14.766949) (xy 13.321847 -14.820588)
			(xy 13.330178 -14.876044) (xy 13.330302 -14.932122) (xy 13.322218 -14.987614) (xy 13.306098 -15.041326)
			(xy 13.282291 -15.092099) (xy 13.281906 -15.09268) (xy 13.583156 -15.09268) (xy 13.587227 -15.037058)
			(xy 13.599353 -14.982621) (xy 13.619276 -14.93053) (xy 13.646572 -14.881895) (xy 13.680658 -14.837752)
			(xy 13.720807 -14.799043) (xy 13.766165 -14.766592) (xy 13.815765 -14.741091) (xy 13.868549 -14.723084)
			(xy 13.923392 -14.712954) (xy 13.979126 -14.710917) (xy 14.034563 -14.717017) (xy 14.08852 -14.731123)
			(xy 14.139849 -14.752935) (xy 14.187455 -14.781989) (xy 14.230323 -14.817664) (xy 14.26754 -14.859201)
			(xy 14.298313 -14.905714) (xy 14.321985 -14.956211) (xy 14.338053 -15.009618) (xy 14.346173 -15.064794)
			(xy 14.346682 -15.09268) (xy 14.346173 -15.120566) (xy 14.338053 -15.175742) (xy 14.321985 -15.229149)
			(xy 14.298313 -15.279646) (xy 14.26754 -15.326159) (xy 14.230323 -15.367696) (xy 14.187455 -15.403371)
			(xy 14.139849 -15.432425) (xy 14.08852 -15.454237) (xy 14.034563 -15.468343) (xy 13.979126 -15.474443)
			(xy 13.923392 -15.472406) (xy 13.868549 -15.462276) (xy 13.815765 -15.444269) (xy 13.766165 -15.418768)
			(xy 13.720807 -15.386317) (xy 13.680658 -15.347608) (xy 13.646572 -15.303465) (xy 13.619276 -15.25483)
			(xy 13.599353 -15.202739) (xy 13.587227 -15.148302) (xy 13.583156 -15.09268) (xy 13.281906 -15.09268)
			(xy 13.251309 -15.138842) (xy 13.213819 -15.180546) (xy 13.170629 -15.216314) (xy 13.122669 -15.245376)
			(xy 13.070972 -15.267105) (xy 13.016651 -15.281033) (xy 12.960877 -15.286861) (xy 12.90485 -15.284463)
			(xy 12.849778 -15.273891) (xy 12.796846 -15.255372) (xy 12.747195 -15.229305) (xy 12.701893 -15.196251)
			(xy 12.661918 -15.156923) (xy 12.644628 -15.134844) (xy 12.630077 -15.116333) (xy 12.595266 -15.084634)
			(xy 12.555211 -15.059892) (xy 12.511282 -15.042953) (xy 12.464985 -15.034398) (xy 12.417903 -15.03452)
			(xy 12.371651 -15.043315) (xy 12.327811 -15.06048) (xy 12.287884 -15.08543) (xy 12.253237 -15.117309)
			(xy 12.238736 -15.13586) (xy 12.221544 -15.158014) (xy 12.181744 -15.197517) (xy 12.136591 -15.230768)
			(xy 12.087057 -15.257054) (xy 12.03421 -15.275806) (xy 11.979187 -15.286622) (xy 11.923173 -15.289267)
			(xy 11.867376 -15.283686) (xy 11.812996 -15.269999) (xy 11.761205 -15.2485) (xy 11.713119 -15.219652)
			(xy 11.669773 -15.184077) (xy 11.6321 -15.142541) (xy 11.600912 -15.095938) (xy 11.576881 -15.045272)
			(xy 11.560524 -14.991635) (xy 11.552194 -14.936182) (xy 11.55207 -14.880106) (xy 4.61518 -14.880106)
			(xy 4.61518 -16.660622) (xy 14.938754 -16.660622) (xy 14.942825 -16.605) (xy 14.954951 -16.550563)
			(xy 14.974874 -16.498472) (xy 15.00217 -16.449837) (xy 15.036256 -16.405694) (xy 15.076405 -16.366985)
			(xy 15.121763 -16.334534) (xy 15.171363 -16.309033) (xy 15.224147 -16.291026) (xy 15.27899 -16.280896)
			(xy 15.334724 -16.278859) (xy 15.390161 -16.284959) (xy 15.444118 -16.299065) (xy 15.495447 -16.320877)
			(xy 15.543053 -16.349931) (xy 15.585921 -16.385606) (xy 15.623138 -16.427143) (xy 15.653911 -16.473656)
			(xy 15.677583 -16.524153) (xy 15.693651 -16.57756) (xy 15.701771 -16.632736) (xy 15.70228 -16.660622)
			(xy 15.701771 -16.688508) (xy 15.693651 -16.743684) (xy 15.677583 -16.797091) (xy 15.653911 -16.847588)
			(xy 15.623138 -16.894101) (xy 15.585921 -16.935638) (xy 15.543053 -16.971313) (xy 15.495447 -17.000367)
			(xy 15.444118 -17.022179) (xy 15.390161 -17.036285) (xy 15.334724 -17.042385) (xy 15.27899 -17.040348)
			(xy 15.224147 -17.030218) (xy 15.171363 -17.012211) (xy 15.121763 -16.98671) (xy 15.076405 -16.954259)
			(xy 15.036256 -16.91555) (xy 15.00217 -16.871407) (xy 14.974874 -16.822772) (xy 14.954951 -16.770681)
			(xy 14.942825 -16.716244) (xy 14.938754 -16.660622) (xy 4.61518 -16.660622) (xy 4.61518 -17.571974)
			(xy 12.658342 -17.571974) (xy 12.662413 -17.516352) (xy 12.674539 -17.461915) (xy 12.694462 -17.409824)
			(xy 12.721758 -17.361189) (xy 12.755844 -17.317046) (xy 12.795993 -17.278337) (xy 12.841351 -17.245886)
			(xy 12.890951 -17.220385) (xy 12.943735 -17.202378) (xy 12.998578 -17.192248) (xy 13.054312 -17.190211)
			(xy 13.109749 -17.196311) (xy 13.163706 -17.210417) (xy 13.215035 -17.232229) (xy 13.262641 -17.261283)
			(xy 13.305509 -17.296958) (xy 13.342726 -17.338495) (xy 13.373499 -17.385008) (xy 13.397171 -17.435505)
			(xy 13.413239 -17.488912) (xy 13.421359 -17.544088) (xy 13.421868 -17.571974) (xy 13.421359 -17.59986)
			(xy 13.413239 -17.655036) (xy 13.397171 -17.708443) (xy 13.373499 -17.75894) (xy 13.342726 -17.805453)
			(xy 13.305509 -17.84699) (xy 13.262641 -17.882665) (xy 13.215035 -17.911719) (xy 13.163706 -17.933531)
			(xy 13.109749 -17.947637) (xy 13.054312 -17.953737) (xy 12.998578 -17.9517) (xy 12.943735 -17.94157)
			(xy 12.890951 -17.923563) (xy 12.841351 -17.898062) (xy 12.795993 -17.865611) (xy 12.755844 -17.826902)
			(xy 12.721758 -17.782759) (xy 12.694462 -17.734124) (xy 12.674539 -17.682033) (xy 12.662413 -17.627596)
			(xy 12.658342 -17.571974) (xy 4.61518 -17.571974) (xy 4.61518 -18.57883) (xy 8.906 -18.57883) (xy 8.910071 -18.523208)
			(xy 8.922197 -18.468771) (xy 8.94212 -18.41668) (xy 8.969416 -18.368045) (xy 9.003502 -18.323902)
			(xy 9.043651 -18.285193) (xy 9.089009 -18.252742) (xy 9.138609 -18.227241) (xy 9.191393 -18.209234)
			(xy 9.246236 -18.199104) (xy 9.30197 -18.197067) (xy 9.357407 -18.203167) (xy 9.411364 -18.217273)
			(xy 9.462693 -18.239085) (xy 9.510299 -18.268139) (xy 9.553167 -18.303814) (xy 9.590384 -18.345351)
			(xy 9.621157 -18.391864) (xy 9.644829 -18.442361) (xy 9.660897 -18.495768) (xy 9.669017 -18.550944)
			(xy 9.669364 -18.56994) (xy 10.205972 -18.56994) (xy 10.210043 -18.514318) (xy 10.222169 -18.459881)
			(xy 10.242092 -18.40779) (xy 10.269388 -18.359155) (xy 10.303474 -18.315012) (xy 10.343623 -18.276303)
			(xy 10.388981 -18.243852) (xy 10.438581 -18.218351) (xy 10.491365 -18.200344) (xy 10.546208 -18.190214)
			(xy 10.601942 -18.188177) (xy 10.657379 -18.194277) (xy 10.711336 -18.208383) (xy 10.762665 -18.230195)
			(xy 10.810271 -18.259249) (xy 10.853139 -18.294924) (xy 10.890356 -18.336461) (xy 10.921129 -18.382974)
			(xy 10.944801 -18.433471) (xy 10.960869 -18.486878) (xy 10.968989 -18.542054) (xy 10.969498 -18.56994)
			(xy 10.968989 -18.597826) (xy 10.960869 -18.653002) (xy 10.944801 -18.706409) (xy 10.921129 -18.756906)
			(xy 10.913581 -18.768314) (xy 11.446762 -18.768314) (xy 11.450833 -18.712692) (xy 11.462959 -18.658255)
			(xy 11.482882 -18.606164) (xy 11.510178 -18.557529) (xy 11.544264 -18.513386) (xy 11.584413 -18.474677)
			(xy 11.629771 -18.442226) (xy 11.679371 -18.416725) (xy 11.732155 -18.398718) (xy 11.786998 -18.388588)
			(xy 11.842732 -18.386551) (xy 11.898169 -18.392651) (xy 11.952126 -18.406757) (xy 12.003455 -18.428569)
			(xy 12.051061 -18.457623) (xy 12.093929 -18.493298) (xy 12.131146 -18.534835) (xy 12.161919 -18.581348)
			(xy 12.185591 -18.631845) (xy 12.201659 -18.685252) (xy 12.209779 -18.740428) (xy 12.210288 -18.768314)
			(xy 12.209779 -18.7962) (xy 12.201659 -18.851376) (xy 12.200372 -18.855653) (xy 13.35979 -18.855653)
			(xy 13.364356 -18.801009) (xy 13.3767 -18.747583) (xy 13.396568 -18.696474) (xy 13.423549 -18.648737)
			(xy 13.457089 -18.605357) (xy 13.496495 -18.567226) (xy 13.540955 -18.535131) (xy 13.589553 -18.509734)
			(xy 13.641288 -18.491558) (xy 13.695092 -18.480978) (xy 13.749856 -18.478212) (xy 13.804452 -18.483317)
			(xy 13.857754 -18.496188) (xy 13.883386 -18.505932) (xy 13.905741 -18.514255) (xy 13.952539 -18.523455)
			(xy 14.000231 -18.523759) (xy 14.047142 -18.515157) (xy 14.091624 -18.497951) (xy 14.132113 -18.472747)
			(xy 14.167187 -18.440429) (xy 14.181836 -18.421604) (xy 14.198552 -18.399869) (xy 14.237197 -18.360973)
			(xy 14.281014 -18.328011) (xy 14.3291 -18.301664) (xy 14.380462 -18.282474) (xy 14.434044 -18.270836)
			(xy 14.48874 -18.266992) (xy 14.543422 -18.27102) (xy 14.596964 -18.282836) (xy 14.648262 -18.302198)
			(xy 14.696259 -18.328707) (xy 14.739966 -18.361815) (xy 14.77848 -18.400841) (xy 14.81101 -18.44498)
			(xy 14.836883 -18.493322) (xy 14.855567 -18.544871) (xy 14.866677 -18.598564) (xy 14.869983 -18.653295)
			(xy 14.865418 -18.707935) (xy 14.853076 -18.761358) (xy 14.83321 -18.812464) (xy 14.806231 -18.860198)
			(xy 14.772695 -18.903576) (xy 14.733292 -18.941705) (xy 14.688836 -18.973799) (xy 14.640241 -18.999196)
			(xy 14.588511 -19.017372) (xy 14.534711 -19.027953) (xy 14.47995 -19.030722) (xy 14.425358 -19.025619)
			(xy 14.372058 -19.012752) (xy 14.346428 -19.00301) (xy 14.324108 -18.994584) (xy 14.277297 -18.985395)
			(xy 14.229594 -18.985104) (xy 14.182674 -18.993721) (xy 14.138187 -19.010944) (xy 14.097696 -19.036167)
			(xy 14.062624 -19.068504) (xy 14.047978 -19.087338) (xy 14.031263 -19.109076) (xy 13.992618 -19.147977)
			(xy 13.948799 -19.180943) (xy 13.900712 -19.207294) (xy 13.849346 -19.226488) (xy 13.795762 -19.238128)
			(xy 13.741063 -19.241974) (xy 13.686377 -19.237948) (xy 13.632831 -19.226132) (xy 13.581528 -19.20677)
			(xy 13.533528 -19.180261) (xy 13.489818 -19.147151) (xy 13.4513 -19.108123) (xy 13.418768 -19.063982)
			(xy 13.392893 -19.015637) (xy 13.374207 -18.964084) (xy 13.363097 -18.910388) (xy 13.35979 -18.855653)
			(xy 12.200372 -18.855653) (xy 12.185591 -18.904783) (xy 12.161919 -18.95528) (xy 12.131146 -19.001793)
			(xy 12.093929 -19.04333) (xy 12.051061 -19.079005) (xy 12.003455 -19.108059) (xy 11.952126 -19.129871)
			(xy 11.898169 -19.143977) (xy 11.842732 -19.150077) (xy 11.786998 -19.14804) (xy 11.732155 -19.13791)
			(xy 11.679371 -19.119903) (xy 11.629771 -19.094402) (xy 11.584413 -19.061951) (xy 11.544264 -19.023242)
			(xy 11.510178 -18.979099) (xy 11.482882 -18.930464) (xy 11.462959 -18.878373) (xy 11.450833 -18.823936)
			(xy 11.446762 -18.768314) (xy 10.913581 -18.768314) (xy 10.890356 -18.803419) (xy 10.853139 -18.844956)
			(xy 10.810271 -18.880631) (xy 10.762665 -18.909685) (xy 10.711336 -18.931497) (xy 10.657379 -18.945603)
			(xy 10.601942 -18.951703) (xy 10.546208 -18.949666) (xy 10.491365 -18.939536) (xy 10.438581 -18.921529)
			(xy 10.388981 -18.896028) (xy 10.343623 -18.863577) (xy 10.303474 -18.824868) (xy 10.269388 -18.780725)
			(xy 10.242092 -18.73209) (xy 10.222169 -18.679999) (xy 10.210043 -18.625562) (xy 10.205972 -18.56994)
			(xy 9.669364 -18.56994) (xy 9.669526 -18.57883) (xy 9.669017 -18.606716) (xy 9.660897 -18.661892)
			(xy 9.644829 -18.715299) (xy 9.621157 -18.765796) (xy 9.590384 -18.812309) (xy 9.553167 -18.853846)
			(xy 9.510299 -18.889521) (xy 9.462693 -18.918575) (xy 9.411364 -18.940387) (xy 9.357407 -18.954493)
			(xy 9.30197 -18.960593) (xy 9.246236 -18.958556) (xy 9.191393 -18.948426) (xy 9.138609 -18.930419)
			(xy 9.089009 -18.904918) (xy 9.043651 -18.872467) (xy 9.003502 -18.833758) (xy 8.969416 -18.789615)
			(xy 8.94212 -18.74098) (xy 8.922197 -18.688889) (xy 8.910071 -18.634452) (xy 8.906 -18.57883) (xy 4.61518 -18.57883)
			(xy 4.61518 -21.496274) (xy 9.555986 -21.496274) (xy 9.560057 -21.440652) (xy 9.572183 -21.386215)
			(xy 9.592106 -21.334124) (xy 9.619402 -21.285489) (xy 9.653488 -21.241346) (xy 9.693637 -21.202637)
			(xy 9.738995 -21.170186) (xy 9.788595 -21.144685) (xy 9.841379 -21.126678) (xy 9.896222 -21.116548)
			(xy 9.951956 -21.114511) (xy 10.007393 -21.120611) (xy 10.06135 -21.134717) (xy 10.112679 -21.156529)
			(xy 10.160285 -21.185583) (xy 10.203153 -21.221258) (xy 10.24037 -21.262795) (xy 10.271143 -21.309308)
			(xy 10.294815 -21.359805) (xy 10.310883 -21.413212) (xy 10.319003 -21.468388) (xy 10.319512 -21.496274)
			(xy 10.319003 -21.52416) (xy 10.310883 -21.579336) (xy 10.294815 -21.632743) (xy 10.271143 -21.68324)
			(xy 10.24037 -21.729753) (xy 10.203153 -21.77129) (xy 10.160285 -21.806965) (xy 10.112679 -21.836019)
			(xy 10.06135 -21.857831) (xy 10.007393 -21.871937) (xy 9.951956 -21.878037) (xy 9.896222 -21.876)
			(xy 9.841379 -21.86587) (xy 9.788595 -21.847863) (xy 9.738995 -21.822362) (xy 9.693637 -21.789911)
			(xy 9.653488 -21.751202) (xy 9.619402 -21.707059) (xy 9.592106 -21.658424) (xy 9.572183 -21.606333)
			(xy 9.560057 -21.551896) (xy 9.555986 -21.496274) (xy 4.61518 -21.496274) (xy 4.61518 -23.118318)
			(xy 8.256014 -23.118318) (xy 8.260085 -23.062696) (xy 8.272211 -23.008259) (xy 8.292134 -22.956168)
			(xy 8.31943 -22.907533) (xy 8.353516 -22.86339) (xy 8.393665 -22.824681) (xy 8.439023 -22.79223)
			(xy 8.488623 -22.766729) (xy 8.541407 -22.748722) (xy 8.59625 -22.738592) (xy 8.651984 -22.736555)
			(xy 8.707421 -22.742655) (xy 8.761378 -22.756761) (xy 8.812707 -22.778573) (xy 8.860313 -22.807627)
			(xy 8.903181 -22.843302) (xy 8.940398 -22.884839) (xy 8.971171 -22.931352) (xy 8.994843 -22.981849)
			(xy 9.010911 -23.035256) (xy 9.019031 -23.090432) (xy 9.01954 -23.118318) (xy 9.019031 -23.146204)
			(xy 9.010911 -23.20138) (xy 8.994843 -23.254787) (xy 8.971171 -23.305284) (xy 8.940398 -23.351797)
			(xy 8.903181 -23.393334) (xy 8.860313 -23.429009) (xy 8.812707 -23.458063) (xy 8.761378 -23.479875)
			(xy 8.707421 -23.493981) (xy 8.651984 -23.500081) (xy 8.59625 -23.498044) (xy 8.541407 -23.487914)
			(xy 8.488623 -23.469907) (xy 8.439023 -23.444406) (xy 8.393665 -23.411955) (xy 8.353516 -23.373246)
			(xy 8.31943 -23.329103) (xy 8.292134 -23.280468) (xy 8.272211 -23.228377) (xy 8.260085 -23.17394)
			(xy 8.256014 -23.118318) (xy 4.61518 -23.118318) (xy 4.61518 -24.612346) (xy 7.812022 -24.612346)
			(xy 7.816093 -24.556724) (xy 7.828219 -24.502287) (xy 7.848142 -24.450196) (xy 7.875438 -24.401561)
			(xy 7.909524 -24.357418) (xy 7.949673 -24.318709) (xy 7.995031 -24.286258) (xy 8.044631 -24.260757)
			(xy 8.097415 -24.24275) (xy 8.152258 -24.23262) (xy 8.207992 -24.230583) (xy 8.263429 -24.236683)
			(xy 8.317386 -24.250789) (xy 8.368715 -24.272601) (xy 8.416321 -24.301655) (xy 8.459189 -24.33733)
			(xy 8.496406 -24.378867) (xy 8.527179 -24.42538) (xy 8.550851 -24.475877) (xy 8.566919 -24.529284)
			(xy 8.575039 -24.58446) (xy 8.575548 -24.612346) (xy 8.575039 -24.640232) (xy 8.566919 -24.695408)
			(xy 8.550851 -24.748815) (xy 8.527179 -24.799312) (xy 8.496406 -24.845825) (xy 8.459189 -24.887362)
			(xy 8.416321 -24.923037) (xy 8.368715 -24.952091) (xy 8.317386 -24.973903) (xy 8.263429 -24.988009)
			(xy 8.207992 -24.994109) (xy 8.152258 -24.992072) (xy 8.097415 -24.981942) (xy 8.044631 -24.963935)
			(xy 7.995031 -24.938434) (xy 7.949673 -24.905983) (xy 7.909524 -24.867274) (xy 7.875438 -24.823131)
			(xy 7.848142 -24.774496) (xy 7.828219 -24.722405) (xy 7.816093 -24.667968) (xy 7.812022 -24.612346)
			(xy 4.61518 -24.612346) (xy 4.61518 -24.818594) (xy 7.225538 -27.428952) (xy 8.906 -27.428952) (xy 8.910071 -27.37333)
			(xy 8.922197 -27.318893) (xy 8.94212 -27.266802) (xy 8.969416 -27.218167) (xy 9.003502 -27.174024)
			(xy 9.043651 -27.135315) (xy 9.089009 -27.102864) (xy 9.138609 -27.077363) (xy 9.191393 -27.059356)
			(xy 9.246236 -27.049226) (xy 9.30197 -27.047189) (xy 9.357407 -27.053289) (xy 9.411364 -27.067395)
			(xy 9.462693 -27.089207) (xy 9.510299 -27.118261) (xy 9.553167 -27.153936) (xy 9.590384 -27.195473)
			(xy 9.621157 -27.241986) (xy 9.629383 -27.259534) (xy 15.305022 -27.259534) (xy 15.309093 -27.203912)
			(xy 15.321219 -27.149475) (xy 15.341142 -27.097384) (xy 15.368438 -27.048749) (xy 15.402524 -27.004606)
			(xy 15.442673 -26.965897) (xy 15.488031 -26.933446) (xy 15.537631 -26.907945) (xy 15.590415 -26.889938)
			(xy 15.645258 -26.879808) (xy 15.700992 -26.877771) (xy 15.756429 -26.883871) (xy 15.810386 -26.897977)
			(xy 15.861715 -26.919789) (xy 15.909321 -26.948843) (xy 15.952189 -26.984518) (xy 15.989406 -27.026055)
			(xy 16.020179 -27.072568) (xy 16.043851 -27.123065) (xy 16.059919 -27.176472) (xy 16.068039 -27.231648)
			(xy 16.068548 -27.259534) (xy 16.068039 -27.28742) (xy 16.059919 -27.342596) (xy 16.043851 -27.396003)
			(xy 16.020179 -27.4465) (xy 15.989406 -27.493013) (xy 15.952189 -27.53455) (xy 15.909321 -27.570225)
			(xy 15.861715 -27.599279) (xy 15.810386 -27.621091) (xy 15.756429 -27.635197) (xy 15.700992 -27.641297)
			(xy 15.645258 -27.63926) (xy 15.590415 -27.62913) (xy 15.537631 -27.611123) (xy 15.488031 -27.585622)
			(xy 15.442673 -27.553171) (xy 15.402524 -27.514462) (xy 15.368438 -27.470319) (xy 15.341142 -27.421684)
			(xy 15.321219 -27.369593) (xy 15.309093 -27.315156) (xy 15.305022 -27.259534) (xy 9.629383 -27.259534)
			(xy 9.644829 -27.292483) (xy 9.660897 -27.34589) (xy 9.669017 -27.401066) (xy 9.669526 -27.428952)
			(xy 9.669017 -27.456838) (xy 9.660897 -27.512014) (xy 9.644829 -27.565421) (xy 9.621157 -27.615918)
			(xy 9.590384 -27.662431) (xy 9.553167 -27.703968) (xy 9.510299 -27.739643) (xy 9.462693 -27.768697)
			(xy 9.411364 -27.790509) (xy 9.402088 -27.792934) (xy 11.685522 -27.792934) (xy 11.689593 -27.737312)
			(xy 11.701719 -27.682875) (xy 11.721642 -27.630784) (xy 11.748938 -27.582149) (xy 11.783024 -27.538006)
			(xy 11.823173 -27.499297) (xy 11.868531 -27.466846) (xy 11.918131 -27.441345) (xy 11.970915 -27.423338)
			(xy 12.025758 -27.413208) (xy 12.081492 -27.411171) (xy 12.136929 -27.417271) (xy 12.190886 -27.431377)
			(xy 12.242215 -27.453189) (xy 12.289821 -27.482243) (xy 12.332689 -27.517918) (xy 12.369906 -27.559455)
			(xy 12.400679 -27.605968) (xy 12.424351 -27.656465) (xy 12.440419 -27.709872) (xy 12.448539 -27.765048)
			(xy 12.449048 -27.792934) (xy 12.448539 -27.82082) (xy 12.440419 -27.875996) (xy 12.424351 -27.929403)
			(xy 12.400679 -27.9799) (xy 12.369906 -28.026413) (xy 12.332689 -28.06795) (xy 12.289821 -28.103625)
			(xy 12.242215 -28.132679) (xy 12.190886 -28.154491) (xy 12.136929 -28.168597) (xy 12.081492 -28.174697)
			(xy 12.025758 -28.17266) (xy 11.970915 -28.16253) (xy 11.918131 -28.144523) (xy 11.868531 -28.119022)
			(xy 11.823173 -28.086571) (xy 11.783024 -28.047862) (xy 11.748938 -28.003719) (xy 11.721642 -27.955084)
			(xy 11.701719 -27.902993) (xy 11.689593 -27.848556) (xy 11.685522 -27.792934) (xy 9.402088 -27.792934)
			(xy 9.357407 -27.804615) (xy 9.30197 -27.810715) (xy 9.246236 -27.808678) (xy 9.191393 -27.798548)
			(xy 9.138609 -27.780541) (xy 9.089009 -27.75504) (xy 9.043651 -27.722589) (xy 9.003502 -27.68388)
			(xy 8.969416 -27.639737) (xy 8.94212 -27.591102) (xy 8.922197 -27.539011) (xy 8.910071 -27.484574)
			(xy 8.906 -27.428952) (xy 7.225538 -27.428952) (xy 8.37692 -28.580334) (xy 13.646402 -28.580334)
			(xy 13.650473 -28.524712) (xy 13.662599 -28.470275) (xy 13.682522 -28.418184) (xy 13.709818 -28.369549)
			(xy 13.743904 -28.325406) (xy 13.784053 -28.286697) (xy 13.829411 -28.254246) (xy 13.879011 -28.228745)
			(xy 13.931795 -28.210738) (xy 13.986638 -28.200608) (xy 14.042372 -28.198571) (xy 14.097809 -28.204671)
			(xy 14.151766 -28.218777) (xy 14.203095 -28.240589) (xy 14.250701 -28.269643) (xy 14.293569 -28.305318)
			(xy 14.330786 -28.346855) (xy 14.361559 -28.393368) (xy 14.385231 -28.443865) (xy 14.401299 -28.497272)
			(xy 14.409419 -28.552448) (xy 14.409928 -28.580334) (xy 14.409419 -28.60822) (xy 14.401299 -28.663396)
			(xy 14.385231 -28.716803) (xy 14.361559 -28.7673) (xy 14.330786 -28.813813) (xy 14.293569 -28.85535)
			(xy 14.250701 -28.891025) (xy 14.203095 -28.920079) (xy 14.151766 -28.941891) (xy 14.097809 -28.955997)
			(xy 14.042372 -28.962097) (xy 13.986638 -28.96006) (xy 13.931795 -28.94993) (xy 13.879011 -28.931923)
			(xy 13.829411 -28.906422) (xy 13.784053 -28.873971) (xy 13.743904 -28.835262) (xy 13.709818 -28.791119)
			(xy 13.682522 -28.742484) (xy 13.662599 -28.690393) (xy 13.650473 -28.635956) (xy 13.646402 -28.580334)
			(xy 8.37692 -28.580334) (xy 11.085322 -31.288736) (xy 11.101801 -31.304529) (xy 11.139322 -31.330514)
			(xy 11.18088 -31.34938) (xy 11.22514 -31.360522) (xy 11.270677 -31.363581) (xy 11.316029 -31.358459)
			(xy 11.359737 -31.34532) (xy 11.400396 -31.324587) (xy 11.4367 -31.296927) (xy 11.46748 -31.263228)
			(xy 11.491747 -31.224574) (xy 11.508722 -31.182208) (xy 11.51382 -31.159958) (xy 11.51897 -31.13259)
			(xy 11.536156 -31.07962) (xy 11.56086 -31.029712) (xy 11.592557 -30.983925) (xy 11.630574 -30.943232)
			(xy 11.674102 -30.908498) (xy 11.722217 -30.880461) (xy 11.773897 -30.859716) (xy 11.828043 -30.846705)
			(xy 11.883506 -30.841703) (xy 11.939107 -30.844816) (xy 11.993664 -30.85598) (xy 12.046019 -30.874956)
			(xy 12.09506 -30.901342) (xy 12.139743 -30.934576) (xy 12.179121 -30.973953) (xy 12.212356 -31.018636)
			(xy 12.238742 -31.067676) (xy 12.257719 -31.120031) (xy 12.268883 -31.174588) (xy 12.269757 -31.190184)
			(xy 13.512544 -31.190184) (xy 13.516615 -31.134562) (xy 13.528741 -31.080125) (xy 13.548664 -31.028034)
			(xy 13.57596 -30.979399) (xy 13.610046 -30.935256) (xy 13.650195 -30.896547) (xy 13.695553 -30.864096)
			(xy 13.745153 -30.838595) (xy 13.797937 -30.820588) (xy 13.85278 -30.810458) (xy 13.908514 -30.808421)
			(xy 13.963951 -30.814521) (xy 14.017908 -30.828627) (xy 14.069237 -30.850439) (xy 14.116843 -30.879493)
			(xy 14.159711 -30.915168) (xy 14.196928 -30.956705) (xy 14.227701 -31.003218) (xy 14.251373 -31.053715)
			(xy 14.267441 -31.107122) (xy 14.275561 -31.162298) (xy 14.27607 -31.190184) (xy 14.275561 -31.21807)
			(xy 14.267441 -31.273246) (xy 14.251373 -31.326653) (xy 14.227701 -31.37715) (xy 14.196928 -31.423663)
			(xy 14.159711 -31.4652) (xy 14.116843 -31.500875) (xy 14.069237 -31.529929) (xy 14.017908 -31.551741)
			(xy 13.963951 -31.565847) (xy 13.908514 -31.571947) (xy 13.85278 -31.56991) (xy 13.797937 -31.55978)
			(xy 13.745153 -31.541773) (xy 13.695553 -31.516272) (xy 13.650195 -31.483821) (xy 13.610046 -31.445112)
			(xy 13.57596 -31.400969) (xy 13.548664 -31.352334) (xy 13.528741 -31.300243) (xy 13.516615 -31.245806)
			(xy 13.512544 -31.190184) (xy 12.269757 -31.190184) (xy 12.271998 -31.230189) (xy 12.266996 -31.285652)
			(xy 12.253985 -31.339799) (xy 12.233241 -31.391479) (xy 12.205205 -31.439594) (xy 12.170471 -31.483123)
			(xy 12.129779 -31.52114) (xy 12.083992 -31.552837) (xy 12.034084 -31.577542) (xy 11.981115 -31.594729)
			(xy 11.953748 -31.599886) (xy 11.931481 -31.604919) (xy 11.889103 -31.621886) (xy 11.850439 -31.646151)
			(xy 11.816732 -31.676933) (xy 11.789066 -31.713242) (xy 11.768332 -31.753909) (xy 11.755196 -31.797627)
			(xy 11.750083 -31.842987) (xy 11.753155 -31.888531) (xy 11.764315 -31.932794) (xy 11.783203 -31.974351)
			(xy 11.809211 -32.011865) (xy 11.82497 -32.028384) (xy 15.457678 -35.661092) (xy 15.469796 -35.672531)
			(xy 15.498635 -35.689207) (xy 15.53081 -35.697839) (xy 15.564124 -35.697839) (xy 15.596299 -35.689207)
			(xy 15.625138 -35.672531) (xy 15.637256 -35.661092) (xy 15.709392 -35.588956) (xy 15.768574 -35.52952)
			(xy 16.334486 -35.52952) (xy 16.366111 -35.53) (xy 16.428874 -35.537843) (xy 16.490179 -35.55341)
			(xy 16.54908 -35.576461) (xy 16.604668 -35.606639) (xy 16.656083 -35.643478) (xy 16.702532 -35.68641)
			(xy 16.743298 -35.734771) (xy 16.77775 -35.787816) (xy 16.805358 -35.844723) (xy 16.825694 -35.904616)
			(xy 16.838445 -35.966568) (xy 16.843414 -36.029623) (xy 16.840523 -36.092808) (xy 16.829818 -36.155147)
			(xy 16.811464 -36.215676) (xy 16.785744 -36.273461) (xy 16.753056 -36.327611) (xy 16.713904 -36.377287)
			(xy 16.668893 -36.421725) (xy 16.65239 -36.434814) (xy 18.536911 -36.434814) (xy 18.536911 -36.345838)
			(xy 18.544887 -36.257219) (xy 18.560774 -36.169673) (xy 18.584445 -36.083902) (xy 18.615709 -36.000599)
			(xy 18.654315 -35.920434) (xy 18.699951 -35.844052) (xy 18.75225 -35.772069) (xy 18.810791 -35.705063)
			(xy 18.875103 -35.643575) (xy 18.944668 -35.588099) (xy 19.018925 -35.539082) (xy 19.097278 -35.496919)
			(xy 19.179094 -35.461948) (xy 19.263716 -35.434453) (xy 19.350462 -35.414654) (xy 19.438633 -35.40271)
			(xy 19.52752 -35.398719) (xy 19.616407 -35.40271) (xy 19.704578 -35.414654) (xy 19.791324 -35.434453)
			(xy 19.875946 -35.461948) (xy 19.957762 -35.496919) (xy 20.036115 -35.539082) (xy 20.110372 -35.588099)
			(xy 20.179937 -35.643575) (xy 20.244249 -35.705063) (xy 20.30279 -35.772069) (xy 20.355089 -35.844052)
			(xy 20.400725 -35.920434) (xy 20.439331 -36.000599) (xy 20.470595 -36.083902) (xy 20.494266 -36.169673)
			(xy 20.510153 -36.257219) (xy 20.518129 -36.345838) (xy 20.518628 -36.390326) (xy 20.518129 -36.434814)
			(xy 21.076911 -36.434814) (xy 21.076911 -36.345838) (xy 21.084887 -36.257219) (xy 21.100774 -36.169673)
			(xy 21.124445 -36.083902) (xy 21.155709 -36.000599) (xy 21.194315 -35.920434) (xy 21.239951 -35.844052)
			(xy 21.29225 -35.772069) (xy 21.350791 -35.705063) (xy 21.415103 -35.643575) (xy 21.484668 -35.588099)
			(xy 21.558925 -35.539082) (xy 21.637278 -35.496919) (xy 21.719094 -35.461948) (xy 21.803716 -35.434453)
			(xy 21.890462 -35.414654) (xy 21.978633 -35.40271) (xy 22.06752 -35.398719) (xy 22.156407 -35.40271)
			(xy 22.244578 -35.414654) (xy 22.331324 -35.434453) (xy 22.415946 -35.461948) (xy 22.497762 -35.496919)
			(xy 22.576115 -35.539082) (xy 22.650372 -35.588099) (xy 22.719937 -35.643575) (xy 22.784249 -35.705063)
			(xy 22.84279 -35.772069) (xy 22.895089 -35.844052) (xy 22.940725 -35.920434) (xy 22.979331 -36.000599)
			(xy 23.010595 -36.083902) (xy 23.034266 -36.169673) (xy 23.050153 -36.257219) (xy 23.058129 -36.345838)
			(xy 23.058628 -36.390326) (xy 23.058129 -36.434814) (xy 23.050153 -36.523433) (xy 23.034266 -36.610979)
			(xy 23.010595 -36.69675) (xy 22.979331 -36.780053) (xy 22.940725 -36.860218) (xy 22.895089 -36.9366)
			(xy 22.84279 -37.008583) (xy 22.784249 -37.075589) (xy 22.719937 -37.137077) (xy 22.650372 -37.192553)
			(xy 22.576115 -37.24157) (xy 22.497762 -37.283733) (xy 22.415946 -37.318704) (xy 22.331324 -37.346199)
			(xy 22.244578 -37.365998) (xy 22.156407 -37.377942) (xy 22.06752 -37.381934) (xy 21.978633 -37.377942)
			(xy 21.890462 -37.365998) (xy 21.803716 -37.346199) (xy 21.719094 -37.318704) (xy 21.637278 -37.283733)
			(xy 21.558925 -37.24157) (xy 21.484668 -37.192553) (xy 21.415103 -37.137077) (xy 21.350791 -37.075589)
			(xy 21.29225 -37.008583) (xy 21.239951 -36.9366) (xy 21.194315 -36.860218) (xy 21.155709 -36.780053)
			(xy 21.124445 -36.69675) (xy 21.100774 -36.610979) (xy 21.084887 -36.523433) (xy 21.076911 -36.434814)
			(xy 20.518129 -36.434814) (xy 20.510153 -36.523433) (xy 20.494266 -36.610979) (xy 20.470595 -36.69675)
			(xy 20.439331 -36.780053) (xy 20.400725 -36.860218) (xy 20.355089 -36.9366) (xy 20.30279 -37.008583)
			(xy 20.244249 -37.075589) (xy 20.179937 -37.137077) (xy 20.110372 -37.192553) (xy 20.036115 -37.24157)
			(xy 19.957762 -37.283733) (xy 19.875946 -37.318704) (xy 19.791324 -37.346199) (xy 19.704578 -37.365998)
			(xy 19.616407 -37.377942) (xy 19.52752 -37.381934) (xy 19.438633 -37.377942) (xy 19.350462 -37.365998)
			(xy 19.263716 -37.346199) (xy 19.179094 -37.318704) (xy 19.097278 -37.283733) (xy 19.018925 -37.24157)
			(xy 18.944668 -37.192553) (xy 18.875103 -37.137077) (xy 18.810791 -37.075589) (xy 18.75225 -37.008583)
			(xy 18.699951 -36.9366) (xy 18.654315 -36.860218) (xy 18.615709 -36.780053) (xy 18.584445 -36.69675)
			(xy 18.560774 -36.610979) (xy 18.544887 -36.523433) (xy 18.536911 -36.434814) (xy 16.65239 -36.434814)
			(xy 16.644112 -36.44138) (xy 16.62723 -36.454887) (xy 16.597886 -36.486634) (xy 16.574339 -36.52289)
			(xy 16.557266 -36.562608) (xy 16.547162 -36.604642) (xy 16.544317 -36.64778) (xy 16.548814 -36.690777)
			(xy 16.560522 -36.732393) (xy 16.579104 -36.771427) (xy 16.604024 -36.806753) (xy 16.618966 -36.82238)
			(xy 18.640298 -38.843712) (xy 18.663158 -38.853364) (xy 18.687233 -38.864063) (xy 18.732438 -38.89112)
			(xy 18.77349 -38.92414) (xy 18.809609 -38.962494) (xy 18.840107 -39.005452) (xy 18.852642 -39.028624)
			(xy 18.861116 -39.043812) (xy 18.884847 -39.069221) (xy 18.914555 -39.087284) (xy 18.948034 -39.096661)
			(xy 18.965418 -39.097204) (xy 19.31162 -39.097204) (xy 19.345957 -39.09771) (xy 19.414127 -39.106028)
			(xy 19.480787 -39.122538) (xy 19.544958 -39.146999) (xy 19.605695 -39.179049) (xy 19.662105 -39.218218)
			(xy 19.713357 -39.263928) (xy 19.758697 -39.315508) (xy 19.778472 -39.343584) (xy 19.787544 -39.356097)
			(xy 19.810599 -39.376671) (xy 19.837928 -39.391092) (xy 19.867924 -39.398511) (xy 19.883374 -39.398956)
			(xy 20.79498 -39.398956) (xy 24.062693 -42.666669) (xy 25.59125 -42.666669) (xy 25.594319 -42.611786)
			(xy 25.605233 -42.557911) (xy 25.623767 -42.50616) (xy 25.649537 -42.457605) (xy 25.682009 -42.413252)
			(xy 25.72051 -42.374018) (xy 25.764244 -42.340717) (xy 25.812304 -42.314037) (xy 25.863697 -42.294531)
			(xy 25.917356 -42.282604) (xy 25.972172 -42.278501) (xy 26.02701 -42.282309) (xy 26.080733 -42.293948)
			(xy 26.132229 -42.313176) (xy 26.180433 -42.339597) (xy 26.224345 -42.372663) (xy 26.244042 -42.391838)
			(xy 26.260119 -42.407301) (xy 26.29658 -42.43299) (xy 26.336966 -42.451916) (xy 26.380038 -42.463498)
			(xy 26.42447 -42.467378) (xy 26.468897 -42.463438) (xy 26.511953 -42.451799) (xy 26.552314 -42.432819)
			(xy 26.58874 -42.407081) (xy 26.620111 -42.375377) (xy 26.63317 -42.357294) (xy 26.649214 -42.334977)
			(xy 26.686644 -42.29473) (xy 26.729463 -42.260272) (xy 26.776784 -42.232316) (xy 26.827627 -42.211441)
			(xy 26.88094 -42.198079) (xy 26.935619 -42.192508) (xy 26.990532 -42.194841) (xy 27.044541 -42.205032)
			(xy 27.096528 -42.222869) (xy 27.145417 -42.247982) (xy 27.190196 -42.279852) (xy 27.229937 -42.317818)
			(xy 27.263817 -42.361096) (xy 27.291136 -42.408788) (xy 27.311327 -42.459907) (xy 27.323972 -42.513394)
			(xy 27.328809 -42.568143) (xy 27.325739 -42.623019) (xy 27.314825 -42.676887) (xy 27.296292 -42.72863)
			(xy 27.270525 -42.777178) (xy 27.238057 -42.821525) (xy 27.199561 -42.860753) (xy 27.155833 -42.89405)
			(xy 27.107778 -42.920726) (xy 27.056393 -42.940229) (xy 27.002741 -42.952155) (xy 26.947932 -42.956258)
			(xy 26.893102 -42.952451) (xy 26.839386 -42.940815) (xy 26.787896 -42.92159) (xy 26.739698 -42.895174)
			(xy 26.695791 -42.862114) (xy 26.676096 -42.842942) (xy 26.660078 -42.827415) (xy 26.623607 -42.80173)
			(xy 26.58321 -42.782809) (xy 26.540129 -42.771233) (xy 26.495689 -42.76736) (xy 26.451256 -42.771307)
			(xy 26.408195 -42.782953) (xy 26.36783 -42.801941) (xy 26.331401 -42.827687) (xy 26.300028 -42.859399)
			(xy 26.286968 -42.877486) (xy 26.270942 -42.89982) (xy 26.23351 -42.940076) (xy 26.190689 -42.974542)
			(xy 26.143364 -43.002506) (xy 26.092515 -43.023388) (xy 26.039196 -43.036756) (xy 25.98451 -43.042333)
			(xy 25.92959 -43.040003) (xy 25.875573 -43.029814) (xy 25.823578 -43.011979) (xy 25.774681 -42.986865)
			(xy 25.729894 -42.954993) (xy 25.690146 -42.917024) (xy 25.656259 -42.873742) (xy 25.628934 -42.826045)
			(xy 25.608739 -42.77492) (xy 25.59609 -42.721425) (xy 25.59125 -42.666669) (xy 24.062693 -42.666669)
			(xy 24.56688 -43.170856) (xy 24.56688 -44.54398) (xy 26.735022 -44.54398) (xy 26.739093 -44.488358)
			(xy 26.751219 -44.433921) (xy 26.771142 -44.38183) (xy 26.798438 -44.333195) (xy 26.832524 -44.289052)
			(xy 26.872673 -44.250343) (xy 26.918031 -44.217892) (xy 26.967631 -44.192391) (xy 27.020415 -44.174384)
			(xy 27.075258 -44.164254) (xy 27.130992 -44.162217) (xy 27.186429 -44.168317) (xy 27.240386 -44.182423)
			(xy 27.291715 -44.204235) (xy 27.339321 -44.233289) (xy 27.382189 -44.268964) (xy 27.419406 -44.310501)
			(xy 27.450179 -44.357014) (xy 27.473851 -44.407511) (xy 27.489919 -44.460918) (xy 27.498039 -44.516094)
			(xy 27.498548 -44.54398) (xy 27.498039 -44.571866) (xy 27.489919 -44.627042) (xy 27.473851 -44.680449)
			(xy 27.450179 -44.730946) (xy 27.419406 -44.777459) (xy 27.382189 -44.818996) (xy 27.339321 -44.854671)
			(xy 27.291715 -44.883725) (xy 27.240386 -44.905537) (xy 27.186429 -44.919643) (xy 27.130992 -44.925743)
			(xy 27.075258 -44.923706) (xy 27.020415 -44.913576) (xy 26.967631 -44.895569) (xy 26.918031 -44.870068)
			(xy 26.872673 -44.837617) (xy 26.832524 -44.798908) (xy 26.798438 -44.754765) (xy 26.771142 -44.70613)
			(xy 26.751219 -44.654039) (xy 26.739093 -44.599602) (xy 26.735022 -44.54398) (xy 24.56688 -44.54398)
			(xy 24.56688 -45.486828) (xy 28.807662 -45.486828) (xy 28.811733 -45.431206) (xy 28.823859 -45.376769)
			(xy 28.843782 -45.324678) (xy 28.871078 -45.276043) (xy 28.905164 -45.2319) (xy 28.945313 -45.193191)
			(xy 28.990671 -45.16074) (xy 29.040271 -45.135239) (xy 29.093055 -45.117232) (xy 29.147898 -45.107102)
			(xy 29.203632 -45.105065) (xy 29.259069 -45.111165) (xy 29.313026 -45.125271) (xy 29.364355 -45.147083)
			(xy 29.411961 -45.176137) (xy 29.454829 -45.211812) (xy 29.492046 -45.253349) (xy 29.522819 -45.299862)
			(xy 29.546491 -45.350359) (xy 29.562559 -45.403766) (xy 29.570679 -45.458942) (xy 29.571188 -45.486828)
			(xy 29.570679 -45.514714) (xy 29.562559 -45.56989) (xy 29.546491 -45.623297) (xy 29.522819 -45.673794)
			(xy 29.492046 -45.720307) (xy 29.454829 -45.761844) (xy 29.411961 -45.797519) (xy 29.364355 -45.826573)
			(xy 29.313026 -45.848385) (xy 29.259069 -45.862491) (xy 29.203632 -45.868591) (xy 29.147898 -45.866554)
			(xy 29.093055 -45.856424) (xy 29.040271 -45.838417) (xy 28.990671 -45.812916) (xy 28.945313 -45.780465)
			(xy 28.905164 -45.741756) (xy 28.871078 -45.697613) (xy 28.843782 -45.648978) (xy 28.823859 -45.596887)
			(xy 28.811733 -45.54245) (xy 28.807662 -45.486828) (xy 24.56688 -45.486828) (xy 24.56688 -47.336202)
			(xy 28.200602 -47.336202) (xy 28.204673 -47.28058) (xy 28.216799 -47.226143) (xy 28.236722 -47.174052)
			(xy 28.264018 -47.125417) (xy 28.298104 -47.081274) (xy 28.338253 -47.042565) (xy 28.383611 -47.010114)
			(xy 28.433211 -46.984613) (xy 28.485995 -46.966606) (xy 28.540838 -46.956476) (xy 28.596572 -46.954439)
			(xy 28.652009 -46.960539) (xy 28.705966 -46.974645) (xy 28.757295 -46.996457) (xy 28.804901 -47.025511)
			(xy 28.847769 -47.061186) (xy 28.884986 -47.102723) (xy 28.915759 -47.149236) (xy 28.939431 -47.199733)
			(xy 28.955499 -47.25314) (xy 28.963619 -47.308316) (xy 28.964128 -47.336202) (xy 28.963619 -47.364088)
			(xy 28.955499 -47.419264) (xy 28.939431 -47.472671) (xy 28.915759 -47.523168) (xy 28.884986 -47.569681)
			(xy 28.847769 -47.611218) (xy 28.804901 -47.646893) (xy 28.757295 -47.675947) (xy 28.705966 -47.697759)
			(xy 28.652009 -47.711865) (xy 28.596572 -47.717965) (xy 28.540838 -47.715928) (xy 28.485995 -47.705798)
			(xy 28.433211 -47.687791) (xy 28.383611 -47.66229) (xy 28.338253 -47.629839) (xy 28.298104 -47.59113)
			(xy 28.264018 -47.546987) (xy 28.236722 -47.498352) (xy 28.216799 -47.446261) (xy 28.204673 -47.391824)
			(xy 28.200602 -47.336202) (xy 24.56688 -47.336202) (xy 24.56688 -49.369472) (xy 25.386028 -49.369472)
			(xy 25.390099 -49.31385) (xy 25.402225 -49.259413) (xy 25.422148 -49.207322) (xy 25.449444 -49.158687)
			(xy 25.48353 -49.114544) (xy 25.523679 -49.075835) (xy 25.569037 -49.043384) (xy 25.618637 -49.017883)
			(xy 25.671421 -48.999876) (xy 25.726264 -48.989746) (xy 25.781998 -48.987709) (xy 25.837435 -48.993809)
			(xy 25.891392 -49.007915) (xy 25.942721 -49.029727) (xy 25.990327 -49.058781) (xy 26.005341 -49.071276)
			(xy 27.281122 -49.071276) (xy 27.285193 -49.015654) (xy 27.297319 -48.961217) (xy 27.317242 -48.909126)
			(xy 27.344538 -48.860491) (xy 27.378624 -48.816348) (xy 27.418773 -48.777639) (xy 27.464131 -48.745188)
			(xy 27.513731 -48.719687) (xy 27.566515 -48.70168) (xy 27.621358 -48.69155) (xy 27.677092 -48.689513)
			(xy 27.732529 -48.695613) (xy 27.786486 -48.709719) (xy 27.837815 -48.731531) (xy 27.885421 -48.760585)
			(xy 27.928289 -48.79626) (xy 27.965506 -48.837797) (xy 27.996279 -48.88431) (xy 28.019951 -48.934807)
			(xy 28.036019 -48.988214) (xy 28.044139 -49.04339) (xy 28.044648 -49.071276) (xy 28.044139 -49.099162)
			(xy 28.036019 -49.154338) (xy 28.019951 -49.207745) (xy 27.996279 -49.258242) (xy 27.965506 -49.304755)
			(xy 27.928289 -49.346292) (xy 27.885421 -49.381967) (xy 27.837815 -49.411021) (xy 27.786486 -49.432833)
			(xy 27.732529 -49.446939) (xy 27.677092 -49.453039) (xy 27.621358 -49.451002) (xy 27.566515 -49.440872)
			(xy 27.513731 -49.422865) (xy 27.464131 -49.397364) (xy 27.418773 -49.364913) (xy 27.378624 -49.326204)
			(xy 27.344538 -49.282061) (xy 27.317242 -49.233426) (xy 27.297319 -49.181335) (xy 27.285193 -49.126898)
			(xy 27.281122 -49.071276) (xy 26.005341 -49.071276) (xy 26.033195 -49.094456) (xy 26.070412 -49.135993)
			(xy 26.101185 -49.182506) (xy 26.124857 -49.233003) (xy 26.140925 -49.28641) (xy 26.149045 -49.341586)
			(xy 26.149554 -49.369472) (xy 26.149045 -49.397358) (xy 26.140925 -49.452534) (xy 26.124857 -49.505941)
			(xy 26.101185 -49.556438) (xy 26.070412 -49.602951) (xy 26.033195 -49.644488) (xy 25.990327 -49.680163)
			(xy 25.942721 -49.709217) (xy 25.891392 -49.731029) (xy 25.837435 -49.745135) (xy 25.781998 -49.751235)
			(xy 25.726264 -49.749198) (xy 25.671421 -49.739068) (xy 25.618637 -49.721061) (xy 25.569037 -49.69556)
			(xy 25.523679 -49.663109) (xy 25.48353 -49.6244) (xy 25.449444 -49.580257) (xy 25.422148 -49.531622)
			(xy 25.402225 -49.479531) (xy 25.390099 -49.425094) (xy 25.386028 -49.369472) (xy 24.56688 -49.369472)
			(xy 24.56688 -53.542184) (xy 26.6733 -53.542184) (xy 26.677371 -53.486562) (xy 26.689497 -53.432125)
			(xy 26.70942 -53.380034) (xy 26.736716 -53.331399) (xy 26.770802 -53.287256) (xy 26.810951 -53.248547)
			(xy 26.856309 -53.216096) (xy 26.905909 -53.190595) (xy 26.958693 -53.172588) (xy 27.013536 -53.162458)
			(xy 27.06927 -53.160421) (xy 27.124707 -53.166521) (xy 27.178664 -53.180627) (xy 27.229993 -53.202439)
			(xy 27.277599 -53.231493) (xy 27.320467 -53.267168) (xy 27.357684 -53.308705) (xy 27.388457 -53.355218)
			(xy 27.412129 -53.405715) (xy 27.428197 -53.459122) (xy 27.436317 -53.514298) (xy 27.436826 -53.542184)
			(xy 27.436317 -53.57007) (xy 27.428197 -53.625246) (xy 27.412129 -53.678653) (xy 27.388457 -53.72915)
			(xy 27.357684 -53.775663) (xy 27.320467 -53.8172) (xy 27.277599 -53.852875) (xy 27.229993 -53.881929)
			(xy 27.178664 -53.903741) (xy 27.124707 -53.917847) (xy 27.06927 -53.923947) (xy 27.013536 -53.92191)
			(xy 26.958693 -53.91178) (xy 26.905909 -53.893773) (xy 26.856309 -53.868272) (xy 26.810951 -53.835821)
			(xy 26.770802 -53.797112) (xy 26.736716 -53.752969) (xy 26.70942 -53.704334) (xy 26.689497 -53.652243)
			(xy 26.677371 -53.597806) (xy 26.6733 -53.542184) (xy 24.56688 -53.542184) (xy 24.56688 -56.19623)
			(xy 24.631142 -56.268366) (xy 24.679402 -56.273954) (xy 24.705884 -56.27748) (xy 24.757571 -56.290985)
			(xy 24.806869 -56.31157) (xy 24.852814 -56.338831) (xy 24.894505 -56.372235) (xy 24.931128 -56.41113)
			(xy 24.961967 -56.454753) (xy 24.986418 -56.502252) (xy 25.004002 -56.552698) (xy 25.014377 -56.605104)
			(xy 25.017339 -56.658445) (xy 25.01283 -56.711677) (xy 25.008557 -56.730392) (xy 25.277062 -56.730392)
			(xy 25.281133 -56.67477) (xy 25.293259 -56.620333) (xy 25.313182 -56.568242) (xy 25.340478 -56.519607)
			(xy 25.374564 -56.475464) (xy 25.414713 -56.436755) (xy 25.460071 -56.404304) (xy 25.509671 -56.378803)
			(xy 25.562455 -56.360796) (xy 25.617298 -56.350666) (xy 25.673032 -56.348629) (xy 25.728469 -56.354729)
			(xy 25.782426 -56.368835) (xy 25.833755 -56.390647) (xy 25.881361 -56.419701) (xy 25.924229 -56.455376)
			(xy 25.961446 -56.496913) (xy 25.992219 -56.543426) (xy 26.015891 -56.593923) (xy 26.031959 -56.64733)
			(xy 26.040079 -56.702506) (xy 26.040588 -56.730392) (xy 26.040079 -56.758278) (xy 26.031959 -56.813454)
			(xy 26.015891 -56.866861) (xy 25.992219 -56.917358) (xy 25.961446 -56.963871) (xy 25.924229 -57.005408)
			(xy 25.881361 -57.041083) (xy 25.833755 -57.070137) (xy 25.782426 -57.091949) (xy 25.728469 -57.106055)
			(xy 25.673032 -57.112155) (xy 25.617298 -57.110118) (xy 25.562455 -57.099988) (xy 25.509671 -57.081981)
			(xy 25.460071 -57.05648) (xy 25.414713 -57.024029) (xy 25.374564 -56.98532) (xy 25.340478 -56.941177)
			(xy 25.313182 -56.892542) (xy 25.293259 -56.840451) (xy 25.281133 -56.786014) (xy 25.277062 -56.730392)
			(xy 25.008557 -56.730392) (xy 25.000938 -56.76376) (xy 24.981896 -56.813674) (xy 24.96947 -56.837326)
			(xy 24.962097 -56.851611) (xy 24.954058 -56.882726) (xy 24.954057 -56.914863) (xy 24.962093 -56.945979)
			(xy 24.96947 -56.960262) (xy 24.981995 -56.983868) (xy 25.001048 -57.033793) (xy 25.012948 -57.085889)
			(xy 25.017461 -57.139135) (xy 25.014501 -57.19249) (xy 25.004124 -57.244911) (xy 24.986533 -57.29537)
			(xy 24.962073 -57.34288) (xy 24.931223 -57.386513) (xy 24.894585 -57.425414) (xy 24.852878 -57.458821)
			(xy 24.806917 -57.486082) (xy 24.757602 -57.506662) (xy 24.705897 -57.520159) (xy 24.679402 -57.523634)
			(xy 24.679148 -57.523634) (xy 24.663874 -57.525845) (xy 24.634981 -57.536669) (xy 24.609537 -57.554121)
			(xy 24.589034 -57.577177) (xy 24.574673 -57.604485) (xy 24.567297 -57.634444) (xy 24.56688 -57.649872)
			(xy 24.56688 -57.823354) (xy 24.80818 -58.064654) (xy 24.80818 -58.830972) (xy 24.808032 -58.845188)
			(xy 24.805867 -58.873539) (xy 24.803862 -58.887614) (xy 24.798528 -58.916062) (xy 24.794565 -58.938528)
			(xy 24.793762 -58.984137) (xy 24.801107 -59.029157) (xy 24.816364 -59.072144) (xy 24.839045 -59.111721)
			(xy 24.868422 -59.146618) (xy 24.903552 -59.175715) (xy 24.943309 -59.198078) (xy 24.986417 -59.212992)
			(xy 25.031494 -59.219977) (xy 25.054306 -59.219846) (xy 25.08541 -59.219195) (xy 25.147156 -59.226774)
			(xy 25.206859 -59.244253) (xy 25.235154 -59.257184) (xy 25.259233 -59.269273) (xy 25.304027 -59.299214)
			(xy 25.344161 -59.33516) (xy 25.378839 -59.376396) (xy 25.407369 -59.422101) (xy 25.429184 -59.471365)
			(xy 25.44385 -59.52321) (xy 25.451076 -59.576602) (xy 25.450716 -59.630479) (xy 25.44278 -59.68377)
			(xy 25.427423 -59.735414) (xy 25.404953 -59.784383) (xy 25.375816 -59.829704) (xy 25.340592 -59.870474)
			(xy 25.299981 -59.905881) (xy 25.254793 -59.935223) (xy 25.230582 -59.947048) (xy 25.206008 -59.957965)
			(xy 25.154548 -59.973559) (xy 25.101406 -59.981764) (xy 25.047639 -59.982417) (xy 24.994314 -59.975505)
			(xy 24.94249 -59.961166) (xy 24.917654 -59.950858) (xy 24.896506 -59.942684) (xy 24.85219 -59.933125)
			(xy 24.806881 -59.931581) (xy 24.762017 -59.938099) (xy 24.719022 -59.952475) (xy 24.679259 -59.97425)
			(xy 24.64399 -60.002735) (xy 24.614335 -60.037026) (xy 24.591234 -60.076033) (xy 24.57542 -60.118521)
			(xy 24.567396 -60.16314) (xy 24.56688 -60.185808) (xy 24.56688 -60.870592) (xy 24.567382 -60.893023)
			(xy 24.575306 -60.93718) (xy 24.590857 -60.979261) (xy 24.613551 -61.01796) (xy 24.642685 -61.052075)
			(xy 24.677354 -61.080548) (xy 24.716482 -61.102495) (xy 24.758854 -61.117234) (xy 24.803156 -61.124308)
			(xy 24.848011 -61.123497) (xy 24.892028 -61.114827) (xy 24.93384 -61.098566) (xy 24.953214 -61.087254)
			(xy 25.008172 -61.05426) (xy 25.121602 -60.994524) (xy 25.238612 -60.942149) (xy 25.358727 -60.897347)
			(xy 25.481457 -60.860303) (xy 25.6063 -60.831167) (xy 25.732748 -60.810058) (xy 25.860285 -60.797062)
			(xy 25.988392 -60.792231) (xy 26.116547 -60.795587) (xy 26.244225 -60.807114) (xy 26.370908 -60.826766)
			(xy 26.496079 -60.854463) (xy 26.619226 -60.890091) (xy 26.739849 -60.933506) (xy 26.857455 -60.984531)
			(xy 26.971565 -61.042958) (xy 27.081714 -61.108548) (xy 27.187452 -61.181033) (xy 27.288348 -61.260119)
			(xy 27.383992 -61.345483) (xy 27.473993 -61.436777) (xy 27.557984 -61.533629) (xy 27.635622 -61.635644)
			(xy 27.706592 -61.742405) (xy 27.770604 -61.853478) (xy 27.827397 -61.96841) (xy 27.876739 -62.086732)
			(xy 27.918429 -62.207962) (xy 27.952297 -62.331605) (xy 27.978205 -62.457158) (xy 27.996048 -62.584108)
			(xy 28.005753 -62.711938) (xy 28.007279 -62.840127) (xy 28.000622 -62.968152) (xy 27.985808 -63.095492)
			(xy 27.962897 -63.221626) (xy 27.931983 -63.346041) (xy 27.913076 -63.40729) (xy 27.893561 -63.467148)
			(xy 27.848019 -63.584537) (xy 27.795207 -63.698841) (xy 27.735334 -63.809609) (xy 27.668635 -63.916405)
			(xy 27.595371 -64.018811) (xy 27.515832 -64.116421) (xy 27.43033 -64.208854) (xy 27.339202 -64.295744)
			(xy 27.242806 -64.376751) (xy 27.141521 -64.451555) (xy 27.035746 -64.519863) (xy 26.925896 -64.581405)
			(xy 26.812405 -64.63594) (xy 26.695718 -64.683252) (xy 26.576294 -64.723157) (xy 26.515568 -64.739774)
			(xy 26.473658 -64.75095) (xy 26.42108 -64.819276) (xy 26.42108 -65.946528) (xy 26.421627 -65.963175)
			(xy 26.430249 -65.995333) (xy 26.446898 -66.024165) (xy 26.470442 -66.047707) (xy 26.499274 -66.064354)
			(xy 26.531433 -66.072975) (xy 26.54808 -66.073528) (xy 26.5557 -66.073528) (xy 26.588447 -66.073991)
			(xy 26.653503 -66.081546) (xy 26.717251 -66.096566) (xy 26.778837 -66.118851) (xy 26.837435 -66.148101)
			(xy 26.892263 -66.183925) (xy 26.942584 -66.225843) (xy 26.987726 -66.273294) (xy 27.027083 -66.325643)
			(xy 27.060129 -66.382188) (xy 27.086422 -66.442172) (xy 27.105608 -66.504792) (xy 27.117431 -66.56921)
			(xy 27.121734 -66.634562) (xy 27.118457 -66.699973) (xy 27.107645 -66.764568) (xy 27.099006 -66.796158)
			(xy 27.089615 -66.827066) (xy 27.064725 -66.88668) (xy 27.033198 -66.943065) (xy 26.995444 -66.995485)
			(xy 26.974038 -67.019678) (xy 26.963267 -67.032353) (xy 26.948042 -67.061912) (xy 26.940965 -67.0944)
			(xy 26.942517 -67.127613) (xy 26.952591 -67.1593) (xy 26.961084 -67.173602) (xy 26.978784 -67.202187)
			(xy 27.008025 -67.262732) (xy 27.029878 -67.326318) (xy 27.044037 -67.392047) (xy 27.050299 -67.45899)
			(xy 27.048579 -67.526205) (xy 27.038899 -67.59274) (xy 27.021396 -67.657659) (xy 26.996318 -67.720043)
			(xy 26.964017 -67.779012) (xy 26.924952 -67.833735) (xy 26.879672 -67.883438) (xy 26.828816 -67.927421)
			(xy 26.773104 -67.965062) (xy 26.71332 -67.995829) (xy 26.65031 -68.01929) (xy 26.584962 -68.035111)
			(xy 26.518198 -68.043071) (xy 26.48458 -68.043552) (xy 26.144728 -68.043552) (xy 25.597104 -68.591176)
			(xy 25.597104 -77.709014) (xy 25.389078 -77.917294) (xy 25.318466 -77.987906) (xy 25.318466 -78.99527)
			(xy 22.83968 -81.474056) (xy 22.83968 -88.862992) (xy 23.993081 -88.862992) (xy 23.993081 -88.736856)
			(xy 24.001001 -88.610968) (xy 24.016811 -88.485826) (xy 24.040446 -88.361923) (xy 24.071815 -88.23975)
			(xy 24.110793 -88.119787) (xy 24.157227 -88.002508) (xy 24.210934 -87.888376) (xy 24.271701 -87.777841)
			(xy 24.339288 -87.671341) (xy 24.413429 -87.569294) (xy 24.493832 -87.472104) (xy 24.580178 -87.380154)
			(xy 24.672128 -87.293808) (xy 24.769318 -87.213405) (xy 24.871365 -87.139264) (xy 24.977865 -87.071677)
			(xy 25.0884 -87.01091) (xy 25.202532 -86.957203) (xy 25.319811 -86.910769) (xy 25.439774 -86.871791)
			(xy 25.561947 -86.840422) (xy 25.68585 -86.816787) (xy 25.810992 -86.800977) (xy 25.93688 -86.793057)
			(xy 26.063016 -86.793057) (xy 26.188904 -86.800977) (xy 26.314046 -86.816787) (xy 26.437949 -86.840422)
			(xy 26.560122 -86.871791) (xy 26.680085 -86.910769) (xy 26.797364 -86.957203) (xy 26.911496 -87.01091)
			(xy 27.022031 -87.071677) (xy 27.128531 -87.139264) (xy 27.230578 -87.213405) (xy 27.327768 -87.293808)
			(xy 27.419718 -87.380154) (xy 27.506064 -87.472104) (xy 27.586467 -87.569294) (xy 27.660608 -87.671341)
			(xy 27.728195 -87.777841) (xy 27.788962 -87.888376) (xy 27.842669 -88.002508) (xy 27.889103 -88.119787)
			(xy 27.928081 -88.23975) (xy 27.95945 -88.361923) (xy 27.983085 -88.485826) (xy 27.998895 -88.610968)
			(xy 28.006815 -88.736856) (xy 28.00731 -88.799924) (xy 28.006815 -88.862992) (xy 27.998895 -88.98888)
			(xy 27.983085 -89.114022) (xy 27.95945 -89.237925) (xy 27.928081 -89.360098) (xy 27.889103 -89.480061)
			(xy 27.842669 -89.59734) (xy 27.788962 -89.711472) (xy 27.728195 -89.822007) (xy 27.660608 -89.928507)
			(xy 27.586467 -90.030554) (xy 27.506064 -90.127744) (xy 27.419718 -90.219694) (xy 27.327768 -90.30604)
			(xy 27.230578 -90.386443) (xy 27.128531 -90.460584) (xy 27.022031 -90.528171) (xy 26.911496 -90.588938)
			(xy 26.797364 -90.642645) (xy 26.680085 -90.689079) (xy 26.560122 -90.728057) (xy 26.437949 -90.759426)
			(xy 26.314046 -90.783061) (xy 26.188904 -90.798871) (xy 26.063016 -90.806791) (xy 25.93688 -90.806791)
			(xy 25.810992 -90.798871) (xy 25.68585 -90.783061) (xy 25.561947 -90.759426) (xy 25.439774 -90.728057)
			(xy 25.319811 -90.689079) (xy 25.202532 -90.642645) (xy 25.0884 -90.588938) (xy 24.977865 -90.528171)
			(xy 24.871365 -90.460584) (xy 24.769318 -90.386443) (xy 24.672128 -90.30604) (xy 24.580178 -90.219694)
			(xy 24.493832 -90.127744) (xy 24.413429 -90.030554) (xy 24.339288 -89.928507) (xy 24.271701 -89.822007)
			(xy 24.210934 -89.711472) (xy 24.157227 -89.59734) (xy 24.110793 -89.480061) (xy 24.071815 -89.360098)
			(xy 24.040446 -89.237925) (xy 24.016811 -89.114022) (xy 24.001001 -88.98888) (xy 23.993081 -88.862992)
			(xy 22.83968 -88.862992) (xy 22.83968 -92.253033) (xy 27.61652 -92.253033) (xy 27.621769 -92.197995)
			(xy 27.634909 -92.144291) (xy 27.655663 -92.093047) (xy 27.683597 -92.045335) (xy 27.700478 -92.023438)
			(xy 27.710745 -92.009697) (xy 27.724228 -91.97817) (xy 27.728832 -91.944192) (xy 27.724224 -91.910214)
			(xy 27.710737 -91.87869) (xy 27.700478 -91.864942) (xy 27.683597 -91.843045) (xy 27.655663 -91.795333)
			(xy 27.634909 -91.744089) (xy 27.621769 -91.690385) (xy 27.61652 -91.635347) (xy 27.61927 -91.580127)
			(xy 27.629963 -91.525883) (xy 27.648374 -91.473751) (xy 27.674117 -91.424822) (xy 27.706655 -91.380122)
			(xy 27.745304 -91.340587) (xy 27.789255 -91.307045) (xy 27.837587 -91.280199) (xy 27.889289 -91.260612)
			(xy 27.943277 -91.248693) (xy 27.99842 -91.244692) (xy 28.053563 -91.248693) (xy 28.107551 -91.260612)
			(xy 28.159253 -91.280199) (xy 28.207585 -91.307045) (xy 28.251536 -91.340587) (xy 28.290185 -91.380122)
			(xy 28.322723 -91.424822) (xy 28.348466 -91.473751) (xy 28.366877 -91.525883) (xy 28.37757 -91.580127)
			(xy 28.38032 -91.635347) (xy 28.375071 -91.690385) (xy 28.361931 -91.744089) (xy 28.341177 -91.795333)
			(xy 28.313243 -91.843045) (xy 28.296362 -91.864942) (xy 28.286118 -91.878697) (xy 28.272638 -91.91022)
			(xy 28.268033 -91.944192) (xy 28.272634 -91.978165) (xy 28.286109 -92.009689) (xy 28.296362 -92.023438)
			(xy 28.313243 -92.045335) (xy 28.341177 -92.093047) (xy 28.361931 -92.144291) (xy 28.375071 -92.197995)
			(xy 28.38032 -92.253033) (xy 28.37757 -92.308253) (xy 28.366877 -92.362497) (xy 28.348466 -92.414629)
			(xy 28.322723 -92.463558) (xy 28.290185 -92.508258) (xy 28.251536 -92.547793) (xy 28.207585 -92.581335)
			(xy 28.159253 -92.608181) (xy 28.107551 -92.627768) (xy 28.053563 -92.639687) (xy 27.99842 -92.643688)
			(xy 27.943277 -92.639687) (xy 27.889289 -92.627768) (xy 27.837587 -92.608181) (xy 27.789255 -92.581335)
			(xy 27.745304 -92.547793) (xy 27.706655 -92.508258) (xy 27.674117 -92.463558) (xy 27.648374 -92.414629)
			(xy 27.629963 -92.362497) (xy 27.61927 -92.308253) (xy 27.61652 -92.253033) (xy 22.83968 -92.253033)
			(xy 22.83968 -93.407136) (xy 23.994317 -93.407136) (xy 24.001013 -93.35147) (xy 24.015785 -93.297384)
			(xy 24.038315 -93.246042) (xy 24.068119 -93.198552) (xy 24.104552 -93.155936) (xy 24.146832 -93.119112)
			(xy 24.194046 -93.088873) (xy 24.245178 -93.065872) (xy 24.299127 -93.050603) (xy 24.354729 -93.043396)
			(xy 24.410787 -93.044405) (xy 24.466094 -93.053609) (xy 24.519458 -93.07081) (xy 24.569729 -93.095637)
			(xy 24.615824 -93.127556) (xy 24.65675 -93.165878) (xy 24.674576 -93.18752) (xy 24.689691 -93.205603)
			(xy 24.7253 -93.236465) (xy 24.765987 -93.260235) (xy 24.810358 -93.276099) (xy 24.856893 -93.283512)
			(xy 24.903997 -93.282221) (xy 24.950056 -93.27227) (xy 24.993491 -93.253999) (xy 25.032815 -93.228036)
			(xy 25.066679 -93.19527) (xy 25.080722 -93.176344) (xy 25.097308 -93.153732) (xy 25.136093 -93.113229)
			(xy 25.180389 -93.078839) (xy 25.229241 -93.051304) (xy 25.281599 -93.031217) (xy 25.336332 -93.019011)
			(xy 25.392263 -93.014949) (xy 25.448186 -93.019117) (xy 25.502897 -93.031428) (xy 25.555216 -93.051614)
			(xy 25.604016 -93.079242) (xy 25.648247 -93.113716) (xy 25.686954 -93.154293) (xy 25.719304 -93.200099)
			(xy 25.744601 -93.250148) (xy 25.762299 -93.30336) (xy 25.772016 -93.35859) (xy 25.773544 -93.414648)
			(xy 25.766849 -93.470325) (xy 25.752076 -93.524422) (xy 25.729543 -93.575775) (xy 25.699736 -93.623275)
			(xy 25.663296 -93.6659) (xy 25.62101 -93.702732) (xy 25.573786 -93.732977) (xy 25.522645 -93.755984)
			(xy 25.468686 -93.771256) (xy 25.413073 -93.778464) (xy 25.357004 -93.777455) (xy 25.301687 -93.768248)
			(xy 25.248313 -93.751043) (xy 25.198033 -93.72621) (xy 25.151929 -93.694284) (xy 25.110996 -93.655953)
			(xy 25.093168 -93.634306) (xy 25.078119 -93.616164) (xy 25.042501 -93.585298) (xy 25.001804 -93.561527)
			(xy 24.957422 -93.545665) (xy 24.910877 -93.538256) (xy 24.863764 -93.539553) (xy 24.817697 -93.549513)
			(xy 24.774256 -93.567794) (xy 24.734929 -93.59377) (xy 24.701064 -93.62655) (xy 24.687022 -93.645482)
			(xy 24.670412 -93.66807) (xy 24.631629 -93.708561) (xy 24.587338 -93.742938) (xy 24.538491 -93.770461)
			(xy 24.486141 -93.790538) (xy 24.431417 -93.802736) (xy 24.375496 -93.806791) (xy 24.319584 -93.802618)
			(xy 24.264885 -93.790304) (xy 24.212578 -93.770117) (xy 24.16379 -93.74249) (xy 24.119571 -93.708019)
			(xy 24.080874 -93.667447) (xy 24.048533 -93.621647) (xy 24.023245 -93.571606) (xy 24.005554 -93.518403)
			(xy 23.995842 -93.463183) (xy 23.994317 -93.407136) (xy 22.83968 -93.407136) (xy 22.83968 -94.390972)
			(xy 22.402292 -94.82836) (xy 25.818336 -94.82836) (xy 25.822407 -94.772738) (xy 25.834533 -94.718301)
			(xy 25.854456 -94.66621) (xy 25.881752 -94.617575) (xy 25.915838 -94.573432) (xy 25.955987 -94.534723)
			(xy 26.001345 -94.502272) (xy 26.050945 -94.476771) (xy 26.103729 -94.458764) (xy 26.158572 -94.448634)
			(xy 26.214306 -94.446597) (xy 26.269743 -94.452697) (xy 26.3237 -94.466803) (xy 26.375029 -94.488615)
			(xy 26.422635 -94.517669) (xy 26.465503 -94.553344) (xy 26.50272 -94.594881) (xy 26.533493 -94.641394)
			(xy 26.557165 -94.691891) (xy 26.573233 -94.745298) (xy 26.581353 -94.800474) (xy 26.581862 -94.82836)
			(xy 26.581353 -94.856246) (xy 26.573233 -94.911422) (xy 26.557165 -94.964829) (xy 26.533493 -95.015326)
			(xy 26.50272 -95.061839) (xy 26.465503 -95.103376) (xy 26.422635 -95.139051) (xy 26.375029 -95.168105)
			(xy 26.3237 -95.189917) (xy 26.269743 -95.204023) (xy 26.214306 -95.210123) (xy 26.158572 -95.208086)
			(xy 26.103729 -95.197956) (xy 26.050945 -95.179949) (xy 26.001345 -95.154448) (xy 25.955987 -95.121997)
			(xy 25.915838 -95.083288) (xy 25.881752 -95.039145) (xy 25.854456 -94.99051) (xy 25.834533 -94.938419)
			(xy 25.822407 -94.883982) (xy 25.818336 -94.82836) (xy 22.402292 -94.82836) (xy 21.558758 -95.671894)
			(xy 23.989536 -95.671894) (xy 23.993607 -95.616272) (xy 24.005733 -95.561835) (xy 24.025656 -95.509744)
			(xy 24.052952 -95.461109) (xy 24.087038 -95.416966) (xy 24.127187 -95.378257) (xy 24.172545 -95.345806)
			(xy 24.222145 -95.320305) (xy 24.274929 -95.302298) (xy 24.329772 -95.292168) (xy 24.385506 -95.290131)
			(xy 24.440943 -95.296231) (xy 24.4949 -95.310337) (xy 24.546229 -95.332149) (xy 24.593835 -95.361203)
			(xy 24.636703 -95.396878) (xy 24.67392 -95.438415) (xy 24.704693 -95.484928) (xy 24.728365 -95.535425)
			(xy 24.744433 -95.588832) (xy 24.752553 -95.644008) (xy 24.753062 -95.671894) (xy 24.752553 -95.69978)
			(xy 24.744433 -95.754956) (xy 24.728365 -95.808363) (xy 24.704693 -95.85886) (xy 24.67392 -95.905373)
			(xy 24.636703 -95.94691) (xy 24.593835 -95.982585) (xy 24.546229 -96.011639) (xy 24.4949 -96.033451)
			(xy 24.440943 -96.047557) (xy 24.385506 -96.053657) (xy 24.329772 -96.05162) (xy 24.274929 -96.04149)
			(xy 24.222145 -96.023483) (xy 24.172545 -95.997982) (xy 24.127187 -95.965531) (xy 24.087038 -95.926822)
			(xy 24.052952 -95.882679) (xy 24.025656 -95.834044) (xy 24.005733 -95.781953) (xy 23.993607 -95.727516)
			(xy 23.989536 -95.671894) (xy 21.558758 -95.671894) (xy 20.98294 -96.247712) (xy 20.98294 -98.455226)
			(xy 21.105876 -98.579686) (xy 21.149818 -98.58502) (xy 21.177198 -98.588878) (xy 21.23053 -98.603471)
			(xy 21.281197 -98.62561) (xy 21.328138 -98.654831) (xy 21.370369 -98.690522) (xy 21.407005 -98.731935)
			(xy 21.43728 -98.778202) (xy 21.460559 -98.828356) (xy 21.476355 -98.881344) (xy 21.484336 -98.936058)
			(xy 21.484335 -98.99135) (xy 21.476353 -99.046064) (xy 21.460556 -99.099052) (xy 21.437276 -99.149205)
			(xy 21.407 -99.195472) (xy 21.370363 -99.236884) (xy 21.328131 -99.272574) (xy 21.28119 -99.301794)
			(xy 21.230522 -99.323931) (xy 21.17719 -99.338523) (xy 21.149818 -99.342448) (xy 21.105876 -99.347782)
			(xy 20.98294 -99.472242) (xy 20.98294 -100.081842) (xy 26.930856 -100.081842) (xy 26.934927 -100.02622)
			(xy 26.947053 -99.971783) (xy 26.966976 -99.919692) (xy 26.994272 -99.871057) (xy 27.028358 -99.826914)
			(xy 27.068507 -99.788205) (xy 27.113865 -99.755754) (xy 27.163465 -99.730253) (xy 27.216249 -99.712246)
			(xy 27.271092 -99.702116) (xy 27.326826 -99.700079) (xy 27.382263 -99.706179) (xy 27.43622 -99.720285)
			(xy 27.487549 -99.742097) (xy 27.535155 -99.771151) (xy 27.578023 -99.806826) (xy 27.61524 -99.848363)
			(xy 27.646013 -99.894876) (xy 27.669685 -99.945373) (xy 27.685753 -99.99878) (xy 27.693873 -100.053956)
			(xy 27.694382 -100.081842) (xy 27.693873 -100.109728) (xy 27.685753 -100.164904) (xy 27.669685 -100.218311)
			(xy 27.646013 -100.268808) (xy 27.61524 -100.315321) (xy 27.578023 -100.356858) (xy 27.535155 -100.392533)
			(xy 27.487549 -100.421587) (xy 27.43622 -100.443399) (xy 27.382263 -100.457505) (xy 27.326826 -100.463605)
			(xy 27.271092 -100.461568) (xy 27.216249 -100.451438) (xy 27.163465 -100.433431) (xy 27.113865 -100.40793)
			(xy 27.068507 -100.375479) (xy 27.028358 -100.33677) (xy 26.994272 -100.292627) (xy 26.966976 -100.243992)
			(xy 26.947053 -100.191901) (xy 26.934927 -100.137464) (xy 26.930856 -100.081842) (xy 20.98294 -100.081842)
			(xy 20.98294 -100.441252) (xy 20.983431 -100.463876) (xy 20.991439 -100.50841) (xy 21.007212 -100.550821)
			(xy 21.030248 -100.589766) (xy 21.059821 -100.624013) (xy 21.094994 -100.652479) (xy 21.134653 -100.674263)
			(xy 21.177545 -100.688675) (xy 21.199856 -100.692458) (xy 21.226679 -100.696899) (xy 21.278794 -100.712385)
			(xy 21.328183 -100.735113) (xy 21.373846 -100.764621) (xy 21.414857 -100.800313) (xy 21.450386 -100.841465)
			(xy 21.479713 -100.887245) (xy 21.49916 -100.929948) (xy 27.682442 -100.929948) (xy 27.686513 -100.874326)
			(xy 27.698639 -100.819889) (xy 27.718562 -100.767798) (xy 27.745858 -100.719163) (xy 27.779944 -100.67502)
			(xy 27.820093 -100.636311) (xy 27.865451 -100.60386) (xy 27.915051 -100.578359) (xy 27.967835 -100.560352)
			(xy 28.022678 -100.550222) (xy 28.078412 -100.548185) (xy 28.133849 -100.554285) (xy 28.187806 -100.568391)
			(xy 28.239135 -100.590203) (xy 28.286741 -100.619257) (xy 28.329609 -100.654932) (xy 28.366826 -100.696469)
			(xy 28.397599 -100.742982) (xy 28.421271 -100.793479) (xy 28.437339 -100.846886) (xy 28.445459 -100.902062)
			(xy 28.445968 -100.929948) (xy 28.445459 -100.957834) (xy 28.437339 -101.01301) (xy 28.421271 -101.066417)
			(xy 28.397599 -101.116914) (xy 28.366826 -101.163427) (xy 28.329609 -101.204964) (xy 28.286741 -101.240639)
			(xy 28.239135 -101.269693) (xy 28.187806 -101.291505) (xy 28.133849 -101.305611) (xy 28.078412 -101.311711)
			(xy 28.022678 -101.309674) (xy 27.967835 -101.299544) (xy 27.915051 -101.281537) (xy 27.865451 -101.256036)
			(xy 27.820093 -101.223585) (xy 27.779944 -101.184876) (xy 27.745858 -101.140733) (xy 27.718562 -101.092098)
			(xy 27.698639 -101.040007) (xy 27.686513 -100.98557) (xy 27.682442 -100.929948) (xy 21.49916 -100.929948)
			(xy 21.502245 -100.936723) (xy 21.517525 -100.9889) (xy 21.525242 -101.042717) (xy 21.525242 -101.097084)
			(xy 21.517524 -101.150901) (xy 21.502245 -101.203077) (xy 21.479713 -101.252556) (xy 21.450386 -101.298335)
			(xy 21.414857 -101.339487) (xy 21.373845 -101.375179) (xy 21.328183 -101.404687) (xy 21.278794 -101.427415)
			(xy 21.226678 -101.442901) (xy 21.199856 -101.447346) (xy 21.17755 -101.451141) (xy 21.134671 -101.465573)
			(xy 21.095023 -101.487366) (xy 21.059858 -101.515833) (xy 21.030288 -101.550074) (xy 21.007245 -101.589009)
			(xy 20.991457 -101.631407) (xy 20.983423 -101.675931) (xy 20.98294 -101.698552) (xy 20.98294 -104.206802)
			(xy 21.449536 -104.206802) (xy 21.453607 -104.15118) (xy 21.465733 -104.096743) (xy 21.485656 -104.044652)
			(xy 21.512952 -103.996017) (xy 21.547038 -103.951874) (xy 21.587187 -103.913165) (xy 21.632545 -103.880714)
			(xy 21.682145 -103.855213) (xy 21.734929 -103.837206) (xy 21.789772 -103.827076) (xy 21.845506 -103.825039)
			(xy 21.900943 -103.831139) (xy 21.9549 -103.845245) (xy 22.006229 -103.867057) (xy 22.053835 -103.896111)
			(xy 22.096703 -103.931786) (xy 22.13392 -103.973323) (xy 22.164693 -104.019836) (xy 22.188365 -104.070333)
			(xy 22.204433 -104.12374) (xy 22.212553 -104.178916) (xy 22.213062 -104.206802) (xy 22.212553 -104.234688)
			(xy 22.204433 -104.289864) (xy 22.188365 -104.343271) (xy 22.164693 -104.393768) (xy 22.13392 -104.440281)
			(xy 22.096703 -104.481818) (xy 22.053835 -104.517493) (xy 22.006229 -104.546547) (xy 21.9549 -104.568359)
			(xy 21.900943 -104.582465) (xy 21.845506 -104.588565) (xy 21.789772 -104.586528) (xy 21.734929 -104.576398)
			(xy 21.682145 -104.558391) (xy 21.632545 -104.53289) (xy 21.587187 -104.500439) (xy 21.547038 -104.46173)
			(xy 21.512952 -104.417587) (xy 21.485656 -104.368952) (xy 21.465733 -104.316861) (xy 21.453607 -104.262424)
			(xy 21.449536 -104.206802) (xy 20.98294 -104.206802) (xy 20.98294 -107.134077) (xy 22.486583 -107.134077)
			(xy 22.487079 -107.079087) (xy 22.495465 -107.024738) (xy 22.511566 -106.972155) (xy 22.53505 -106.922429)
			(xy 22.565429 -106.87659) (xy 22.583394 -106.855768) (xy 22.598994 -106.83746) (xy 22.623733 -106.796217)
			(xy 22.640278 -106.75106) (xy 22.64804 -106.703597) (xy 22.646743 -106.655522) (xy 22.636432 -106.608547)
			(xy 22.617476 -106.564348) (xy 22.604476 -106.54411) (xy 22.589465 -106.521067) (xy 22.565498 -106.471573)
			(xy 22.548884 -106.419149) (xy 22.539969 -106.364884) (xy 22.538937 -106.309901) (xy 22.545809 -106.25534)
			(xy 22.560443 -106.20233) (xy 22.582536 -106.151971) (xy 22.61163 -106.105304) (xy 22.647122 -106.063299)
			(xy 22.688277 -106.026823) (xy 22.734243 -105.996634) (xy 22.784066 -105.973357) (xy 22.836715 -105.957474)
			(xy 22.891099 -105.949314) (xy 22.946091 -105.949046) (xy 23.000551 -105.956676) (xy 23.053352 -105.972046)
			(xy 23.1034 -105.994837) (xy 23.149657 -106.024577) (xy 23.191166 -106.06065) (xy 23.227065 -106.102308)
			(xy 23.256612 -106.148688) (xy 23.279194 -106.198831) (xy 23.294344 -106.251695) (xy 23.301747 -106.306187)
			(xy 23.30125 -106.361178) (xy 23.292864 -106.415527) (xy 23.276762 -106.468109) (xy 23.253277 -106.517835)
			(xy 23.222897 -106.563675) (xy 23.204932 -106.584496) (xy 23.189364 -106.602831) (xy 23.164621 -106.644066)
			(xy 23.148071 -106.689218) (xy 23.140304 -106.736676) (xy 23.141596 -106.784748) (xy 23.151901 -106.83172)
			(xy 23.170853 -106.875917) (xy 23.18385 -106.896154) (xy 23.198865 -106.919193) (xy 23.222833 -106.968688)
			(xy 23.239446 -107.021111) (xy 23.248361 -107.075376) (xy 23.249393 -107.130359) (xy 23.246665 -107.152021)
			(xy 24.614274 -107.152021) (xy 24.620036 -107.097337) (xy 24.633589 -107.044047) (xy 24.65465 -106.993253)
			(xy 24.682783 -106.946009) (xy 24.699722 -106.924348) (xy 24.714438 -106.905357) (xy 24.737148 -106.863027)
			(xy 24.751494 -106.817181) (xy 24.756962 -106.769455) (xy 24.753357 -106.721552) (xy 24.740809 -106.675182)
			(xy 24.719765 -106.631999) (xy 24.705818 -106.612436) (xy 24.689735 -106.590132) (xy 24.663457 -106.541832)
			(xy 24.644383 -106.490259) (xy 24.63291 -106.436483) (xy 24.629274 -106.381617) (xy 24.63355 -106.326797)
			(xy 24.645652 -106.273159) (xy 24.665327 -106.221813) (xy 24.692168 -106.173823) (xy 24.725619 -106.130182)
			(xy 24.764988 -106.091795) (xy 24.80946 -106.059456) (xy 24.858112 -106.033835) (xy 24.909939 -106.015463)
			(xy 24.963866 -106.00472) (xy 25.018776 -106.001829) (xy 25.073533 -106.006849) (xy 25.127002 -106.019677)
			(xy 25.178076 -106.040047) (xy 25.225698 -106.067536) (xy 25.268881 -106.101577) (xy 25.30673 -106.141463)
			(xy 25.338463 -106.186369) (xy 25.363421 -106.235365) (xy 25.381089 -106.287436) (xy 25.391099 -106.341503)
			(xy 25.393245 -106.396448) (xy 25.387483 -106.451131) (xy 25.373931 -106.504422) (xy 25.35287 -106.555215)
			(xy 25.324737 -106.602459) (xy 25.307798 -106.62412) (xy 25.293112 -106.643133) (xy 25.270397 -106.685457)
			(xy 25.256047 -106.731298) (xy 25.250574 -106.77902) (xy 25.254174 -106.82692) (xy 25.266717 -106.873288)
			(xy 25.287757 -106.916469) (xy 25.301702 -106.936032) (xy 25.317785 -106.958336) (xy 25.344064 -107.006636)
			(xy 25.363138 -107.058209) (xy 25.374612 -107.111985) (xy 25.378248 -107.166852) (xy 25.373971 -107.221672)
			(xy 25.36187 -107.27531) (xy 25.342195 -107.326657) (xy 25.315354 -107.374647) (xy 25.281902 -107.418288)
			(xy 25.242533 -107.456675) (xy 25.198061 -107.489015) (xy 25.149408 -107.514636) (xy 25.097582 -107.533008)
			(xy 25.043655 -107.543751) (xy 24.988744 -107.546642) (xy 24.933987 -107.541622) (xy 24.880518 -107.528794)
			(xy 24.829443 -107.508424) (xy 24.781821 -107.480934) (xy 24.738638 -107.446894) (xy 24.700788 -107.407007)
			(xy 24.669056 -107.362101) (xy 24.644097 -107.313105) (xy 24.62643 -107.261034) (xy 24.61642 -107.206966)
			(xy 24.614274 -107.152021) (xy 23.246665 -107.152021) (xy 23.242521 -107.18492) (xy 23.227887 -107.23793)
			(xy 23.205795 -107.288289) (xy 23.176701 -107.334955) (xy 23.141209 -107.376961) (xy 23.100054 -107.413436)
			(xy 23.054089 -107.443625) (xy 23.004266 -107.466902) (xy 22.951617 -107.482786) (xy 22.897233 -107.490946)
			(xy 22.842242 -107.491214) (xy 22.787781 -107.483584) (xy 22.73498 -107.468215) (xy 22.684932 -107.445425)
			(xy 22.638675 -107.415685) (xy 22.597167 -107.379613) (xy 22.561267 -107.337955) (xy 22.531719 -107.291575)
			(xy 22.509137 -107.241433) (xy 22.493987 -107.188569) (xy 22.486583 -107.134077) (xy 20.98294 -107.134077)
			(xy 20.98294 -108.889456) (xy 21.474849 -108.889456) (xy 21.479505 -108.834722) (xy 21.491965 -108.781221)
			(xy 21.511973 -108.730062) (xy 21.539113 -108.682303) (xy 21.572825 -108.638932) (xy 21.592286 -108.619544)
			(xy 21.608307 -108.603404) (xy 21.634939 -108.566547) (xy 21.654592 -108.525543) (xy 21.666641 -108.481697)
			(xy 21.670701 -108.436407) (xy 21.666643 -108.391117) (xy 21.654597 -108.34727) (xy 21.634946 -108.306265)
			(xy 21.608316 -108.269406) (xy 21.592286 -108.253276) (xy 21.572825 -108.233888) (xy 21.539113 -108.190517)
			(xy 21.511973 -108.142758) (xy 21.491965 -108.091599) (xy 21.479505 -108.038098) (xy 21.474849 -107.983364)
			(xy 21.478094 -107.928528) (xy 21.489173 -107.874724) (xy 21.507857 -107.823067) (xy 21.533759 -107.774625)
			(xy 21.566343 -107.730401) (xy 21.604935 -107.691309) (xy 21.648737 -107.658158) (xy 21.696842 -107.631634)
			(xy 21.748254 -107.612287) (xy 21.80191 -107.600516) (xy 21.8567 -107.596565) (xy 21.91149 -107.600516)
			(xy 21.965146 -107.612287) (xy 22.016558 -107.631634) (xy 22.064663 -107.658158) (xy 22.108465 -107.691309)
			(xy 22.147057 -107.730401) (xy 22.179641 -107.774625) (xy 22.205543 -107.823067) (xy 22.224227 -107.874724)
			(xy 22.235306 -107.928528) (xy 22.238551 -107.983364) (xy 22.233895 -108.038098) (xy 22.221435 -108.091599)
			(xy 22.201427 -108.142758) (xy 22.174287 -108.190517) (xy 22.140575 -108.233888) (xy 22.121114 -108.253276)
			(xy 22.105073 -108.269397) (xy 22.078442 -108.306257) (xy 22.05879 -108.347265) (xy 22.046743 -108.391114)
			(xy 22.042685 -108.436407) (xy 22.046745 -108.481699) (xy 22.058795 -108.525548) (xy 22.078449 -108.566555)
			(xy 22.105082 -108.603414) (xy 22.121114 -108.619544) (xy 22.140575 -108.638932) (xy 22.174287 -108.682303)
			(xy 22.201427 -108.730062) (xy 22.221435 -108.781221) (xy 22.233895 -108.834722) (xy 22.238414 -108.887843)
			(xy 25.437478 -108.887843) (xy 25.443485 -108.832471) (xy 25.457483 -108.778562) (xy 25.479174 -108.727262)
			(xy 25.508097 -108.679664) (xy 25.525476 -108.657898) (xy 25.539156 -108.640656) (xy 25.561018 -108.602461)
			(xy 25.575968 -108.561069) (xy 25.583558 -108.517719) (xy 25.58356 -108.47371) (xy 25.575976 -108.430359)
			(xy 25.561031 -108.388966) (xy 25.539173 -108.350768) (xy 25.525476 -108.33354) (xy 25.508097 -108.311774)
			(xy 25.479174 -108.264176) (xy 25.457483 -108.212876) (xy 25.443485 -108.158967) (xy 25.437478 -108.103595)
			(xy 25.43959 -108.047939) (xy 25.449776 -107.993181) (xy 25.467819 -107.940488) (xy 25.493335 -107.89098)
			(xy 25.525782 -107.84571) (xy 25.564469 -107.805642) (xy 25.608573 -107.771628) (xy 25.657156 -107.744392)
			(xy 25.709185 -107.724512) (xy 25.763551 -107.712413) (xy 25.8191 -107.708351) (xy 25.874649 -107.712413)
			(xy 25.929015 -107.724512) (xy 25.981044 -107.744392) (xy 26.029627 -107.771628) (xy 26.073731 -107.805642)
			(xy 26.112418 -107.84571) (xy 26.144865 -107.89098) (xy 26.170381 -107.940488) (xy 26.188424 -107.993181)
			(xy 26.19861 -108.047939) (xy 26.200722 -108.103595) (xy 26.194715 -108.158967) (xy 26.180717 -108.212876)
			(xy 26.159026 -108.264176) (xy 26.130103 -108.311774) (xy 26.112724 -108.33354) (xy 26.09904 -108.350769)
			(xy 26.07724 -108.388983) (xy 26.062336 -108.430377) (xy 26.054773 -108.473717) (xy 26.054775 -108.517712)
			(xy 26.062344 -108.561051) (xy 26.077252 -108.602444) (xy 26.099057 -108.640655) (xy 26.112724 -108.657898)
			(xy 26.130103 -108.679664) (xy 26.159026 -108.727262) (xy 26.180717 -108.778562) (xy 26.194715 -108.832471)
			(xy 26.200722 -108.887843) (xy 26.19861 -108.943499) (xy 26.188424 -108.998257) (xy 26.170381 -109.05095)
			(xy 26.144865 -109.100458) (xy 26.112418 -109.145728) (xy 26.073731 -109.185796) (xy 26.029627 -109.21981)
			(xy 25.981044 -109.247046) (xy 25.929015 -109.266926) (xy 25.874649 -109.279025) (xy 25.8191 -109.283087)
			(xy 25.763551 -109.279025) (xy 25.709185 -109.266926) (xy 25.657156 -109.247046) (xy 25.608573 -109.21981)
			(xy 25.564469 -109.185796) (xy 25.525782 -109.145728) (xy 25.493335 -109.100458) (xy 25.467819 -109.05095)
			(xy 25.449776 -108.998257) (xy 25.43959 -108.943499) (xy 25.437478 -108.887843) (xy 22.238414 -108.887843)
			(xy 22.238551 -108.889456) (xy 22.235306 -108.944292) (xy 22.224227 -108.998096) (xy 22.205543 -109.049753)
			(xy 22.179641 -109.098195) (xy 22.147057 -109.142419) (xy 22.108465 -109.181511) (xy 22.064663 -109.214662)
			(xy 22.016558 -109.241186) (xy 21.965146 -109.260533) (xy 21.91149 -109.272304) (xy 21.8567 -109.276255)
			(xy 21.80191 -109.272304) (xy 21.748254 -109.260533) (xy 21.696842 -109.241186) (xy 21.648737 -109.214662)
			(xy 21.604935 -109.181511) (xy 21.566343 -109.142419) (xy 21.533759 -109.098195) (xy 21.507857 -109.049753)
			(xy 21.489173 -108.998096) (xy 21.478094 -108.944292) (xy 21.474849 -108.889456) (xy 20.98294 -108.889456)
			(xy 20.98294 -111.117352) (xy 21.474783 -111.117352) (xy 21.478675 -111.062997) (xy 21.490263 -111.00975)
			(xy 21.509311 -110.958694) (xy 21.535432 -110.910868) (xy 21.551392 -110.88878) (xy 21.565007 -110.869781)
			(xy 21.585738 -110.827894) (xy 21.598462 -110.782923) (xy 21.60275 -110.736384) (xy 21.598456 -110.689845)
			(xy 21.585727 -110.644876) (xy 21.56499 -110.602992) (xy 21.551392 -110.58398) (xy 21.535432 -110.561892)
			(xy 21.509311 -110.514066) (xy 21.490263 -110.46301) (xy 21.478675 -110.409763) (xy 21.474783 -110.355408)
			(xy 21.478667 -110.301053) (xy 21.490247 -110.247804) (xy 21.509288 -110.196745) (xy 21.535402 -110.148915)
			(xy 21.568057 -110.105289) (xy 21.606588 -110.066755) (xy 21.650212 -110.034097) (xy 21.698039 -110.00798)
			(xy 21.749097 -109.988935) (xy 21.802345 -109.977351) (xy 21.8567 -109.973463) (xy 21.911055 -109.977351)
			(xy 21.964303 -109.988935) (xy 22.015361 -110.00798) (xy 22.063188 -110.034097) (xy 22.106812 -110.066755)
			(xy 22.145343 -110.105289) (xy 22.177998 -110.148915) (xy 22.204112 -110.196745) (xy 22.223153 -110.247804)
			(xy 22.234733 -110.301053) (xy 22.238617 -110.355408) (xy 22.234725 -110.409763) (xy 22.223137 -110.46301)
			(xy 22.204089 -110.514066) (xy 22.177968 -110.561892) (xy 22.162008 -110.58398) (xy 22.148431 -110.603005)
			(xy 22.127696 -110.644885) (xy 22.114967 -110.68985) (xy 22.110674 -110.736384) (xy 22.114419 -110.777023)
			(xy 25.43748 -110.777023) (xy 25.439512 -110.721312) (xy 25.449633 -110.666491) (xy 25.467629 -110.613727)
			(xy 25.493115 -110.564146) (xy 25.525548 -110.518804) (xy 25.544526 -110.498382) (xy 25.555488 -110.486316)
			(xy 25.571483 -110.457925) (xy 25.579753 -110.426405) (xy 25.579756 -110.393819) (xy 25.571492 -110.362297)
			(xy 25.555503 -110.333903) (xy 25.544526 -110.321852) (xy 25.525548 -110.30143) (xy 25.493115 -110.256088)
			(xy 25.467629 -110.206507) (xy 25.449633 -110.153743) (xy 25.439512 -110.098922) (xy 25.43748 -110.043211)
			(xy 25.44358 -109.987798) (xy 25.457684 -109.933864) (xy 25.47949 -109.882558) (xy 25.508533 -109.834973)
			(xy 25.544196 -109.792124) (xy 25.585716 -109.754924) (xy 25.632211 -109.724165) (xy 25.682688 -109.700503)
			(xy 25.736072 -109.684443) (xy 25.791226 -109.676327) (xy 25.846974 -109.676327) (xy 25.902128 -109.684443)
			(xy 25.955512 -109.700503) (xy 26.005989 -109.724165) (xy 26.052484 -109.754924) (xy 26.094004 -109.792124)
			(xy 26.129667 -109.834973) (xy 26.145146 -109.860334) (xy 40.654984 -109.860334) (xy 40.659055 -109.804712)
			(xy 40.671181 -109.750275) (xy 40.691104 -109.698184) (xy 40.7184 -109.649549) (xy 40.752486 -109.605406)
			(xy 40.792635 -109.566697) (xy 40.837993 -109.534246) (xy 40.887593 -109.508745) (xy 40.940377 -109.490738)
			(xy 40.99522 -109.480608) (xy 41.050954 -109.478571) (xy 41.106391 -109.484671) (xy 41.160348 -109.498777)
			(xy 41.211677 -109.520589) (xy 41.259283 -109.549643) (xy 41.302151 -109.585318) (xy 41.339368 -109.626855)
			(xy 41.370141 -109.673368) (xy 41.393813 -109.723865) (xy 41.409881 -109.777272) (xy 41.418001 -109.832448)
			(xy 41.41851 -109.860334) (xy 41.418001 -109.88822) (xy 41.409881 -109.943396) (xy 41.393813 -109.996803)
			(xy 41.370141 -110.0473) (xy 41.339368 -110.093813) (xy 41.302151 -110.13535) (xy 41.259283 -110.171025)
			(xy 41.211677 -110.200079) (xy 41.160348 -110.221891) (xy 41.106391 -110.235997) (xy 41.050954 -110.242097)
			(xy 40.99522 -110.24006) (xy 40.940377 -110.22993) (xy 40.887593 -110.211923) (xy 40.837993 -110.186422)
			(xy 40.792635 -110.153971) (xy 40.752486 -110.115262) (xy 40.7184 -110.071119) (xy 40.691104 -110.022484)
			(xy 40.671181 -109.970393) (xy 40.659055 -109.915956) (xy 40.654984 -109.860334) (xy 26.145146 -109.860334)
			(xy 26.15871 -109.882558) (xy 26.180516 -109.933864) (xy 26.19462 -109.987798) (xy 26.20072 -110.043211)
			(xy 26.198688 -110.098922) (xy 26.188567 -110.153743) (xy 26.170571 -110.206507) (xy 26.145085 -110.256088)
			(xy 26.112652 -110.30143) (xy 26.093674 -110.321852) (xy 26.082722 -110.33391) (xy 26.066805 -110.36232)
			(xy 26.058582 -110.39383) (xy 26.058585 -110.426395) (xy 26.066815 -110.457903) (xy 26.082737 -110.48631)
			(xy 26.093674 -110.498382) (xy 26.112652 -110.518804) (xy 26.145085 -110.564146) (xy 26.170571 -110.613727)
			(xy 26.188567 -110.666491) (xy 26.198688 -110.721312) (xy 26.20072 -110.777023) (xy 26.19462 -110.832436)
			(xy 26.180516 -110.88637) (xy 26.15871 -110.937676) (xy 26.129667 -110.985261) (xy 26.094004 -111.02811)
			(xy 26.052484 -111.06531) (xy 26.005989 -111.096069) (xy 25.955512 -111.119731) (xy 25.902128 -111.135791)
			(xy 25.846974 -111.143907) (xy 25.791226 -111.143907) (xy 25.736072 -111.135791) (xy 25.682688 -111.119731)
			(xy 25.632211 -111.096069) (xy 25.585716 -111.06531) (xy 25.544196 -111.02811) (xy 25.508533 -110.985261)
			(xy 25.47949 -110.937676) (xy 25.457684 -110.88637) (xy 25.44358 -110.832436) (xy 25.43748 -110.777023)
			(xy 22.114419 -110.777023) (xy 22.114962 -110.782919) (xy 22.127684 -110.827885) (xy 22.148414 -110.869768)
			(xy 22.162008 -110.88878) (xy 22.177968 -110.910868) (xy 22.204089 -110.958694) (xy 22.223137 -111.00975)
			(xy 22.234725 -111.062997) (xy 22.238617 -111.117352) (xy 22.234733 -111.171707) (xy 22.223153 -111.224956)
			(xy 22.204112 -111.276015) (xy 22.177998 -111.323845) (xy 22.150025 -111.361216) (xy 34.780961 -111.361216)
			(xy 34.785243 -111.304164) (xy 34.797996 -111.248391) (xy 34.818935 -111.195148) (xy 34.847591 -111.145629)
			(xy 34.865056 -111.122968) (xy 34.87529 -111.109206) (xy 34.888769 -111.077686) (xy 34.893375 -111.043716)
			(xy 34.888777 -111.009745) (xy 34.875306 -110.978221) (xy 34.865056 -110.964472) (xy 34.848175 -110.942575)
			(xy 34.820241 -110.894863) (xy 34.799487 -110.843619) (xy 34.786347 -110.789915) (xy 34.781098 -110.734877)
			(xy 34.783848 -110.679657) (xy 34.794541 -110.625413) (xy 34.812952 -110.573281) (xy 34.838695 -110.524352)
			(xy 34.871233 -110.479652) (xy 34.909882 -110.440117) (xy 34.953833 -110.406575) (xy 35.002165 -110.379729)
			(xy 35.053867 -110.360142) (xy 35.107855 -110.348223) (xy 35.162998 -110.344222) (xy 35.218141 -110.348223)
			(xy 35.272129 -110.360142) (xy 35.323831 -110.379729) (xy 35.372163 -110.406575) (xy 35.416114 -110.440117)
			(xy 35.454763 -110.479652) (xy 35.487301 -110.524352) (xy 35.51159 -110.570518) (xy 44.8851 -110.570518)
			(xy 44.889171 -110.514896) (xy 44.901297 -110.460459) (xy 44.92122 -110.408368) (xy 44.948516 -110.359733)
			(xy 44.982602 -110.31559) (xy 45.022751 -110.276881) (xy 45.068109 -110.24443) (xy 45.117709 -110.218929)
			(xy 45.170493 -110.200922) (xy 45.225336 -110.190792) (xy 45.28107 -110.188755) (xy 45.336507 -110.194855)
			(xy 45.390464 -110.208961) (xy 45.441793 -110.230773) (xy 45.489399 -110.259827) (xy 45.532267 -110.295502)
			(xy 45.569484 -110.337039) (xy 45.600257 -110.383552) (xy 45.623929 -110.434049) (xy 45.639997 -110.487456)
			(xy 45.648117 -110.542632) (xy 45.648603 -110.569248) (xy 46.069248 -110.569248) (xy 46.073319 -110.513626)
			(xy 46.085445 -110.459189) (xy 46.105368 -110.407098) (xy 46.132664 -110.358463) (xy 46.16675 -110.31432)
			(xy 46.206899 -110.275611) (xy 46.252257 -110.24316) (xy 46.301857 -110.217659) (xy 46.354641 -110.199652)
			(xy 46.409484 -110.189522) (xy 46.465218 -110.187485) (xy 46.520655 -110.193585) (xy 46.574612 -110.207691)
			(xy 46.625941 -110.229503) (xy 46.673547 -110.258557) (xy 46.716415 -110.294232) (xy 46.753632 -110.335769)
			(xy 46.784405 -110.382282) (xy 46.808077 -110.432779) (xy 46.824145 -110.486186) (xy 46.832265 -110.541362)
			(xy 46.832774 -110.569248) (xy 46.832265 -110.597134) (xy 46.824145 -110.65231) (xy 46.808077 -110.705717)
			(xy 46.784405 -110.756214) (xy 46.753632 -110.802727) (xy 46.716415 -110.844264) (xy 46.673547 -110.879939)
			(xy 46.663223 -110.88624) (xy 55.855106 -110.88624) (xy 55.859177 -110.830618) (xy 55.871303 -110.776181)
			(xy 55.891226 -110.72409) (xy 55.918522 -110.675455) (xy 55.952608 -110.631312) (xy 55.992757 -110.592603)
			(xy 56.038115 -110.560152) (xy 56.087715 -110.534651) (xy 56.140499 -110.516644) (xy 56.195342 -110.506514)
			(xy 56.251076 -110.504477) (xy 56.306513 -110.510577) (xy 56.36047 -110.524683) (xy 56.411799 -110.546495)
			(xy 56.459405 -110.575549) (xy 56.502273 -110.611224) (xy 56.53949 -110.652761) (xy 56.570263 -110.699274)
			(xy 56.593935 -110.749771) (xy 56.610003 -110.803178) (xy 56.618123 -110.858354) (xy 56.618631 -110.886212)
			(xy 57.760207 -110.886212) (xy 57.764099 -110.831857) (xy 57.775687 -110.77861) (xy 57.794735 -110.727554)
			(xy 57.820856 -110.679728) (xy 57.836816 -110.65764) (xy 57.850374 -110.638602) (xy 57.871108 -110.596725)
			(xy 57.883837 -110.551763) (xy 57.888133 -110.505232) (xy 57.883849 -110.4587) (xy 57.871131 -110.413735)
			(xy 57.850407 -110.371852) (xy 57.836816 -110.35284) (xy 57.820856 -110.330752) (xy 57.794735 -110.282926)
			(xy 57.775687 -110.23187) (xy 57.764099 -110.178623) (xy 57.760207 -110.124268) (xy 57.764091 -110.069913)
			(xy 57.775671 -110.016664) (xy 57.794712 -109.965605) (xy 57.820826 -109.917775) (xy 57.853481 -109.874149)
			(xy 57.892012 -109.835615) (xy 57.935636 -109.802957) (xy 57.983463 -109.77684) (xy 58.034521 -109.757795)
			(xy 58.087769 -109.746211) (xy 58.142124 -109.742323) (xy 58.196479 -109.746211) (xy 58.249727 -109.757795)
			(xy 58.300785 -109.77684) (xy 58.348612 -109.802957) (xy 58.392236 -109.835615) (xy 58.430767 -109.874149)
			(xy 58.463422 -109.917775) (xy 58.489536 -109.965605) (xy 58.508577 -110.016664) (xy 58.520157 -110.069913)
			(xy 58.524041 -110.124268) (xy 58.520149 -110.178623) (xy 58.508561 -110.23187) (xy 58.489513 -110.282926)
			(xy 58.463392 -110.330752) (xy 58.447432 -110.35284) (xy 58.433798 -110.371826) (xy 58.413066 -110.413716)
			(xy 58.400343 -110.45869) (xy 58.396058 -110.505232) (xy 58.400355 -110.551773) (xy 58.413089 -110.596744)
			(xy 58.428359 -110.627578) (xy 61.644239 -110.627578) (xy 61.650892 -110.571904) (xy 61.665625 -110.517805)
			(xy 61.688119 -110.466446) (xy 61.71789 -110.418933) (xy 61.735716 -110.39729) (xy 61.745107 -110.385591)
			(xy 61.758741 -110.358881) (xy 61.765755 -110.329725) (xy 61.765762 -110.299736) (xy 61.758762 -110.270576)
			(xy 61.745141 -110.243859) (xy 61.735716 -110.23219) (xy 61.71789 -110.210547) (xy 61.688119 -110.163034)
			(xy 61.665625 -110.111675) (xy 61.650892 -110.057576) (xy 61.644239 -110.001902) (xy 61.645808 -109.945855)
			(xy 61.655566 -109.890641) (xy 61.673303 -109.837451) (xy 61.698636 -109.787431) (xy 61.731019 -109.741659)
			(xy 61.769754 -109.70112) (xy 61.814007 -109.66669) (xy 61.862824 -109.63911) (xy 61.915153 -109.618974)
			(xy 61.969866 -109.606716) (xy 62.025784 -109.6026) (xy 62.081702 -109.606716) (xy 62.136415 -109.618974)
			(xy 62.188744 -109.63911) (xy 62.237561 -109.66669) (xy 62.281814 -109.70112) (xy 62.320549 -109.741659)
			(xy 62.352932 -109.787431) (xy 62.378265 -109.837451) (xy 62.396002 -109.890641) (xy 62.40576 -109.945855)
			(xy 62.407329 -110.001902) (xy 62.400676 -110.057576) (xy 62.385943 -110.111675) (xy 62.363449 -110.163034)
			(xy 62.333678 -110.210547) (xy 62.315852 -110.23219) (xy 62.306386 -110.243831) (xy 62.292763 -110.270559)
			(xy 62.285762 -110.299731) (xy 62.285769 -110.32973) (xy 62.292784 -110.358898) (xy 62.30642 -110.385619)
			(xy 62.315852 -110.39729) (xy 62.333678 -110.418933) (xy 62.363449 -110.466446) (xy 62.385943 -110.517805)
			(xy 62.400676 -110.571904) (xy 62.407329 -110.627578) (xy 62.40576 -110.683625) (xy 62.396002 -110.738839)
			(xy 62.378265 -110.792029) (xy 62.352932 -110.842049) (xy 62.320549 -110.887821) (xy 62.281814 -110.92836)
			(xy 62.237561 -110.96279) (xy 62.188744 -110.99037) (xy 62.136415 -111.010506) (xy 62.081702 -111.022764)
			(xy 62.025784 -111.02688) (xy 61.969866 -111.022764) (xy 61.915153 -111.010506) (xy 61.862824 -110.99037)
			(xy 61.814007 -110.96279) (xy 61.769754 -110.92836) (xy 61.731019 -110.887821) (xy 61.698636 -110.842049)
			(xy 61.673303 -110.792029) (xy 61.655566 -110.738839) (xy 61.645808 -110.683625) (xy 61.644239 -110.627578)
			(xy 58.428359 -110.627578) (xy 58.433831 -110.638628) (xy 58.447432 -110.65764) (xy 58.463392 -110.679728)
			(xy 58.489513 -110.727554) (xy 58.508561 -110.77861) (xy 58.520149 -110.831857) (xy 58.524041 -110.886212)
			(xy 58.520157 -110.940567) (xy 58.508577 -110.993816) (xy 58.489536 -111.044875) (xy 58.463422 -111.092705)
			(xy 58.430767 -111.136331) (xy 58.392236 -111.174865) (xy 58.348612 -111.207523) (xy 58.300785 -111.23364)
			(xy 58.249727 -111.252685) (xy 58.196479 -111.264269) (xy 58.142124 -111.268157) (xy 58.087769 -111.264269)
			(xy 58.034521 -111.252685) (xy 57.983463 -111.23364) (xy 57.935636 -111.207523) (xy 57.892012 -111.174865)
			(xy 57.853481 -111.136331) (xy 57.820826 -111.092705) (xy 57.794712 -111.044875) (xy 57.775671 -110.993816)
			(xy 57.764091 -110.940567) (xy 57.760207 -110.886212) (xy 56.618631 -110.886212) (xy 56.618632 -110.88624)
			(xy 56.618123 -110.914126) (xy 56.610003 -110.969302) (xy 56.593935 -111.022709) (xy 56.570263 -111.073206)
			(xy 56.53949 -111.119719) (xy 56.502273 -111.161256) (xy 56.459405 -111.196931) (xy 56.411799 -111.225985)
			(xy 56.36047 -111.247797) (xy 56.306513 -111.261903) (xy 56.251076 -111.268003) (xy 56.195342 -111.265966)
			(xy 56.140499 -111.255836) (xy 56.087715 -111.237829) (xy 56.038115 -111.212328) (xy 55.992757 -111.179877)
			(xy 55.952608 -111.141168) (xy 55.918522 -111.097025) (xy 55.891226 -111.04839) (xy 55.871303 -110.996299)
			(xy 55.859177 -110.941862) (xy 55.855106 -110.88624) (xy 46.663223 -110.88624) (xy 46.625941 -110.908993)
			(xy 46.574612 -110.930805) (xy 46.520655 -110.944911) (xy 46.465218 -110.951011) (xy 46.409484 -110.948974)
			(xy 46.354641 -110.938844) (xy 46.301857 -110.920837) (xy 46.252257 -110.895336) (xy 46.206899 -110.862885)
			(xy 46.16675 -110.824176) (xy 46.132664 -110.780033) (xy 46.105368 -110.731398) (xy 46.085445 -110.679307)
			(xy 46.073319 -110.62487) (xy 46.069248 -110.569248) (xy 45.648603 -110.569248) (xy 45.648626 -110.570518)
			(xy 45.648117 -110.598404) (xy 45.639997 -110.65358) (xy 45.623929 -110.706987) (xy 45.600257 -110.757484)
			(xy 45.569484 -110.803997) (xy 45.532267 -110.845534) (xy 45.489399 -110.881209) (xy 45.441793 -110.910263)
			(xy 45.390464 -110.932075) (xy 45.336507 -110.946181) (xy 45.28107 -110.952281) (xy 45.225336 -110.950244)
			(xy 45.170493 -110.940114) (xy 45.117709 -110.922107) (xy 45.068109 -110.896606) (xy 45.022751 -110.864155)
			(xy 44.982602 -110.825446) (xy 44.948516 -110.781303) (xy 44.92122 -110.732668) (xy 44.901297 -110.680577)
			(xy 44.889171 -110.62614) (xy 44.8851 -110.570518) (xy 35.51159 -110.570518) (xy 35.513044 -110.573281)
			(xy 35.531455 -110.625413) (xy 35.542148 -110.679657) (xy 35.544898 -110.734877) (xy 35.539649 -110.789915)
			(xy 35.526509 -110.843619) (xy 35.505755 -110.894863) (xy 35.477821 -110.942575) (xy 35.467598 -110.955836)
			(xy 40.65854 -110.955836) (xy 40.662611 -110.900214) (xy 40.674737 -110.845777) (xy 40.69466 -110.793686)
			(xy 40.721956 -110.745051) (xy 40.756042 -110.700908) (xy 40.796191 -110.662199) (xy 40.841549 -110.629748)
			(xy 40.891149 -110.604247) (xy 40.943933 -110.58624) (xy 40.998776 -110.57611) (xy 41.05451 -110.574073)
			(xy 41.109947 -110.580173) (xy 41.163904 -110.594279) (xy 41.215233 -110.616091) (xy 41.262839 -110.645145)
			(xy 41.305707 -110.68082) (xy 41.342924 -110.722357) (xy 41.373697 -110.76887) (xy 41.397369 -110.819367)
			(xy 41.413437 -110.872774) (xy 41.421557 -110.92795) (xy 41.422066 -110.955836) (xy 42.971464 -110.955836)
			(xy 42.975535 -110.900214) (xy 42.987661 -110.845777) (xy 43.007584 -110.793686) (xy 43.03488 -110.745051)
			(xy 43.068966 -110.700908) (xy 43.109115 -110.662199) (xy 43.154473 -110.629748) (xy 43.204073 -110.604247)
			(xy 43.256857 -110.58624) (xy 43.3117 -110.57611) (xy 43.367434 -110.574073) (xy 43.422871 -110.580173)
			(xy 43.476828 -110.594279) (xy 43.528157 -110.616091) (xy 43.575763 -110.645145) (xy 43.618631 -110.68082)
			(xy 43.655848 -110.722357) (xy 43.686621 -110.76887) (xy 43.710293 -110.819367) (xy 43.726361 -110.872774)
			(xy 43.734481 -110.92795) (xy 43.73499 -110.955836) (xy 43.734481 -110.983722) (xy 43.726361 -111.038898)
			(xy 43.710293 -111.092305) (xy 43.686621 -111.142802) (xy 43.655848 -111.189315) (xy 43.618631 -111.230852)
			(xy 43.575763 -111.266527) (xy 43.528157 -111.295581) (xy 43.476828 -111.317393) (xy 43.422871 -111.331499)
			(xy 43.367434 -111.337599) (xy 43.3117 -111.335562) (xy 43.256857 -111.325432) (xy 43.204073 -111.307425)
			(xy 43.154473 -111.281924) (xy 43.109115 -111.249473) (xy 43.068966 -111.210764) (xy 43.03488 -111.166621)
			(xy 43.007584 -111.117986) (xy 42.987661 -111.065895) (xy 42.975535 -111.011458) (xy 42.971464 -110.955836)
			(xy 41.422066 -110.955836) (xy 41.421557 -110.983722) (xy 41.413437 -111.038898) (xy 41.397369 -111.092305)
			(xy 41.373697 -111.142802) (xy 41.342924 -111.189315) (xy 41.305707 -111.230852) (xy 41.262839 -111.266527)
			(xy 41.215233 -111.295581) (xy 41.163904 -111.317393) (xy 41.109947 -111.331499) (xy 41.05451 -111.337599)
			(xy 40.998776 -111.335562) (xy 40.943933 -111.325432) (xy 40.891149 -111.307425) (xy 40.841549 -111.281924)
			(xy 40.796191 -111.249473) (xy 40.756042 -111.210764) (xy 40.721956 -111.166621) (xy 40.69466 -111.117986)
			(xy 40.674737 -111.065895) (xy 40.662611 -111.011458) (xy 40.65854 -110.955836) (xy 35.467598 -110.955836)
			(xy 35.46094 -110.964472) (xy 35.450669 -110.978209) (xy 35.437196 -111.009738) (xy 35.432597 -111.043716)
			(xy 35.437204 -111.077692) (xy 35.450685 -111.109218) (xy 35.46094 -111.122968) (xy 35.478426 -111.145615)
			(xy 35.507084 -111.195137) (xy 35.528025 -111.248383) (xy 35.540779 -111.30416) (xy 35.545061 -111.361216)
			(xy 35.540774 -111.418271) (xy 35.528015 -111.474046) (xy 35.50707 -111.527291) (xy 35.478409 -111.576811)
			(xy 35.46094 -111.599472) (xy 35.450669 -111.613209) (xy 35.437196 -111.644738) (xy 35.432597 -111.678716)
			(xy 35.437204 -111.712692) (xy 35.450685 -111.744218) (xy 35.46094 -111.757968) (xy 35.477821 -111.779865)
			(xy 35.505755 -111.827577) (xy 35.526509 -111.878821) (xy 35.539649 -111.932525) (xy 35.544898 -111.987563)
			(xy 35.542148 -112.042783) (xy 35.531455 -112.097027) (xy 35.513044 -112.149159) (xy 35.487301 -112.198088)
			(xy 35.454763 -112.242788) (xy 35.416114 -112.282323) (xy 35.372163 -112.315865) (xy 35.323831 -112.342711)
			(xy 35.272129 -112.362298) (xy 35.218141 -112.374217) (xy 35.162998 -112.378218) (xy 35.107855 -112.374217)
			(xy 35.053867 -112.362298) (xy 35.002165 -112.342711) (xy 34.953833 -112.315865) (xy 34.909882 -112.282323)
			(xy 34.871233 -112.242788) (xy 34.838695 -112.198088) (xy 34.812952 -112.149159) (xy 34.794541 -112.097027)
			(xy 34.783848 -112.042783) (xy 34.781098 -111.987563) (xy 34.786347 -111.932525) (xy 34.799487 -111.878821)
			(xy 34.820241 -111.827577) (xy 34.848175 -111.779865) (xy 34.865056 -111.757968) (xy 34.87529 -111.744206)
			(xy 34.888769 -111.712686) (xy 34.893375 -111.678716) (xy 34.888777 -111.644745) (xy 34.875306 -111.613221)
			(xy 34.865056 -111.599472) (xy 34.847608 -111.576797) (xy 34.818949 -111.52728) (xy 34.798005 -111.474039)
			(xy 34.785247 -111.418267) (xy 34.780961 -111.361216) (xy 22.150025 -111.361216) (xy 22.145343 -111.367471)
			(xy 22.106812 -111.406005) (xy 22.063188 -111.438663) (xy 22.015361 -111.46478) (xy 21.964303 -111.483825)
			(xy 21.911055 -111.495409) (xy 21.8567 -111.499297) (xy 21.802345 -111.495409) (xy 21.749097 -111.483825)
			(xy 21.698039 -111.46478) (xy 21.650212 -111.438663) (xy 21.606588 -111.406005) (xy 21.568057 -111.367471)
			(xy 21.535402 -111.323845) (xy 21.509288 -111.276015) (xy 21.490247 -111.224956) (xy 21.478667 -111.171707)
			(xy 21.474783 -111.117352) (xy 20.98294 -111.117352) (xy 20.98294 -112.07115) (xy 21.251418 -112.339628)
			(xy 21.26868 -112.356109) (xy 21.308136 -112.382948) (xy 21.351907 -112.401954) (xy 21.398456 -112.41246)
			(xy 21.446148 -112.414098) (xy 21.493307 -112.406808) (xy 21.538279 -112.390848) (xy 21.579483 -112.366779)
			(xy 21.597874 -112.351566) (xy 21.618044 -112.333577) (xy 21.662523 -112.302879) (xy 21.710891 -112.278765)
			(xy 21.762177 -112.26172) (xy 21.815356 -112.252084) (xy 21.869362 -112.250049) (xy 21.923115 -112.255658)
			(xy 21.975538 -112.268797) (xy 22.025582 -112.289203) (xy 22.072245 -112.316468) (xy 22.114593 -112.350046)
			(xy 22.151778 -112.389265) (xy 22.183055 -112.43334) (xy 22.207798 -112.481388) (xy 22.225513 -112.532447)
			(xy 22.235843 -112.585495) (xy 22.238583 -112.63947) (xy 22.233678 -112.693292) (xy 22.221226 -112.745882)
			(xy 22.201475 -112.796189) (xy 22.174823 -112.843204) (xy 22.158706 -112.8649) (xy 22.145975 -112.883526)
			(xy 22.12661 -112.924268) (xy 22.114743 -112.96779) (xy 22.110749 -113.012723) (xy 22.114752 -113.057655)
			(xy 22.126626 -113.101175) (xy 22.145999 -113.141914) (xy 22.158706 -113.160556) (xy 22.173145 -113.179905)
			(xy 22.197551 -113.221562) (xy 22.216507 -113.265965) (xy 22.223476 -113.28908) (xy 22.231479 -113.316868)
			(xy 25.42232 -113.316868) (xy 25.429064 -113.261734) (xy 25.443732 -113.208161) (xy 25.466014 -113.157281)
			(xy 25.495439 -113.110171) (xy 25.51303 -113.088674) (xy 25.526791 -113.071806) (xy 25.548909 -113.034316)
			(xy 25.56431 -112.993603) (xy 25.572544 -112.95086) (xy 25.573368 -112.90734) (xy 25.56676 -112.864316)
			(xy 25.552911 -112.823049) (xy 25.532229 -112.784748) (xy 25.519126 -112.767364) (xy 25.502358 -112.74522)
			(xy 25.474736 -112.697031) (xy 25.454395 -112.645346) (xy 25.441764 -112.591257) (xy 25.43711 -112.535909)
			(xy 25.440531 -112.48047) (xy 25.451956 -112.426114) (xy 25.471143 -112.373989) (xy 25.497686 -112.325198)
			(xy 25.531024 -112.280771) (xy 25.570452 -112.241649) (xy 25.615137 -112.208658) (xy 25.664134 -112.182496)
			(xy 25.716406 -112.163716) (xy 25.77085 -112.152714) (xy 25.826313 -112.149724) (xy 25.881624 -112.154809)
			(xy 25.935613 -112.167861) (xy 25.987138 -112.188605) (xy 26.03511 -112.216601) (xy 26.078516 -112.251258)
			(xy 26.116436 -112.291843) (xy 26.148071 -112.337498) (xy 26.17275 -112.387258) (xy 26.189952 -112.440071)
			(xy 26.199313 -112.494821) (xy 26.200637 -112.550349) (xy 26.193893 -112.605482) (xy 26.179226 -112.659054)
			(xy 26.156945 -112.709933) (xy 26.127521 -112.757043) (xy 26.10993 -112.77854) (xy 26.096154 -112.795397)
			(xy 26.074032 -112.832888) (xy 26.058628 -112.873603) (xy 26.050394 -112.916349) (xy 26.049571 -112.959872)
			(xy 26.056183 -113.002899) (xy 26.070037 -113.044167) (xy 26.090727 -113.082467) (xy 26.103834 -113.09985)
			(xy 26.120603 -113.121994) (xy 26.148225 -113.170184) (xy 26.168568 -113.221869) (xy 26.1812 -113.275959)
			(xy 26.185854 -113.331308) (xy 26.182433 -113.386747) (xy 26.171008 -113.441105) (xy 26.151821 -113.49323)
			(xy 26.125278 -113.542023) (xy 26.09194 -113.58645) (xy 26.052511 -113.625573) (xy 26.007826 -113.658565)
			(xy 25.958829 -113.684727) (xy 25.906555 -113.703508) (xy 25.852111 -113.71451) (xy 25.796647 -113.7175)
			(xy 25.741335 -113.712415) (xy 25.687346 -113.699362) (xy 25.63582 -113.678618) (xy 25.587847 -113.650622)
			(xy 25.544441 -113.615964) (xy 25.50652 -113.575378) (xy 25.474885 -113.529722) (xy 25.450206 -113.479961)
			(xy 25.433004 -113.427147) (xy 25.423642 -113.372397) (xy 25.42232 -113.316868) (xy 22.231479 -113.316868)
			(xy 22.23262 -113.32083) (xy 22.647663 -113.735873) (xy 37.102232 -113.735873) (xy 37.10652 -113.678817)
			(xy 37.119281 -113.62304) (xy 37.140228 -113.569795) (xy 37.168892 -113.520275) (xy 37.186362 -113.497614)
			(xy 37.196646 -113.483886) (xy 37.210117 -113.452354) (xy 37.214713 -113.418373) (xy 37.210103 -113.384395)
			(xy 37.196619 -113.352868) (xy 37.186362 -113.339118) (xy 37.169147 -113.316657) (xy 37.14074 -113.267717)
			(xy 37.119873 -113.215119) (xy 37.107002 -113.160015) (xy 37.102411 -113.103615) (xy 37.106201 -113.047155)
			(xy 37.118287 -112.991874) (xy 37.138404 -112.938984) (xy 37.166113 -112.889645) (xy 37.200804 -112.844939)
			(xy 37.220906 -112.825022) (xy 37.237477 -112.808517) (xy 37.264804 -112.770564) (xy 37.284728 -112.728254)
			(xy 37.296577 -112.683013) (xy 37.299951 -112.636368) (xy 37.294736 -112.589892) (xy 37.281108 -112.545155)
			(xy 37.259528 -112.503665) (xy 37.245544 -112.484916) (xy 37.22898 -112.46294) (xy 37.201667 -112.415165)
			(xy 37.181502 -112.363962) (xy 37.168902 -112.310394) (xy 37.164128 -112.255571) (xy 37.167281 -112.20063)
			(xy 37.178294 -112.146713) (xy 37.196939 -112.094937) (xy 37.222829 -112.046377) (xy 37.255427 -112.002041)
			(xy 37.294057 -111.962847) (xy 37.337917 -111.929611) (xy 37.386097 -111.90302) (xy 37.437597 -111.883627)
			(xy 37.49135 -111.871834) (xy 37.546239 -111.867887) (xy 37.601125 -111.871866) (xy 37.654871 -111.883689)
			(xy 37.70636 -111.903111) (xy 37.754525 -111.929729) (xy 37.798366 -111.962991) (xy 37.836973 -112.002206)
			(xy 37.869546 -112.046561) (xy 37.895409 -112.095136) (xy 37.914025 -112.146922) (xy 37.925007 -112.200846)
			(xy 37.928128 -112.255788) (xy 37.923324 -112.310608) (xy 37.910693 -112.36417) (xy 37.890499 -112.415361)
			(xy 37.863159 -112.46312) (xy 37.829241 -112.506455) (xy 37.809678 -112.52581) (xy 37.793171 -112.542378)
			(xy 37.765834 -112.580315) (xy 37.745899 -112.622613) (xy 37.73404 -112.667844) (xy 37.730656 -112.714482)
			(xy 37.735863 -112.760951) (xy 37.749483 -112.805684) (xy 37.771059 -112.847169) (xy 37.78504 -112.865916)
			(xy 37.802125 -112.888569) (xy 37.830014 -112.937981) (xy 37.850284 -112.990976) (xy 37.862488 -113.046388)
			(xy 37.866358 -113.102995) (xy 37.861809 -113.159552) (xy 37.84894 -113.214813) (xy 37.828036 -113.267561)
			(xy 37.799555 -113.316635) (xy 37.782246 -113.339118) (xy 37.772025 -113.352889) (xy 37.758544 -113.384406)
			(xy 37.753935 -113.418373) (xy 37.75853 -113.452343) (xy 37.771998 -113.483865) (xy 37.782246 -113.497614)
			(xy 37.79968 -113.520299) (xy 37.82834 -113.569814) (xy 37.849285 -113.623053) (xy 37.862044 -113.678823)
			(xy 37.866332 -113.735873) (xy 37.862052 -113.792924) (xy 37.849301 -113.848696) (xy 37.832939 -113.890301)
			(xy 42.910815 -113.890301) (xy 42.914815 -113.835161) (xy 42.926734 -113.781177) (xy 42.94632 -113.729478)
			(xy 42.973163 -113.681147) (xy 43.006702 -113.637198) (xy 43.046234 -113.59855) (xy 43.090931 -113.566014)
			(xy 43.139856 -113.54027) (xy 43.191985 -113.521859) (xy 43.246225 -113.511165) (xy 43.301442 -113.508413)
			(xy 43.356477 -113.51366) (xy 43.410178 -113.526796) (xy 43.461421 -113.547547) (xy 43.509132 -113.575477)
			(xy 43.531028 -113.592356) (xy 43.544776 -113.602612) (xy 43.576301 -113.616092) (xy 43.610276 -113.620696)
			(xy 43.644251 -113.616092) (xy 43.675776 -113.602612) (xy 43.689524 -113.592356) (xy 43.711423 -113.575476)
			(xy 43.759137 -113.547538) (xy 43.810384 -113.52678) (xy 43.86409 -113.513638) (xy 43.919131 -113.508386)
			(xy 43.974354 -113.511135) (xy 44.028601 -113.521827) (xy 44.080737 -113.540238) (xy 44.129669 -113.565982)
			(xy 44.174372 -113.59852) (xy 44.21391 -113.637171) (xy 44.247454 -113.681124) (xy 44.274302 -113.72946)
			(xy 44.293891 -113.781164) (xy 44.305811 -113.835155) (xy 44.309812 -113.890301) (xy 44.30581 -113.945447)
			(xy 44.29389 -113.999438) (xy 44.274301 -114.051143) (xy 44.247453 -114.099478) (xy 44.213908 -114.143431)
			(xy 44.17437 -114.182081) (xy 44.129667 -114.214619) (xy 44.080735 -114.240363) (xy 44.028599 -114.258773)
			(xy 43.974351 -114.269465) (xy 43.919129 -114.272213) (xy 43.864088 -114.266961) (xy 43.810381 -114.253819)
			(xy 43.759135 -114.233061) (xy 43.711421 -114.205123) (xy 43.689524 -114.18824) (xy 43.675776 -114.177984)
			(xy 43.644251 -114.164504) (xy 43.610276 -114.1599) (xy 43.576301 -114.164504) (xy 43.544776 -114.177984)
			(xy 43.531028 -114.18824) (xy 43.509134 -114.205121) (xy 43.461423 -114.233052) (xy 43.410181 -114.253803)
			(xy 43.356479 -114.26694) (xy 43.301444 -114.272187) (xy 43.246228 -114.269435) (xy 43.191987 -114.258742)
			(xy 43.139858 -114.240331) (xy 43.090933 -114.214587) (xy 43.046236 -114.182051) (xy 43.006704 -114.143404)
			(xy 42.973165 -114.099455) (xy 42.946321 -114.051125) (xy 42.926734 -113.999426) (xy 42.914816 -113.945441)
			(xy 42.910815 -113.890301) (xy 37.832939 -113.890301) (xy 37.828363 -113.901938) (xy 37.79971 -113.951457)
			(xy 37.782246 -113.974118) (xy 37.772025 -113.987889) (xy 37.758544 -114.019406) (xy 37.753935 -114.053373)
			(xy 37.75853 -114.087343) (xy 37.771998 -114.118865) (xy 37.782246 -114.132614) (xy 37.799127 -114.154511)
			(xy 37.827061 -114.202223) (xy 37.847815 -114.253467) (xy 37.85485 -114.28222) (xy 38.827962 -114.28222)
			(xy 38.832033 -114.226598) (xy 38.844159 -114.172161) (xy 38.864082 -114.12007) (xy 38.891378 -114.071435)
			(xy 38.925464 -114.027292) (xy 38.965613 -113.988583) (xy 39.010971 -113.956132) (xy 39.060571 -113.930631)
			(xy 39.113355 -113.912624) (xy 39.168198 -113.902494) (xy 39.223932 -113.900457) (xy 39.279369 -113.906557)
			(xy 39.333326 -113.920663) (xy 39.384655 -113.942475) (xy 39.432261 -113.971529) (xy 39.475129 -114.007204)
			(xy 39.512346 -114.048741) (xy 39.543119 -114.095254) (xy 39.566791 -114.145751) (xy 39.582859 -114.199158)
			(xy 39.590979 -114.254334) (xy 39.591488 -114.28222) (xy 39.590979 -114.310106) (xy 39.582859 -114.365282)
			(xy 39.566791 -114.418689) (xy 39.543119 -114.469186) (xy 39.512346 -114.515699) (xy 39.475129 -114.557236)
			(xy 39.432261 -114.592911) (xy 39.384655 -114.621965) (xy 39.333326 -114.643777) (xy 39.279369 -114.657883)
			(xy 39.223932 -114.663983) (xy 39.168198 -114.661946) (xy 39.113355 -114.651816) (xy 39.060571 -114.633809)
			(xy 39.010971 -114.608308) (xy 38.965613 -114.575857) (xy 38.925464 -114.537148) (xy 38.891378 -114.493005)
			(xy 38.864082 -114.44437) (xy 38.844159 -114.392279) (xy 38.832033 -114.337842) (xy 38.827962 -114.28222)
			(xy 37.85485 -114.28222) (xy 37.860955 -114.307171) (xy 37.866204 -114.362209) (xy 37.863454 -114.417429)
			(xy 37.852761 -114.471673) (xy 37.83435 -114.523805) (xy 37.808607 -114.572734) (xy 37.776069 -114.617434)
			(xy 37.73742 -114.656969) (xy 37.693469 -114.690511) (xy 37.645137 -114.717357) (xy 37.593435 -114.736944)
			(xy 37.539447 -114.748863) (xy 37.484304 -114.752864) (xy 37.429161 -114.748863) (xy 37.375173 -114.736944)
			(xy 37.323471 -114.717357) (xy 37.275139 -114.690511) (xy 37.231188 -114.656969) (xy 37.192539 -114.617434)
			(xy 37.160001 -114.572734) (xy 37.134258 -114.523805) (xy 37.115847 -114.471673) (xy 37.105154 -114.417429)
			(xy 37.102404 -114.362209) (xy 37.107653 -114.307171) (xy 37.120793 -114.253467) (xy 37.141547 -114.202223)
			(xy 37.169481 -114.154511) (xy 37.186362 -114.132614) (xy 37.196646 -114.118886) (xy 37.210117 -114.087354)
			(xy 37.214713 -114.053373) (xy 37.210103 -114.019395) (xy 37.196619 -113.987868) (xy 37.186362 -113.974118)
			(xy 37.168862 -113.951481) (xy 37.140205 -113.901957) (xy 37.119265 -113.848709) (xy 37.106512 -113.792931)
			(xy 37.102232 -113.735873) (xy 22.647663 -113.735873) (xy 24.060658 -115.148868)
		)
		(stroke
			(width 0)
			(type solid)
		)
		(fill yes)
		(layer "In6.Cu")
		(net "P5V_STB_NODE1")
	)
	(gr_poly
		(pts
			(xy 67.38239 -68.666614) (xy 67.406563 -68.656535) (xy 67.456977 -68.642346) (xy 67.508858 -68.635184)
			(xy 67.56123 -68.635184) (xy 67.613111 -68.642346) (xy 67.663525 -68.656535) (xy 67.687698 -68.666614)
			(xy 67.712082 -68.677282) (xy 68.212716 -68.677282) (xy 68.228393 -68.676808) (xy 68.258796 -68.669146)
			(xy 68.286419 -68.65431) (xy 68.309597 -68.633194) (xy 68.326936 -68.60707) (xy 68.332604 -68.592446)
			(xy 68.332604 -68.592192) (xy 68.342141 -68.566327) (xy 68.367602 -68.517433) (xy 68.399838 -68.472714)
			(xy 68.438176 -68.433102) (xy 68.481818 -68.399422) (xy 68.529854 -68.372377) (xy 68.581283 -68.35253)
			(xy 68.635035 -68.340294) (xy 68.689988 -68.335925) (xy 68.744997 -68.339513) (xy 68.798917 -68.350984)
			(xy 68.850623 -68.370099) (xy 68.899039 -68.396459) (xy 68.921376 -68.412614) (xy 68.940388 -68.42621)
			(xy 68.982271 -68.446942) (xy 69.027239 -68.459668) (xy 69.073776 -68.463958) (xy 69.120313 -68.459668)
			(xy 69.165281 -68.446942) (xy 69.207164 -68.42621) (xy 69.226176 -68.412614) (xy 69.248267 -68.396652)
			(xy 69.296098 -68.370529) (xy 69.347161 -68.35148) (xy 69.400415 -68.339894) (xy 69.454776 -68.336005)
			(xy 69.509137 -68.339894) (xy 69.562391 -68.35148) (xy 69.613454 -68.370529) (xy 69.661285 -68.396652)
			(xy 69.683376 -68.412614) (xy 69.702388 -68.42621) (xy 69.744271 -68.446942) (xy 69.789239 -68.459668)
			(xy 69.835776 -68.463958) (xy 69.882313 -68.459668) (xy 69.927281 -68.446942) (xy 69.969164 -68.42621)
			(xy 69.988176 -68.412614) (xy 70.010267 -68.396652) (xy 70.058098 -68.370529) (xy 70.109161 -68.35148)
			(xy 70.162415 -68.339894) (xy 70.216776 -68.336005) (xy 70.271137 -68.339894) (xy 70.324391 -68.35148)
			(xy 70.375454 -68.370529) (xy 70.423285 -68.396652) (xy 70.445376 -68.412614) (xy 70.464388 -68.42621)
			(xy 70.506271 -68.446942) (xy 70.551239 -68.459668) (xy 70.597776 -68.463958) (xy 70.644313 -68.459668)
			(xy 70.689281 -68.446942) (xy 70.731164 -68.42621) (xy 70.750176 -68.412614) (xy 70.773888 -68.395539)
			(xy 70.825433 -68.368026) (xy 70.880564 -68.348672) (xy 70.90918 -68.342764) (xy 70.948042 -68.335652)
			(xy 71.209408 -68.074286) (xy 73.724008 -68.074286) (xy 73.746364 -68.073823) (xy 73.790389 -68.066011)
			(xy 73.832366 -68.050611) (xy 73.870999 -68.028101) (xy 73.905093 -67.999174) (xy 73.933597 -67.964725)
			(xy 73.95563 -67.925818) (xy 73.97051 -67.883654) (xy 73.977778 -67.839536) (xy 73.97721 -67.794827)
			(xy 73.973436 -67.772788) (xy 73.968689 -67.745067) (xy 73.966435 -67.688873) (xy 73.972455 -67.632956)
			(xy 73.986618 -67.578529) (xy 74.008617 -67.526771) (xy 74.037975 -67.478802) (xy 74.074057 -67.435663)
			(xy 74.11608 -67.398288) (xy 74.163135 -67.367486) (xy 74.214202 -67.343925) (xy 74.268174 -67.328116)
			(xy 74.323881 -67.320401) (xy 74.380118 -67.320947) (xy 74.435666 -67.329743) (xy 74.489321 -67.346597)
			(xy 74.53992 -67.371145) (xy 74.586368 -67.402854) (xy 74.60742 -67.421506) (xy 74.623609 -67.435882)
			(xy 74.659917 -67.459465) (xy 74.699695 -67.476553) (xy 74.741795 -67.486651) (xy 74.784997 -67.489469)
			(xy 74.828051 -67.484924) (xy 74.869712 -67.473148) (xy 74.908775 -67.454481) (xy 74.926698 -67.442334)
			(xy 74.938447 -67.433373) (xy 74.963112 -67.417095) (xy 74.975974 -67.409822) (xy 74.989962 -67.401542)
			(xy 75.013524 -67.379165) (xy 75.030668 -67.35156) (xy 75.040283 -67.32052) (xy 75.041744 -67.288058)
			(xy 75.034956 -67.256279) (xy 75.020361 -67.227246) (xy 74.998904 -67.202843) (xy 74.971978 -67.184651)
			(xy 74.94133 -67.173852) (xy 74.925174 -67.172078) (xy 74.8983 -67.169286) (xy 74.845667 -67.157089)
			(xy 74.795281 -67.137588) (xy 74.74815 -67.111173) (xy 74.705217 -67.078373) (xy 74.667342 -67.039844)
			(xy 74.635282 -66.996356) (xy 74.609677 -66.94878) (xy 74.591042 -66.898067) (xy 74.579748 -66.845233)
			(xy 74.576021 -66.791333) (xy 74.579936 -66.737447) (xy 74.591414 -66.684652) (xy 74.610227 -66.634005)
			(xy 74.635997 -66.586519) (xy 74.668209 -66.543143) (xy 74.706219 -66.504746) (xy 74.749265 -66.472096)
			(xy 74.796488 -66.445846) (xy 74.821542 -66.435732) (xy 74.847439 -66.426315) (xy 74.90119 -66.414183)
			(xy 74.956128 -66.40991) (xy 75.011109 -66.413587) (xy 75.064989 -66.425135) (xy 75.116647 -66.444315)
			(xy 75.165007 -66.470728) (xy 75.209065 -66.503825) (xy 75.247902 -66.542915) (xy 75.280711 -66.587187)
			(xy 75.306808 -66.635719) (xy 75.325652 -66.6875) (xy 75.33685 -66.741454) (xy 75.340168 -66.796458)
			(xy 75.335538 -66.851366) (xy 75.323057 -66.905038) (xy 75.302983 -66.956355) (xy 75.275734 -67.00425)
			(xy 75.259184 -67.026282) (xy 75.246074 -67.043885) (xy 75.225473 -67.082637) (xy 75.211835 -67.124352)
			(xy 75.205565 -67.16779) (xy 75.20685 -67.211658) (xy 75.215651 -67.254655) (xy 75.22845 -67.287214)
			(xy 75.93976 -67.287214) (xy 75.947244 -67.233259) (xy 75.962324 -67.180918) (xy 75.984694 -67.131252)
			(xy 76.0139 -67.085272) (xy 76.049346 -67.043913) (xy 76.090314 -67.008014) (xy 76.112878 -66.992754)
			(xy 76.132095 -66.979645) (xy 76.165834 -66.947627) (xy 76.193179 -66.910001) (xy 76.213215 -66.868025)
			(xy 76.225272 -66.823102) (xy 76.228948 -66.776734) (xy 76.224119 -66.730472) (xy 76.218034 -66.70802)
			(xy 76.210723 -66.681783) (xy 76.202858 -66.627887) (xy 76.202736 -66.573421) (xy 76.21036 -66.51949)
			(xy 76.225575 -66.467192) (xy 76.248071 -66.417588) (xy 76.277393 -66.371687) (xy 76.312943 -66.330422)
			(xy 76.353999 -66.294632) (xy 76.399728 -66.265042) (xy 76.449199 -66.242256) (xy 76.501408 -66.226736)
			(xy 76.555292 -66.218797) (xy 76.609759 -66.2186) (xy 76.6637 -66.22615) (xy 76.716019 -66.241294)
			(xy 76.765653 -66.263723) (xy 76.811594 -66.292981) (xy 76.852907 -66.328475) (xy 76.888754 -66.369483)
			(xy 76.918406 -66.415171) (xy 76.94126 -66.464611) (xy 76.956851 -66.516798) (xy 76.964864 -66.570672)
			(xy 76.965135 -66.625138) (xy 76.957658 -66.679089) (xy 76.942586 -66.731429) (xy 76.920225 -66.781094)
			(xy 76.891029 -66.827074) (xy 76.855592 -66.868436) (xy 76.814634 -66.904339) (xy 76.792074 -66.919602)
			(xy 76.772831 -66.932677) (xy 76.739088 -66.964698) (xy 76.711742 -67.00233) (xy 76.691707 -67.044313)
			(xy 76.679654 -67.089243) (xy 76.675986 -67.135617) (xy 76.680826 -67.181883) (xy 76.686918 -67.204336)
			(xy 76.694179 -67.23059) (xy 76.702049 -67.28449) (xy 76.702174 -67.33896) (xy 76.694552 -67.392895)
			(xy 76.679338 -67.445198) (xy 76.656841 -67.494807) (xy 76.627519 -67.540712) (xy 76.591966 -67.58198)
			(xy 76.550907 -67.617774) (xy 76.505175 -67.647366) (xy 76.4557 -67.670154) (xy 76.403487 -67.685674)
			(xy 76.349597 -67.693613) (xy 76.295127 -67.693807) (xy 76.241182 -67.686254) (xy 76.18886 -67.671107)
			(xy 76.139223 -67.648674) (xy 76.09328 -67.61941) (xy 76.051966 -67.58391) (xy 76.01612 -67.542897)
			(xy 75.98647 -67.497202) (xy 75.963619 -67.447756) (xy 75.948031 -67.395563) (xy 75.940024 -67.341684)
			(xy 75.93976 -67.287214) (xy 75.22845 -67.287214) (xy 75.231707 -67.2955) (xy 75.25454 -67.33298)
			(xy 75.283472 -67.365981) (xy 75.317643 -67.393522) (xy 75.336654 -67.404488) (xy 75.359412 -67.416772)
			(xy 75.401687 -67.446561) (xy 75.439549 -67.481789) (xy 75.472304 -67.521809) (xy 75.499351 -67.565889)
			(xy 75.520194 -67.613219) (xy 75.53445 -67.662931) (xy 75.538584 -67.68846) (xy 75.541852 -67.713611)
			(xy 75.542484 -67.764326) (xy 75.539854 -67.789552) (xy 75.537698 -67.810954) (xy 75.539757 -67.853916)
			(xy 75.549025 -67.895916) (xy 75.565237 -67.935755) (xy 75.587929 -67.972293) (xy 75.616453 -68.004485)
			(xy 75.649993 -68.031412) (xy 75.68759 -68.052303) (xy 75.728169 -68.066561) (xy 75.77057 -68.073778)
			(xy 75.792076 -68.074286) (xy 83.010248 -68.074286) (xy 86.284816 -64.799718) (xy 86.284816 -39.08044)
			(xy 86.212426 -39.006526) (xy 86.160356 -39.00551) (xy 86.132189 -39.004425) (xy 86.076618 -38.994989)
			(xy 86.02304 -38.977481) (xy 85.97262 -38.952281) (xy 85.926456 -38.919939) (xy 85.885551 -38.881157)
			(xy 85.850797 -38.83678) (xy 85.822949 -38.787773) (xy 85.802613 -38.735203) (xy 85.790232 -38.680213)
			(xy 85.786074 -38.624) (xy 85.790232 -38.567787) (xy 85.802613 -38.512797) (xy 85.822949 -38.460227)
			(xy 85.850797 -38.41122) (xy 85.885551 -38.366843) (xy 85.926455 -38.328062) (xy 85.97262 -38.295719)
			(xy 86.02304 -38.270519) (xy 86.076618 -38.253011) (xy 86.132189 -38.243575) (xy 86.160356 -38.242494)
			(xy 86.212426 -38.241478) (xy 86.284816 -38.167564) (xy 86.284816 -28.272994) (xy 83.939126 -25.927304)
			(xy 83.922857 -25.911727) (xy 83.885893 -25.885997) (xy 83.844974 -25.867184) (xy 83.801379 -25.855876)
			(xy 83.756474 -25.852425) (xy 83.711664 -25.856942) (xy 83.668351 -25.869283) (xy 83.62789 -25.889064)
			(xy 83.591548 -25.915664) (xy 83.575652 -25.931622) (xy 83.567859 -25.93966) (xy 83.551466 -25.95491)
			(xy 83.542886 -25.962102) (xy 83.526182 -25.976597) (xy 83.497573 -26.010319) (xy 83.475241 -26.048487)
			(xy 83.459861 -26.089949) (xy 83.451898 -26.133448) (xy 83.451594 -26.177669) (xy 83.458958 -26.221274)
			(xy 83.465924 -26.242264) (xy 83.474728 -26.268579) (xy 83.485504 -26.323011) (xy 83.488282 -26.378429)
			(xy 83.483004 -26.433665) (xy 83.469781 -26.487555) (xy 83.448892 -26.538961) (xy 83.420777 -26.586799)
			(xy 83.38603 -26.630061) (xy 83.345383 -26.667833) (xy 83.299694 -26.69932) (xy 83.249926 -26.723857)
			(xy 83.197129 -26.740926) (xy 83.142416 -26.750169) (xy 83.086941 -26.751389) (xy 83.031875 -26.744561)
			(xy 82.978378 -26.729829) (xy 82.927579 -26.707504) (xy 82.88055 -26.678056) (xy 82.838282 -26.642107)
			(xy 82.801667 -26.600415) (xy 82.771476 -26.553859) (xy 82.748347 -26.503421) (xy 82.732768 -26.450165)
			(xy 82.725067 -26.395214) (xy 82.725406 -26.339727) (xy 82.733779 -26.284874) (xy 82.750008 -26.231812)
			(xy 82.773752 -26.181661) (xy 82.804509 -26.135478) (xy 82.841632 -26.094236) (xy 82.862674 -26.076148)
			(xy 82.879377 -26.061653) (xy 82.907982 -26.027933) (xy 82.930311 -25.989765) (xy 82.945685 -25.948304)
			(xy 82.953642 -25.904807) (xy 82.953938 -25.860588) (xy 82.946566 -25.816988) (xy 82.939636 -25.795986)
			(xy 82.931821 -25.772698) (xy 82.921505 -25.724671) (xy 82.919062 -25.700228) (xy 82.916585 -25.677114)
			(xy 82.904317 -25.632282) (xy 82.884113 -25.590422) (xy 82.856643 -25.552928) (xy 82.822822 -25.521044)
			(xy 82.783774 -25.495831) (xy 82.740796 -25.478128) (xy 82.718148 -25.472898) (xy 82.692089 -25.466984)
			(xy 82.641827 -25.448841) (xy 82.59459 -25.423859) (xy 82.551303 -25.392529) (xy 82.512813 -25.355463)
			(xy 82.479873 -25.313387) (xy 82.453129 -25.267125) (xy 82.433105 -25.217583) (xy 82.420192 -25.165731)
			(xy 82.414643 -25.112584) (xy 82.416567 -25.059183) (xy 82.425926 -25.006573) (xy 82.442538 -24.955784)
			(xy 82.466076 -24.907812) (xy 82.49608 -24.863595) (xy 82.513678 -24.843486) (xy 82.527789 -24.827265)
			(xy 82.550903 -24.791019) (xy 82.567582 -24.751396) (xy 82.577348 -24.709531) (xy 82.579923 -24.666618)
			(xy 82.575232 -24.623886) (xy 82.56341 -24.582553) (xy 82.544795 -24.543803) (xy 82.519918 -24.508742)
			(xy 82.505042 -24.49322) (xy 82.35569 -24.343868) (xy 81.26349 -24.343868) (xy 81.141316 -24.444706)
			(xy 81.130394 -24.48179) (xy 81.125488 -24.497727) (xy 81.11328 -24.528759) (xy 81.10601 -24.543766)
			(xy 81.099221 -24.558467) (xy 81.09254 -24.590141) (xy 81.094053 -24.622476) (xy 81.103662 -24.653388)
			(xy 81.120747 -24.680883) (xy 81.132172 -24.692356) (xy 81.144206 -24.703178) (xy 81.172483 -24.718901)
			(xy 81.20381 -24.726987) (xy 81.236164 -24.726913) (xy 81.267455 -24.718685) (xy 81.281778 -24.711152)
			(xy 81.30646 -24.697912) (xy 81.358816 -24.678012) (xy 81.413519 -24.665982) (xy 81.469393 -24.66208)
			(xy 81.525237 -24.666389) (xy 81.579851 -24.678818) (xy 81.63206 -24.699099) (xy 81.680743 -24.726796)
			(xy 81.724853 -24.761313) (xy 81.763441 -24.80191) (xy 81.795679 -24.847712) (xy 81.820873 -24.897736)
			(xy 81.838481 -24.950906) (xy 81.848126 -25.00608) (xy 81.8496 -25.06207) (xy 81.842871 -25.117675)
			(xy 81.828084 -25.171698) (xy 81.805556 -25.222978) (xy 81.775773 -25.270413) (xy 81.739373 -25.312983)
			(xy 81.697141 -25.349773) (xy 81.649982 -25.379993) (xy 81.598912 -25.402992) (xy 81.545028 -25.418277)
			(xy 81.489488 -25.425518) (xy 81.433486 -25.424561) (xy 81.378226 -25.415425) (xy 81.324896 -25.398307)
			(xy 81.274642 -25.373576) (xy 81.228544 -25.341762) (xy 81.187594 -25.303549) (xy 81.152671 -25.25976)
			(xy 81.124526 -25.211334) (xy 81.103765 -25.159314) (xy 81.090833 -25.104817) (xy 81.086009 -25.049015)
			(xy 81.087214 -25.021032) (xy 81.088064 -24.998934) (xy 81.083034 -24.955003) (xy 81.070476 -24.912606)
			(xy 81.050767 -24.873023) (xy 81.024504 -24.83745) (xy 80.992479 -24.80696) (xy 80.955659 -24.782475)
			(xy 80.915156 -24.764734) (xy 80.872193 -24.754272) (xy 80.828068 -24.751406) (xy 80.806036 -24.753316)
			(xy 80.779552 -24.755759) (xy 80.726391 -24.754165) (xy 80.673966 -24.745205) (xy 80.623293 -24.729055)
			(xy 80.575352 -24.706025) (xy 80.531073 -24.676563) (xy 80.491314 -24.641238) (xy 80.456843 -24.600736)
			(xy 80.428329 -24.555841) (xy 80.406325 -24.507421) (xy 80.398366 -24.482044) (xy 80.387444 -24.444706)
			(xy 80.26527 -24.343868) (xy 79.930498 -24.343868) (xy 79.90832 -24.34435) (xy 79.864637 -24.352049)
			(xy 79.822952 -24.367211) (xy 79.784532 -24.389378) (xy 79.750541 -24.417876) (xy 79.722012 -24.45184)
			(xy 79.69981 -24.49024) (xy 79.684609 -24.53191) (xy 79.680308 -24.553672) (xy 79.675094 -24.580487)
			(xy 79.658016 -24.632375) (xy 79.633718 -24.6813) (xy 79.602695 -24.726263) (xy 79.565582 -24.766346)
			(xy 79.523136 -24.800731) (xy 79.476223 -24.828716) (xy 79.4512 -24.839676) (xy 79.431228 -24.848486)
			(xy 79.394395 -24.871904) (xy 79.3621 -24.901265) (xy 79.33529 -24.935709) (xy 79.314753 -24.974223)
			(xy 79.301091 -25.015677) (xy 79.294706 -25.058855) (xy 79.295784 -25.102489) (xy 79.304295 -25.145298)
			(xy 79.311754 -25.165812) (xy 79.321387 -25.192065) (xy 79.333738 -25.246603) (xy 79.337996 -25.302361)
			(xy 79.33407 -25.358142) (xy 79.322045 -25.412754) (xy 79.302178 -25.465025) (xy 79.274894 -25.513837)
			(xy 79.240777 -25.558144) (xy 79.20056 -25.596997) (xy 79.155102 -25.629563) (xy 79.105377 -25.655146)
			(xy 79.052451 -25.673198) (xy 78.997458 -25.683331) (xy 78.941574 -25.685329) (xy 78.885996 -25.679149)
			(xy 78.831917 -25.664923) (xy 78.780492 -25.642956) (xy 78.732825 -25.613719) (xy 78.689935 -25.577838)
			(xy 78.652742 -25.53608) (xy 78.622041 -25.489342) (xy 78.598492 -25.438622) (xy 78.582597 -25.385009)
			(xy 78.574698 -25.32965) (xy 78.574964 -25.273731) (xy 78.583388 -25.21845) (xy 78.599791 -25.16499)
			(xy 78.623821 -25.114497) (xy 78.654964 -25.068052) (xy 78.692552 -25.026649) (xy 78.73578 -24.991177)
			(xy 78.783723 -24.962393) (xy 78.809342 -24.951182) (xy 78.829315 -24.942375) (xy 78.866151 -24.91896)
			(xy 78.898449 -24.889601) (xy 78.925259 -24.855158) (xy 78.945796 -24.816643) (xy 78.959455 -24.775187)
			(xy 78.965836 -24.732009) (xy 78.96475 -24.688374) (xy 78.956232 -24.645566) (xy 78.948788 -24.625046)
			(xy 78.942322 -24.607657) (xy 78.932395 -24.571907) (xy 78.928976 -24.553672) (xy 78.924673 -24.531907)
			(xy 78.909492 -24.49022) (xy 78.887302 -24.451805) (xy 78.858777 -24.417827) (xy 78.824784 -24.38932)
			(xy 78.786356 -24.36715) (xy 78.744662 -24.351992) (xy 78.700968 -24.344306) (xy 78.678786 -24.343868)
			(xy 77.22235 -24.343868) (xy 77.206866 -24.344275) (xy 77.176797 -24.351673) (xy 77.149394 -24.366094)
			(xy 77.126271 -24.38669) (xy 77.117194 -24.39924) (xy 77.111419 -24.407652) (xy 77.099094 -24.423917)
			(xy 77.092556 -24.431752) (xy 77.08296 -24.443748) (xy 77.069232 -24.471221) (xy 77.062467 -24.501178)
			(xy 77.063057 -24.531883) (xy 77.070966 -24.561558) (xy 77.085737 -24.588484) (xy 77.106515 -24.6111)
			(xy 77.132095 -24.628096) (xy 77.146404 -24.633682) (xy 77.172511 -24.643547) (xy 77.221749 -24.669817)
			(xy 77.266634 -24.702982) (xy 77.306208 -24.742332) (xy 77.339626 -24.78703) (xy 77.366174 -24.836119)
			(xy 77.385286 -24.888553) (xy 77.396553 -24.943211) (xy 77.399737 -24.998929) (xy 77.394767 -25.054515)
			(xy 77.381752 -25.108785) (xy 77.360967 -25.160578) (xy 77.332858 -25.20879) (xy 77.298023 -25.252392)
			(xy 77.257207 -25.290453) (xy 77.211281 -25.32216) (xy 77.161225 -25.346837) (xy 77.108108 -25.363957)
			(xy 77.053063 -25.373155) (xy 76.997265 -25.374233) (xy 76.941905 -25.36717) (xy 76.888166 -25.352116)
			(xy 76.837193 -25.329392) (xy 76.790076 -25.299484) (xy 76.74782 -25.263029) (xy 76.711326 -25.220806)
			(xy 76.681374 -25.173716) (xy 76.658603 -25.122765) (xy 76.6435 -25.069039) (xy 76.636386 -25.013686)
			(xy 76.637413 -24.957888) (xy 76.64656 -24.902834) (xy 76.663631 -24.849701) (xy 76.675488 -24.824436)
			(xy 76.685141 -24.803748) (xy 76.697671 -24.759853) (xy 76.702162 -24.714426) (xy 76.698466 -24.668927)
			(xy 76.686705 -24.624819) (xy 76.667255 -24.583522) (xy 76.640743 -24.546362) (xy 76.60802 -24.514534)
			(xy 76.589382 -24.501348) (xy 76.569457 -24.487517) (xy 76.532932 -24.455601) (xy 76.500742 -24.419318)
			(xy 76.486766 -24.399494) (xy 76.477699 -24.386915) (xy 76.454612 -24.366227) (xy 76.427207 -24.351739)
			(xy 76.397111 -24.344309) (xy 76.38161 -24.343868) (xy 75.68311 -24.343868) (xy 75.661274 -24.344321)
			(xy 75.618245 -24.351788) (xy 75.577128 -24.366504) (xy 75.539132 -24.388035) (xy 75.505379 -24.415747)
			(xy 75.476862 -24.448823) (xy 75.454423 -24.486289) (xy 75.438721 -24.527041) (xy 75.43022 -24.569877)
			(xy 75.42917 -24.613536) (xy 75.431904 -24.635206) (xy 75.435335 -24.661464) (xy 75.435774 -24.714418)
			(xy 75.428885 -24.766924) (xy 75.414801 -24.817973) (xy 75.393793 -24.866583) (xy 75.366263 -24.91182)
			(xy 75.332742 -24.952816) (xy 75.293873 -24.988781) (xy 75.272392 -25.004268) (xy 75.254993 -25.016914)
			(xy 75.224323 -25.047064) (xy 75.199171 -25.081951) (xy 75.180258 -25.120578) (xy 75.168124 -25.16184)
			(xy 75.163117 -25.204555) (xy 75.165379 -25.247504) (xy 75.174846 -25.289458) (xy 75.191248 -25.329216)
			(xy 75.202288 -25.347676) (xy 75.215379 -25.369322) (xy 75.236361 -25.415352) (xy 75.25108 -25.46375)
			(xy 75.259277 -25.513669) (xy 75.260454 -25.538938) (xy 75.261594 -25.561006) (xy 75.270539 -25.604277)
			(xy 75.286833 -25.645348) (xy 75.309984 -25.682983) (xy 75.339294 -25.716047) (xy 75.37388 -25.743545)
			(xy 75.412701 -25.764647) (xy 75.454586 -25.778718) (xy 75.476354 -25.782524) (xy 75.503867 -25.787162)
			(xy 75.557237 -25.803426) (xy 75.607669 -25.827292) (xy 75.654085 -25.85825) (xy 75.695497 -25.895639)
			(xy 75.73102 -25.938663) (xy 75.759897 -25.986402) (xy 75.781511 -26.037839) (xy 75.795402 -26.091875)
			(xy 75.801272 -26.147359) (xy 75.798998 -26.203106) (xy 75.788626 -26.257927) (xy 75.770379 -26.310652)
			(xy 75.744646 -26.360157) (xy 75.711975 -26.405385) (xy 75.673064 -26.44537) (xy 75.628744 -26.479261)
			(xy 75.579959 -26.506334) (xy 75.527751 -26.526012) (xy 75.473233 -26.537874) (xy 75.417568 -26.541667)
			(xy 75.361945 -26.537311) (xy 75.30755 -26.524898) (xy 75.255543 -26.504694) (xy 75.207035 -26.477129)
			(xy 75.163059 -26.442791) (xy 75.124555 -26.402414) (xy 75.092344 -26.356858) (xy 75.067112 -26.307096)
			(xy 75.049399 -26.254189) (xy 75.039583 -26.199266) (xy 75.038204 -26.171398) (xy 75.037067 -26.149329)
			(xy 75.028126 -26.106056) (xy 75.011834 -26.064983) (xy 74.988684 -26.027346) (xy 74.959373 -25.994281)
			(xy 74.924784 -25.966783) (xy 74.885961 -25.945683) (xy 74.844073 -25.931616) (xy 74.822304 -25.927812)
			(xy 74.79957 -25.924064) (xy 74.755151 -25.911817) (xy 74.71253 -25.89431) (xy 74.692256 -25.883362)
			(xy 74.678664 -25.876195) (xy 74.649065 -25.867967) (xy 74.618358 -25.867065) (xy 74.588328 -25.873542)
			(xy 74.560722 -25.887021) (xy 74.537147 -25.906717) (xy 74.518973 -25.931486) (xy 74.507258 -25.959885)
			(xy 74.502684 -25.990263) (xy 74.505517 -26.020853) (xy 74.510138 -26.035508) (xy 74.51865 -26.06169)
			(xy 74.52892 -26.115776) (xy 74.531308 -26.170777) (xy 74.525764 -26.22555) (xy 74.512404 -26.278957)
			(xy 74.491505 -26.329889) (xy 74.463501 -26.377288) (xy 74.428975 -26.420168) (xy 74.388642 -26.45764)
			(xy 74.343342 -26.488924) (xy 74.294015 -26.513372) (xy 74.241686 -26.530474) (xy 74.187442 -26.539876)
			(xy 74.13241 -26.541383) (xy 74.077733 -26.534963) (xy 74.024547 -26.520749) (xy 73.973956 -26.499037)
			(xy 73.927012 -26.470278) (xy 73.88469 -26.435069) (xy 73.847869 -26.394142) (xy 73.817314 -26.348347)
			(xy 73.79366 -26.298635) (xy 73.777397 -26.246039) (xy 73.768865 -26.191651) (xy 73.76824 -26.136602)
			(xy 73.775535 -26.082035) (xy 73.790598 -26.029083) (xy 73.813117 -25.978846) (xy 73.842624 -25.932369)
			(xy 73.878506 -25.890616) (xy 73.920018 -25.854455) (xy 73.966296 -25.824637) (xy 74.016381 -25.801782)
			(xy 74.069231 -25.786364) (xy 74.123748 -25.778704) (xy 74.1788 -25.77896) (xy 74.2061 -25.782524)
			(xy 74.227412 -25.785276) (xy 74.270372 -25.78443) (xy 74.312579 -25.776373) (xy 74.352829 -25.761332)
			(xy 74.389977 -25.739738) (xy 74.422964 -25.712204) (xy 74.450852 -25.679515) (xy 74.472846 -25.642601)
			(xy 74.488319 -25.602515) (xy 74.49683 -25.560398) (xy 74.497946 -25.538938) (xy 74.499427 -25.509322)
			(xy 74.510405 -25.451052) (xy 74.530257 -25.395179) (xy 74.558505 -25.343045) (xy 74.59447 -25.295903)
			(xy 74.637289 -25.254886) (xy 74.661268 -25.23744) (xy 74.67867 -25.224795) (xy 74.709346 -25.194647)
			(xy 74.734503 -25.15976) (xy 74.753421 -25.121132) (xy 74.765558 -25.079868) (xy 74.770567 -25.03715)
			(xy 74.768305 -24.994198) (xy 74.758836 -24.952241) (xy 74.742432 -24.912481) (xy 74.731372 -24.894032)
			(xy 74.715692 -24.86795) (xy 74.691917 -24.811934) (xy 74.677335 -24.752855) (xy 74.674222 -24.722582)
			(xy 74.671781 -24.699401) (xy 74.659542 -24.654429) (xy 74.639311 -24.612442) (xy 74.611766 -24.574845)
			(xy 74.577829 -24.542899) (xy 74.538638 -24.517674) (xy 74.495506 -24.500015) (xy 74.4728 -24.494744)
			(xy 74.444518 -24.488309) (xy 74.390177 -24.468039) (xy 74.339529 -24.439779) (xy 74.293742 -24.404178)
			(xy 74.27341 -24.383492) (xy 74.255376 -24.364442) (xy 74.20737 -24.343868) (xy 74.045318 -24.343868)
			(xy 73.973436 -24.407368) (xy 73.96734 -24.45512) (xy 73.96734 -24.455374) (xy 73.963308 -24.483354)
			(xy 73.948059 -24.537788) (xy 73.924946 -24.589377) (xy 73.894474 -24.63699) (xy 73.857309 -24.679585)
			(xy 73.814266 -24.716231) (xy 73.766287 -24.746124) (xy 73.714422 -24.768609) (xy 73.659807 -24.783196)
			(xy 73.603637 -24.789565) (xy 73.547143 -24.787575) (xy 73.49156 -24.777271) (xy 73.438107 -24.758878)
			(xy 73.387952 -24.732799) (xy 73.342195 -24.699605) (xy 73.321672 -24.680164) (xy 73.304432 -24.663961)
			(xy 73.265133 -24.637629) (xy 73.221637 -24.619028) (xy 73.175449 -24.608803) (xy 73.128167 -24.607308)
			(xy 73.081425 -24.614593) (xy 73.036841 -24.630407) (xy 73.01611 -24.64181) (xy 72.992596 -24.654953)
			(xy 72.942688 -24.67522) (xy 72.890425 -24.688264) (xy 72.836846 -24.693825) (xy 72.783018 -24.691794)
			(xy 72.730011 -24.68221) (xy 72.678879 -24.665263) (xy 72.630641 -24.641292) (xy 72.586254 -24.610773)
			(xy 72.546602 -24.574313) (xy 72.512475 -24.532637) (xy 72.484549 -24.486574) (xy 72.473566 -24.461978)
			(xy 72.459596 -24.42972) (xy 72.341232 -24.343868) (xy 70.191122 -24.343868) (xy 70.1692 -24.344327)
			(xy 70.126007 -24.351851) (xy 70.084747 -24.366679) (xy 70.046645 -24.38837) (xy 70.012834 -24.416281)
			(xy 69.984316 -24.449583) (xy 69.961939 -24.487286) (xy 69.946368 -24.528271) (xy 69.938065 -24.571321)
			(xy 69.937276 -24.615157) (xy 69.944025 -24.658478) (xy 69.950584 -24.679402) (xy 69.959043 -24.705953)
			(xy 69.969054 -24.760769) (xy 69.970986 -24.816458) (xy 69.964799 -24.871836) (xy 69.950623 -24.925726)
			(xy 69.928761 -24.976981) (xy 69.899677 -25.024511) (xy 69.86399 -25.067306) (xy 69.822458 -25.104456)
			(xy 69.775965 -25.135171) (xy 69.725499 -25.158797) (xy 69.672133 -25.174833) (xy 69.617003 -25.182937)
			(xy 69.561281 -25.182937) (xy 69.506151 -25.174833) (xy 69.452785 -25.158797) (xy 69.402319 -25.135171)
			(xy 69.355826 -25.104456) (xy 69.314294 -25.067306) (xy 69.278607 -25.024511) (xy 69.249523 -24.976981)
			(xy 69.227661 -24.925726) (xy 69.213485 -24.871836) (xy 69.207298 -24.816458) (xy 69.20923 -24.760769)
			(xy 69.219241 -24.705953) (xy 69.2277 -24.679402) (xy 69.234297 -24.658492) (xy 69.241028 -24.61517)
			(xy 69.240224 -24.571336) (xy 69.23191 -24.52829) (xy 69.216332 -24.48731) (xy 69.193952 -24.44961)
			(xy 69.165434 -24.416311) (xy 69.131625 -24.3884) (xy 69.093528 -24.366706) (xy 69.052272 -24.351871)
			(xy 69.009083 -24.344337) (xy 68.987162 -24.343868) (xy 67.744594 -24.343868) (xy 67.722005 -24.344368)
			(xy 67.677542 -24.35237) (xy 67.635192 -24.368104) (xy 67.596289 -24.391074) (xy 67.562057 -24.420557)
			(xy 67.533575 -24.455625) (xy 67.511738 -24.495175) (xy 67.497233 -24.537962) (xy 67.490518 -24.582638)
			(xy 67.490594 -24.605234) (xy 67.490888 -24.632409) (xy 67.484712 -24.686401) (xy 67.470938 -24.738971)
			(xy 67.449844 -24.789054) (xy 67.421858 -24.835638) (xy 67.387544 -24.87778) (xy 67.367912 -24.896572)
			(xy 67.350848 -24.912995) (xy 67.322549 -24.950966) (xy 67.301769 -24.99352) (xy 67.289228 -25.039185)
			(xy 67.285359 -25.086382) (xy 67.290295 -25.13348) (xy 67.303867 -25.17885) (xy 67.314318 -25.200102)
			(xy 67.326006 -25.223668) (xy 67.343523 -25.273267) (xy 67.354073 -25.3248) (xy 67.357456 -25.377293)
			(xy 67.355974 -25.403556) (xy 67.354728 -25.427458) (xy 67.360135 -25.475007) (xy 67.374348 -25.520703)
			(xy 67.396863 -25.562931) (xy 67.426886 -25.600198) (xy 67.463353 -25.631187) (xy 67.504977 -25.654801)
			(xy 67.5343 -25.664771) (xy 70.422988 -25.664771) (xy 70.427747 -25.609108) (xy 70.440574 -25.554733)
			(xy 70.461194 -25.502811) (xy 70.489165 -25.454451) (xy 70.52389 -25.410688) (xy 70.564627 -25.372457)
			(xy 70.610503 -25.340575) (xy 70.660539 -25.315725) (xy 70.713664 -25.298438) (xy 70.768742 -25.289084)
			(xy 70.796658 -25.287986) (xy 70.819585 -25.28696) (xy 70.86453 -25.277704) (xy 70.907086 -25.260534)
			(xy 70.945869 -25.236006) (xy 70.979621 -25.204916) (xy 71.007246 -25.168274) (xy 71.027847 -25.12727)
			(xy 71.040756 -25.083235) (xy 71.045553 -25.037598) (xy 71.044308 -25.014682) (xy 71.042666 -24.987154)
			(xy 71.046436 -24.932136) (xy 71.058086 -24.878233) (xy 71.077373 -24.826569) (xy 71.103895 -24.778219)
			(xy 71.137101 -24.734189) (xy 71.176298 -24.695398) (xy 71.220671 -24.662653) (xy 71.269295 -24.636635)
			(xy 71.321157 -24.617887) (xy 71.375178 -24.606799) (xy 71.430232 -24.603602) (xy 71.485173 -24.608363)
			(xy 71.538857 -24.620982) (xy 71.590165 -24.641196) (xy 71.63803 -24.668586) (xy 71.681454 -24.702579)
			(xy 71.719532 -24.742469) (xy 71.751473 -24.787425) (xy 71.77661 -24.836509) (xy 71.794421 -24.888701)
			(xy 71.804534 -24.942913) (xy 71.806738 -24.998016) (xy 71.800988 -25.052862) (xy 71.787404 -25.10631)
			(xy 71.766268 -25.157246) (xy 71.738021 -25.204609) (xy 71.70325 -25.247413) (xy 71.662681 -25.284767)
			(xy 71.617157 -25.315892) (xy 71.567628 -25.340141) (xy 71.515123 -25.357009) (xy 71.460738 -25.366143)
			(xy 71.433182 -25.367234) (xy 71.410255 -25.368274) (xy 71.365309 -25.377524) (xy 71.322752 -25.39469)
			(xy 71.283967 -25.419215) (xy 71.250213 -25.450303) (xy 71.222588 -25.486945) (xy 71.201986 -25.527949)
			(xy 71.189079 -25.571985) (xy 71.184285 -25.617622) (xy 71.185532 -25.640538) (xy 71.187137 -25.668628)
			(xy 71.183093 -25.724743) (xy 71.170851 -25.779657) (xy 71.150677 -25.832177) (xy 71.123009 -25.881164)
			(xy 71.088446 -25.925557) (xy 71.068438 -25.945338) (xy 71.052687 -25.960997) (xy 71.026396 -25.99679)
			(xy 71.006726 -26.036608) (xy 70.994277 -26.079239) (xy 70.989428 -26.123385) (xy 70.992326 -26.167702)
			(xy 71.002882 -26.210841) (xy 71.020776 -26.251488) (xy 71.045463 -26.288406) (xy 71.076191 -26.320471)
			(xy 71.093838 -26.333958) (xy 71.115698 -26.350547) (xy 71.154885 -26.388962) (xy 71.188162 -26.432597)
			(xy 71.214843 -26.48055) (xy 71.234377 -26.531831) (xy 71.246361 -26.585382) (xy 71.250547 -26.640098)
			(xy 71.246848 -26.694849) (xy 71.235343 -26.748505) (xy 71.216266 -26.799958) (xy 71.190014 -26.848147)
			(xy 71.157127 -26.892077) (xy 71.118284 -26.93084) (xy 71.090319 -26.951686) (xy 72.667112 -26.951686)
			(xy 72.671183 -26.896064) (xy 72.683309 -26.841627) (xy 72.703232 -26.789536) (xy 72.730528 -26.740901)
			(xy 72.764614 -26.696758) (xy 72.804763 -26.658049) (xy 72.850121 -26.625598) (xy 72.899721 -26.600097)
			(xy 72.952505 -26.58209) (xy 73.007348 -26.57196) (xy 73.063082 -26.569923) (xy 73.118519 -26.576023)
			(xy 73.172476 -26.590129) (xy 73.223805 -26.611941) (xy 73.271411 -26.640995) (xy 73.314279 -26.67667)
			(xy 73.351496 -26.718207) (xy 73.382269 -26.76472) (xy 73.405941 -26.815217) (xy 73.422009 -26.868624)
			(xy 73.430129 -26.9238) (xy 73.430638 -26.951686) (xy 73.430129 -26.979572) (xy 73.422009 -27.034748)
			(xy 73.405941 -27.088155) (xy 73.382269 -27.138652) (xy 73.351496 -27.185165) (xy 73.314279 -27.226702)
			(xy 73.271411 -27.262377) (xy 73.223805 -27.291431) (xy 73.172476 -27.313243) (xy 73.118519 -27.327349)
			(xy 73.063082 -27.333449) (xy 73.007348 -27.331412) (xy 72.952505 -27.321282) (xy 72.899721 -27.303275)
			(xy 72.850121 -27.277774) (xy 72.804763 -27.245323) (xy 72.764614 -27.206614) (xy 72.730528 -27.162471)
			(xy 72.703232 -27.113836) (xy 72.683309 -27.061745) (xy 72.671183 -27.007308) (xy 72.667112 -26.951686)
			(xy 71.090319 -26.951686) (xy 71.074287 -26.963637) (xy 71.026045 -26.98979) (xy 70.974552 -27.008761)
			(xy 70.920873 -27.020156) (xy 70.866115 -27.023742) (xy 70.811407 -27.019444) (xy 70.757881 -27.007351)
			(xy 70.70664 -26.987712) (xy 70.658742 -26.960932) (xy 70.615175 -26.927566) (xy 70.57684 -26.8883)
			(xy 70.544528 -26.843947) (xy 70.518905 -26.79542) (xy 70.5005 -26.743723) (xy 70.489693 -26.689922)
			(xy 70.486708 -26.635128) (xy 70.491606 -26.580471) (xy 70.504285 -26.52708) (xy 70.524485 -26.476057)
			(xy 70.551787 -26.428456) (xy 70.58563 -26.385258) (xy 70.605142 -26.365962) (xy 70.620896 -26.350305)
			(xy 70.647189 -26.314512) (xy 70.66686 -26.274694) (xy 70.67931 -26.232062) (xy 70.68416 -26.187915)
			(xy 70.681262 -26.143597) (xy 70.670705 -26.100458) (xy 70.652809 -26.05981) (xy 70.62812 -26.022892)
			(xy 70.59739 -25.990828) (xy 70.579742 -25.977342) (xy 70.557502 -25.960432) (xy 70.517704 -25.921225)
			(xy 70.48405 -25.876633) (xy 70.457258 -25.82761) (xy 70.437903 -25.775203) (xy 70.426397 -25.720534)
			(xy 70.422988 -25.664771) (xy 67.5343 -25.664771) (xy 67.550285 -25.670206) (xy 67.573906 -25.674066)
			(xy 67.601277 -25.678423) (xy 67.654463 -25.694014) (xy 67.704831 -25.717138) (xy 67.751324 -25.747307)
			(xy 67.792961 -25.783887) (xy 67.828866 -25.826108) (xy 67.858283 -25.87308) (xy 67.880593 -25.923814)
			(xy 67.895326 -25.977244) (xy 67.902172 -26.032242) (xy 67.900986 -26.087653) (xy 67.891795 -26.142309)
			(xy 67.87479 -26.195059) (xy 67.850331 -26.244793) (xy 67.818932 -26.290464) (xy 67.781255 -26.331111)
			(xy 67.738092 -26.365877) (xy 67.690352 -26.39403) (xy 67.63904 -26.414979) (xy 67.585237 -26.428281)
			(xy 67.530075 -26.433658) (xy 67.474716 -26.430995) (xy 67.420324 -26.420348) (xy 67.368047 -26.401943)
			(xy 67.318983 -26.376166) (xy 67.274165 -26.34356) (xy 67.234538 -26.304811) (xy 67.200936 -26.260736)
			(xy 67.174066 -26.212262) (xy 67.154494 -26.16041) (xy 67.142631 -26.106271) (xy 67.138728 -26.050985)
			(xy 67.140328 -26.023316) (xy 67.141581 -25.99941) (xy 67.136184 -25.951851) (xy 67.121979 -25.906143)
			(xy 67.099468 -25.863903) (xy 67.069446 -25.826624) (xy 67.032976 -25.795625) (xy 66.991347 -25.772002)
			(xy 66.946032 -25.75659) (xy 66.922396 -25.752806) (xy 66.895809 -25.748601) (xy 66.844089 -25.733687)
			(xy 66.794979 -25.71165) (xy 66.749455 -25.682927) (xy 66.708422 -25.648089) (xy 66.672694 -25.607828)
			(xy 66.642982 -25.562944) (xy 66.619875 -25.514329) (xy 66.603833 -25.462947) (xy 66.595174 -25.409821)
			(xy 66.59407 -25.356004) (xy 66.600543 -25.302568) (xy 66.614465 -25.250572) (xy 66.635559 -25.201049)
			(xy 66.663406 -25.154985) (xy 66.697452 -25.113293) (xy 66.71691 -25.094692) (xy 66.73397 -25.078268)
			(xy 66.762261 -25.040297) (xy 66.783032 -24.997745) (xy 66.795566 -24.952082) (xy 66.799429 -24.904889)
			(xy 66.794488 -24.857796) (xy 66.780914 -24.812433) (xy 66.770504 -24.791162) (xy 66.75635 -24.762295)
			(xy 66.736841 -24.70104) (xy 66.727858 -24.637384) (xy 66.728086 -24.605234) (xy 66.728255 -24.582632)
			(xy 66.721564 -24.537936) (xy 66.70707 -24.495128) (xy 66.68523 -24.455561) (xy 66.656733 -24.420483)
			(xy 66.62248 -24.391) (xy 66.58355 -24.368044) (xy 66.541172 -24.352338) (xy 66.496684 -24.344379)
			(xy 66.474086 -24.343868) (xy 64.789558 -24.343868) (xy 64.694816 -24.387302) (xy 64.678306 -24.404574)
			(xy 64.657864 -24.425) (xy 64.611932 -24.460067) (xy 64.561238 -24.487805) (xy 64.50694 -24.507582)
			(xy 64.45028 -24.518944) (xy 64.392556 -24.521631) (xy 64.335086 -24.515582) (xy 64.279185 -24.500936)
			(xy 64.226133 -24.478027) (xy 64.177142 -24.44738) (xy 64.133333 -24.409695) (xy 64.114172 -24.388064)
			(xy 64.101819 -24.374616) (xy 64.071162 -24.354804) (xy 64.036156 -24.344461) (xy 64.017906 -24.343868)
			(xy 63.491618 -24.343868) (xy 63.441326 -24.366982) (xy 63.423292 -24.388064) (xy 63.404076 -24.409643)
			(xy 63.360271 -24.447321) (xy 63.311286 -24.477964) (xy 63.258241 -24.50087) (xy 63.202349 -24.515518)
			(xy 63.144887 -24.521571) (xy 63.087169 -24.518891) (xy 63.030515 -24.50754) (xy 62.976221 -24.487777)
			(xy 62.925526 -24.460053) (xy 62.879591 -24.425004) (xy 62.859158 -24.404574) (xy 62.842648 -24.387302)
			(xy 62.747906 -24.343868) (xy 60.399168 -24.343868) (xy 60.376761 -24.344345) (xy 60.332643 -24.35221)
			(xy 60.290587 -24.36769) (xy 60.251899 -24.390305) (xy 60.217775 -24.419355) (xy 60.189275 -24.453938)
			(xy 60.167282 -24.492984) (xy 60.152477 -24.535281) (xy 60.145319 -24.57952) (xy 60.145168 -24.601932)
			(xy 60.145092 -24.632398) (xy 60.136913 -24.692768) (xy 60.119797 -24.751236) (xy 60.09413 -24.806487)
			(xy 60.060489 -24.857277) (xy 60.01963 -24.902466) (xy 59.972473 -24.941036) (xy 59.94654 -24.957024)
			(xy 59.926769 -24.969317) (xy 59.89168 -24.999905) (xy 59.862747 -25.036371) (xy 59.840938 -25.077496)
			(xy 59.826983 -25.121905) (xy 59.821347 -25.168112) (xy 59.824219 -25.214573) (xy 59.829108 -25.234138)
			(xy 64.675764 -25.234138) (xy 64.679835 -25.178516) (xy 64.691961 -25.124079) (xy 64.711884 -25.071988)
			(xy 64.73918 -25.023353) (xy 64.773266 -24.97921) (xy 64.813415 -24.940501) (xy 64.858773 -24.90805)
			(xy 64.908373 -24.882549) (xy 64.961157 -24.864542) (xy 65.016 -24.854412) (xy 65.071734 -24.852375)
			(xy 65.127171 -24.858475) (xy 65.181128 -24.872581) (xy 65.232457 -24.894393) (xy 65.280063 -24.923447)
			(xy 65.322931 -24.959122) (xy 65.360148 -25.000659) (xy 65.390921 -25.047172) (xy 65.414593 -25.097669)
			(xy 65.430661 -25.151076) (xy 65.438781 -25.206252) (xy 65.43929 -25.234138) (xy 65.438781 -25.262024)
			(xy 65.430661 -25.3172) (xy 65.414593 -25.370607) (xy 65.390921 -25.421104) (xy 65.360148 -25.467617)
			(xy 65.322931 -25.509154) (xy 65.280063 -25.544829) (xy 65.232457 -25.573883) (xy 65.181128 -25.595695)
			(xy 65.127171 -25.609801) (xy 65.071734 -25.615901) (xy 65.016 -25.613864) (xy 64.961157 -25.603734)
			(xy 64.908373 -25.585727) (xy 64.858773 -25.560226) (xy 64.813415 -25.527775) (xy 64.773266 -25.489066)
			(xy 64.73918 -25.444923) (xy 64.711884 -25.396288) (xy 64.691961 -25.344197) (xy 64.679835 -25.28976)
			(xy 64.675764 -25.234138) (xy 59.829108 -25.234138) (xy 59.835504 -25.259734) (xy 59.844686 -25.281128)
			(xy 59.855555 -25.306093) (xy 59.870902 -25.358333) (xy 59.878666 -25.412224) (xy 59.878688 -25.466672)
			(xy 59.870967 -25.52057) (xy 59.855661 -25.572822) (xy 59.833081 -25.622367) (xy 59.803686 -25.668198)
			(xy 59.768072 -25.709384) (xy 59.726965 -25.745087) (xy 59.681198 -25.774582) (xy 59.631702 -25.79727)
			(xy 59.579483 -25.81269) (xy 59.525603 -25.820528) (xy 59.471155 -25.820625) (xy 59.417247 -25.812979)
			(xy 59.364973 -25.797745) (xy 59.315397 -25.775234) (xy 59.269525 -25.745902) (xy 59.228291 -25.710345)
			(xy 59.192531 -25.669287) (xy 59.162972 -25.623561) (xy 59.140216 -25.574097) (xy 59.124724 -25.5219)
			(xy 59.116811 -25.46803) (xy 59.116639 -25.413582) (xy 59.12421 -25.359663) (xy 59.139371 -25.307369)
			(xy 59.161814 -25.257762) (xy 59.191083 -25.211849) (xy 59.226582 -25.170566) (xy 59.267591 -25.134749)
			(xy 59.290204 -25.119584) (xy 59.309451 -25.106473) (xy 59.343247 -25.07444) (xy 59.370649 -25.036791)
			(xy 59.390742 -24.994784) (xy 59.402855 -24.949822) (xy 59.406583 -24.903406) (xy 59.401802 -24.857087)
			(xy 59.388671 -24.812412) (xy 59.378596 -24.791416) (xy 59.36464 -24.762568) (xy 59.344987 -24.701574)
			(xy 59.33948 -24.670004) (xy 59.335595 -24.647876) (xy 59.321076 -24.605364) (xy 59.299313 -24.566066)
			(xy 59.270982 -24.531203) (xy 59.236965 -24.501861) (xy 59.198322 -24.478954) (xy 59.156255 -24.463193)
			(xy 59.134248 -24.458676) (xy 59.109772 -24.453766) (xy 59.062266 -24.438426) (xy 59.017163 -24.417029)
			(xy 58.97523 -24.38994) (xy 58.95594 -24.374094) (xy 58.92038 -24.343868) (xy 54.967124 -24.343868)
			(xy 54.944204 -24.344382) (xy 54.899114 -24.352649) (xy 54.856236 -24.368865) (xy 54.81696 -24.392505)
			(xy 54.782558 -24.422804) (xy 54.754146 -24.458778) (xy 54.732642 -24.499263) (xy 54.718745 -24.542948)
			(xy 54.712904 -24.588416) (xy 54.713632 -24.61133) (xy 54.714628 -24.639497) (xy 54.709318 -24.695606)
			(xy 54.695811 -24.750324) (xy 54.674402 -24.802459) (xy 54.645556 -24.850878) (xy 54.609902 -24.894526)
			(xy 54.568214 -24.932455) (xy 54.5214 -24.963838) (xy 54.470479 -24.987993) (xy 54.416559 -25.004395)
			(xy 54.360812 -25.012686) (xy 54.304452 -25.012686) (xy 54.248705 -25.004395) (xy 54.194785 -24.987993)
			(xy 54.143864 -24.963838) (xy 54.09705 -24.932455) (xy 54.055362 -24.894526) (xy 54.019708 -24.850878)
			(xy 53.990862 -24.802459) (xy 53.969453 -24.750324) (xy 53.955946 -24.695606) (xy 53.950636 -24.639497)
			(xy 53.951632 -24.61133) (xy 53.952364 -24.588412) (xy 53.946551 -24.542934) (xy 53.932671 -24.499237)
			(xy 53.911174 -24.458741) (xy 53.882759 -24.42276) (xy 53.848348 -24.392463) (xy 53.809059 -24.368832)
			(xy 53.766166 -24.352637) (xy 53.721064 -24.344402) (xy 53.69814 -24.343868) (xy 53.697124 -24.343868)
			(xy 53.674204 -24.344382) (xy 53.629114 -24.352649) (xy 53.586236 -24.368865) (xy 53.54696 -24.392505)
			(xy 53.512558 -24.422804) (xy 53.484146 -24.458778) (xy 53.462642 -24.499263) (xy 53.448745 -24.542948)
			(xy 53.442904 -24.588416) (xy 53.443632 -24.61133) (xy 53.444615 -24.63907) (xy 53.439515 -24.69434)
			(xy 53.426459 -24.748288) (xy 53.405723 -24.799774) (xy 53.377744 -24.847711) (xy 53.343113 -24.891088)
			(xy 53.302562 -24.928988) (xy 53.256946 -24.96061) (xy 53.207229 -24.985289) (xy 53.15446 -25.002501)
			(xy 53.099754 -25.011885) (xy 53.044265 -25.013241) (xy 53.016658 -25.010364) (xy 52.993902 -25.008077)
			(xy 52.948248 -25.01075) (xy 52.903809 -25.021546) (xy 52.862018 -25.040116) (xy 52.824222 -25.065861)
			(xy 52.79164 -25.097952) (xy 52.765323 -25.135353) (xy 52.755292 -25.155906) (xy 52.744689 -25.177969)
			(xy 52.718962 -25.219616) (xy 52.688425 -25.257876) (xy 52.671218 -25.275286) (xy 52.654518 -25.292481)
			(xy 52.627243 -25.33189) (xy 52.607833 -25.37571) (xy 52.596976 -25.422391) (xy 52.595055 -25.470279)
			(xy 52.602138 -25.51768) (xy 52.617975 -25.562914) (xy 52.629562 -25.583896) (xy 52.643213 -25.608442)
			(xy 52.663948 -25.660638) (xy 52.676806 -25.715311) (xy 52.681509 -25.771277) (xy 52.677956 -25.827329)
			(xy 52.666223 -25.882254) (xy 52.646565 -25.934865) (xy 52.619404 -25.984025) (xy 52.58533 -26.028672)
			(xy 52.545078 -26.06784) (xy 52.499518 -26.100684) (xy 52.449635 -26.126492) (xy 52.396507 -26.144708)
			(xy 52.341282 -26.154938) (xy 52.285155 -26.15696) (xy 52.229337 -26.150731) (xy 52.175036 -26.136386)
			(xy 52.123425 -26.114234) (xy 52.07562 -26.084755) (xy 52.032653 -26.048585) (xy 51.995454 -26.006506)
			(xy 51.964826 -25.959428) (xy 51.941432 -25.908368) (xy 51.925777 -25.85443) (xy 51.918199 -25.79878)
			(xy 51.918862 -25.74262) (xy 51.927752 -25.687164) (xy 51.944677 -25.63361) (xy 51.969271 -25.583117)
			(xy 52.001003 -25.536776) (xy 52.019708 -25.515824) (xy 52.035599 -25.497861) (xy 52.061021 -25.457201)
			(xy 52.078371 -25.412496) (xy 52.087035 -25.365332) (xy 52.086705 -25.317379) (xy 52.077393 -25.270339)
			(xy 52.059429 -25.225877) (xy 52.046886 -25.205436) (xy 52.03261 -25.182444) (xy 52.009617 -25.133452)
			(xy 51.993347 -25.081836) (xy 51.984089 -25.028514) (xy 51.982007 -24.974435) (xy 51.98714 -24.920559)
			(xy 51.999394 -24.867845) (xy 52.018554 -24.817231) (xy 52.044278 -24.769615) (xy 52.05984 -24.747474)
			(xy 52.07314 -24.728333) (xy 52.093261 -24.686294) (xy 52.105378 -24.641292) (xy 52.109086 -24.594834)
			(xy 52.10426 -24.548479) (xy 52.091062 -24.503782) (xy 52.069935 -24.462241) (xy 52.041586 -24.425248)
			(xy 52.006968 -24.394046) (xy 51.96724 -24.369679) (xy 51.923734 -24.352966) (xy 51.877911 -24.344465)
			(xy 51.854608 -24.343868) (xy 51.52009 -24.343868) (xy 51.497962 -24.344348) (xy 51.454377 -24.352019)
			(xy 51.412781 -24.367126) (xy 51.374431 -24.389213) (xy 51.340489 -24.417611) (xy 51.311982 -24.451461)
			(xy 51.289772 -24.48974) (xy 51.274531 -24.531287) (xy 51.26672 -24.574848) (xy 51.266576 -24.619102)
			(xy 51.274103 -24.662713) (xy 51.281076 -24.68372) (xy 51.290094 -24.710356) (xy 51.301099 -24.765504)
			(xy 51.30389 -24.821669) (xy 51.298407 -24.877636) (xy 51.284768 -24.932192) (xy 51.263269 -24.984154)
			(xy 51.234376 -25.032399) (xy 51.198715 -25.07588) (xy 51.157057 -25.113655) (xy 51.110306 -25.144907)
			(xy 51.059474 -25.168959) (xy 51.005663 -25.185288) (xy 50.950037 -25.193542) (xy 50.893803 -25.193542)
			(xy 50.838177 -25.185288) (xy 50.784366 -25.168959) (xy 50.733534 -25.144907) (xy 50.686783 -25.113655)
			(xy 50.645125 -25.07588) (xy 50.609464 -25.032399) (xy 50.580571 -24.984154) (xy 50.559072 -24.932192)
			(xy 50.545433 -24.877636) (xy 50.53995 -24.821669) (xy 50.542741 -24.765504) (xy 50.553746 -24.710356)
			(xy 50.562764 -24.68372) (xy 50.569789 -24.662733) (xy 50.5773 -24.619121) (xy 50.577142 -24.574867)
			(xy 50.56932 -24.531311) (xy 50.554071 -24.489767) (xy 50.531855 -24.451494) (xy 50.503345 -24.417648)
			(xy 50.469403 -24.389252) (xy 50.431054 -24.367166) (xy 50.38946 -24.352057) (xy 50.345877 -24.344382)
			(xy 50.32375 -24.343868) (xy 50.252884 -24.343868) (xy 50.237971 -24.344277) (xy 50.20896 -24.351205)
			(xy 50.18235 -24.364679) (xy 50.159595 -24.383961) (xy 50.141938 -24.408) (xy 50.13579 -24.421592)
			(xy 50.13579 -24.421846) (xy 50.124506 -24.447472) (xy 50.095531 -24.495385) (xy 50.059864 -24.538548)
			(xy 50.018271 -24.576034) (xy 49.971645 -24.607037) (xy 49.920988 -24.630892) (xy 49.867388 -24.647085)
			(xy 49.811996 -24.65527) (xy 49.756004 -24.65527) (xy 49.700612 -24.647085) (xy 49.647012 -24.630892)
			(xy 49.596355 -24.607037) (xy 49.549729 -24.576034) (xy 49.508136 -24.538548) (xy 49.472469 -24.495385)
			(xy 49.443494 -24.447472) (xy 49.43221 -24.421846) (xy 49.43221 -24.421592) (xy 49.42605 -24.408003)
			(xy 49.40841 -24.383948) (xy 49.38566 -24.364655) (xy 49.359047 -24.351181) (xy 49.330031 -24.344264)
			(xy 49.315116 -24.343868) (xy 47.199042 -24.343868) (xy 47.183594 -24.344308) (xy 47.153606 -24.351746)
			(xy 47.126284 -24.366172) (xy 47.103228 -24.38674) (xy 47.09414 -24.39924) (xy 47.078464 -24.421386)
			(xy 47.041851 -24.461429) (xy 46.999927 -24.495871) (xy 46.953539 -24.524016) (xy 46.928786 -24.53513)
			(xy 46.908967 -24.544101) (xy 46.872477 -24.567783) (xy 46.840551 -24.597331) (xy 46.814123 -24.631884)
			(xy 46.793964 -24.670432) (xy 46.780662 -24.711849) (xy 46.774605 -24.754927) (xy 46.775972 -24.798406)
			(xy 46.784721 -24.841019) (xy 46.800597 -24.881519) (xy 46.811438 -24.900382) (xy 46.829218 -24.933402)
			(xy 46.839608 -24.95388) (xy 46.86661 -24.991017) (xy 46.899845 -25.022697) (xy 46.938232 -25.04789)
			(xy 46.980521 -25.065775) (xy 47.025336 -25.07577) (xy 47.071217 -25.077549) (xy 47.116671 -25.071056)
			(xy 47.13859 -25.064212) (xy 47.164687 -25.056003) (xy 47.218523 -25.046284) (xy 47.273196 -25.044354)
			(xy 47.327583 -25.050253) (xy 47.38057 -25.063862) (xy 47.43107 -25.084899) (xy 47.478047 -25.112934)
			(xy 47.520538 -25.147392) (xy 47.557671 -25.187567) (xy 47.588684 -25.232633) (xy 47.612942 -25.281668)
			(xy 47.626804 -25.324054) (xy 47.903382 -25.324054) (xy 47.907453 -25.268432) (xy 47.919579 -25.213995)
			(xy 47.939502 -25.161904) (xy 47.966798 -25.113269) (xy 48.000884 -25.069126) (xy 48.041033 -25.030417)
			(xy 48.086391 -24.997966) (xy 48.135991 -24.972465) (xy 48.188775 -24.954458) (xy 48.243618 -24.944328)
			(xy 48.299352 -24.942291) (xy 48.354789 -24.948391) (xy 48.408746 -24.962497) (xy 48.460075 -24.984309)
			(xy 48.507681 -25.013363) (xy 48.550549 -25.049038) (xy 48.587766 -25.090575) (xy 48.618539 -25.137088)
			(xy 48.642211 -25.187585) (xy 48.658279 -25.240992) (xy 48.666399 -25.296168) (xy 48.666908 -25.324054)
			(xy 48.666399 -25.35194) (xy 48.658279 -25.407116) (xy 48.642211 -25.460523) (xy 48.618539 -25.51102)
			(xy 48.587766 -25.557533) (xy 48.550549 -25.59907) (xy 48.507681 -25.634745) (xy 48.460075 -25.663799)
			(xy 48.408746 -25.685611) (xy 48.354789 -25.699717) (xy 48.299352 -25.705817) (xy 48.243618 -25.70378)
			(xy 48.188775 -25.69365) (xy 48.135991 -25.675643) (xy 48.086391 -25.650142) (xy 48.041033 -25.617691)
			(xy 48.000884 -25.578982) (xy 47.966798 -25.534839) (xy 47.939502 -25.486204) (xy 47.919579 -25.434113)
			(xy 47.907453 -25.379676) (xy 47.903382 -25.324054) (xy 47.626804 -25.324054) (xy 47.629947 -25.333664)
			(xy 47.63935 -25.387557) (xy 47.640958 -25.44224) (xy 47.634739 -25.496592) (xy 47.620819 -25.549498)
			(xy 47.599485 -25.599874) (xy 47.571174 -25.646685) (xy 47.536467 -25.688972) (xy 47.496075 -25.725868)
			(xy 47.450827 -25.756616) (xy 47.40165 -25.780585) (xy 47.349555 -25.797284) (xy 47.295608 -25.80637)
			(xy 47.240916 -25.807656) (xy 47.186602 -25.801118) (xy 47.133778 -25.786887) (xy 47.083529 -25.765258)
			(xy 47.036885 -25.736672) (xy 46.994803 -25.701716) (xy 46.958145 -25.661108) (xy 46.927664 -25.61568)
			(xy 46.915324 -25.591262) (xy 46.904937 -25.570783) (xy 46.877938 -25.533645) (xy 46.844704 -25.501965)
			(xy 46.806317 -25.476774) (xy 46.764027 -25.458893) (xy 46.719212 -25.448904) (xy 46.673332 -25.447133)
			(xy 46.62788 -25.453638) (xy 46.605952 -25.460452) (xy 46.579568 -25.468729) (xy 46.525136 -25.478459)
			(xy 46.46987 -25.48023) (xy 46.414927 -25.474004) (xy 46.361458 -25.459913) (xy 46.310583 -25.43825)
			(xy 46.263368 -25.40947) (xy 46.220803 -25.374176) (xy 46.183778 -25.333107) (xy 46.153069 -25.287123)
			(xy 46.12932 -25.237188) (xy 46.113029 -25.184348) (xy 46.104535 -25.12971) (xy 46.104018 -25.074417)
			(xy 46.111488 -25.01963) (xy 46.126789 -24.966494) (xy 46.1496 -24.916124) (xy 46.179443 -24.869574)
			(xy 46.215693 -24.827819) (xy 46.257591 -24.791735) (xy 46.304259 -24.762077) (xy 46.35472 -24.739467)
			(xy 46.407916 -24.724378) (xy 46.435264 -24.720296) (xy 46.478698 -24.714454) (xy 46.535848 -24.65578)
			(xy 46.547083 -24.64348) (xy 46.563368 -24.614434) (xy 46.571582 -24.582163) (xy 46.571164 -24.548865)
			(xy 46.562144 -24.516811) (xy 46.545135 -24.488182) (xy 46.533562 -24.476202) (xy 46.531022 -24.473916)
			(xy 46.528482 -24.471376) (xy 46.510454 -24.455189) (xy 46.478223 -24.419012) (xy 46.46422 -24.39924)
			(xy 46.44644 -24.373332) (xy 46.390814 -24.343868) (xy 45.612304 -24.343868) (xy 45.590307 -24.344309)
			(xy 45.546961 -24.351836) (xy 45.505561 -24.366718) (xy 45.467343 -24.38851) (xy 45.433451 -24.416559)
			(xy 45.404897 -24.450028) (xy 45.382537 -24.487915) (xy 45.367037 -24.529088) (xy 45.358862 -24.572316)
			(xy 45.358257 -24.616306) (xy 45.365238 -24.659742) (xy 45.37202 -24.680672) (xy 45.380601 -24.707138)
			(xy 45.390885 -24.761815) (xy 45.393117 -24.817406) (xy 45.387252 -24.872732) (xy 45.373412 -24.926619)
			(xy 45.351893 -24.977925) (xy 45.323149 -25.025561) (xy 45.287791 -25.068516) (xy 45.246569 -25.105881)
			(xy 45.200357 -25.136861) (xy 45.150135 -25.160801) (xy 45.096969 -25.177193) (xy 45.041985 -25.185688)
			(xy 44.986351 -25.186107) (xy 44.931246 -25.17844) (xy 44.877838 -25.162851) (xy 44.827262 -25.13967)
			(xy 44.780589 -25.109388) (xy 44.759372 -25.09139) (xy 44.741792 -25.076605) (xy 44.702401 -25.052982)
			(xy 44.659408 -25.036816) (xy 44.614212 -25.028632) (xy 44.56828 -25.028696) (xy 44.523107 -25.037006)
			(xy 44.480159 -25.053292) (xy 44.440834 -25.077024) (xy 44.42333 -25.091898) (xy 44.402117 -25.109979)
			(xy 44.355436 -25.140432) (xy 44.30482 -25.163769) (xy 44.251347 -25.179493) (xy 44.196156 -25.187268)
			(xy 44.14042 -25.18693) (xy 44.085327 -25.178485) (xy 44.032049 -25.162114) (xy 43.98172 -25.138164)
			(xy 43.935412 -25.107146) (xy 43.89411 -25.06972) (xy 43.858694 -25.026683) (xy 43.829916 -24.97895)
			(xy 43.808391 -24.927537) (xy 43.794576 -24.87354) (xy 43.788765 -24.818107) (xy 43.791081 -24.762419)
			(xy 43.801477 -24.70766) (xy 43.810174 -24.68118) (xy 43.816948 -24.660233) (xy 43.823998 -24.61678)
			(xy 43.823454 -24.572763) (xy 43.815334 -24.529498) (xy 43.79988 -24.488279) (xy 43.777554 -24.45034)
			(xy 43.749024 -24.416816) (xy 43.715144 -24.388709) (xy 43.676928 -24.366861) (xy 43.635518 -24.351926)
			(xy 43.592154 -24.34435) (xy 43.570144 -24.343868) (xy 40.016684 -24.343868) (xy 39.994964 -24.344312)
			(xy 39.952156 -24.351699) (xy 39.911227 -24.366256) (xy 39.873368 -24.387558) (xy 39.839681 -24.414986)
			(xy 39.811147 -24.447741) (xy 39.788596 -24.484869) (xy 39.772685 -24.525291) (xy 39.763876 -24.567829)
			(xy 39.762427 -24.611246) (xy 39.76838 -24.654277) (xy 39.774622 -24.675084) (xy 39.789156 -24.722213)
			(xy 39.811545 -24.81827) (xy 39.826187 -24.91581) (xy 39.832988 -25.014208) (xy 39.831905 -25.112834)
			(xy 39.822944 -25.211059) (xy 39.806164 -25.308253) (xy 39.781671 -25.403796) (xy 39.749622 -25.497077)
			(xy 39.710221 -25.587498) (xy 39.663722 -25.674481) (xy 39.610421 -25.757472) (xy 39.550659 -25.835937)
			(xy 39.541697 -25.845933) (xy 41.345468 -25.845933) (xy 41.351506 -25.790698) (xy 41.365495 -25.736923)
			(xy 41.38714 -25.685747) (xy 41.415983 -25.638254) (xy 41.451412 -25.59545) (xy 41.492678 -25.55824)
			(xy 41.538906 -25.527412) (xy 41.563798 -25.515062) (xy 41.583896 -25.504971) (xy 41.620503 -25.478857)
			(xy 41.651938 -25.446705) (xy 41.677219 -25.409518) (xy 41.695555 -25.36846) (xy 41.706373 -25.324815)
			(xy 41.709334 -25.279946) (xy 41.704346 -25.235257) (xy 41.698418 -25.213564) (xy 41.690645 -25.185884)
			(xy 41.682274 -25.129) (xy 41.682025 -25.071505) (xy 41.689903 -25.014551) (xy 41.70575 -24.959282)
			(xy 41.729247 -24.906806) (xy 41.759924 -24.858178) (xy 41.797164 -24.814372) (xy 41.840221 -24.776268)
			(xy 41.88823 -24.74463) (xy 41.940228 -24.720094) (xy 41.995171 -24.703151) (xy 42.051957 -24.694142)
			(xy 42.109446 -24.693247) (xy 42.166484 -24.700485) (xy 42.221928 -24.71571) (xy 42.274664 -24.738617)
			(xy 42.323634 -24.768746) (xy 42.367855 -24.805492) (xy 42.38752 -24.826468) (xy 42.402235 -24.842027)
			(xy 42.435881 -24.868512) (xy 42.473489 -24.888986) (xy 42.513996 -24.902868) (xy 42.556257 -24.909765)
			(xy 42.599076 -24.909484) (xy 42.641242 -24.902032) (xy 42.681563 -24.887619) (xy 42.700448 -24.877522)
			(xy 42.724534 -24.864538) (xy 42.775541 -24.844738) (xy 42.828853 -24.83243) (xy 42.883378 -24.827865)
			(xy 42.937995 -24.831138) (xy 42.991584 -24.84218) (xy 43.043046 -24.860766) (xy 43.091324 -24.886515)
			(xy 43.135427 -24.918896) (xy 43.174452 -24.957248) (xy 43.207597 -25.000781) (xy 43.234181 -25.048604)
			(xy 43.25366 -25.099734) (xy 43.265633 -25.153123) (xy 43.269856 -25.207675) (xy 43.26624 -25.262271)
			(xy 43.254862 -25.315789) (xy 43.235953 -25.367133) (xy 43.209902 -25.415249) (xy 43.177244 -25.459148)
			(xy 43.138649 -25.497931) (xy 43.094908 -25.530802) (xy 43.046919 -25.557086) (xy 42.995668 -25.576243)
			(xy 42.942205 -25.587882) (xy 42.887627 -25.591761) (xy 42.833056 -25.587804) (xy 42.779609 -25.576089)
			(xy 42.728385 -25.556859) (xy 42.680434 -25.530506) (xy 42.63674 -25.497573) (xy 42.617136 -25.478486)
			(xy 42.601708 -25.463603) (xy 42.566841 -25.438673) (xy 42.528284 -25.41995) (xy 42.487131 -25.407963)
			(xy 42.444551 -25.403054) (xy 42.40175 -25.405361) (xy 42.359944 -25.41482) (xy 42.320319 -25.431161)
			(xy 42.301922 -25.442164) (xy 42.288176 -25.450591) (xy 42.259565 -25.465466) (xy 42.244772 -25.471882)
			(xy 42.22424 -25.481059) (xy 42.186544 -25.505579) (xy 42.153752 -25.536352) (xy 42.126889 -25.572416)
			(xy 42.106794 -25.612645) (xy 42.094094 -25.655784) (xy 42.089185 -25.700485) (xy 42.092222 -25.745351)
			(xy 42.097198 -25.767284) (xy 42.103352 -25.794383) (xy 42.108687 -25.848056) (xy 44.748702 -25.848056)
			(xy 44.752773 -25.792434) (xy 44.764899 -25.737997) (xy 44.784822 -25.685906) (xy 44.812118 -25.637271)
			(xy 44.846204 -25.593128) (xy 44.886353 -25.554419) (xy 44.931711 -25.521968) (xy 44.981311 -25.496467)
			(xy 45.034095 -25.47846) (xy 45.088938 -25.46833) (xy 45.144672 -25.466293) (xy 45.200109 -25.472393)
			(xy 45.254066 -25.486499) (xy 45.305395 -25.508311) (xy 45.353001 -25.537365) (xy 45.395869 -25.57304)
			(xy 45.433086 -25.614577) (xy 45.463859 -25.66109) (xy 45.487531 -25.711587) (xy 45.503599 -25.764994)
			(xy 45.511719 -25.82017) (xy 45.512228 -25.848056) (xy 45.511719 -25.875942) (xy 45.503599 -25.931118)
			(xy 45.487531 -25.984525) (xy 45.463859 -26.035022) (xy 45.433086 -26.081535) (xy 45.395869 -26.123072)
			(xy 45.353001 -26.158747) (xy 45.305395 -26.187801) (xy 45.254066 -26.209613) (xy 45.200109 -26.223719)
			(xy 45.144672 -26.229819) (xy 45.088938 -26.227782) (xy 45.034095 -26.217652) (xy 44.981311 -26.199645)
			(xy 44.931711 -26.174144) (xy 44.886353 -26.141693) (xy 44.846204 -26.102984) (xy 44.812118 -26.058841)
			(xy 44.784822 -26.010206) (xy 44.764899 -25.958115) (xy 44.752773 -25.903678) (xy 44.748702 -25.848056)
			(xy 42.108687 -25.848056) (xy 42.108848 -25.849675) (xy 42.106262 -25.90518) (xy 42.095648 -25.959721)
			(xy 42.077232 -26.012145) (xy 42.051403 -26.061342) (xy 42.018708 -26.10627) (xy 41.97984 -26.145977)
			(xy 41.935621 -26.179624) (xy 41.886987 -26.206497) (xy 41.834968 -26.226029) (xy 41.780665 -26.237804)
			(xy 41.725228 -26.241575) (xy 41.669831 -26.237261) (xy 41.615647 -26.224954) (xy 41.563822 -26.204913)
			(xy 41.515453 -26.177564) (xy 41.471566 -26.143486) (xy 41.433089 -26.103399) (xy 41.400836 -26.058153)
			(xy 41.37549 -26.008706) (xy 41.357589 -25.956104) (xy 41.34751 -25.901461) (xy 41.345468 -25.845933)
			(xy 39.541697 -25.845933) (xy 39.484818 -25.909377) (xy 39.413319 -25.97732) (xy 39.33662 -26.039333)
			(xy 39.255212 -26.09502) (xy 39.169613 -26.144023) (xy 39.080373 -26.18603) (xy 38.988062 -26.220771)
			(xy 38.89327 -26.248026) (xy 38.796603 -26.267619) (xy 38.69868 -26.279425) (xy 38.600126 -26.283369)
			(xy 38.501572 -26.279425) (xy 38.403649 -26.267619) (xy 38.306982 -26.248026) (xy 38.21219 -26.220771)
			(xy 38.119879 -26.18603) (xy 38.030639 -26.144023) (xy 37.94504 -26.09502) (xy 37.863632 -26.039333)
			(xy 37.786933 -25.97732) (xy 37.715434 -25.909377) (xy 37.649593 -25.835937) (xy 37.589831 -25.757472)
			(xy 37.53653 -25.674481) (xy 37.490031 -25.587498) (xy 37.45063 -25.497077) (xy 37.418581 -25.403796)
			(xy 37.394088 -25.308253) (xy 37.377308 -25.211059) (xy 37.368347 -25.112834) (xy 37.367264 -25.014208)
			(xy 37.374065 -24.91581) (xy 37.388707 -24.81827) (xy 37.411096 -24.722213) (xy 37.42563 -24.675084)
			(xy 37.431806 -24.654271) (xy 37.437777 -24.611272) (xy 37.436352 -24.567884) (xy 37.427572 -24.525369)
			(xy 37.411691 -24.484967) (xy 37.389174 -24.447852) (xy 37.360674 -24.415105) (xy 37.327023 -24.38768)
			(xy 37.289199 -24.366375) (xy 37.248304 -24.35181) (xy 37.205528 -24.344409) (xy 37.183822 -24.343868)
			(xy 36.191444 -24.343868) (xy 33.255966 -25.129236) (xy 32.877252 -25.50795) (xy 32.877252 -25.51811)
			(xy 31.9913 -26.404062) (xy 31.9913 -27.086446) (xy 42.673881 -27.086446) (xy 42.67566 -27.031081)
			(xy 42.68543 -26.976556) (xy 42.702984 -26.924017) (xy 42.727953 -26.874571) (xy 42.759812 -26.829256)
			(xy 42.797891 -26.789026) (xy 42.841388 -26.754728) (xy 42.88939 -26.727083) (xy 42.940886 -26.706672)
			(xy 42.994792 -26.693924) (xy 43.049976 -26.689108) (xy 43.105276 -26.692326) (xy 43.132502 -26.697432)
			(xy 43.148686 -26.700302) (xy 43.181496 -26.698459) (xy 43.212746 -26.688295) (xy 43.240362 -26.670483)
			(xy 43.26251 -26.646207) (xy 43.277721 -26.617077) (xy 43.281854 -26.601166) (xy 43.288465 -26.57393)
			(xy 43.308326 -26.521519) (xy 43.335219 -26.472345) (xy 43.368631 -26.427344) (xy 43.407923 -26.387376)
			(xy 43.452347 -26.353202) (xy 43.501056 -26.325474) (xy 43.553121 -26.304722) (xy 43.607548 -26.29134)
			(xy 43.663299 -26.285584) (xy 43.719312 -26.287565) (xy 43.774518 -26.297243) (xy 43.827864 -26.314435)
			(xy 43.878333 -26.338813) (xy 43.924962 -26.369911) (xy 43.966862 -26.407137) (xy 44.003234 -26.449781)
			(xy 44.018708 -26.47315) (xy 44.027763 -26.486472) (xy 44.051295 -26.508453) (xy 44.079582 -26.523841)
			(xy 44.110821 -26.531654) (xy 44.143021 -26.531394) (xy 44.17413 -26.523078) (xy 44.18838 -26.515568)
			(xy 44.206715 -26.505479) (xy 44.245158 -26.488935) (xy 44.265088 -26.482548) (xy 44.292151 -26.474796)
			(xy 44.34783 -26.466494) (xy 44.404125 -26.466461) (xy 44.459814 -26.474698) (xy 44.513689 -26.491028)
			(xy 44.56458 -26.515094) (xy 44.611383 -26.546376) (xy 44.626425 -26.560018) (xy 47.421544 -26.560018)
			(xy 47.425615 -26.504396) (xy 47.437741 -26.449959) (xy 47.457664 -26.397868) (xy 47.48496 -26.349233)
			(xy 47.519046 -26.30509) (xy 47.559195 -26.266381) (xy 47.604553 -26.23393) (xy 47.654153 -26.208429)
			(xy 47.706937 -26.190422) (xy 47.76178 -26.180292) (xy 47.817514 -26.178255) (xy 47.872951 -26.184355)
			(xy 47.926908 -26.198461) (xy 47.978237 -26.220273) (xy 48.025843 -26.249327) (xy 48.068711 -26.285002)
			(xy 48.103472 -26.323798) (xy 50.416204 -26.323798) (xy 50.420275 -26.268176) (xy 50.432401 -26.213739)
			(xy 50.452324 -26.161648) (xy 50.47962 -26.113013) (xy 50.513706 -26.06887) (xy 50.553855 -26.030161)
			(xy 50.599213 -25.99771) (xy 50.648813 -25.972209) (xy 50.701597 -25.954202) (xy 50.75644 -25.944072)
			(xy 50.812174 -25.942035) (xy 50.867611 -25.948135) (xy 50.921568 -25.962241) (xy 50.972897 -25.984053)
			(xy 51.020503 -26.013107) (xy 51.063371 -26.048782) (xy 51.100588 -26.090319) (xy 51.131361 -26.136832)
			(xy 51.155033 -26.187329) (xy 51.171101 -26.240736) (xy 51.179221 -26.295912) (xy 51.17973 -26.323798)
			(xy 51.179221 -26.351684) (xy 51.171101 -26.40686) (xy 51.155033 -26.460267) (xy 51.131361 -26.510764)
			(xy 51.100588 -26.557277) (xy 51.063371 -26.598814) (xy 51.020503 -26.634489) (xy 50.975327 -26.66206)
			(xy 53.573318 -26.66206) (xy 53.576797 -26.607576) (xy 53.588005 -26.554144) (xy 53.606713 -26.502855)
			(xy 53.63254 -26.454755) (xy 53.664959 -26.410828) (xy 53.703307 -26.371969) (xy 53.746802 -26.338972)
			(xy 53.794555 -26.312511) (xy 53.845592 -26.293126) (xy 53.87213 -26.286714) (xy 53.893592 -26.281372)
			(xy 53.934414 -26.264368) (xy 53.971677 -26.240554) (xy 54.004256 -26.21065) (xy 54.031166 -26.175558)
			(xy 54.051597 -26.136339) (xy 54.064931 -26.094175) (xy 54.070766 -26.050339) (xy 54.068926 -26.006155)
			(xy 54.064662 -25.984454) (xy 54.05922 -25.957182) (xy 54.055272 -25.901714) (xy 54.059419 -25.84626)
			(xy 54.071572 -25.791996) (xy 54.091475 -25.740071) (xy 54.118704 -25.691585) (xy 54.152685 -25.647567)
			(xy 54.192695 -25.608947) (xy 54.237889 -25.576546) (xy 54.287307 -25.551048) (xy 54.339904 -25.532995)
			(xy 54.394564 -25.522769) (xy 54.45013 -25.520587) (xy 54.505424 -25.526494) (xy 54.559274 -25.540367)
			(xy 54.61054 -25.56191) (xy 54.658136 -25.590667) (xy 54.701052 -25.626029) (xy 54.73838 -25.667247)
			(xy 54.754272 -25.690068) (xy 54.767088 -25.708444) (xy 54.798151 -25.740725) (xy 54.834393 -25.767059)
			(xy 54.87469 -25.786631) (xy 54.917795 -25.798834) (xy 54.962372 -25.80329) (xy 55.00704 -25.799861)
			(xy 55.028846 -25.794716) (xy 55.057659 -25.787817) (xy 55.116575 -25.781573) (xy 55.146194 -25.78227)
			(xy 55.169291 -25.782704) (xy 55.215018 -25.776171) (xy 55.258811 -25.761481) (xy 55.299229 -25.739118)
			(xy 55.334939 -25.709819) (xy 55.364767 -25.674549) (xy 55.387729 -25.634469) (xy 55.395876 -25.612852)
			(xy 55.40561 -25.586857) (xy 55.431484 -25.537751) (xy 55.464202 -25.492913) (xy 55.503072 -25.453291)
			(xy 55.547275 -25.419719) (xy 55.595875 -25.392908) (xy 55.647849 -25.373424) (xy 55.702097 -25.361677)
			(xy 55.757475 -25.357916) (xy 55.812813 -25.362221) (xy 55.866944 -25.374499) (xy 55.918723 -25.394493)
			(xy 55.967059 -25.42178) (xy 56.010929 -25.455783) (xy 56.049409 -25.495786) (xy 56.081685 -25.540943)
			(xy 56.107076 -25.5903) (xy 56.125045 -25.642816) (xy 56.135215 -25.697382) (xy 56.137369 -25.752846)
			(xy 56.131462 -25.808036) (xy 56.11762 -25.861788) (xy 56.096134 -25.912966) (xy 56.067457 -25.960491)
			(xy 56.032196 -26.003357) (xy 55.991095 -26.040661) (xy 55.945022 -26.071614) (xy 55.894949 -26.095564)
			(xy 55.841934 -26.112004) (xy 55.787097 -26.120588) (xy 55.75935 -26.12136) (xy 55.736271 -26.122097)
			(xy 55.690943 -26.130869) (xy 55.647944 -26.147681) (xy 55.608686 -26.171979) (xy 55.574459 -26.202965)
			(xy 55.546389 -26.239621) (xy 55.525398 -26.280743) (xy 55.518304 -26.302716) (xy 55.516807 -26.307449)
			(xy 60.012165 -26.307449) (xy 60.017499 -26.25198) (xy 60.030845 -26.197877) (xy 60.051917 -26.146289)
			(xy 60.080267 -26.098315) (xy 60.115294 -26.054974) (xy 60.156251 -26.017188) (xy 60.202269 -25.985761)
			(xy 60.252368 -25.96136) (xy 60.278772 -25.95245) (xy 60.299561 -25.945376) (xy 60.338524 -25.925129)
			(xy 60.373424 -25.898483) (xy 60.403221 -25.866232) (xy 60.427027 -25.829336) (xy 60.444132 -25.788896)
			(xy 60.454028 -25.746116) (xy 60.456418 -25.702272) (xy 60.454286 -25.680416) (xy 60.45156 -25.652688)
			(xy 60.453045 -25.596996) (xy 60.462614 -25.542113) (xy 60.480063 -25.489205) (xy 60.505021 -25.439397)
			(xy 60.536958 -25.393749) (xy 60.575193 -25.35323) (xy 60.618915 -25.318703) (xy 60.667194 -25.290902)
			(xy 60.719002 -25.270417) (xy 60.773239 -25.257685) (xy 60.828751 -25.252977) (xy 60.884357 -25.256391)
			(xy 60.938876 -25.267856) (xy 60.991147 -25.287129) (xy 61.04006 -25.313798) (xy 61.084574 -25.347298)
			(xy 61.123743 -25.386915) (xy 61.156734 -25.431807) (xy 61.182845 -25.48102) (xy 61.201522 -25.533507)
			(xy 61.212366 -25.588153) (xy 61.215148 -25.643795) (xy 61.209808 -25.699249) (xy 61.19646 -25.753338)
			(xy 61.175388 -25.80491) (xy 61.147039 -25.852869) (xy 61.112017 -25.896195) (xy 61.071066 -25.933967)
			(xy 61.025057 -25.965383) (xy 60.974968 -25.989772) (xy 60.94857 -25.998678) (xy 60.927779 -26.005749)
			(xy 60.888813 -26.025993) (xy 60.853911 -26.052637) (xy 60.824112 -26.084889) (xy 60.800305 -26.121786)
			(xy 60.7832 -26.162228) (xy 60.773307 -26.20501) (xy 60.770921 -26.248856) (xy 60.773056 -26.270712)
			(xy 60.775922 -26.298431) (xy 60.774448 -26.354136) (xy 60.764888 -26.409035) (xy 60.747444 -26.46196)
			(xy 60.72249 -26.511785) (xy 60.690554 -26.557451) (xy 60.652316 -26.597987) (xy 60.608589 -26.63253)
			(xy 60.560303 -26.660347) (xy 60.508485 -26.680846) (xy 60.454237 -26.69359) (xy 60.398712 -26.698309)
			(xy 60.343091 -26.694902) (xy 60.288557 -26.683443) (xy 60.23627 -26.664174) (xy 60.18734 -26.637505)
			(xy 60.14281 -26.604003) (xy 60.103626 -26.564382) (xy 60.07062 -26.519483) (xy 60.044496 -26.470261)
			(xy 60.025808 -26.417762) (xy 60.014954 -26.363105) (xy 60.012165 -26.307449) (xy 55.516807 -26.307449)
			(xy 55.509459 -26.330675) (xy 55.484814 -26.383887) (xy 55.452758 -26.43299) (xy 55.413958 -26.47696)
			(xy 55.369225 -26.514879) (xy 55.319494 -26.545953) (xy 55.265804 -26.569535) (xy 55.209274 -26.585132)
			(xy 55.151088 -26.592417) (xy 55.092458 -26.59124) (xy 55.034611 -26.581624) (xy 54.978753 -26.56377)
			(xy 54.926053 -26.538051) (xy 54.87761 -26.505004) (xy 54.834436 -26.46532) (xy 54.797433 -26.419828)
			(xy 54.781958 -26.394918) (xy 54.770097 -26.375917) (xy 54.740765 -26.34207) (xy 54.705946 -26.313897)
			(xy 54.666724 -26.292272) (xy 54.624314 -26.277869) (xy 54.580035 -26.271133) (xy 54.535261 -26.272275)
			(xy 54.513226 -26.2763) (xy 54.487233 -26.281144) (xy 54.434464 -26.284461) (xy 54.40807 -26.282904)
			(xy 54.392817 -26.282223) (xy 54.362704 -26.287183) (xy 54.334636 -26.299168) (xy 54.310228 -26.31749)
			(xy 54.290882 -26.341095) (xy 54.277711 -26.368626) (xy 54.271472 -26.398501) (xy 54.272523 -26.429003)
			(xy 54.280804 -26.458378) (xy 54.287928 -26.47188) (xy 54.30089 -26.495908) (xy 54.320621 -26.546813)
			(xy 54.332896 -26.60001) (xy 54.337464 -26.654413) (xy 54.334232 -26.708912) (xy 54.323266 -26.762394)
			(xy 54.30479 -26.813767) (xy 54.27918 -26.861983) (xy 54.246961 -26.906057) (xy 54.208789 -26.945088)
			(xy 54.165443 -26.978282) (xy 54.11781 -27.004958) (xy 54.066861 -27.024574) (xy 54.013637 -27.036729)
			(xy 53.959223 -27.041174) (xy 53.904732 -27.037819) (xy 53.851275 -27.026732) (xy 53.799943 -27.008139)
			(xy 53.751786 -26.982421) (xy 53.707785 -26.950102) (xy 53.66884 -26.911841) (xy 53.635745 -26.868421)
			(xy 53.609175 -26.820728) (xy 53.589675 -26.769735) (xy 53.57764 -26.716483) (xy 53.573318 -26.66206)
			(xy 50.975327 -26.66206) (xy 50.972897 -26.663543) (xy 50.921568 -26.685355) (xy 50.867611 -26.699461)
			(xy 50.812174 -26.705561) (xy 50.75644 -26.703524) (xy 50.701597 -26.693394) (xy 50.648813 -26.675387)
			(xy 50.599213 -26.649886) (xy 50.553855 -26.617435) (xy 50.513706 -26.578726) (xy 50.47962 -26.534583)
			(xy 50.452324 -26.485948) (xy 50.432401 -26.433857) (xy 50.420275 -26.37942) (xy 50.416204 -26.323798)
			(xy 48.103472 -26.323798) (xy 48.105928 -26.326539) (xy 48.136701 -26.373052) (xy 48.160373 -26.423549)
			(xy 48.176441 -26.476956) (xy 48.184561 -26.532132) (xy 48.18507 -26.560018) (xy 48.184561 -26.587904)
			(xy 48.176441 -26.64308) (xy 48.160373 -26.696487) (xy 48.136701 -26.746984) (xy 48.105928 -26.793497)
			(xy 48.068711 -26.835034) (xy 48.025843 -26.870709) (xy 47.978237 -26.899763) (xy 47.926908 -26.921575)
			(xy 47.872951 -26.935681) (xy 47.817514 -26.941781) (xy 47.76178 -26.939744) (xy 47.706937 -26.929614)
			(xy 47.654153 -26.911607) (xy 47.604553 -26.886106) (xy 47.559195 -26.853655) (xy 47.519046 -26.814946)
			(xy 47.48496 -26.770803) (xy 47.457664 -26.722168) (xy 47.437741 -26.670077) (xy 47.425615 -26.61564)
			(xy 47.421544 -26.560018) (xy 44.626425 -26.560018) (xy 44.653083 -26.584194) (xy 44.688775 -26.627728)
			(xy 44.717685 -26.676033) (xy 44.739184 -26.728061) (xy 44.752807 -26.782683) (xy 44.758257 -26.838713)
			(xy 44.75734 -26.86685) (xy 44.755477 -26.894577) (xy 44.744635 -26.94908) (xy 44.726 -27.001433)
			(xy 44.699966 -27.050528) (xy 44.667084 -27.095327) (xy 44.628051 -27.13488) (xy 44.583691 -27.168352)
			(xy 44.534944 -27.195033) (xy 44.482842 -27.214359) (xy 44.428488 -27.225921) (xy 44.373031 -27.229474)
			(xy 44.317645 -27.224943) (xy 44.263502 -27.212424) (xy 44.211749 -27.192182) (xy 44.163481 -27.164645)
			(xy 44.119719 -27.130396) (xy 44.081389 -27.09016) (xy 44.064936 -27.067764) (xy 44.055283 -27.054879)
			(xy 44.030704 -27.034095) (xy 44.001705 -27.020127) (xy 43.970132 -27.013864) (xy 43.937996 -27.015705)
			(xy 43.907345 -27.025533) (xy 43.893486 -27.033728) (xy 43.870026 -27.048009) (xy 43.820048 -27.070786)
			(xy 43.767453 -27.086607) (xy 43.713203 -27.095182) (xy 43.658292 -27.096355) (xy 43.603726 -27.090104)
			(xy 43.577002 -27.083766) (xy 43.560932 -27.080274) (xy 43.528064 -27.08056) (xy 43.496357 -27.089223)
			(xy 43.46791 -27.105689) (xy 43.444606 -27.128869) (xy 43.427988 -27.157228) (xy 43.423078 -27.17292)
			(xy 43.415176 -27.199471) (xy 43.39281 -27.250148) (xy 43.363348 -27.297056) (xy 43.32741 -27.33921)
			(xy 43.285753 -27.375721) (xy 43.239253 -27.405823) (xy 43.188887 -27.428882) (xy 43.135715 -27.444413)
			(xy 43.080856 -27.452089) (xy 43.025464 -27.451749) (xy 42.970704 -27.443399) (xy 42.917727 -27.427217)
			(xy 42.867648 -27.403541) (xy 42.821521 -27.37287) (xy 42.780315 -27.335849) (xy 42.744898 -27.293257)
			(xy 42.716015 -27.24599) (xy 42.694273 -27.195043) (xy 42.680129 -27.141485) (xy 42.673881 -27.086446)
			(xy 31.9913 -27.086446) (xy 31.9913 -27.646376) (xy 40.268142 -27.646376) (xy 40.272213 -27.590754)
			(xy 40.284339 -27.536317) (xy 40.304262 -27.484226) (xy 40.331558 -27.435591) (xy 40.365644 -27.391448)
			(xy 40.405793 -27.352739) (xy 40.451151 -27.320288) (xy 40.500751 -27.294787) (xy 40.553535 -27.27678)
			(xy 40.608378 -27.26665) (xy 40.664112 -27.264613) (xy 40.719549 -27.270713) (xy 40.773506 -27.284819)
			(xy 40.824835 -27.306631) (xy 40.872441 -27.335685) (xy 40.915309 -27.37136) (xy 40.952526 -27.412897)
			(xy 40.983299 -27.45941) (xy 41.006971 -27.509907) (xy 41.023039 -27.563314) (xy 41.031159 -27.61849)
			(xy 41.031325 -27.62758) (xy 45.589442 -27.62758) (xy 45.593513 -27.571958) (xy 45.605639 -27.517521)
			(xy 45.625562 -27.46543) (xy 45.652858 -27.416795) (xy 45.686944 -27.372652) (xy 45.727093 -27.333943)
			(xy 45.772451 -27.301492) (xy 45.822051 -27.275991) (xy 45.874835 -27.257984) (xy 45.929678 -27.247854)
			(xy 45.985412 -27.245817) (xy 46.040849 -27.251917) (xy 46.094806 -27.266023) (xy 46.146135 -27.287835)
			(xy 46.193741 -27.316889) (xy 46.236609 -27.352564) (xy 46.273826 -27.394101) (xy 46.304599 -27.440614)
			(xy 46.328271 -27.491111) (xy 46.344339 -27.544518) (xy 46.352459 -27.599694) (xy 46.352968 -27.62758)
			(xy 46.352705 -27.641995) (xy 49.268516 -27.641995) (xy 49.270248 -27.587427) (xy 49.279742 -27.533662)
			(xy 49.296804 -27.481801) (xy 49.321085 -27.432901) (xy 49.352089 -27.387962) (xy 49.389183 -27.347903)
			(xy 49.431609 -27.31354) (xy 49.454816 -27.299158) (xy 49.474139 -27.28704) (xy 49.508466 -27.257012)
			(xy 49.53689 -27.221346) (xy 49.558502 -27.181185) (xy 49.572608 -27.137814) (xy 49.578757 -27.092624)
			(xy 49.576752 -27.047061) (xy 49.566657 -27.002585) (xy 49.558194 -26.981404) (xy 49.547864 -26.956129)
			(xy 49.533829 -26.903361) (xy 49.52746 -26.849131) (xy 49.528887 -26.794547) (xy 49.538082 -26.740724)
			(xy 49.554855 -26.688762) (xy 49.578865 -26.639721) (xy 49.609621 -26.594604) (xy 49.646495 -26.554333)
			(xy 49.688733 -26.51973) (xy 49.735473 -26.491501) (xy 49.78576 -26.470225) (xy 49.838566 -26.456334)
			(xy 49.892813 -26.450114) (xy 49.947393 -26.451691) (xy 50.001191 -26.461032) (xy 50.053107 -26.477948)
			(xy 50.102082 -26.502092) (xy 50.147114 -26.532971) (xy 50.187285 -26.569955) (xy 50.221772 -26.612288)
			(xy 50.249872 -26.659105) (xy 50.271011 -26.709449) (xy 50.284757 -26.762294) (xy 50.290829 -26.816558)
			(xy 50.289103 -26.871133) (xy 50.279614 -26.924905) (xy 50.262557 -26.976775) (xy 50.238279 -27.025683)
			(xy 50.207277 -27.070631) (xy 50.170183 -27.1107) (xy 50.127756 -27.145072) (xy 50.104548 -27.159458)
			(xy 50.085225 -27.171578) (xy 50.050893 -27.201602) (xy 50.022465 -27.237266) (xy 50.00085 -27.277428)
			(xy 49.986743 -27.320799) (xy 49.980595 -27.365991) (xy 49.981232 -27.380438) (xy 51.068222 -27.380438)
			(xy 51.072293 -27.324816) (xy 51.084419 -27.270379) (xy 51.104342 -27.218288) (xy 51.131638 -27.169653)
			(xy 51.165724 -27.12551) (xy 51.205873 -27.086801) (xy 51.251231 -27.05435) (xy 51.300831 -27.028849)
			(xy 51.353615 -27.010842) (xy 51.408458 -27.000712) (xy 51.464192 -26.998675) (xy 51.519629 -27.004775)
			(xy 51.573586 -27.018881) (xy 51.624915 -27.040693) (xy 51.672521 -27.069747) (xy 51.715389 -27.105422)
			(xy 51.752606 -27.146959) (xy 51.783379 -27.193472) (xy 51.807051 -27.243969) (xy 51.823119 -27.297376)
			(xy 51.831239 -27.352552) (xy 51.831748 -27.380438) (xy 51.831239 -27.408324) (xy 51.823119 -27.4635)
			(xy 51.807051 -27.516907) (xy 51.792439 -27.548078) (xy 53.009544 -27.548078) (xy 53.013615 -27.492456)
			(xy 53.025741 -27.438019) (xy 53.045664 -27.385928) (xy 53.07296 -27.337293) (xy 53.107046 -27.29315)
			(xy 53.147195 -27.254441) (xy 53.192553 -27.22199) (xy 53.242153 -27.196489) (xy 53.294937 -27.178482)
			(xy 53.34978 -27.168352) (xy 53.405514 -27.166315) (xy 53.460951 -27.172415) (xy 53.514908 -27.186521)
			(xy 53.566237 -27.208333) (xy 53.613843 -27.237387) (xy 53.656711 -27.273062) (xy 53.693928 -27.314599)
			(xy 53.724701 -27.361112) (xy 53.748373 -27.411609) (xy 53.764441 -27.465016) (xy 53.772561 -27.520192)
			(xy 53.77307 -27.548078) (xy 53.772561 -27.575964) (xy 53.765482 -27.624064) (xy 55.268752 -27.624064)
			(xy 55.269768 -27.568748) (xy 55.278765 -27.51416) (xy 55.295555 -27.461445) (xy 55.319785 -27.411709)
			(xy 55.350947 -27.365995) (xy 55.388387 -27.325264) (xy 55.431319 -27.290369) (xy 55.478842 -27.262043)
			(xy 55.52996 -27.240881) (xy 55.556658 -27.233626) (xy 55.577392 -27.227894) (xy 55.616725 -27.210489)
			(xy 55.652567 -27.186711) (xy 55.683895 -27.157238) (xy 55.709815 -27.122913) (xy 55.729586 -27.084714)
			(xy 55.742645 -27.043732) (xy 55.748619 -27.001136) (xy 55.748428 -26.979626) (xy 55.74809 -26.951957)
			(xy 55.754441 -26.89699) (xy 55.768668 -26.843517) (xy 55.790472 -26.792661) (xy 55.819394 -26.745489)
			(xy 55.854829 -26.702991) (xy 55.896033 -26.666059) (xy 55.94214 -26.635467) (xy 55.992184 -26.611859)
			(xy 56.045113 -26.595729) (xy 56.099818 -26.587415) (xy 56.15515 -26.587094) (xy 56.209948 -26.59477)
			(xy 56.263062 -26.610283) (xy 56.313377 -26.633308) (xy 56.359837 -26.663361) (xy 56.401467 -26.699812)
			(xy 56.437394 -26.741895) (xy 56.466864 -26.788727) (xy 56.489257 -26.839326) (xy 56.504105 -26.89263)
			(xy 56.511095 -26.947519) (xy 56.510081 -27.002843) (xy 56.501084 -27.05744) (xy 56.484293 -27.110163)
			(xy 56.46006 -27.159908) (xy 56.428895 -27.205629) (xy 56.39145 -27.246367) (xy 56.348512 -27.281268)
			(xy 56.300981 -27.309598) (xy 56.249856 -27.330763) (xy 56.223154 -27.33802) (xy 56.202409 -27.343717)
			(xy 56.163073 -27.361125) (xy 56.127228 -27.384907) (xy 56.095899 -27.414384) (xy 56.06998 -27.448715)
			(xy 56.050212 -27.48692) (xy 56.037157 -27.527908) (xy 56.03119 -27.570508) (xy 56.031239 -27.575929)
			(xy 58.201847 -27.575929) (xy 58.20333 -27.520206) (xy 58.21291 -27.465293) (xy 58.230382 -27.41236)
			(xy 58.255374 -27.362534) (xy 58.287354 -27.316878) (xy 58.32564 -27.276363) (xy 58.369416 -27.241855)
			(xy 58.39333 -27.22753) (xy 58.413365 -27.215389) (xy 58.448972 -27.184953) (xy 58.478405 -27.148512)
			(xy 58.50067 -27.1073) (xy 58.515015 -27.062708) (xy 58.520956 -27.016244) (xy 58.51829 -26.969478)
			(xy 58.513218 -26.946606) (xy 58.50692 -26.918933) (xy 58.501228 -26.862467) (xy 58.503469 -26.805759)
			(xy 58.513601 -26.749918) (xy 58.531425 -26.696037) (xy 58.556592 -26.64517) (xy 58.58861 -26.598312)
			(xy 58.626853 -26.55638) (xy 58.670572 -26.520194) (xy 58.718913 -26.490461) (xy 58.770929 -26.467764)
			(xy 58.825603 -26.452546) (xy 58.881866 -26.445106) (xy 58.938616 -26.445588) (xy 58.994744 -26.453984)
			(xy 59.049151 -26.470129) (xy 59.100774 -26.493707) (xy 59.148602 -26.524257) (xy 59.1917 -26.561182)
			(xy 59.229225 -26.603758) (xy 59.260441 -26.651154) (xy 59.28474 -26.702441) (xy 59.301645 -26.756617)
			(xy 59.310826 -26.812622) (xy 59.312103 -26.86936) (xy 59.305452 -26.925722) (xy 59.291001 -26.980604)
			(xy 59.269035 -27.032932) (xy 59.239982 -27.081685) (xy 59.204412 -27.125906) (xy 59.163019 -27.164733)
			(xy 59.116614 -27.197404) (xy 59.091576 -27.210766) (xy 59.070965 -27.221907) (xy 59.033865 -27.25051)
			(xy 59.00263 -27.285424) (xy 58.978317 -27.325467) (xy 58.961747 -27.369285) (xy 58.953481 -27.415396)
			(xy 58.953798 -27.462241) (xy 58.957718 -27.48534) (xy 58.962457 -27.512812) (xy 58.965026 -27.568495)
			(xy 58.95946 -27.623959) (xy 58.952678 -27.650956) (xy 60.668885 -27.650956) (xy 60.669026 -27.595707)
			(xy 60.677131 -27.541055) (xy 60.693033 -27.488144) (xy 60.716398 -27.438078) (xy 60.746739 -27.391905)
			(xy 60.783421 -27.350589) (xy 60.825676 -27.314995) (xy 60.872623 -27.285866) (xy 60.92328 -27.263811)
			(xy 60.976587 -27.249292) (xy 61.031431 -27.242611) (xy 61.05906 -27.24277) (xy 61.082121 -27.242786)
			(xy 61.127649 -27.235481) (xy 61.171114 -27.220086) (xy 61.211091 -27.197106) (xy 61.246269 -27.167295)
			(xy 61.275495 -27.131629) (xy 61.297812 -27.091278) (xy 61.312487 -27.047565) (xy 61.319039 -27.001922)
			(xy 61.318648 -26.978864) (xy 61.31809 -26.951821) (xy 61.323659 -26.89802) (xy 61.336764 -26.845543)
			(xy 61.357141 -26.79544) (xy 61.384383 -26.748713) (xy 61.417946 -26.706297) (xy 61.457157 -26.669041)
			(xy 61.478922 -26.652982) (xy 61.496642 -26.639773) (xy 61.527732 -26.608366) (xy 61.552912 -26.572051)
			(xy 61.571423 -26.531923) (xy 61.582706 -26.489197) (xy 61.586419 -26.445161) (xy 61.58245 -26.401149)
			(xy 61.57092 -26.358488) (xy 61.56198 -26.338276) (xy 61.55059 -26.312805) (xy 61.53454 -26.259368)
			(xy 61.526445 -26.204164) (xy 61.526479 -26.148369) (xy 61.534642 -26.093174) (xy 61.550758 -26.039758)
			(xy 61.574484 -25.989259) (xy 61.605315 -25.942755) (xy 61.642591 -25.90124) (xy 61.685518 -25.865598)
			(xy 61.733179 -25.83659) (xy 61.784558 -25.814835) (xy 61.838558 -25.800797) (xy 61.894027 -25.794776)
			(xy 61.949782 -25.7969) (xy 62.004632 -25.807125) (xy 62.057407 -25.825231) (xy 62.106982 -25.850833)
			(xy 62.152297 -25.883383) (xy 62.192387 -25.922189) (xy 62.226396 -25.966421) (xy 62.253599 -26.015135)
			(xy 62.273414 -26.067293) (xy 62.285418 -26.121781) (xy 62.289357 -26.177437) (xy 62.285145 -26.233073)
			(xy 62.272873 -26.287501) (xy 62.252803 -26.339561) (xy 62.225362 -26.388142) (xy 62.191136 -26.432206)
			(xy 62.150856 -26.470815) (xy 62.1284 -26.487374) (xy 62.110642 -26.500536) (xy 62.079551 -26.531949)
			(xy 62.05437 -26.568272) (xy 62.035861 -26.608408) (xy 62.024583 -26.651142) (xy 62.020877 -26.695184)
			(xy 62.024855 -26.739203) (xy 62.036397 -26.781867) (xy 62.045342 -26.80208) (xy 62.056723 -26.827347)
			(xy 62.070492 -26.872946) (xy 62.554879 -26.872946) (xy 62.558829 -26.816459) (xy 62.570602 -26.761071)
			(xy 62.589969 -26.70786) (xy 62.616553 -26.657863) (xy 62.649837 -26.612052) (xy 62.689172 -26.571319)
			(xy 62.733793 -26.536457) (xy 62.782832 -26.508144) (xy 62.835334 -26.486932) (xy 62.890278 -26.473233)
			(xy 62.946593 -26.467314) (xy 63.003184 -26.46929) (xy 63.058949 -26.479123) (xy 63.112803 -26.496622)
			(xy 63.163698 -26.521444) (xy 63.210642 -26.553109) (xy 63.252723 -26.590999) (xy 63.289121 -26.634376)
			(xy 63.319128 -26.682397) (xy 63.34216 -26.734127) (xy 63.357768 -26.788559) (xy 63.365648 -26.844633)
			(xy 63.366142 -26.872946) (xy 63.365841 -26.890218) (xy 63.799464 -26.890218) (xy 63.803535 -26.834596)
			(xy 63.815661 -26.780159) (xy 63.835584 -26.728068) (xy 63.86288 -26.679433) (xy 63.896966 -26.63529)
			(xy 63.937115 -26.596581) (xy 63.982473 -26.56413) (xy 64.032073 -26.538629) (xy 64.084857 -26.520622)
			(xy 64.1397 -26.510492) (xy 64.195434 -26.508455) (xy 64.250871 -26.514555) (xy 64.304828 -26.528661)
			(xy 64.356157 -26.550473) (xy 64.403763 -26.579527) (xy 64.446631 -26.615202) (xy 64.483848 -26.656739)
			(xy 64.514621 -26.703252) (xy 64.538293 -26.753749) (xy 64.554361 -26.807156) (xy 64.562481 -26.862332)
			(xy 64.56299 -26.890218) (xy 64.562481 -26.918104) (xy 64.554361 -26.97328) (xy 64.538293 -27.026687)
			(xy 64.514621 -27.077184) (xy 64.483848 -27.123697) (xy 64.44953 -27.161998) (xy 66.286124 -27.161998)
			(xy 66.290195 -27.106376) (xy 66.302321 -27.051939) (xy 66.322244 -26.999848) (xy 66.34954 -26.951213)
			(xy 66.383626 -26.90707) (xy 66.423775 -26.868361) (xy 66.469133 -26.83591) (xy 66.518733 -26.810409)
			(xy 66.571517 -26.792402) (xy 66.62636 -26.782272) (xy 66.682094 -26.780235) (xy 66.737531 -26.786335)
			(xy 66.791488 -26.800441) (xy 66.842817 -26.822253) (xy 66.890423 -26.851307) (xy 66.933291 -26.886982)
			(xy 66.970508 -26.928519) (xy 67.001281 -26.975032) (xy 67.024953 -27.025529) (xy 67.041021 -27.078936)
			(xy 67.049141 -27.134112) (xy 67.04965 -27.161998) (xy 67.049141 -27.189884) (xy 67.041021 -27.24506)
			(xy 67.024953 -27.298467) (xy 67.001281 -27.348964) (xy 66.970508 -27.395477) (xy 66.933291 -27.437014)
			(xy 66.890423 -27.472689) (xy 66.870526 -27.484832) (xy 82.785202 -27.484832) (xy 82.789273 -27.42921)
			(xy 82.801399 -27.374773) (xy 82.821322 -27.322682) (xy 82.848618 -27.274047) (xy 82.882704 -27.229904)
			(xy 82.922853 -27.191195) (xy 82.968211 -27.158744) (xy 83.017811 -27.133243) (xy 83.070595 -27.115236)
			(xy 83.125438 -27.105106) (xy 83.181172 -27.103069) (xy 83.236609 -27.109169) (xy 83.290566 -27.123275)
			(xy 83.341895 -27.145087) (xy 83.389501 -27.174141) (xy 83.432369 -27.209816) (xy 83.469586 -27.251353)
			(xy 83.500359 -27.297866) (xy 83.524031 -27.348363) (xy 83.540099 -27.40177) (xy 83.548219 -27.456946)
			(xy 83.548728 -27.484832) (xy 83.548219 -27.512718) (xy 83.540099 -27.567894) (xy 83.524031 -27.621301)
			(xy 83.500359 -27.671798) (xy 83.469586 -27.718311) (xy 83.432369 -27.759848) (xy 83.389501 -27.795523)
			(xy 83.341895 -27.824577) (xy 83.290566 -27.846389) (xy 83.236609 -27.860495) (xy 83.181172 -27.866595)
			(xy 83.125438 -27.864558) (xy 83.070595 -27.854428) (xy 83.017811 -27.836421) (xy 82.968211 -27.81092)
			(xy 82.922853 -27.778469) (xy 82.882704 -27.73976) (xy 82.848618 -27.695617) (xy 82.821322 -27.646982)
			(xy 82.801399 -27.594891) (xy 82.789273 -27.540454) (xy 82.785202 -27.484832) (xy 66.870526 -27.484832)
			(xy 66.842817 -27.501743) (xy 66.791488 -27.523555) (xy 66.737531 -27.537661) (xy 66.682094 -27.543761)
			(xy 66.62636 -27.541724) (xy 66.571517 -27.531594) (xy 66.518733 -27.513587) (xy 66.469133 -27.488086)
			(xy 66.423775 -27.455635) (xy 66.383626 -27.416926) (xy 66.34954 -27.372783) (xy 66.322244 -27.324148)
			(xy 66.302321 -27.272057) (xy 66.290195 -27.21762) (xy 66.286124 -27.161998) (xy 64.44953 -27.161998)
			(xy 64.446631 -27.165234) (xy 64.403763 -27.200909) (xy 64.356157 -27.229963) (xy 64.304828 -27.251775)
			(xy 64.250871 -27.265881) (xy 64.195434 -27.271981) (xy 64.1397 -27.269944) (xy 64.084857 -27.259814)
			(xy 64.032073 -27.241807) (xy 63.982473 -27.216306) (xy 63.937115 -27.183855) (xy 63.896966 -27.145146)
			(xy 63.86288 -27.101003) (xy 63.835584 -27.052368) (xy 63.815661 -27.000277) (xy 63.803535 -26.94584)
			(xy 63.799464 -26.890218) (xy 63.365841 -26.890218) (xy 63.365648 -26.901259) (xy 63.357768 -26.957333)
			(xy 63.34216 -27.011765) (xy 63.319128 -27.063495) (xy 63.289121 -27.111516) (xy 63.252723 -27.154893)
			(xy 63.210642 -27.192783) (xy 63.163698 -27.224448) (xy 63.112803 -27.24927) (xy 63.058949 -27.266769)
			(xy 63.003184 -27.276602) (xy 62.946593 -27.278578) (xy 62.890278 -27.272659) (xy 62.835334 -27.25896)
			(xy 62.782832 -27.237748) (xy 62.733793 -27.209435) (xy 62.689172 -27.174573) (xy 62.649837 -27.13384)
			(xy 62.616553 -27.088029) (xy 62.589969 -27.038032) (xy 62.570602 -26.984821) (xy 62.558829 -26.929433)
			(xy 62.554879 -26.872946) (xy 62.070492 -26.872946) (xy 62.072742 -26.880399) (xy 62.080916 -26.935211)
			(xy 62.081073 -26.990629) (xy 62.07321 -27.045486) (xy 62.057492 -27.098628) (xy 62.034251 -27.148937)
			(xy 62.003976 -27.195353) (xy 61.967302 -27.236901) (xy 61.925004 -27.272705) (xy 61.877969 -27.302012)
			(xy 61.82719 -27.324206) (xy 61.773733 -27.338818) (xy 61.718725 -27.345543) (xy 61.691012 -27.345386)
			(xy 61.667953 -27.345389) (xy 61.622428 -27.352698) (xy 61.578967 -27.368094) (xy 61.538994 -27.391073)
			(xy 61.503818 -27.420881) (xy 61.474592 -27.456543) (xy 61.452274 -27.496889) (xy 61.437595 -27.540597)
			(xy 61.431036 -27.586236) (xy 61.431424 -27.609292) (xy 61.432037 -27.636914) (xy 61.426227 -27.691857)
			(xy 61.412554 -27.745388) (xy 61.391305 -27.796388) (xy 61.362924 -27.843791) (xy 61.328005 -27.886606)
			(xy 61.287276 -27.923938) (xy 61.24159 -27.955007) (xy 61.191901 -27.979163) (xy 61.139248 -27.995902)
			(xy 61.084732 -28.004873) (xy 61.029492 -28.00589) (xy 60.974683 -27.99893) (xy 60.92145 -27.984139)
			(xy 60.870906 -27.961827) (xy 60.824108 -27.93246) (xy 60.782033 -27.896652) (xy 60.745562 -27.85515)
			(xy 60.715456 -27.808824) (xy 60.692346 -27.75864) (xy 60.676713 -27.705648) (xy 60.668885 -27.650956)
			(xy 58.952678 -27.650956) (xy 58.945879 -27.678021) (xy 58.924572 -27.729531) (xy 58.895992 -27.777389)
			(xy 58.86075 -27.820577) (xy 58.819596 -27.858174) (xy 58.773407 -27.88938) (xy 58.723167 -27.913528)
			(xy 58.669946 -27.930104) (xy 58.614879 -27.938756) (xy 58.55914 -27.939299) (xy 58.503915 -27.931722)
			(xy 58.450381 -27.916185) (xy 58.39968 -27.89302) (xy 58.352892 -27.86272) (xy 58.311013 -27.825932)
			(xy 58.274937 -27.783439) (xy 58.245431 -27.736146) (xy 58.223124 -27.685061) (xy 58.208492 -27.631274)
			(xy 58.201847 -27.575929) (xy 56.031239 -27.575929) (xy 56.031384 -27.59202) (xy 56.03166 -27.619686)
			(xy 56.025304 -27.674644) (xy 56.011073 -27.728108) (xy 55.989267 -27.778953) (xy 55.960344 -27.826115)
			(xy 55.92491 -27.868604) (xy 55.883709 -27.905526) (xy 55.837606 -27.936109) (xy 55.787568 -27.959709)
			(xy 55.734645 -27.975832) (xy 55.679947 -27.98414) (xy 55.624624 -27.984457) (xy 55.569835 -27.976778)
			(xy 55.51673 -27.961263) (xy 55.466424 -27.938238) (xy 55.419973 -27.908187) (xy 55.378351 -27.871739)
			(xy 55.342432 -27.829661) (xy 55.312969 -27.782834) (xy 55.290582 -27.732241) (xy 55.275739 -27.678945)
			(xy 55.268752 -27.624064) (xy 53.765482 -27.624064) (xy 53.764441 -27.63114) (xy 53.748373 -27.684547)
			(xy 53.724701 -27.735044) (xy 53.693928 -27.781557) (xy 53.656711 -27.823094) (xy 53.613843 -27.858769)
			(xy 53.566237 -27.887823) (xy 53.514908 -27.909635) (xy 53.460951 -27.923741) (xy 53.405514 -27.929841)
			(xy 53.34978 -27.927804) (xy 53.294937 -27.917674) (xy 53.242153 -27.899667) (xy 53.192553 -27.874166)
			(xy 53.147195 -27.841715) (xy 53.107046 -27.803006) (xy 53.07296 -27.758863) (xy 53.045664 -27.710228)
			(xy 53.025741 -27.658137) (xy 53.013615 -27.6037) (xy 53.009544 -27.548078) (xy 51.792439 -27.548078)
			(xy 51.783379 -27.567404) (xy 51.752606 -27.613917) (xy 51.715389 -27.655454) (xy 51.672521 -27.691129)
			(xy 51.624915 -27.720183) (xy 51.573586 -27.741995) (xy 51.519629 -27.756101) (xy 51.464192 -27.762201)
			(xy 51.408458 -27.760164) (xy 51.353615 -27.750034) (xy 51.300831 -27.732027) (xy 51.251231 -27.706526)
			(xy 51.205873 -27.674075) (xy 51.165724 -27.635366) (xy 51.131638 -27.591223) (xy 51.104342 -27.542588)
			(xy 51.084419 -27.490497) (xy 51.072293 -27.43606) (xy 51.068222 -27.380438) (xy 49.981232 -27.380438)
			(xy 49.982604 -27.411556) (xy 49.992704 -27.456032) (xy 50.00117 -27.477212) (xy 50.011405 -27.502524)
			(xy 50.025433 -27.555287) (xy 50.031795 -27.609511) (xy 50.030362 -27.664089) (xy 50.021163 -27.717904)
			(xy 50.004386 -27.769859) (xy 49.980374 -27.818891) (xy 49.949616 -27.863999) (xy 49.912743 -27.904262)
			(xy 49.870506 -27.938856) (xy 49.823768 -27.967076) (xy 49.773485 -27.988344) (xy 49.720683 -28.002227)
			(xy 49.666442 -28.008441) (xy 49.611869 -28.006858) (xy 49.558079 -27.997512) (xy 49.50617 -27.980592)
			(xy 49.457204 -27.956446) (xy 49.412181 -27.925565) (xy 49.372019 -27.888581) (xy 49.337541 -27.846249)
			(xy 49.309449 -27.799434) (xy 49.288319 -27.749093) (xy 49.274581 -27.696254) (xy 49.268516 -27.641995)
			(xy 46.352705 -27.641995) (xy 46.352459 -27.655466) (xy 46.344339 -27.710642) (xy 46.328271 -27.764049)
			(xy 46.304599 -27.814546) (xy 46.273826 -27.861059) (xy 46.236609 -27.902596) (xy 46.193741 -27.938271)
			(xy 46.146135 -27.967325) (xy 46.094806 -27.989137) (xy 46.040849 -28.003243) (xy 45.985412 -28.009343)
			(xy 45.929678 -28.007306) (xy 45.874835 -27.997176) (xy 45.822051 -27.979169) (xy 45.772451 -27.953668)
			(xy 45.727093 -27.921217) (xy 45.686944 -27.882508) (xy 45.652858 -27.838365) (xy 45.625562 -27.78973)
			(xy 45.605639 -27.737639) (xy 45.593513 -27.683202) (xy 45.589442 -27.62758) (xy 41.031325 -27.62758)
			(xy 41.031668 -27.646376) (xy 41.031159 -27.674262) (xy 41.023039 -27.729438) (xy 41.006971 -27.782845)
			(xy 40.983299 -27.833342) (xy 40.952526 -27.879855) (xy 40.915309 -27.921392) (xy 40.872441 -27.957067)
			(xy 40.824835 -27.986121) (xy 40.773506 -28.007933) (xy 40.719549 -28.022039) (xy 40.664112 -28.028139)
			(xy 40.608378 -28.026102) (xy 40.553535 -28.015972) (xy 40.500751 -27.997965) (xy 40.451151 -27.972464)
			(xy 40.405793 -27.940013) (xy 40.365644 -27.901304) (xy 40.331558 -27.857161) (xy 40.304262 -27.808526)
			(xy 40.284339 -27.756435) (xy 40.272213 -27.701998) (xy 40.268142 -27.646376) (xy 31.9913 -27.646376)
			(xy 31.9913 -29.033978) (xy 62.979044 -29.033978) (xy 62.983115 -28.978356) (xy 62.995241 -28.923919)
			(xy 63.015164 -28.871828) (xy 63.04246 -28.823193) (xy 63.076546 -28.77905) (xy 63.116695 -28.740341)
			(xy 63.162053 -28.70789) (xy 63.211653 -28.682389) (xy 63.264437 -28.664382) (xy 63.31928 -28.654252)
			(xy 63.375014 -28.652215) (xy 63.430451 -28.658315) (xy 63.484408 -28.672421) (xy 63.535737 -28.694233)
			(xy 63.583343 -28.723287) (xy 63.626211 -28.758962) (xy 63.663428 -28.800499) (xy 63.694201 -28.847012)
			(xy 63.717873 -28.897509) (xy 63.733941 -28.950916) (xy 63.742061 -29.006092) (xy 63.74257 -29.033978)
			(xy 63.742061 -29.061864) (xy 63.733941 -29.11704) (xy 63.717873 -29.170447) (xy 63.694201 -29.220944)
			(xy 63.663428 -29.267457) (xy 63.626211 -29.308994) (xy 63.583343 -29.344669) (xy 63.535737 -29.373723)
			(xy 63.484408 -29.395535) (xy 63.430451 -29.409641) (xy 63.375014 -29.415741) (xy 63.31928 -29.413704)
			(xy 63.264437 -29.403574) (xy 63.211653 -29.385567) (xy 63.162053 -29.360066) (xy 63.116695 -29.327615)
			(xy 63.076546 -29.288906) (xy 63.04246 -29.244763) (xy 63.015164 -29.196128) (xy 62.995241 -29.144037)
			(xy 62.983115 -29.0896) (xy 62.979044 -29.033978) (xy 31.9913 -29.033978) (xy 31.9913 -32.463986)
			(xy 39.163339 -32.463986) (xy 39.166784 -32.362508) (xy 39.178319 -32.261629) (xy 39.197871 -32.161994)
			(xy 39.225313 -32.064236) (xy 39.260472 -31.968982) (xy 39.303123 -31.876838) (xy 39.352993 -31.788393)
			(xy 39.409764 -31.704211) (xy 39.473075 -31.62483) (xy 39.54252 -31.550755) (xy 39.617656 -31.482461)
			(xy 39.698005 -31.420383) (xy 39.783052 -31.364917) (xy 39.872256 -31.316418) (xy 39.965047 -31.275194)
			(xy 40.060833 -31.241508) (xy 40.159002 -31.215577) (xy 40.258927 -31.197565) (xy 40.359972 -31.187587)
			(xy 40.461491 -31.185708) (xy 40.562835 -31.191938) (xy 40.663359 -31.206239) (xy 40.762421 -31.228518)
			(xy 40.859388 -31.258635) (xy 40.9067 -31.277052) (xy 40.921853 -31.282616) (xy 40.953858 -31.286737)
			(xy 40.985872 -31.282687) (xy 41.015842 -31.270726) (xy 41.029128 -31.261558) (xy 41.071951 -31.230775)
			(xy 41.161856 -31.175627) (xy 41.256027 -31.128127) (xy 41.353812 -31.088601) (xy 41.45454 -31.057323)
			(xy 41.557515 -31.034509) (xy 41.662027 -31.020314) (xy 41.767357 -31.014838) (xy 41.820084 -31.01594)
			(xy 41.84304 -31.016122) (xy 41.88843 -31.009303) (xy 41.931856 -30.994438) (xy 41.971903 -30.97201)
			(xy 42.007268 -30.94275) (xy 42.036799 -30.907611) (xy 42.059533 -30.867738) (xy 42.074732 -30.824427)
			(xy 42.0819 -30.77909) (xy 42.080803 -30.733204) (xy 42.076624 -30.710632) (xy 42.071512 -30.683495)
			(xy 42.068217 -30.628375) (xy 42.072903 -30.573355) (xy 42.085472 -30.519586) (xy 42.105662 -30.468191)
			(xy 42.13305 -30.420243) (xy 42.167065 -30.376745) (xy 42.206996 -30.338605) (xy 42.252008 -30.30662)
			(xy 42.301161 -30.281459) (xy 42.353428 -30.263647) (xy 42.407717 -30.253556) (xy 42.462893 -30.251397)
			(xy 42.517805 -30.257216) (xy 42.571304 -30.27089) (xy 42.622272 -30.292134) (xy 42.669645 -30.320505)
			(xy 42.712434 -30.355409) (xy 42.749743 -30.396117) (xy 42.780794 -30.441778) (xy 42.804937 -30.491439)
			(xy 42.821669 -30.544062) (xy 42.830639 -30.598547) (xy 42.83166 -30.653756) (xy 42.824712 -30.708536)
			(xy 42.817796 -30.73527) (xy 42.81217 -30.75749) (xy 42.808091 -30.803139) (xy 42.812255 -30.848781)
			(xy 42.824529 -30.892938) (xy 42.844514 -30.934183) (xy 42.871564 -30.97118) (xy 42.904804 -31.002733)
			(xy 42.923714 -31.015686) (xy 42.94595 -31.030798) (xy 42.986394 -31.066216) (xy 43.021465 -31.106962)
			(xy 43.05047 -31.152226) (xy 43.072834 -31.201114) (xy 43.088114 -31.252658) (xy 43.096007 -31.305836)
			(xy 43.096025 -31.30862) (xy 43.604092 -31.30862) (xy 43.611737 -31.254738) (xy 43.626963 -31.20249)
			(xy 43.64946 -31.152937) (xy 43.678772 -31.107084) (xy 43.714303 -31.065863) (xy 43.755332 -31.030109)
			(xy 43.777916 -31.014924) (xy 43.797134 -31.001898) (xy 43.830849 -30.969985) (xy 43.858216 -30.932486)
			(xy 43.878328 -30.890646) (xy 43.890517 -30.845851) (xy 43.89438 -30.799589) (xy 43.889788 -30.753393)
			(xy 43.883834 -30.730952) (xy 43.876433 -30.703943) (xy 43.868848 -30.648456) (xy 43.869457 -30.592457)
			(xy 43.878247 -30.537148) (xy 43.89503 -30.483719) (xy 43.919444 -30.433318) (xy 43.950965 -30.387029)
			(xy 43.988915 -30.345845) (xy 44.032478 -30.310653) (xy 44.08072 -30.282208) (xy 44.132601 -30.261122)
			(xy 44.187008 -30.247849) (xy 44.242771 -30.242673) (xy 44.298692 -30.245706) (xy 44.353568 -30.256882)
			(xy 44.40622 -30.275962) (xy 44.455517 -30.302535) (xy 44.500399 -30.33603) (xy 44.539901 -30.375727)
			(xy 44.556934 -30.397958) (xy 44.570703 -30.415812) (xy 44.603482 -30.446764) (xy 44.641205 -30.471453)
			(xy 44.682689 -30.489106) (xy 44.726635 -30.499169) (xy 44.771667 -30.501328) (xy 44.816374 -30.495514)
			(xy 44.859356 -30.481911) (xy 44.899267 -30.460943) (xy 44.91736 -30.447488) (xy 44.939261 -30.43102)
			(xy 44.98686 -30.403875) (xy 45.037854 -30.38382) (xy 45.091192 -30.371267) (xy 45.145777 -30.366476)
			(xy 45.200486 -30.369544) (xy 45.254194 -30.380408) (xy 45.305794 -30.398846) (xy 45.354225 -30.424477)
			(xy 45.398491 -30.456774) (xy 45.43768 -30.495072) (xy 45.470985 -30.538583) (xy 45.497723 -30.586413)
			(xy 45.517341 -30.637576) (xy 45.529437 -30.691019) (xy 45.533762 -30.745643) (xy 45.531197 -30.785308)
			(xy 47.047402 -30.785308) (xy 47.051473 -30.729686) (xy 47.063599 -30.675249) (xy 47.083522 -30.623158)
			(xy 47.110818 -30.574523) (xy 47.144904 -30.53038) (xy 47.185053 -30.491671) (xy 47.230411 -30.45922)
			(xy 47.280011 -30.433719) (xy 47.332795 -30.415712) (xy 47.387638 -30.405582) (xy 47.443372 -30.403545)
			(xy 47.498809 -30.409645) (xy 47.552766 -30.423751) (xy 47.604095 -30.445563) (xy 47.651701 -30.474617)
			(xy 47.694569 -30.510292) (xy 47.731786 -30.551829) (xy 47.762559 -30.598342) (xy 47.786231 -30.648839)
			(xy 47.802299 -30.702246) (xy 47.810419 -30.757422) (xy 47.810928 -30.785308) (xy 47.810419 -30.813194)
			(xy 47.802299 -30.86837) (xy 47.786231 -30.921777) (xy 47.762559 -30.972274) (xy 47.731786 -31.018787)
			(xy 47.694569 -31.060324) (xy 47.651701 -31.095999) (xy 47.604095 -31.125053) (xy 47.574896 -31.137461)
			(xy 49.011767 -31.137461) (xy 49.017173 -31.083285) (xy 49.030225 -31.030428) (xy 49.05066 -30.979963)
			(xy 49.078062 -30.932916) (xy 49.111874 -30.890243) (xy 49.151409 -30.852811) (xy 49.195864 -30.821379)
			(xy 49.244337 -30.796587) (xy 49.295842 -30.778938) (xy 49.349333 -30.76879) (xy 49.403723 -30.766351)
			(xy 49.457908 -30.771669) (xy 49.510786 -30.784636) (xy 49.553416 -30.801818) (xy 53.116224 -30.801818)
			(xy 53.120295 -30.746196) (xy 53.132421 -30.691759) (xy 53.152344 -30.639668) (xy 53.17964 -30.591033)
			(xy 53.213726 -30.54689) (xy 53.253875 -30.508181) (xy 53.299233 -30.47573) (xy 53.348833 -30.450229)
			(xy 53.401617 -30.432222) (xy 53.45646 -30.422092) (xy 53.512194 -30.420055) (xy 53.567631 -30.426155)
			(xy 53.621588 -30.440261) (xy 53.672917 -30.462073) (xy 53.720523 -30.491127) (xy 53.763391 -30.526802)
			(xy 53.800608 -30.568339) (xy 53.831381 -30.614852) (xy 53.855053 -30.665349) (xy 53.871121 -30.718756)
			(xy 53.879241 -30.773932) (xy 53.87975 -30.801818) (xy 53.879241 -30.829704) (xy 53.871121 -30.88488)
			(xy 53.855053 -30.938287) (xy 53.831381 -30.988784) (xy 53.830723 -30.989778) (xy 57.203084 -30.989778)
			(xy 57.207155 -30.934156) (xy 57.219281 -30.879719) (xy 57.239204 -30.827628) (xy 57.2665 -30.778993)
			(xy 57.300586 -30.73485) (xy 57.340735 -30.696141) (xy 57.386093 -30.66369) (xy 57.435693 -30.638189)
			(xy 57.488477 -30.620182) (xy 57.54332 -30.610052) (xy 57.599054 -30.608015) (xy 57.654491 -30.614115)
			(xy 57.708448 -30.628221) (xy 57.759777 -30.650033) (xy 57.807383 -30.679087) (xy 57.850251 -30.714762)
			(xy 57.887468 -30.756299) (xy 57.918241 -30.802812) (xy 57.941913 -30.853309) (xy 57.957981 -30.906716)
			(xy 57.960299 -30.922468) (xy 58.868054 -30.922468) (xy 58.872125 -30.866846) (xy 58.884251 -30.812409)
			(xy 58.904174 -30.760318) (xy 58.93147 -30.711683) (xy 58.965556 -30.66754) (xy 59.005705 -30.628831)
			(xy 59.051063 -30.59638) (xy 59.100663 -30.570879) (xy 59.153447 -30.552872) (xy 59.20829 -30.542742)
			(xy 59.264024 -30.540705) (xy 59.319461 -30.546805) (xy 59.373418 -30.560911) (xy 59.424747 -30.582723)
			(xy 59.472353 -30.611777) (xy 59.515221 -30.647452) (xy 59.552438 -30.688989) (xy 59.583211 -30.735502)
			(xy 59.606883 -30.785999) (xy 59.622951 -30.839406) (xy 59.631071 -30.894582) (xy 59.63158 -30.922468)
			(xy 59.631071 -30.950354) (xy 59.622951 -31.00553) (xy 59.606883 -31.058937) (xy 59.583211 -31.109434)
			(xy 59.552438 -31.155947) (xy 59.515221 -31.197484) (xy 59.472353 -31.233159) (xy 59.424747 -31.262213)
			(xy 59.373418 -31.284025) (xy 59.319461 -31.298131) (xy 59.264024 -31.304231) (xy 59.20829 -31.302194)
			(xy 59.153447 -31.292064) (xy 59.100663 -31.274057) (xy 59.051063 -31.248556) (xy 59.005705 -31.216105)
			(xy 58.965556 -31.177396) (xy 58.93147 -31.133253) (xy 58.904174 -31.084618) (xy 58.884251 -31.032527)
			(xy 58.872125 -30.97809) (xy 58.868054 -30.922468) (xy 57.960299 -30.922468) (xy 57.966101 -30.961892)
			(xy 57.96661 -30.989778) (xy 57.966101 -31.017664) (xy 57.957981 -31.07284) (xy 57.941913 -31.126247)
			(xy 57.918241 -31.176744) (xy 57.887468 -31.223257) (xy 57.850251 -31.264794) (xy 57.807383 -31.300469)
			(xy 57.759777 -31.329523) (xy 57.708448 -31.351335) (xy 57.654491 -31.365441) (xy 57.599054 -31.371541)
			(xy 57.54332 -31.369504) (xy 57.488477 -31.359374) (xy 57.435693 -31.341367) (xy 57.386093 -31.315866)
			(xy 57.340735 -31.283415) (xy 57.300586 -31.244706) (xy 57.2665 -31.200563) (xy 57.239204 -31.151928)
			(xy 57.219281 -31.099837) (xy 57.207155 -31.0454) (xy 57.203084 -30.989778) (xy 53.830723 -30.989778)
			(xy 53.800608 -31.035297) (xy 53.763391 -31.076834) (xy 53.720523 -31.112509) (xy 53.672917 -31.141563)
			(xy 53.621588 -31.163375) (xy 53.567631 -31.177481) (xy 53.512194 -31.183581) (xy 53.45646 -31.181544)
			(xy 53.401617 -31.171414) (xy 53.348833 -31.153407) (xy 53.299233 -31.127906) (xy 53.253875 -31.095455)
			(xy 53.213726 -31.056746) (xy 53.17964 -31.012603) (xy 53.152344 -30.963968) (xy 53.132421 -30.911877)
			(xy 53.120295 -30.85744) (xy 53.116224 -30.801818) (xy 49.553416 -30.801818) (xy 49.561283 -30.804989)
			(xy 49.608374 -30.832315) (xy 49.651102 -30.866058) (xy 49.688598 -30.905533) (xy 49.720102 -30.949937)
			(xy 49.744972 -30.99837) (xy 49.762704 -31.049846) (xy 49.772938 -31.103321) (xy 49.775465 -31.157707)
			(xy 49.773332 -31.18485) (xy 49.771625 -31.208027) (xy 49.775684 -31.254319) (xy 49.788081 -31.299104)
			(xy 49.808403 -31.340894) (xy 49.835975 -31.3783) (xy 49.86988 -31.410078) (xy 49.899446 -31.429048)
			(xy 65.411612 -31.429048) (xy 65.415154 -31.374749) (xy 65.426375 -31.321504) (xy 65.445048 -31.270394)
			(xy 65.470793 -31.222455) (xy 65.503089 -31.178661) (xy 65.52184 -31.158942) (xy 65.537772 -31.1421)
			(xy 65.563752 -31.103706) (xy 65.582334 -31.061235) (xy 65.592903 -31.016098) (xy 65.595106 -30.969793)
			(xy 65.588872 -30.923856) (xy 65.574407 -30.879812) (xy 65.56375 -30.859222) (xy 65.551066 -30.835147)
			(xy 65.532021 -30.78417) (xy 65.520412 -30.731004) (xy 65.516475 -30.676728) (xy 65.520291 -30.622444)
			(xy 65.53178 -30.569252) (xy 65.55071 -30.518233) (xy 65.576698 -30.47042) (xy 65.609215 -30.426786)
			(xy 65.647603 -30.388214) (xy 65.691081 -30.355488) (xy 65.738768 -30.329272) (xy 65.789696 -30.310097)
			(xy 65.842832 -30.298353) (xy 65.897098 -30.294278) (xy 65.951392 -30.297954) (xy 66.004613 -30.309308)
			(xy 66.05568 -30.328109) (xy 66.103558 -30.353974) (xy 66.147276 -30.38638) (xy 66.185945 -30.424669)
			(xy 66.218782 -30.468064) (xy 66.24512 -30.515684) (xy 66.264424 -30.566563) (xy 66.276304 -30.619669)
			(xy 66.280517 -30.673924) (xy 66.276979 -30.728227) (xy 66.265761 -30.781477) (xy 66.247091 -30.832592)
			(xy 66.221348 -30.880536) (xy 66.189053 -30.924336) (xy 66.170302 -30.944058) (xy 66.156131 -30.959044)
			(xy 66.922902 -30.959044) (xy 66.926973 -30.903422) (xy 66.939099 -30.848985) (xy 66.959022 -30.796894)
			(xy 66.986318 -30.748259) (xy 67.020404 -30.704116) (xy 67.060553 -30.665407) (xy 67.105911 -30.632956)
			(xy 67.155511 -30.607455) (xy 67.208295 -30.589448) (xy 67.263138 -30.579318) (xy 67.318872 -30.577281)
			(xy 67.374309 -30.583381) (xy 67.428266 -30.597487) (xy 67.479595 -30.619299) (xy 67.527201 -30.648353)
			(xy 67.570069 -30.684028) (xy 67.607286 -30.725565) (xy 67.638059 -30.772078) (xy 67.661731 -30.822575)
			(xy 67.677799 -30.875982) (xy 67.681126 -30.898592) (xy 67.946522 -30.898592) (xy 67.950593 -30.84297)
			(xy 67.962719 -30.788533) (xy 67.982642 -30.736442) (xy 68.009938 -30.687807) (xy 68.044024 -30.643664)
			(xy 68.084173 -30.604955) (xy 68.129531 -30.572504) (xy 68.179131 -30.547003) (xy 68.231915 -30.528996)
			(xy 68.286758 -30.518866) (xy 68.342492 -30.516829) (xy 68.397929 -30.522929) (xy 68.451886 -30.537035)
			(xy 68.503215 -30.558847) (xy 68.550821 -30.587901) (xy 68.593689 -30.623576) (xy 68.630906 -30.665113)
			(xy 68.661679 -30.711626) (xy 68.685351 -30.762123) (xy 68.701419 -30.81553) (xy 68.709539 -30.870706)
			(xy 68.710048 -30.898592) (xy 68.709539 -30.926478) (xy 68.701419 -30.981654) (xy 68.685351 -31.035061)
			(xy 68.672048 -31.063438) (xy 84.061044 -31.063438) (xy 84.065115 -31.007816) (xy 84.077241 -30.953379)
			(xy 84.097164 -30.901288) (xy 84.12446 -30.852653) (xy 84.158546 -30.80851) (xy 84.198695 -30.769801)
			(xy 84.244053 -30.73735) (xy 84.293653 -30.711849) (xy 84.346437 -30.693842) (xy 84.40128 -30.683712)
			(xy 84.457014 -30.681675) (xy 84.512451 -30.687775) (xy 84.566408 -30.701881) (xy 84.617737 -30.723693)
			(xy 84.665343 -30.752747) (xy 84.708211 -30.788422) (xy 84.745428 -30.829959) (xy 84.776201 -30.876472)
			(xy 84.799873 -30.926969) (xy 84.815941 -30.980376) (xy 84.824061 -31.035552) (xy 84.82457 -31.063438)
			(xy 84.824061 -31.091324) (xy 84.815941 -31.1465) (xy 84.799873 -31.199907) (xy 84.776201 -31.250404)
			(xy 84.745428 -31.296917) (xy 84.708211 -31.338454) (xy 84.665343 -31.374129) (xy 84.617737 -31.403183)
			(xy 84.566408 -31.424995) (xy 84.512451 -31.439101) (xy 84.457014 -31.445201) (xy 84.40128 -31.443164)
			(xy 84.346437 -31.433034) (xy 84.293653 -31.415027) (xy 84.244053 -31.389526) (xy 84.198695 -31.357075)
			(xy 84.158546 -31.318366) (xy 84.12446 -31.274223) (xy 84.097164 -31.225588) (xy 84.077241 -31.173497)
			(xy 84.065115 -31.11906) (xy 84.061044 -31.063438) (xy 68.672048 -31.063438) (xy 68.661679 -31.085558)
			(xy 68.630906 -31.132071) (xy 68.593689 -31.173608) (xy 68.550821 -31.209283) (xy 68.503215 -31.238337)
			(xy 68.451886 -31.260149) (xy 68.397929 -31.274255) (xy 68.342492 -31.280355) (xy 68.286758 -31.278318)
			(xy 68.231915 -31.268188) (xy 68.179131 -31.250181) (xy 68.129531 -31.22468) (xy 68.084173 -31.192229)
			(xy 68.044024 -31.15352) (xy 68.009938 -31.109377) (xy 67.982642 -31.060742) (xy 67.962719 -31.008651)
			(xy 67.950593 -30.954214) (xy 67.946522 -30.898592) (xy 67.681126 -30.898592) (xy 67.685919 -30.931158)
			(xy 67.686428 -30.959044) (xy 67.685919 -30.98693) (xy 67.677799 -31.042106) (xy 67.661731 -31.095513)
			(xy 67.638059 -31.14601) (xy 67.607286 -31.192523) (xy 67.570069 -31.23406) (xy 67.527201 -31.269735)
			(xy 67.479595 -31.298789) (xy 67.428266 -31.320601) (xy 67.374309 -31.334707) (xy 67.318872 -31.340807)
			(xy 67.263138 -31.33877) (xy 67.208295 -31.32864) (xy 67.155511 -31.310633) (xy 67.105911 -31.285132)
			(xy 67.060553 -31.252681) (xy 67.020404 -31.213972) (xy 66.986318 -31.169829) (xy 66.959022 -31.121194)
			(xy 66.939099 -31.069103) (xy 66.926973 -31.014666) (xy 66.922902 -30.959044) (xy 66.156131 -30.959044)
			(xy 66.154373 -30.960903) (xy 66.12839 -30.999295) (xy 66.109805 -31.041765) (xy 66.099235 -31.086902)
			(xy 66.097031 -31.133208) (xy 66.103266 -31.179145) (xy 66.117734 -31.223188) (xy 66.128392 -31.243778)
			(xy 66.141016 -31.267884) (xy 66.160056 -31.318858) (xy 66.171661 -31.372021) (xy 66.175595 -31.426293)
			(xy 66.171777 -31.480573) (xy 66.160285 -31.53376) (xy 66.141353 -31.584775) (xy 66.115365 -31.632582)
			(xy 66.082847 -31.676212) (xy 66.04446 -31.714778) (xy 66.000983 -31.747499) (xy 65.953298 -31.773711)
			(xy 65.902372 -31.792881) (xy 65.849239 -31.804621) (xy 65.794978 -31.808692) (xy 65.740688 -31.805013)
			(xy 65.687472 -31.793656) (xy 65.636409 -31.774854) (xy 65.588536 -31.748987) (xy 65.544824 -31.71658)
			(xy 65.50616 -31.678292) (xy 65.473329 -31.634898) (xy 65.446996 -31.587279) (xy 65.427696 -31.536402)
			(xy 65.415822 -31.4833) (xy 65.411612 -31.429048) (xy 49.899446 -31.429048) (xy 49.908991 -31.435172)
			(xy 49.930304 -31.444438) (xy 49.955313 -31.455193) (xy 50.002305 -31.482672) (xy 50.044913 -31.516552)
			(xy 50.082271 -31.556145) (xy 50.113622 -31.600648) (xy 50.138327 -31.649155) (xy 50.155886 -31.700682)
			(xy 50.16594 -31.754182) (xy 50.168287 -31.808567) (xy 50.162879 -31.862734) (xy 50.149825 -31.915582)
			(xy 50.134383 -31.953708) (xy 57.565034 -31.953708) (xy 57.569105 -31.898086) (xy 57.581231 -31.843649)
			(xy 57.601154 -31.791558) (xy 57.62845 -31.742923) (xy 57.662536 -31.69878) (xy 57.702685 -31.660071)
			(xy 57.748043 -31.62762) (xy 57.797643 -31.602119) (xy 57.850427 -31.584112) (xy 57.90527 -31.573982)
			(xy 57.961004 -31.571945) (xy 58.016441 -31.578045) (xy 58.070398 -31.592151) (xy 58.121727 -31.613963)
			(xy 58.169333 -31.643017) (xy 58.212201 -31.678692) (xy 58.249418 -31.720229) (xy 58.280191 -31.766742)
			(xy 58.303863 -31.817239) (xy 58.319931 -31.870646) (xy 58.328051 -31.925822) (xy 58.32856 -31.953708)
			(xy 58.835034 -31.953708) (xy 58.839105 -31.898086) (xy 58.851231 -31.843649) (xy 58.871154 -31.791558)
			(xy 58.89845 -31.742923) (xy 58.932536 -31.69878) (xy 58.972685 -31.660071) (xy 59.018043 -31.62762)
			(xy 59.067643 -31.602119) (xy 59.120427 -31.584112) (xy 59.17527 -31.573982) (xy 59.231004 -31.571945)
			(xy 59.286441 -31.578045) (xy 59.340398 -31.592151) (xy 59.391727 -31.613963) (xy 59.439333 -31.643017)
			(xy 59.482201 -31.678692) (xy 59.519418 -31.720229) (xy 59.550191 -31.766742) (xy 59.573863 -31.817239)
			(xy 59.589931 -31.870646) (xy 59.598051 -31.925822) (xy 59.59856 -31.953708) (xy 59.598051 -31.981594)
			(xy 59.589931 -32.03677) (xy 59.573863 -32.090177) (xy 59.550191 -32.140674) (xy 59.519418 -32.187187)
			(xy 59.482201 -32.228724) (xy 59.439333 -32.264399) (xy 59.391727 -32.293453) (xy 59.340398 -32.315265)
			(xy 59.286441 -32.329371) (xy 59.231004 -32.335471) (xy 59.17527 -32.333434) (xy 59.120427 -32.323304)
			(xy 59.067643 -32.305297) (xy 59.018043 -32.279796) (xy 58.972685 -32.247345) (xy 58.932536 -32.208636)
			(xy 58.89845 -32.164493) (xy 58.871154 -32.115858) (xy 58.851231 -32.063767) (xy 58.839105 -32.00933)
			(xy 58.835034 -31.953708) (xy 58.32856 -31.953708) (xy 58.328051 -31.981594) (xy 58.319931 -32.03677)
			(xy 58.303863 -32.090177) (xy 58.280191 -32.140674) (xy 58.249418 -32.187187) (xy 58.212201 -32.228724)
			(xy 58.169333 -32.264399) (xy 58.121727 -32.293453) (xy 58.070398 -32.315265) (xy 58.016441 -32.329371)
			(xy 57.961004 -32.335471) (xy 57.90527 -32.333434) (xy 57.850427 -32.323304) (xy 57.797643 -32.305297)
			(xy 57.748043 -32.279796) (xy 57.702685 -32.247345) (xy 57.662536 -32.208636) (xy 57.62845 -32.164493)
			(xy 57.601154 -32.115858) (xy 57.581231 -32.063767) (xy 57.569105 -32.00933) (xy 57.565034 -31.953708)
			(xy 50.134383 -31.953708) (xy 50.12939 -31.966037) (xy 50.10199 -32.013075) (xy 50.068182 -32.05574)
			(xy 50.028651 -32.093165) (xy 49.984201 -32.12459) (xy 49.935735 -32.149377) (xy 49.884238 -32.167022)
			(xy 49.830755 -32.177167) (xy 49.776374 -32.179605) (xy 49.722198 -32.174287) (xy 49.669328 -32.161322)
			(xy 49.618838 -32.140972) (xy 49.571755 -32.113651) (xy 49.529033 -32.079914) (xy 49.491542 -32.040446)
			(xy 49.460042 -31.99605) (xy 49.435174 -31.947626) (xy 49.417443 -31.896158) (xy 49.407208 -31.842692)
			(xy 49.404679 -31.788315) (xy 49.40681 -31.761176) (xy 49.408467 -31.737997) (xy 49.404412 -31.69171)
			(xy 49.392022 -31.646928) (xy 49.371708 -31.605141) (xy 49.344145 -31.567735) (xy 49.310249 -31.535955)
			(xy 49.271147 -31.510857) (xy 49.249838 -31.501588) (xy 49.22481 -31.490868) (xy 49.177808 -31.463391)
			(xy 49.135189 -31.42951) (xy 49.09782 -31.389914) (xy 49.06646 -31.345408) (xy 49.041746 -31.296895)
			(xy 49.02418 -31.245362) (xy 49.014119 -31.191855) (xy 49.011767 -31.137461) (xy 47.574896 -31.137461)
			(xy 47.552766 -31.146865) (xy 47.498809 -31.160971) (xy 47.443372 -31.167071) (xy 47.387638 -31.165034)
			(xy 47.332795 -31.154904) (xy 47.280011 -31.136897) (xy 47.230411 -31.111396) (xy 47.185053 -31.078945)
			(xy 47.144904 -31.040236) (xy 47.110818 -30.996093) (xy 47.083522 -30.947458) (xy 47.063599 -30.895367)
			(xy 47.051473 -30.84093) (xy 47.047402 -30.785308) (xy 45.531197 -30.785308) (xy 45.530226 -30.800325)
			(xy 45.518903 -30.853937) (xy 45.500025 -30.905378) (xy 45.47398 -30.953588) (xy 45.441306 -30.997576)
			(xy 45.402674 -31.036436) (xy 45.358879 -31.069368) (xy 45.310823 -31.095695) (xy 45.259494 -31.114876)
			(xy 45.205949 -31.126514) (xy 45.15129 -31.130371) (xy 45.096641 -31.126368) (xy 45.043127 -31.114587)
			(xy 44.99185 -31.095269) (xy 44.943864 -31.068814) (xy 44.900158 -31.035765) (xy 44.861629 -30.996802)
			(xy 44.84497 -30.975046) (xy 44.831196 -30.957196) (xy 44.798418 -30.926243) (xy 44.760696 -30.901554)
			(xy 44.719213 -30.8839) (xy 44.675267 -30.873837) (xy 44.630236 -30.871677) (xy 44.585529 -30.877491)
			(xy 44.542547 -30.891094) (xy 44.502637 -30.912062) (xy 44.484544 -30.925516) (xy 44.457366 -30.94482)
			(xy 44.43818 -30.957889) (xy 44.404466 -30.989795) (xy 44.377099 -31.027286) (xy 44.356984 -31.069119)
			(xy 44.344789 -31.113906) (xy 44.340918 -31.160162) (xy 44.3455 -31.206352) (xy 44.351448 -31.228792)
			(xy 44.358534 -31.255069) (xy 44.366132 -31.308957) (xy 44.365993 -31.363378) (xy 44.358122 -31.417227)
			(xy 44.342677 -31.46941) (xy 44.319972 -31.518869) (xy 44.290469 -31.564599) (xy 44.254765 -31.605671)
			(xy 44.213587 -31.641252) (xy 44.167769 -31.670619) (xy 44.118243 -31.693176) (xy 44.066014 -31.708465)
			(xy 44.012142 -31.716176) (xy 43.957721 -31.716152) (xy 43.903855 -31.708393) (xy 43.85164 -31.693058)
			(xy 43.802134 -31.670457) (xy 43.756342 -31.641049) (xy 43.715195 -31.605432) (xy 43.679528 -31.564328)
			(xy 43.650065 -31.518572) (xy 43.627404 -31.469094) (xy 43.612006 -31.416896) (xy 43.604182 -31.363041)
			(xy 43.604092 -31.30862) (xy 43.096025 -31.30862) (xy 43.096357 -31.359595) (xy 43.089158 -31.412871)
			(xy 43.074552 -31.464609) (xy 43.052827 -31.513785) (xy 43.024415 -31.559424) (xy 42.989878 -31.600623)
			(xy 42.970196 -31.618936) (xy 42.958637 -31.630024) (xy 42.940952 -31.656719) (xy 42.93048 -31.686978)
			(xy 42.92788 -31.718893) (xy 42.933318 -31.750448) (xy 42.939462 -31.76524) (xy 42.959562 -31.811325)
			(xy 42.993378 -31.906018) (xy 43.019603 -32.003088) (xy 43.038073 -32.101926) (xy 43.048672 -32.201916)
			(xy 43.051334 -32.30243) (xy 43.046043 -32.402841) (xy 43.032831 -32.502519) (xy 43.011781 -32.600841)
			(xy 42.983943 -32.694118) (xy 83.840064 -32.694118) (xy 83.844135 -32.638496) (xy 83.856261 -32.584059)
			(xy 83.876184 -32.531968) (xy 83.90348 -32.483333) (xy 83.937566 -32.43919) (xy 83.977715 -32.400481)
			(xy 84.023073 -32.36803) (xy 84.072673 -32.342529) (xy 84.125457 -32.324522) (xy 84.1803 -32.314392)
			(xy 84.236034 -32.312355) (xy 84.291471 -32.318455) (xy 84.345428 -32.332561) (xy 84.396757 -32.354373)
			(xy 84.444363 -32.383427) (xy 84.487231 -32.419102) (xy 84.524448 -32.460639) (xy 84.555221 -32.507152)
			(xy 84.578893 -32.557649) (xy 84.594961 -32.611056) (xy 84.603081 -32.666232) (xy 84.60359 -32.694118)
			(xy 84.603081 -32.722004) (xy 84.594961 -32.77718) (xy 84.578893 -32.830587) (xy 84.555221 -32.881084)
			(xy 84.524448 -32.927597) (xy 84.487231 -32.969134) (xy 84.444363 -33.004809) (xy 84.396757 -33.033863)
			(xy 84.345428 -33.055675) (xy 84.291471 -33.069781) (xy 84.236034 -33.075881) (xy 84.1803 -33.073844)
			(xy 84.125457 -33.063714) (xy 84.072673 -33.045707) (xy 84.023073 -33.020206) (xy 83.977715 -32.987755)
			(xy 83.937566 -32.949046) (xy 83.90348 -32.904903) (xy 83.876184 -32.856268) (xy 83.856261 -32.804177)
			(xy 83.844135 -32.74974) (xy 83.840064 -32.694118) (xy 42.983943 -32.694118) (xy 42.983026 -32.697191)
			(xy 42.946744 -32.790966) (xy 42.903163 -32.881581) (xy 42.852555 -32.968467) (xy 42.795238 -33.05108)
			(xy 42.746481 -33.110678) (xy 74.261724 -33.110678) (xy 74.265795 -33.055056) (xy 74.277921 -33.000619)
			(xy 74.297844 -32.948528) (xy 74.32514 -32.899893) (xy 74.359226 -32.85575) (xy 74.399375 -32.817041)
			(xy 74.444733 -32.78459) (xy 74.494333 -32.759089) (xy 74.547117 -32.741082) (xy 74.60196 -32.730952)
			(xy 74.657694 -32.728915) (xy 74.713131 -32.735015) (xy 74.767088 -32.749121) (xy 74.818417 -32.770933)
			(xy 74.866023 -32.799987) (xy 74.908891 -32.835662) (xy 74.946108 -32.877199) (xy 74.976881 -32.923712)
			(xy 75.000553 -32.974209) (xy 75.016621 -33.027616) (xy 75.024741 -33.082792) (xy 75.02525 -33.110678)
			(xy 75.024741 -33.138564) (xy 75.016621 -33.19374) (xy 75.000553 -33.247147) (xy 74.976881 -33.297644)
			(xy 74.946108 -33.344157) (xy 74.908891 -33.385694) (xy 74.866023 -33.421369) (xy 74.818417 -33.450423)
			(xy 74.767088 -33.472235) (xy 74.713131 -33.486341) (xy 74.657694 -33.492441) (xy 74.60196 -33.490404)
			(xy 74.547117 -33.480274) (xy 74.494333 -33.462267) (xy 74.444733 -33.436766) (xy 74.399375 -33.404315)
			(xy 74.359226 -33.365606) (xy 74.32514 -33.321463) (xy 74.297844 -33.272828) (xy 74.277921 -33.220737)
			(xy 74.265795 -33.1663) (xy 74.261724 -33.110678) (xy 42.746481 -33.110678) (xy 42.73157 -33.128905)
			(xy 42.66195 -33.201453) (xy 42.586813 -33.268271) (xy 42.506629 -33.328941) (xy 42.4219 -33.383082)
			(xy 42.333157 -33.430357) (xy 42.240955 -33.470469) (xy 42.14587 -33.503167) (xy 42.048498 -33.528247)
			(xy 41.949449 -33.545551) (xy 41.849341 -33.554972) (xy 41.748802 -33.55645) (xy 41.648461 -33.549977)
			(xy 41.548946 -33.535592) (xy 41.450879 -33.513386) (xy 41.354874 -33.483497) (xy 41.30802 -33.465262)
			(xy 41.292862 -33.459712) (xy 41.26086 -33.455586) (xy 41.228847 -33.459632) (xy 41.198877 -33.47159)
			(xy 41.185592 -33.480756) (xy 41.144355 -33.510373) (xy 41.057948 -33.563696) (xy 40.96756 -33.609951)
			(xy 40.873767 -33.648843) (xy 40.77717 -33.680124) (xy 40.678383 -33.703594) (xy 40.578039 -33.719103)
			(xy 40.476776 -33.726552) (xy 40.375242 -33.725894) (xy 40.274085 -33.717133) (xy 40.17395 -33.700325)
			(xy 40.075476 -33.675576) (xy 39.979292 -33.643046) (xy 39.886012 -33.602941) (xy 39.796231 -33.555518)
			(xy 39.710522 -33.50108) (xy 39.629433 -33.439973) (xy 39.55348 -33.372588) (xy 39.483149 -33.299355)
			(xy 39.418888 -33.220741) (xy 39.361108 -33.137248) (xy 39.310177 -33.049409) (xy 39.266421 -32.957785)
			(xy 39.230119 -32.862961) (xy 39.201502 -32.765541) (xy 39.180753 -32.666147) (xy 39.168005 -32.565415)
			(xy 39.163339 -32.463986) (xy 31.9913 -32.463986) (xy 31.9913 -34.061384) (xy 32.727129 -34.061384)
			(xy 32.73373 -34.005705) (xy 32.748408 -33.951591) (xy 32.770847 -33.900206) (xy 32.800562 -33.852659)
			(xy 32.836916 -33.809971) (xy 32.857694 -33.791144) (xy 32.873711 -33.776557) (xy 32.90103 -33.742941)
			(xy 32.922246 -33.705174) (xy 32.936742 -33.664354) (xy 32.944097 -33.621665) (xy 32.944098 -33.578347)
			(xy 32.936745 -33.535658) (xy 32.922251 -33.494837) (xy 32.901037 -33.457069) (xy 32.873719 -33.423451)
			(xy 32.857694 -33.408874) (xy 32.836916 -33.390047) (xy 32.800562 -33.347359) (xy 32.770847 -33.299812)
			(xy 32.748408 -33.248427) (xy 32.73373 -33.194313) (xy 32.727129 -33.138634) (xy 32.728746 -33.082587)
			(xy 32.738546 -33.027381) (xy 32.756319 -32.974202) (xy 32.781682 -32.924197) (xy 32.814089 -32.878442)
			(xy 32.852843 -32.83792) (xy 32.897108 -32.803506) (xy 32.945933 -32.775939) (xy 32.998267 -32.755814)
			(xy 33.052981 -32.743562) (xy 33.1089 -32.739449) (xy 33.164819 -32.743562) (xy 33.219533 -32.755814)
			(xy 33.271867 -32.775939) (xy 33.320692 -32.803506) (xy 33.364957 -32.83792) (xy 33.403711 -32.878442)
			(xy 33.436118 -32.924197) (xy 33.461481 -32.974202) (xy 33.479254 -33.027381) (xy 33.489054 -33.082587)
			(xy 33.490671 -33.138634) (xy 33.489007 -33.152668) (xy 34.058097 -33.152668) (xy 34.05944 -33.096963)
			(xy 34.068871 -33.042046) (xy 34.08619 -32.989085) (xy 34.111029 -32.939206) (xy 34.142858 -32.893471)
			(xy 34.181001 -32.852852) (xy 34.224647 -32.818212) (xy 34.272867 -32.79029) (xy 34.324636 -32.769679)
			(xy 34.378852 -32.756817) (xy 34.434363 -32.751978) (xy 34.489987 -32.755264) (xy 34.544541 -32.766607)
			(xy 34.596866 -32.785764) (xy 34.645847 -32.812328) (xy 34.690444 -32.845734) (xy 34.729707 -32.885272)
			(xy 34.762801 -32.930101) (xy 34.789023 -32.979266) (xy 34.807815 -33.031723) (xy 34.818777 -33.086355)
			(xy 34.821676 -33.142) (xy 34.81645 -33.197476) (xy 34.80321 -33.251601) (xy 34.782238 -33.303225)
			(xy 34.75398 -33.351249) (xy 34.719038 -33.394653) (xy 34.69894 -33.413954) (xy 34.681938 -33.430417)
			(xy 34.653749 -33.468423) (xy 34.633081 -33.510991) (xy 34.62065 -33.556649) (xy 34.616884 -33.603818)
			(xy 34.621915 -33.65087) (xy 34.635568 -33.696177) (xy 34.657371 -33.738174) (xy 34.686572 -33.77541)
			(xy 34.692101 -33.780476) (xy 76.562202 -33.780476) (xy 76.566273 -33.724854) (xy 76.578399 -33.670417)
			(xy 76.598322 -33.618326) (xy 76.625618 -33.569691) (xy 76.659704 -33.525548) (xy 76.699853 -33.486839)
			(xy 76.745211 -33.454388) (xy 76.794811 -33.428887) (xy 76.847595 -33.41088) (xy 76.902438 -33.40075)
			(xy 76.958172 -33.398713) (xy 77.013609 -33.404813) (xy 77.067566 -33.418919) (xy 77.118895 -33.440731)
			(xy 77.166501 -33.469785) (xy 77.209369 -33.50546) (xy 77.246586 -33.546997) (xy 77.277359 -33.59351)
			(xy 77.301031 -33.644007) (xy 77.317099 -33.697414) (xy 77.325219 -33.75259) (xy 77.325728 -33.780476)
			(xy 77.325219 -33.808362) (xy 77.317099 -33.863538) (xy 77.301031 -33.916945) (xy 77.277359 -33.967442)
			(xy 77.246586 -34.013955) (xy 77.209369 -34.055492) (xy 77.166501 -34.091167) (xy 77.118895 -34.120221)
			(xy 77.067566 -34.142033) (xy 77.013609 -34.156139) (xy 76.958172 -34.162239) (xy 76.902438 -34.160202)
			(xy 76.847595 -34.150072) (xy 76.794811 -34.132065) (xy 76.745211 -34.106564) (xy 76.699853 -34.074113)
			(xy 76.659704 -34.035404) (xy 76.625618 -33.991261) (xy 76.598322 -33.942626) (xy 76.578399 -33.890535)
			(xy 76.566273 -33.836098) (xy 76.562202 -33.780476) (xy 34.692101 -33.780476) (xy 34.70402 -33.791398)
			(xy 34.724648 -33.81013) (xy 34.760786 -33.85254) (xy 34.790371 -33.899755) (xy 34.812773 -33.950772)
			(xy 34.827516 -34.004504) (xy 34.834287 -34.059809) (xy 34.832942 -34.115512) (xy 34.823509 -34.170426)
			(xy 34.806188 -34.223384) (xy 34.781349 -34.273259) (xy 34.749519 -34.318991) (xy 34.711376 -34.359607)
			(xy 34.667731 -34.394243) (xy 34.619512 -34.422162) (xy 34.567744 -34.44277) (xy 34.51353 -34.455629)
			(xy 34.458022 -34.460466) (xy 34.402401 -34.457177) (xy 34.347849 -34.445833) (xy 34.295528 -34.426675)
			(xy 34.24655 -34.40011) (xy 34.201957 -34.366704) (xy 34.162697 -34.327166) (xy 34.129605 -34.282339)
			(xy 34.103386 -34.233175) (xy 34.084597 -34.18072) (xy 34.073638 -34.12609) (xy 34.070741 -34.070447)
			(xy 34.075969 -34.014974) (xy 34.08921 -33.960852) (xy 34.110182 -33.909231) (xy 34.13844 -33.86121)
			(xy 34.173382 -33.81781) (xy 34.19348 -33.79851) (xy 34.210517 -33.782082) (xy 34.238703 -33.744068)
			(xy 34.259368 -33.701494) (xy 34.271795 -33.655831) (xy 34.275556 -33.608657) (xy 34.27052 -33.561602)
			(xy 34.256863 -33.516292) (xy 34.235055 -33.474292) (xy 34.20585 -33.437055) (xy 34.1884 -33.421066)
			(xy 34.167753 -33.402354) (xy 34.131611 -33.359944) (xy 34.102023 -33.312728) (xy 34.079617 -33.26171)
			(xy 34.064871 -33.207976) (xy 34.058097 -33.152668) (xy 33.489007 -33.152668) (xy 33.48407 -33.194313)
			(xy 33.469392 -33.248427) (xy 33.446953 -33.299812) (xy 33.417238 -33.347359) (xy 33.380884 -33.390047)
			(xy 33.360106 -33.408874) (xy 33.344098 -33.423457) (xy 33.31683 -33.457094) (xy 33.295658 -33.494866)
			(xy 33.281194 -33.53568) (xy 33.273856 -33.578355) (xy 33.273857 -33.621657) (xy 33.281197 -33.664331)
			(xy 33.295663 -33.705144) (xy 33.316837 -33.742915) (xy 33.344106 -33.776551) (xy 33.360106 -33.791144)
			(xy 33.380884 -33.809971) (xy 33.417238 -33.852659) (xy 33.446953 -33.900206) (xy 33.469392 -33.951591)
			(xy 33.48407 -34.005705) (xy 33.490671 -34.061384) (xy 33.489054 -34.117431) (xy 33.479254 -34.172637)
			(xy 33.461481 -34.225816) (xy 33.436118 -34.275821) (xy 33.403711 -34.321576) (xy 33.364957 -34.362098)
			(xy 33.320692 -34.396512) (xy 33.271867 -34.424079) (xy 33.219533 -34.444204) (xy 33.164819 -34.456456)
			(xy 33.1089 -34.460569) (xy 33.052981 -34.456456) (xy 32.998267 -34.444204) (xy 32.945933 -34.424079)
			(xy 32.897108 -34.396512) (xy 32.852843 -34.362098) (xy 32.814089 -34.321576) (xy 32.781682 -34.275821)
			(xy 32.756319 -34.225816) (xy 32.738546 -34.172637) (xy 32.728746 -34.117431) (xy 32.727129 -34.061384)
			(xy 31.9913 -34.061384) (xy 31.9913 -35.742626) (xy 32.877252 -36.628578) (xy 32.877252 -44.503848)
			(xy 52.235098 -44.503848) (xy 52.239169 -44.448226) (xy 52.251295 -44.393789) (xy 52.271218 -44.341698)
			(xy 52.298514 -44.293063) (xy 52.3326 -44.24892) (xy 52.372749 -44.210211) (xy 52.418107 -44.17776)
			(xy 52.467707 -44.152259) (xy 52.520491 -44.134252) (xy 52.575334 -44.124122) (xy 52.631068 -44.122085)
			(xy 52.686505 -44.128185) (xy 52.740462 -44.142291) (xy 52.791791 -44.164103) (xy 52.839397 -44.193157)
			(xy 52.882265 -44.228832) (xy 52.919482 -44.270369) (xy 52.950255 -44.316882) (xy 52.973927 -44.367379)
			(xy 52.989995 -44.420786) (xy 52.998115 -44.475962) (xy 52.998624 -44.503848) (xy 52.998115 -44.531734)
			(xy 52.989995 -44.58691) (xy 52.973927 -44.640317) (xy 52.950255 -44.690814) (xy 52.919482 -44.737327)
			(xy 52.882265 -44.778864) (xy 52.839397 -44.814539) (xy 52.791791 -44.843593) (xy 52.740462 -44.865405)
			(xy 52.686505 -44.879511) (xy 52.631068 -44.885611) (xy 52.575334 -44.883574) (xy 52.520491 -44.873444)
			(xy 52.467707 -44.855437) (xy 52.418107 -44.829936) (xy 52.372749 -44.797485) (xy 52.3326 -44.758776)
			(xy 52.298514 -44.714633) (xy 52.271218 -44.665998) (xy 52.251295 -44.613907) (xy 52.239169 -44.55947)
			(xy 52.235098 -44.503848) (xy 32.877252 -44.503848) (xy 32.877252 -45.654976) (xy 52.213762 -45.654976)
			(xy 52.217833 -45.599354) (xy 52.229959 -45.544917) (xy 52.249882 -45.492826) (xy 52.277178 -45.444191)
			(xy 52.311264 -45.400048) (xy 52.351413 -45.361339) (xy 52.396771 -45.328888) (xy 52.446371 -45.303387)
			(xy 52.499155 -45.28538) (xy 52.553998 -45.27525) (xy 52.609732 -45.273213) (xy 52.665169 -45.279313)
			(xy 52.719126 -45.293419) (xy 52.770455 -45.315231) (xy 52.818061 -45.344285) (xy 52.860929 -45.37996)
			(xy 52.898146 -45.421497) (xy 52.928919 -45.46801) (xy 52.952591 -45.518507) (xy 52.968659 -45.571914)
			(xy 52.976779 -45.62709) (xy 52.977288 -45.654976) (xy 52.976779 -45.682862) (xy 52.968659 -45.738038)
			(xy 52.952591 -45.791445) (xy 52.928919 -45.841942) (xy 52.898146 -45.888455) (xy 52.860929 -45.929992)
			(xy 52.818061 -45.965667) (xy 52.770455 -45.994721) (xy 52.719126 -46.016533) (xy 52.665169 -46.030639)
			(xy 52.609732 -46.036739) (xy 52.553998 -46.034702) (xy 52.499155 -46.024572) (xy 52.446371 -46.006565)
			(xy 52.396771 -45.981064) (xy 52.351413 -45.948613) (xy 52.311264 -45.909904) (xy 52.277178 -45.865761)
			(xy 52.249882 -45.817126) (xy 52.229959 -45.765035) (xy 52.217833 -45.710598) (xy 52.213762 -45.654976)
			(xy 32.877252 -45.654976) (xy 32.877252 -46.863508) (xy 52.206396 -46.863508) (xy 52.210467 -46.807886)
			(xy 52.222593 -46.753449) (xy 52.242516 -46.701358) (xy 52.269812 -46.652723) (xy 52.303898 -46.60858)
			(xy 52.344047 -46.569871) (xy 52.389405 -46.53742) (xy 52.439005 -46.511919) (xy 52.491789 -46.493912)
			(xy 52.546632 -46.483782) (xy 52.602366 -46.481745) (xy 52.657803 -46.487845) (xy 52.71176 -46.501951)
			(xy 52.763089 -46.523763) (xy 52.810695 -46.552817) (xy 52.853563 -46.588492) (xy 52.89078 -46.630029)
			(xy 52.921553 -46.676542) (xy 52.945225 -46.727039) (xy 52.961293 -46.780446) (xy 52.969413 -46.835622)
			(xy 52.969922 -46.863508) (xy 52.969413 -46.891394) (xy 52.961293 -46.94657) (xy 52.945225 -46.999977)
			(xy 52.921553 -47.050474) (xy 52.89078 -47.096987) (xy 52.853563 -47.138524) (xy 52.810695 -47.174199)
			(xy 52.763089 -47.203253) (xy 52.71176 -47.225065) (xy 52.657803 -47.239171) (xy 52.602366 -47.245271)
			(xy 52.546632 -47.243234) (xy 52.491789 -47.233104) (xy 52.439005 -47.215097) (xy 52.389405 -47.189596)
			(xy 52.344047 -47.157145) (xy 52.303898 -47.118436) (xy 52.269812 -47.074293) (xy 52.242516 -47.025658)
			(xy 52.222593 -46.973567) (xy 52.210467 -46.91913) (xy 52.206396 -46.863508) (xy 32.877252 -46.863508)
			(xy 32.877252 -48.000412) (xy 52.213762 -48.000412) (xy 52.217833 -47.94479) (xy 52.229959 -47.890353)
			(xy 52.249882 -47.838262) (xy 52.277178 -47.789627) (xy 52.311264 -47.745484) (xy 52.351413 -47.706775)
			(xy 52.396771 -47.674324) (xy 52.446371 -47.648823) (xy 52.499155 -47.630816) (xy 52.553998 -47.620686)
			(xy 52.609732 -47.618649) (xy 52.665169 -47.624749) (xy 52.719126 -47.638855) (xy 52.770455 -47.660667)
			(xy 52.818061 -47.689721) (xy 52.860929 -47.725396) (xy 52.898146 -47.766933) (xy 52.928919 -47.813446)
			(xy 52.952591 -47.863943) (xy 52.968659 -47.91735) (xy 52.976779 -47.972526) (xy 52.977288 -48.000412)
			(xy 52.976779 -48.028298) (xy 52.968659 -48.083474) (xy 52.952591 -48.136881) (xy 52.928919 -48.187378)
			(xy 52.898146 -48.233891) (xy 52.860929 -48.275428) (xy 52.818061 -48.311103) (xy 52.770455 -48.340157)
			(xy 52.719126 -48.361969) (xy 52.665169 -48.376075) (xy 52.609732 -48.382175) (xy 52.553998 -48.380138)
			(xy 52.499155 -48.370008) (xy 52.446371 -48.352001) (xy 52.396771 -48.3265) (xy 52.351413 -48.294049)
			(xy 52.311264 -48.25534) (xy 52.277178 -48.211197) (xy 52.249882 -48.162562) (xy 52.229959 -48.110471)
			(xy 52.217833 -48.056034) (xy 52.213762 -48.000412) (xy 32.877252 -48.000412) (xy 32.877252 -55.631588)
			(xy 33.752028 -56.506364) (xy 64.76695 -56.506364) (xy 64.771021 -56.450742) (xy 64.783147 -56.396305)
			(xy 64.80307 -56.344214) (xy 64.830366 -56.295579) (xy 64.864452 -56.251436) (xy 64.904601 -56.212727)
			(xy 64.949959 -56.180276) (xy 64.999559 -56.154775) (xy 65.052343 -56.136768) (xy 65.107186 -56.126638)
			(xy 65.16292 -56.124601) (xy 65.218357 -56.130701) (xy 65.272314 -56.144807) (xy 65.323643 -56.166619)
			(xy 65.371249 -56.195673) (xy 65.414117 -56.231348) (xy 65.451334 -56.272885) (xy 65.482107 -56.319398)
			(xy 65.505779 -56.369895) (xy 65.521847 -56.423302) (xy 65.529967 -56.478478) (xy 65.530476 -56.506364)
			(xy 65.529967 -56.53425) (xy 65.521847 -56.589426) (xy 65.505779 -56.642833) (xy 65.482107 -56.69333)
			(xy 65.451334 -56.739843) (xy 65.414117 -56.78138) (xy 65.371249 -56.817055) (xy 65.323643 -56.846109)
			(xy 65.272314 -56.867921) (xy 65.218357 -56.882027) (xy 65.16292 -56.888127) (xy 65.107186 -56.88609)
			(xy 65.052343 -56.87596) (xy 64.999559 -56.857953) (xy 64.949959 -56.832452) (xy 64.904601 -56.800001)
			(xy 64.864452 -56.761292) (xy 64.830366 -56.717149) (xy 64.80307 -56.668514) (xy 64.783147 -56.616423)
			(xy 64.771021 -56.561986) (xy 64.76695 -56.506364) (xy 33.752028 -56.506364) (xy 34.82975 -57.584086)
			(xy 64.46088 -57.584086) (xy 64.464951 -57.528464) (xy 64.477077 -57.474027) (xy 64.497 -57.421936)
			(xy 64.524296 -57.373301) (xy 64.558382 -57.329158) (xy 64.598531 -57.290449) (xy 64.643889 -57.257998)
			(xy 64.693489 -57.232497) (xy 64.746273 -57.21449) (xy 64.801116 -57.20436) (xy 64.85685 -57.202323)
			(xy 64.912287 -57.208423) (xy 64.966244 -57.222529) (xy 65.017573 -57.244341) (xy 65.065179 -57.273395)
			(xy 65.108047 -57.30907) (xy 65.145264 -57.350607) (xy 65.176037 -57.39712) (xy 65.199709 -57.447617)
			(xy 65.215777 -57.501024) (xy 65.223897 -57.5562) (xy 65.224406 -57.584086) (xy 65.223897 -57.611972)
			(xy 65.215777 -57.667148) (xy 65.199709 -57.720555) (xy 65.176037 -57.771052) (xy 65.145264 -57.817565)
			(xy 65.108047 -57.859102) (xy 65.065179 -57.894777) (xy 65.017573 -57.923831) (xy 64.966244 -57.945643)
			(xy 64.912287 -57.959749) (xy 64.85685 -57.965849) (xy 64.801116 -57.963812) (xy 64.746273 -57.953682)
			(xy 64.693489 -57.935675) (xy 64.643889 -57.910174) (xy 64.598531 -57.877723) (xy 64.558382 -57.839014)
			(xy 64.524296 -57.794871) (xy 64.497 -57.746236) (xy 64.477077 -57.694145) (xy 64.464951 -57.639708)
			(xy 64.46088 -57.584086) (xy 34.82975 -57.584086) (xy 35.496754 -58.25109) (xy 44.554394 -58.25109)
			(xy 44.627292 -58.183272) (xy 44.630848 -58.133234) (xy 44.633377 -58.105049) (xy 44.645706 -58.049822)
			(xy 44.66606 -57.997023) (xy 44.693994 -57.947812) (xy 44.728893 -57.903269) (xy 44.769992 -57.864372)
			(xy 44.816388 -57.831977) (xy 44.867062 -57.806793) (xy 44.920901 -57.789375) (xy 44.976723 -57.780104)
			(xy 45.033302 -57.779185) (xy 45.089396 -57.786637) (xy 45.11675 -57.79389) (xy 45.144082 -57.786571)
			(xy 45.200172 -57.779148) (xy 45.256744 -57.780093) (xy 45.312556 -57.789383) (xy 45.366384 -57.806816)
			(xy 45.417045 -57.832009) (xy 45.46343 -57.864409) (xy 45.50452 -57.903305) (xy 45.539413 -57.947844)
			(xy 45.567345 -57.997049) (xy 45.587701 -58.04984) (xy 45.600037 -58.105059) (xy 45.602652 -58.133234)
			(xy 45.606208 -58.183272) (xy 45.679106 -58.25109) (xy 46.390814 -58.25109) (xy 46.441106 -58.227976)
			(xy 46.45914 -58.206894) (xy 46.477347 -58.186399) (xy 46.51863 -58.150329) (xy 46.56465 -58.12054)
			(xy 46.61446 -58.097643) (xy 46.667034 -58.082112) (xy 46.72129 -58.074265) (xy 46.77611 -58.074265)
			(xy 46.830366 -58.082112) (xy 46.88294 -58.097643) (xy 46.93275 -58.12054) (xy 46.97877 -58.150329)
			(xy 47.020053 -58.186399) (xy 47.03826 -58.206894) (xy 47.056294 -58.227976) (xy 47.106586 -58.25109)
			(xy 51.576478 -58.25109) (xy 51.598833 -58.250614) (xy 51.642853 -58.242782) (xy 51.684824 -58.227373)
			(xy 51.723455 -58.204863) (xy 51.757555 -58.175944) (xy 51.786072 -58.141509) (xy 51.808128 -58.102617)
			(xy 51.823044 -58.060467) (xy 51.827176 -58.038492) (xy 51.831213 -58.010393) (xy 51.846507 -57.955728)
			(xy 51.86971 -57.903922) (xy 51.88458 -57.879742) (xy 51.899676 -57.856993) (xy 51.935338 -57.815653)
			(xy 51.97653 -57.77982) (xy 52.02241 -57.750225) (xy 52.07204 -57.727474) (xy 52.124407 -57.71203)
			(xy 52.178441 -57.70421) (xy 52.233037 -57.704172) (xy 52.287081 -57.711919) (xy 52.339469 -57.727291)
			(xy 52.389131 -57.749974) (xy 52.435051 -57.779506) (xy 52.476292 -57.815283) (xy 52.512011 -57.856573)
			(xy 52.541479 -57.902534) (xy 52.564094 -57.952227) (xy 52.579393 -58.004636) (xy 52.587065 -58.058691)
			(xy 52.587398 -58.08599) (xy 52.586863 -58.112428) (xy 52.579385 -58.164775) (xy 52.564738 -58.215585)
			(xy 52.554378 -58.239914) (xy 52.538376 -58.276236) (xy 52.552854 -58.353706) (xy 53.466492 -59.267344)
			(xy 53.56606 -59.2709) (xy 53.603906 -59.238388) (xy 53.629665 -59.217176) (xy 53.687016 -59.183077)
			(xy 53.717952 -59.17057) (xy 53.732454 -59.164598) (xy 53.758195 -59.146696) (xy 53.778787 -59.123051)
			(xy 53.792983 -59.095095) (xy 53.799925 -59.064519) (xy 53.799193 -59.033174) (xy 53.790831 -59.002955)
			(xy 53.775345 -58.975693) (xy 53.753672 -58.953035) (xy 53.727124 -58.936354) (xy 53.712364 -58.931048)
			(xy 53.686193 -58.921923) (xy 53.636598 -58.89718) (xy 53.591106 -58.865522) (xy 53.550673 -58.827613)
			(xy 53.516151 -58.784254) (xy 53.488266 -58.736356) (xy 53.467605 -58.684927) (xy 53.454602 -58.631049)
			(xy 53.449533 -58.575858) (xy 53.452502 -58.520513) (xy 53.463448 -58.466181) (xy 53.482141 -58.414004)
			(xy 53.508186 -58.365081) (xy 53.541037 -58.320441) (xy 53.58 -58.281025) (xy 53.624257 -58.247661)
			(xy 53.672876 -58.221051) (xy 53.724833 -58.201757) (xy 53.779035 -58.190183) (xy 53.834342 -58.186574)
			(xy 53.889588 -58.191006) (xy 53.943612 -58.203384) (xy 53.995277 -58.223449) (xy 54.043494 -58.250779)
			(xy 54.08725 -58.284798) (xy 54.125623 -58.32479) (xy 54.157805 -58.369913) (xy 54.18312 -58.419218)
			(xy 54.201034 -58.471667) (xy 54.211171 -58.526156) (xy 54.212815 -58.56859) (xy 54.770272 -58.56859)
			(xy 54.774343 -58.512968) (xy 54.786469 -58.458531) (xy 54.806392 -58.40644) (xy 54.833688 -58.357805)
			(xy 54.867774 -58.313662) (xy 54.907923 -58.274953) (xy 54.953281 -58.242502) (xy 55.002881 -58.217001)
			(xy 55.055665 -58.198994) (xy 55.110508 -58.188864) (xy 55.166242 -58.186827) (xy 55.221679 -58.192927)
			(xy 55.275636 -58.207033) (xy 55.326965 -58.228845) (xy 55.374571 -58.257899) (xy 55.417439 -58.293574)
			(xy 55.454656 -58.335111) (xy 55.485429 -58.381624) (xy 55.509101 -58.432121) (xy 55.525169 -58.485528)
			(xy 55.533289 -58.540704) (xy 55.533798 -58.56859) (xy 55.533289 -58.596476) (xy 55.525169 -58.651652)
			(xy 55.509101 -58.705059) (xy 55.485429 -58.755556) (xy 55.454656 -58.802069) (xy 55.417439 -58.843606)
			(xy 55.374571 -58.879281) (xy 55.326965 -58.908335) (xy 55.275636 -58.930147) (xy 55.221679 -58.944253)
			(xy 55.166242 -58.950353) (xy 55.110508 -58.948316) (xy 55.055665 -58.938186) (xy 55.002881 -58.920179)
			(xy 54.953281 -58.894678) (xy 54.907923 -58.862227) (xy 54.867774 -58.823518) (xy 54.833688 -58.779375)
			(xy 54.806392 -58.73074) (xy 54.786469 -58.678649) (xy 54.774343 -58.624212) (xy 54.770272 -58.56859)
			(xy 54.212815 -58.56859) (xy 54.213317 -58.581539) (xy 54.207427 -58.636649) (xy 54.193625 -58.690327)
			(xy 54.172201 -58.741443) (xy 54.143606 -58.788921) (xy 54.108443 -58.831762) (xy 54.088284 -58.850784)
			(xy 54.072663 -58.865647) (xy 54.04617 -58.899661) (xy 54.025797 -58.937659) (xy 54.01213 -58.97855)
			(xy 54.00556 -59.021161) (xy 54.006277 -59.06427) (xy 54.014259 -59.106639) (xy 54.029278 -59.147053)
			(xy 54.050902 -59.184352) (xy 54.078512 -59.217467) (xy 54.094634 -59.231784) (xy 54.115781 -59.249707)
			(xy 54.153174 -59.290629) (xy 54.172832 -59.319668) (xy 57.024522 -59.319668) (xy 57.028593 -59.264046)
			(xy 57.040719 -59.209609) (xy 57.060642 -59.157518) (xy 57.087938 -59.108883) (xy 57.122024 -59.06474)
			(xy 57.162173 -59.026031) (xy 57.207531 -58.99358) (xy 57.257131 -58.968079) (xy 57.309915 -58.950072)
			(xy 57.364758 -58.939942) (xy 57.420492 -58.937905) (xy 57.475929 -58.944005) (xy 57.529886 -58.958111)
			(xy 57.581215 -58.979923) (xy 57.628821 -59.008977) (xy 57.671689 -59.044652) (xy 57.708906 -59.086189)
			(xy 57.739679 -59.132702) (xy 57.763351 -59.183199) (xy 57.779419 -59.236606) (xy 57.787539 -59.291782)
			(xy 57.788048 -59.319668) (xy 57.787539 -59.347554) (xy 57.779419 -59.40273) (xy 57.765818 -59.447938)
			(xy 58.786774 -59.447938) (xy 58.790845 -59.392316) (xy 58.802971 -59.337879) (xy 58.822894 -59.285788)
			(xy 58.85019 -59.237153) (xy 58.884276 -59.19301) (xy 58.924425 -59.154301) (xy 58.969783 -59.12185)
			(xy 59.019383 -59.096349) (xy 59.072167 -59.078342) (xy 59.12701 -59.068212) (xy 59.182744 -59.066175)
			(xy 59.238181 -59.072275) (xy 59.292138 -59.086381) (xy 59.343467 -59.108193) (xy 59.391073 -59.137247)
			(xy 59.433941 -59.172922) (xy 59.471158 -59.214459) (xy 59.501931 -59.260972) (xy 59.525603 -59.311469)
			(xy 59.541671 -59.364876) (xy 59.549791 -59.420052) (xy 59.5503 -59.447938) (xy 59.549791 -59.475824)
			(xy 59.541671 -59.531) (xy 59.526954 -59.579918) (xy 64.180109 -59.579918) (xy 64.182468 -59.524358)
			(xy 64.19287 -59.469729) (xy 64.211094 -59.41719) (xy 64.236753 -59.367853) (xy 64.269304 -59.322766)
			(xy 64.308057 -59.282882) (xy 64.329818 -59.265566) (xy 64.347814 -59.251179) (xy 64.378716 -59.217011)
			(xy 64.402951 -59.177831) (xy 64.419725 -59.134924) (xy 64.428489 -59.089695) (xy 64.428954 -59.043628)
			(xy 64.421107 -58.998232) (xy 64.405203 -58.954994) (xy 64.381765 -58.915332) (xy 64.35156 -58.880546)
			(xy 64.333882 -58.86577) (xy 64.312503 -58.847975) (xy 64.274572 -58.807296) (xy 64.24295 -58.761539)
			(xy 64.218307 -58.711676) (xy 64.201166 -58.658763) (xy 64.19189 -58.603922) (xy 64.190676 -58.548315)
			(xy 64.197549 -58.493121) (xy 64.212364 -58.43951) (xy 64.234806 -58.388619) (xy 64.264401 -58.341525)
			(xy 64.30052 -58.299229) (xy 64.342398 -58.262625) (xy 64.389148 -58.232491) (xy 64.439777 -58.209464)
			(xy 64.493214 -58.194033) (xy 64.548325 -58.186525) (xy 64.603943 -58.187099) (xy 64.658887 -58.195744)
			(xy 64.711994 -58.212275) (xy 64.762137 -58.236342) (xy 64.808255 -58.267436) (xy 64.849368 -58.304896)
			(xy 64.884606 -58.34793) (xy 64.913222 -58.395624) (xy 64.934609 -58.446968) (xy 64.948314 -58.500873)
			(xy 64.954045 -58.556197) (xy 64.951683 -58.611767) (xy 64.941277 -58.666405) (xy 64.923047 -58.718953)
			(xy 64.897379 -58.768297) (xy 64.864819 -58.813391) (xy 64.826056 -58.853278) (xy 64.80429 -58.870596)
			(xy 64.786331 -58.885027) (xy 64.755429 -58.919188) (xy 64.731192 -58.958361) (xy 64.714415 -59.001262)
			(xy 64.705648 -59.046484) (xy 64.705178 -59.092546) (xy 64.713021 -59.137938) (xy 64.728919 -59.181172)
			(xy 64.752352 -59.220832) (xy 64.782551 -59.255616) (xy 64.800226 -59.270392) (xy 64.821592 -59.288194)
			(xy 64.859512 -59.328871) (xy 64.891123 -59.374622) (xy 64.915757 -59.424479) (xy 64.93289 -59.477384)
			(xy 64.942159 -59.532216) (xy 64.943369 -59.587813) (xy 64.936493 -59.642996) (xy 64.921677 -59.696596)
			(xy 64.899235 -59.747477) (xy 64.869643 -59.79456) (xy 64.833528 -59.836847) (xy 64.791656 -59.873442)
			(xy 64.744914 -59.903569) (xy 64.694292 -59.92659) (xy 64.640865 -59.942016) (xy 64.585763 -59.949521)
			(xy 64.530156 -59.948946) (xy 64.475222 -59.940303) (xy 64.422125 -59.923775) (xy 64.37199 -59.899712)
			(xy 64.325881 -59.868624) (xy 64.284775 -59.831171) (xy 64.249543 -59.788146) (xy 64.220931 -59.740461)
			(xy 64.199546 -59.689127) (xy 64.185842 -59.635232) (xy 64.180109 -59.579918) (xy 59.526954 -59.579918)
			(xy 59.525603 -59.584407) (xy 59.501931 -59.634904) (xy 59.471158 -59.681417) (xy 59.433941 -59.722954)
			(xy 59.391073 -59.758629) (xy 59.343467 -59.787683) (xy 59.292138 -59.809495) (xy 59.238181 -59.823601)
			(xy 59.182744 -59.829701) (xy 59.12701 -59.827664) (xy 59.072167 -59.817534) (xy 59.019383 -59.799527)
			(xy 58.969783 -59.774026) (xy 58.924425 -59.741575) (xy 58.884276 -59.702866) (xy 58.85019 -59.658723)
			(xy 58.822894 -59.610088) (xy 58.802971 -59.557997) (xy 58.790845 -59.50356) (xy 58.786774 -59.447938)
			(xy 57.765818 -59.447938) (xy 57.763351 -59.456137) (xy 57.739679 -59.506634) (xy 57.708906 -59.553147)
			(xy 57.671689 -59.594684) (xy 57.628821 -59.630359) (xy 57.581215 -59.659413) (xy 57.529886 -59.681225)
			(xy 57.475929 -59.695331) (xy 57.420492 -59.701431) (xy 57.364758 -59.699394) (xy 57.309915 -59.689264)
			(xy 57.257131 -59.671257) (xy 57.207531 -59.645756) (xy 57.162173 -59.613305) (xy 57.122024 -59.574596)
			(xy 57.087938 -59.530453) (xy 57.060642 -59.481818) (xy 57.040719 -59.429727) (xy 57.028593 -59.37529)
			(xy 57.024522 -59.319668) (xy 54.172832 -59.319668) (xy 54.184248 -59.336532) (xy 54.20835 -59.386451)
			(xy 54.224972 -59.439333) (xy 54.233762 -59.494064) (xy 54.234537 -59.549491) (xy 54.227279 -59.604447)
			(xy 54.212142 -59.657773) (xy 54.189444 -59.708345) (xy 54.159665 -59.755099) (xy 54.141878 -59.77636)
			(xy 54.109366 -59.814206) (xy 54.112922 -59.913774) (xy 54.399688 -60.20054) (xy 54.415543 -60.215736)
			(xy 54.451471 -60.240985) (xy 54.491204 -60.259682) (xy 54.53356 -60.271271) (xy 54.577277 -60.275406)
			(xy 54.621054 -60.271966) (xy 54.663589 -60.261052) (xy 54.703614 -60.242989) (xy 54.739939 -60.218315)
			(xy 54.771482 -60.187764) (xy 54.797304 -60.152246) (xy 54.807358 -60.132722) (xy 54.819458 -60.108236)
			(xy 54.849614 -60.062699) (xy 54.885954 -60.021926) (xy 54.927736 -59.986751) (xy 54.974106 -59.957893)
			(xy 55.024117 -59.93594) (xy 55.076747 -59.921342) (xy 55.130921 -59.914397) (xy 55.185531 -59.915246)
			(xy 55.239463 -59.923872) (xy 55.291613 -59.9401) (xy 55.340918 -59.963597) (xy 55.386368 -59.993883)
			(xy 55.427036 -60.03034) (xy 55.462091 -60.072223) (xy 55.490817 -60.118676) (xy 55.512626 -60.16875)
			(xy 55.520336 -60.194952) (xy 55.527175 -60.221769) (xy 55.533939 -60.276696) (xy 55.532695 -60.332024)
			(xy 55.529975 -60.348114) (xy 61.202822 -60.348114) (xy 61.206893 -60.292492) (xy 61.219019 -60.238055)
			(xy 61.238942 -60.185964) (xy 61.266238 -60.137329) (xy 61.300324 -60.093186) (xy 61.340473 -60.054477)
			(xy 61.385831 -60.022026) (xy 61.435431 -59.996525) (xy 61.488215 -59.978518) (xy 61.543058 -59.968388)
			(xy 61.598792 -59.966351) (xy 61.654229 -59.972451) (xy 61.708186 -59.986557) (xy 61.759515 -60.008369)
			(xy 61.807121 -60.037423) (xy 61.849989 -60.073098) (xy 61.887206 -60.114635) (xy 61.917979 -60.161148)
			(xy 61.926205 -60.178696) (xy 65.137282 -60.178696) (xy 65.141353 -60.123074) (xy 65.153479 -60.068637)
			(xy 65.173402 -60.016546) (xy 65.200698 -59.967911) (xy 65.234784 -59.923768) (xy 65.274933 -59.885059)
			(xy 65.320291 -59.852608) (xy 65.369891 -59.827107) (xy 65.422675 -59.8091) (xy 65.477518 -59.79897)
			(xy 65.533252 -59.796933) (xy 65.588689 -59.803033) (xy 65.642646 -59.817139) (xy 65.693975 -59.838951)
			(xy 65.741581 -59.868005) (xy 65.784449 -59.90368) (xy 65.821666 -59.945217) (xy 65.852439 -59.99173)
			(xy 65.876111 -60.042227) (xy 65.892179 -60.095634) (xy 65.900299 -60.15081) (xy 65.900808 -60.178696)
			(xy 65.900299 -60.206582) (xy 65.892179 -60.261758) (xy 65.876111 -60.315165) (xy 65.852439 -60.365662)
			(xy 65.821666 -60.412175) (xy 65.784449 -60.453712) (xy 65.741581 -60.489387) (xy 65.693975 -60.518441)
			(xy 65.642646 -60.540253) (xy 65.588689 -60.554359) (xy 65.533252 -60.560459) (xy 65.477518 -60.558422)
			(xy 65.422675 -60.548292) (xy 65.369891 -60.530285) (xy 65.320291 -60.504784) (xy 65.274933 -60.472333)
			(xy 65.234784 -60.433624) (xy 65.200698 -60.389481) (xy 65.173402 -60.340846) (xy 65.153479 -60.288755)
			(xy 65.141353 -60.234318) (xy 65.137282 -60.178696) (xy 61.926205 -60.178696) (xy 61.941651 -60.211645)
			(xy 61.957719 -60.265052) (xy 61.965839 -60.320228) (xy 61.966348 -60.348114) (xy 61.965839 -60.376)
			(xy 61.957719 -60.431176) (xy 61.941651 -60.484583) (xy 61.917979 -60.53508) (xy 61.887206 -60.581593)
			(xy 61.849989 -60.62313) (xy 61.807121 -60.658805) (xy 61.759515 -60.687859) (xy 61.708186 -60.709671)
			(xy 61.654229 -60.723777) (xy 61.598792 -60.729877) (xy 61.543058 -60.72784) (xy 61.488215 -60.71771)
			(xy 61.435431 -60.699703) (xy 61.385831 -60.674202) (xy 61.340473 -60.641751) (xy 61.300324 -60.603042)
			(xy 61.266238 -60.558899) (xy 61.238942 -60.510264) (xy 61.219019 -60.458173) (xy 61.206893 -60.403736)
			(xy 61.202822 -60.348114) (xy 55.529975 -60.348114) (xy 55.523471 -60.386591) (xy 55.506459 -60.439253)
			(xy 55.482017 -60.488905) (xy 55.450657 -60.534504) (xy 55.432198 -60.555124) (xy 55.416478 -60.572894)
			(xy 55.39128 -60.613087) (xy 55.373979 -60.657259) (xy 55.365175 -60.703873) (xy 55.365173 -60.751312)
			(xy 55.373975 -60.797927) (xy 55.391274 -60.842099) (xy 55.416469 -60.882294) (xy 55.432198 -60.900056)
			(xy 55.451769 -60.921976) (xy 55.484624 -60.970695) (xy 55.509618 -61.023876) (xy 55.516364 -61.046868)
			(xy 57.024522 -61.046868) (xy 57.028593 -60.991246) (xy 57.040719 -60.936809) (xy 57.060642 -60.884718)
			(xy 57.087938 -60.836083) (xy 57.122024 -60.79194) (xy 57.162173 -60.753231) (xy 57.207531 -60.72078)
			(xy 57.257131 -60.695279) (xy 57.309915 -60.677272) (xy 57.364758 -60.667142) (xy 57.420492 -60.665105)
			(xy 57.475929 -60.671205) (xy 57.529886 -60.685311) (xy 57.581215 -60.707123) (xy 57.628821 -60.736177)
			(xy 57.671689 -60.771852) (xy 57.708906 -60.813389) (xy 57.739679 -60.859902) (xy 57.763351 -60.910399)
			(xy 57.779419 -60.963806) (xy 57.787539 -61.018982) (xy 57.788048 -61.046868) (xy 57.787539 -61.074754)
			(xy 57.779419 -61.12993) (xy 57.763351 -61.183337) (xy 57.739679 -61.233834) (xy 57.708906 -61.280347)
			(xy 57.671689 -61.321884) (xy 57.628821 -61.357559) (xy 57.581215 -61.386613) (xy 57.529886 -61.408425)
			(xy 57.475929 -61.422531) (xy 57.420492 -61.428631) (xy 57.364758 -61.426594) (xy 57.309915 -61.416464)
			(xy 57.257131 -61.398457) (xy 57.207531 -61.372956) (xy 57.162173 -61.340505) (xy 57.122024 -61.301796)
			(xy 57.087938 -61.257653) (xy 57.060642 -61.209018) (xy 57.040719 -61.156927) (xy 57.028593 -61.10249)
			(xy 57.024522 -61.046868) (xy 55.516364 -61.046868) (xy 55.526161 -61.080261) (xy 55.533861 -61.138516)
			(xy 55.532536 -61.197263) (xy 55.522217 -61.255111) (xy 55.513224 -61.283088) (xy 55.506366 -61.303154)
			(xy 55.506366 -61.853826) (xy 55.513224 -61.873892) (xy 55.521013 -61.897867) (xy 55.522244 -61.904)
			(xy 58.47272 -61.904) (xy 58.473984 -61.848707) (xy 58.483219 -61.794175) (xy 58.500229 -61.741547)
			(xy 58.52466 -61.691927) (xy 58.555998 -61.646354) (xy 58.574432 -61.625734) (xy 58.590181 -61.60799)
			(xy 58.615372 -61.56779) (xy 58.632667 -61.523614) (xy 58.641465 -61.476997) (xy 58.641461 -61.429556)
			(xy 58.632654 -61.38294) (xy 58.615351 -61.338768) (xy 58.590152 -61.298573) (xy 58.574432 -61.280802)
			(xy 58.555998 -61.260182) (xy 58.52466 -61.214609) (xy 58.500229 -61.164989) (xy 58.483219 -61.112361)
			(xy 58.473984 -61.057829) (xy 58.47272 -61.002536) (xy 58.479451 -60.947639) (xy 58.494038 -60.894288)
			(xy 58.516174 -60.843603) (xy 58.545395 -60.796645) (xy 58.58109 -60.754397) (xy 58.622511 -60.717745)
			(xy 58.668789 -60.687457) (xy 58.718954 -60.664168) (xy 58.771957 -60.648365) (xy 58.826686 -60.64038)
			(xy 58.881994 -60.64038) (xy 58.936723 -60.648365) (xy 58.989726 -60.664168) (xy 59.039891 -60.687457)
			(xy 59.086169 -60.717745) (xy 59.12759 -60.754397) (xy 59.163285 -60.796645) (xy 59.192506 -60.843603)
			(xy 59.214642 -60.894288) (xy 59.229229 -60.947639) (xy 59.23596 -61.002536) (xy 59.234696 -61.057829)
			(xy 59.233756 -61.063378) (xy 64.240154 -61.063378) (xy 64.244225 -61.007756) (xy 64.256351 -60.953319)
			(xy 64.276274 -60.901228) (xy 64.30357 -60.852593) (xy 64.337656 -60.80845) (xy 64.377805 -60.769741)
			(xy 64.423163 -60.73729) (xy 64.472763 -60.711789) (xy 64.525547 -60.693782) (xy 64.58039 -60.683652)
			(xy 64.636124 -60.681615) (xy 64.691561 -60.687715) (xy 64.745518 -60.701821) (xy 64.796847 -60.723633)
			(xy 64.844453 -60.752687) (xy 64.887321 -60.788362) (xy 64.924538 -60.829899) (xy 64.955311 -60.876412)
			(xy 64.978983 -60.926909) (xy 64.995051 -60.980316) (xy 65.003171 -61.035492) (xy 65.003536 -61.055504)
			(xy 65.685414 -61.055504) (xy 65.689485 -60.999882) (xy 65.701611 -60.945445) (xy 65.721534 -60.893354)
			(xy 65.74883 -60.844719) (xy 65.782916 -60.800576) (xy 65.823065 -60.761867) (xy 65.868423 -60.729416)
			(xy 65.918023 -60.703915) (xy 65.970807 -60.685908) (xy 66.02565 -60.675778) (xy 66.081384 -60.673741)
			(xy 66.136821 -60.679841) (xy 66.190778 -60.693947) (xy 66.242107 -60.715759) (xy 66.289713 -60.744813)
			(xy 66.332581 -60.780488) (xy 66.369798 -60.822025) (xy 66.400571 -60.868538) (xy 66.424243 -60.919035)
			(xy 66.440311 -60.972442) (xy 66.448431 -61.027618) (xy 66.44894 -61.055504) (xy 66.448431 -61.08339)
			(xy 66.440311 -61.138566) (xy 66.424243 -61.191973) (xy 66.400571 -61.24247) (xy 66.369798 -61.288983)
			(xy 66.332581 -61.33052) (xy 66.289713 -61.366195) (xy 66.242107 -61.395249) (xy 66.190778 -61.417061)
			(xy 66.136821 -61.431167) (xy 66.081384 -61.437267) (xy 66.02565 -61.43523) (xy 65.970807 -61.4251)
			(xy 65.918023 -61.407093) (xy 65.868423 -61.381592) (xy 65.823065 -61.349141) (xy 65.782916 -61.310432)
			(xy 65.74883 -61.266289) (xy 65.721534 -61.217654) (xy 65.701611 -61.165563) (xy 65.689485 -61.111126)
			(xy 65.685414 -61.055504) (xy 65.003536 -61.055504) (xy 65.00368 -61.063378) (xy 65.003171 -61.091264)
			(xy 64.995051 -61.14644) (xy 64.978983 -61.199847) (xy 64.955311 -61.250344) (xy 64.924538 -61.296857)
			(xy 64.887321 -61.338394) (xy 64.844453 -61.374069) (xy 64.796847 -61.403123) (xy 64.745518 -61.424935)
			(xy 64.691561 -61.439041) (xy 64.636124 -61.445141) (xy 64.58039 -61.443104) (xy 64.525547 -61.432974)
			(xy 64.472763 -61.414967) (xy 64.423163 -61.389466) (xy 64.377805 -61.357015) (xy 64.337656 -61.318306)
			(xy 64.30357 -61.274163) (xy 64.276274 -61.225528) (xy 64.256351 -61.173437) (xy 64.244225 -61.119)
			(xy 64.240154 -61.063378) (xy 59.233756 -61.063378) (xy 59.225461 -61.112361) (xy 59.208451 -61.164989)
			(xy 59.18402 -61.214609) (xy 59.152682 -61.260182) (xy 59.134248 -61.280802) (xy 59.118563 -61.2986)
			(xy 59.093371 -61.338788) (xy 59.076072 -61.382953) (xy 59.067268 -61.429561) (xy 59.067263 -61.476992)
			(xy 59.076059 -61.523602) (xy 59.09335 -61.56777) (xy 59.118535 -61.607963) (xy 59.134248 -61.625734)
			(xy 59.152682 -61.646354) (xy 59.18402 -61.691927) (xy 59.208451 -61.741547) (xy 59.225461 -61.794175)
			(xy 59.234696 -61.848707) (xy 59.23596 -61.904) (xy 59.229229 -61.958897) (xy 59.221636 -61.986668)
			(xy 59.742322 -61.986668) (xy 59.746393 -61.931046) (xy 59.758519 -61.876609) (xy 59.778442 -61.824518)
			(xy 59.805738 -61.775883) (xy 59.839824 -61.73174) (xy 59.879973 -61.693031) (xy 59.925331 -61.66058)
			(xy 59.974931 -61.635079) (xy 60.027715 -61.617072) (xy 60.082558 -61.606942) (xy 60.138292 -61.604905)
			(xy 60.193729 -61.611005) (xy 60.247686 -61.625111) (xy 60.299015 -61.646923) (xy 60.346621 -61.675977)
			(xy 60.389489 -61.711652) (xy 60.426706 -61.753189) (xy 60.457479 -61.799702) (xy 60.481151 -61.850199)
			(xy 60.497219 -61.903606) (xy 60.505339 -61.958782) (xy 60.505848 -61.986668) (xy 60.505339 -62.014554)
			(xy 60.497219 -62.06973) (xy 60.481151 -62.123137) (xy 60.457479 -62.173634) (xy 60.426706 -62.220147)
			(xy 60.389489 -62.261684) (xy 60.346621 -62.297359) (xy 60.299015 -62.326413) (xy 60.247686 -62.348225)
			(xy 60.193729 -62.362331) (xy 60.138292 -62.368431) (xy 60.082558 -62.366394) (xy 60.027715 -62.356264)
			(xy 59.974931 -62.338257) (xy 59.925331 -62.312756) (xy 59.879973 -62.280305) (xy 59.839824 -62.241596)
			(xy 59.805738 -62.197453) (xy 59.778442 -62.148818) (xy 59.758519 -62.096727) (xy 59.746393 -62.04229)
			(xy 59.742322 -61.986668) (xy 59.221636 -61.986668) (xy 59.214642 -62.012248) (xy 59.192506 -62.062933)
			(xy 59.163285 -62.109891) (xy 59.12759 -62.152139) (xy 59.086169 -62.188791) (xy 59.039891 -62.219079)
			(xy 58.989726 -62.242368) (xy 58.936723 -62.258171) (xy 58.881994 -62.266156) (xy 58.826686 -62.266156)
			(xy 58.771957 -62.258171) (xy 58.718954 -62.242368) (xy 58.668789 -62.219079) (xy 58.622511 -62.188791)
			(xy 58.58109 -62.152139) (xy 58.545395 -62.109891) (xy 58.516174 -62.062933) (xy 58.494038 -62.012248)
			(xy 58.479451 -61.958897) (xy 58.47272 -61.904) (xy 55.522244 -61.904) (xy 55.530935 -61.947291)
			(xy 55.534263 -61.997591) (xy 55.530938 -62.047891) (xy 55.521018 -62.097315) (xy 55.513224 -62.121288)
			(xy 55.506366 -62.141354) (xy 55.506366 -63.542926) (xy 55.506874 -63.566485) (xy 55.515546 -63.612798)
			(xy 55.532607 -63.656718) (xy 55.557471 -63.696741) (xy 55.589286 -63.731495) (xy 55.626963 -63.759789)
			(xy 55.66921 -63.780652) (xy 55.714578 -63.793371) (xy 55.761514 -63.797509) (xy 55.785004 -63.795656)
			(xy 55.810659 -63.793596) (xy 55.862091 -63.795561) (xy 55.912793 -63.804415) (xy 55.961847 -63.819996)
			(xy 56.008364 -63.842022) (xy 56.051504 -63.870094) (xy 56.071262 -63.886588) (xy 56.091757 -63.904911)
			(xy 56.127788 -63.94643) (xy 56.157486 -63.992692) (xy 56.180237 -64.042737) (xy 56.195569 -64.095529)
			(xy 56.203165 -64.149976) (xy 56.202952 -64.189393) (xy 59.966824 -64.189393) (xy 59.972203 -64.13491)
			(xy 59.985314 -64.081754) (xy 60.005886 -64.031017) (xy 60.033498 -63.983742) (xy 60.050172 -63.962026)
			(xy 60.064512 -63.943183) (xy 60.086611 -63.901309) (xy 60.100569 -63.856066) (xy 60.105903 -63.809021)
			(xy 60.102429 -63.761801) (xy 60.090267 -63.716043) (xy 60.069838 -63.673329) (xy 60.056268 -63.653924)
			(xy 60.040491 -63.631554) (xy 60.014811 -63.583212) (xy 59.996302 -63.531696) (xy 59.985345 -63.478064)
			(xy 59.982165 -63.423417) (xy 59.986827 -63.368876) (xy 59.999234 -63.315561) (xy 60.019134 -63.264567)
			(xy 60.046116 -63.216939) (xy 60.079628 -63.173656) (xy 60.118981 -63.135607) (xy 60.163367 -63.103571)
			(xy 60.211876 -63.078207) (xy 60.263512 -63.060036) (xy 60.317214 -63.04943) (xy 60.371881 -63.046607)
			(xy 60.42639 -63.051625) (xy 60.479623 -63.064381) (xy 60.530486 -63.084614) (xy 60.577936 -63.111907)
			(xy 60.620999 -63.145701) (xy 60.658791 -63.185302) (xy 60.690535 -63.229897) (xy 60.715581 -63.27857)
			(xy 60.733415 -63.330324) (xy 60.743669 -63.384094) (xy 60.746135 -63.438778) (xy 60.743725 -63.463204)
			(xy 67.229498 -63.463204) (xy 67.233377 -63.408095) (xy 67.245164 -63.354122) (xy 67.264613 -63.302413)
			(xy 67.291318 -63.254051) (xy 67.324719 -63.210046) (xy 67.364117 -63.171319) (xy 67.40869 -63.13868)
			(xy 67.457505 -63.112812) (xy 67.509541 -63.094255) (xy 67.563709 -63.083399) (xy 67.618876 -63.080469)
			(xy 67.67389 -63.085527) (xy 67.727598 -63.098467) (xy 67.778878 -63.119019) (xy 67.803014 -63.132462)
			(xy 67.81735 -63.140247) (xy 67.84879 -63.148922) (xy 67.881402 -63.149336) (xy 67.913051 -63.141461)
			(xy 67.941667 -63.125814) (xy 67.965377 -63.103419) (xy 67.982628 -63.075741) (xy 67.992293 -63.044591)
			(xy 67.993514 -63.028322) (xy 67.994022 -63.02121) (xy 67.995046 -62.997974) (xy 67.989464 -62.9518)
			(xy 67.97557 -62.907414) (xy 67.953829 -62.866298) (xy 67.924968 -62.829826) (xy 67.88995 -62.799217)
			(xy 67.849945 -62.775493) (xy 67.806291 -62.759447) (xy 67.783456 -62.755018) (xy 67.756905 -62.750028)
			(xy 67.705491 -62.733439) (xy 67.65693 -62.709763) (xy 67.612196 -62.679474) (xy 67.572181 -62.643176)
			(xy 67.537688 -62.601596) (xy 67.509405 -62.555567) (xy 67.487899 -62.506007) (xy 67.473599 -62.45391)
			(xy 67.466792 -62.400315) (xy 67.467613 -62.346297) (xy 67.476047 -62.292935) (xy 67.491924 -62.241296)
			(xy 67.514928 -62.192413) (xy 67.544597 -62.147265) (xy 67.580339 -62.106753) (xy 67.621438 -62.071689)
			(xy 67.667073 -62.042774) (xy 67.716331 -62.020585) (xy 67.768226 -62.005567) (xy 67.821721 -61.998021)
			(xy 67.848734 -61.99759) (xy 67.870067 -61.997224) (xy 67.912144 -61.990174) (xy 67.952453 -61.976193)
			(xy 67.989859 -61.955675) (xy 68.023312 -61.929196) (xy 68.051871 -61.8975) (xy 68.074733 -61.861479)
			(xy 68.091257 -61.822144) (xy 68.100977 -61.780602) (xy 68.102734 -61.759338) (xy 68.104867 -61.732164)
			(xy 68.115957 -61.678794) (xy 68.134528 -61.627547) (xy 68.160204 -61.579464) (xy 68.192462 -61.535525)
			(xy 68.230645 -61.496624) (xy 68.273976 -61.463553) (xy 68.321572 -61.436985) (xy 68.372464 -61.417462)
			(xy 68.425618 -61.40538) (xy 68.452746 -61.402722) (xy 68.46791 -61.401018) (xy 68.496863 -61.39142)
			(xy 68.522704 -61.375213) (xy 68.54395 -61.353326) (xy 68.559382 -61.327015) (xy 68.568115 -61.297789)
			(xy 68.569332 -61.28258) (xy 68.571243 -61.254542) (xy 68.582347 -61.199451) (xy 68.60141 -61.146585)
			(xy 68.628021 -61.097086) (xy 68.661603 -61.052025) (xy 68.701431 -61.012377) (xy 68.746643 -60.978998)
			(xy 68.796261 -60.952611) (xy 68.82257 -60.942728) (xy 68.836497 -60.9373) (xy 68.861552 -60.921016)
			(xy 68.882138 -60.899357) (xy 68.897128 -60.873507) (xy 68.905701 -60.844881) (xy 68.907389 -60.815047)
			(xy 68.902098 -60.785638) (xy 68.896484 -60.771786) (xy 68.88861 -60.75299) (xy 68.880363 -60.73249)
			(xy 68.857826 -60.694485) (xy 68.829051 -60.660956) (xy 68.794906 -60.632913) (xy 68.756423 -60.611204)
			(xy 68.714763 -60.596485) (xy 68.671183 -60.589199) (xy 68.649088 -60.588906) (xy 68.62135 -60.588614)
			(xy 68.566402 -60.581027) (xy 68.513132 -60.565565) (xy 68.462661 -60.542553) (xy 68.416054 -60.512477)
			(xy 68.374293 -60.475969) (xy 68.338257 -60.4338) (xy 68.308707 -60.386857) (xy 68.286264 -60.336131)
			(xy 68.271402 -60.28269) (xy 68.264433 -60.227661) (xy 68.265506 -60.172202) (xy 68.274596 -60.117483)
			(xy 68.291514 -60.064657) (xy 68.315901 -60.014836) (xy 68.347244 -59.969072) (xy 68.384883 -59.928327)
			(xy 68.428025 -59.893461) (xy 68.47576 -59.865209) (xy 68.527083 -59.844166) (xy 68.580911 -59.830775)
			(xy 68.636111 -59.825318) (xy 68.69152 -59.827911) (xy 68.745969 -59.838499) (xy 68.798311 -59.856859)
			(xy 68.847444 -59.882603) (xy 68.892332 -59.91519) (xy 68.932029 -59.953932) (xy 68.965698 -59.998014)
			(xy 68.992631 -60.046506) (xy 69.00291 -60.07227) (xy 69.011108 -60.092791) (xy 69.033656 -60.130794)
			(xy 69.062441 -60.164321) (xy 69.096594 -60.19236) (xy 69.135084 -60.214065) (xy 69.17675 -60.228781)
			(xy 69.220335 -60.236063) (xy 69.242432 -60.236354) (xy 69.270139 -60.236678) (xy 69.325026 -60.244252)
			(xy 69.37824 -60.259686) (xy 69.428662 -60.282655) (xy 69.47523 -60.312677) (xy 69.516966 -60.349119)
			(xy 69.552992 -60.391215) (xy 69.562013 -60.405518) (xy 70.524876 -60.405518) (xy 70.528947 -60.349896)
			(xy 70.541073 -60.295459) (xy 70.560996 -60.243368) (xy 70.588292 -60.194733) (xy 70.622378 -60.15059)
			(xy 70.662527 -60.111881) (xy 70.707885 -60.07943) (xy 70.757485 -60.053929) (xy 70.810269 -60.035922)
			(xy 70.865112 -60.025792) (xy 70.920846 -60.023755) (xy 70.976283 -60.029855) (xy 71.03024 -60.043961)
			(xy 71.081569 -60.065773) (xy 71.129175 -60.094827) (xy 71.172043 -60.130502) (xy 71.20926 -60.172039)
			(xy 71.240033 -60.218552) (xy 71.263705 -60.269049) (xy 71.279773 -60.322456) (xy 71.287893 -60.377632)
			(xy 71.288402 -60.405518) (xy 71.287893 -60.433404) (xy 71.279773 -60.48858) (xy 71.263705 -60.541987)
			(xy 71.240033 -60.592484) (xy 71.20926 -60.638997) (xy 71.172043 -60.680534) (xy 71.129175 -60.716209)
			(xy 71.081569 -60.745263) (xy 71.03024 -60.767075) (xy 70.976283 -60.781181) (xy 70.920846 -60.787281)
			(xy 70.865112 -60.785244) (xy 70.810269 -60.775114) (xy 70.757485 -60.757107) (xy 70.707885 -60.731606)
			(xy 70.662527 -60.699155) (xy 70.622378 -60.660446) (xy 70.588292 -60.616303) (xy 70.560996 -60.567668)
			(xy 70.541073 -60.515577) (xy 70.528947 -60.46114) (xy 70.524876 -60.405518) (xy 69.562013 -60.405518)
			(xy 69.582549 -60.43808) (xy 69.605016 -60.488727) (xy 69.61992 -60.542092) (xy 69.626948 -60.597052)
			(xy 69.625952 -60.65245) (xy 69.616953 -60.707121) (xy 69.600139 -60.759915) (xy 69.575866 -60.809722)
			(xy 69.544643 -60.855494) (xy 69.507127 -60.896268) (xy 69.464108 -60.931186) (xy 69.440552 -60.945776)
			(xy 69.421311 -60.957884) (xy 69.387036 -60.987738) (xy 69.358616 -61.023211) (xy 69.336958 -61.063174)
			(xy 69.322753 -61.106351) (xy 69.316453 -61.151367) (xy 69.31826 -61.196785) (xy 69.322696 -61.21908)
			(xy 69.328723 -61.248874) (xy 69.332374 -61.309548) (xy 69.326362 -61.370034) (xy 69.310837 -61.428801)
			(xy 69.286194 -61.484365) (xy 69.270118 -61.510164) (xy 69.25827 -61.529331) (xy 69.240732 -61.570831)
			(xy 69.230784 -61.614773) (xy 69.228736 -61.65978) (xy 69.234654 -61.704444) (xy 69.248353 -61.747365)
			(xy 69.269402 -61.787199) (xy 69.297143 -61.8227) (xy 69.330707 -61.852755) (xy 69.34962 -61.865002)
			(xy 69.373127 -61.880011) (xy 69.415845 -61.915868) (xy 69.452888 -61.957563) (xy 69.483465 -62.004206)
			(xy 69.50347 -62.047347) (xy 70.319905 -62.047347) (xy 70.323838 -61.992631) (xy 70.335567 -61.939043)
			(xy 70.35485 -61.887687) (xy 70.381291 -61.839623) (xy 70.414344 -61.795842) (xy 70.453327 -61.757246)
			(xy 70.497436 -61.724632) (xy 70.545762 -61.698673) (xy 70.597308 -61.679903) (xy 70.651011 -61.66871)
			(xy 70.705764 -61.665325) (xy 70.760436 -61.669817) (xy 70.813902 -61.682094) (xy 70.865058 -61.701903)
			(xy 70.912849 -61.728834) (xy 70.956289 -61.762333) (xy 70.975728 -61.78169) (xy 70.991484 -61.797339)
			(xy 71.02744 -61.823393) (xy 71.067379 -61.8428) (xy 71.110083 -61.854969) (xy 71.154252 -61.85953)
			(xy 71.198542 -61.856342) (xy 71.241603 -61.845504) (xy 71.282124 -61.827345) (xy 71.318872 -61.802418)
			(xy 71.350727 -61.771483) (xy 71.364094 -61.75375) (xy 71.381004 -61.731152) (xy 71.42045 -61.690782)
			(xy 71.465413 -61.656665) (xy 71.514913 -61.629546) (xy 71.567869 -61.610017) (xy 71.623124 -61.598504)
			(xy 71.679473 -61.595259) (xy 71.735684 -61.600353) (xy 71.790532 -61.613674) (xy 71.842817 -61.634931)
			(xy 71.8914 -61.663661) (xy 71.935219 -61.699236) (xy 71.954644 -61.719714) (xy 71.96952 -61.735358)
			(xy 72.003638 -61.761804) (xy 72.041735 -61.782102) (xy 72.082716 -61.795668) (xy 72.125399 -61.802111)
			(xy 72.168558 -61.801246) (xy 72.21095 -61.793098) (xy 72.251354 -61.777902) (xy 72.288608 -61.756094)
			(xy 72.321639 -61.728303) (xy 72.335898 -61.712094) (xy 72.354314 -61.691008) (xy 72.39632 -61.653999)
			(xy 72.443284 -61.623526) (xy 72.494197 -61.600244) (xy 72.547966 -61.584652) (xy 72.603436 -61.577086)
			(xy 72.659416 -61.577706) (xy 72.714705 -61.586502) (xy 72.768115 -61.603282) (xy 72.818499 -61.627688)
			(xy 72.864775 -61.659195) (xy 72.90595 -61.697127) (xy 72.94114 -61.740668) (xy 72.969589 -61.788885)
			(xy 72.990686 -61.840742) (xy 73.003978 -61.895125) (xy 73.00918 -61.950866) (xy 73.007736 -61.977778)
			(xy 73.317098 -61.977778) (xy 73.321169 -61.922156) (xy 73.333295 -61.867719) (xy 73.353218 -61.815628)
			(xy 73.380514 -61.766993) (xy 73.4146 -61.72285) (xy 73.454749 -61.684141) (xy 73.500107 -61.65169)
			(xy 73.549707 -61.626189) (xy 73.602491 -61.608182) (xy 73.657334 -61.598052) (xy 73.713068 -61.596015)
			(xy 73.768505 -61.602115) (xy 73.822462 -61.616221) (xy 73.873791 -61.638033) (xy 73.921397 -61.667087)
			(xy 73.964265 -61.702762) (xy 74.001482 -61.744299) (xy 74.032255 -61.790812) (xy 74.055927 -61.841309)
			(xy 74.071995 -61.894716) (xy 74.080115 -61.949892) (xy 74.080624 -61.977778) (xy 74.080115 -62.005664)
			(xy 74.071995 -62.06084) (xy 74.055927 -62.114247) (xy 74.032255 -62.164744) (xy 74.001482 -62.211257)
			(xy 73.964265 -62.252794) (xy 73.921397 -62.288469) (xy 73.873791 -62.317523) (xy 73.822462 -62.339335)
			(xy 73.768505 -62.353441) (xy 73.713068 -62.359541) (xy 73.657334 -62.357504) (xy 73.602491 -62.347374)
			(xy 73.549707 -62.329367) (xy 73.500107 -62.303866) (xy 73.454749 -62.271415) (xy 73.4146 -62.232706)
			(xy 73.380514 -62.188563) (xy 73.353218 -62.139928) (xy 73.333295 -62.087837) (xy 73.321169 -62.0334)
			(xy 73.317098 -61.977778) (xy 73.007736 -61.977778) (xy 73.00618 -62.00677) (xy 72.995042 -62.061635)
			(xy 72.976007 -62.114283) (xy 72.949481 -62.163584) (xy 72.916035 -62.208479) (xy 72.876388 -62.248005)
			(xy 72.83139 -62.281312) (xy 72.782007 -62.307685) (xy 72.729301 -62.326559) (xy 72.674402 -62.337527)
			(xy 72.618489 -62.340355) (xy 72.562764 -62.334981) (xy 72.508422 -62.321522) (xy 72.456631 -62.300265)
			(xy 72.408502 -62.271668) (xy 72.365069 -62.236344) (xy 72.345804 -62.21603) (xy 72.330876 -62.200439)
			(xy 72.296765 -62.173999) (xy 72.258675 -62.153703) (xy 72.217704 -62.140137) (xy 72.175029 -62.133691)
			(xy 72.131878 -62.13455) (xy 72.089494 -62.14269) (xy 72.049094 -62.157876) (xy 72.011843 -62.179671)
			(xy 71.978811 -62.207448) (xy 71.96455 -62.22365) (xy 71.947026 -62.243596) (xy 71.90745 -62.278985)
			(xy 71.86335 -62.308547) (xy 71.815577 -62.331708) (xy 71.765055 -62.348024) (xy 71.712758 -62.357177)
			(xy 71.659698 -62.358992) (xy 71.606899 -62.353433) (xy 71.555379 -62.340609) (xy 71.506136 -62.320765)
			(xy 71.460119 -62.294286) (xy 71.418217 -62.261684) (xy 71.3994 -62.242954) (xy 71.38362 -62.227329)
			(xy 71.347669 -62.201269) (xy 71.307735 -62.181857) (xy 71.265034 -62.169683) (xy 71.220866 -62.165119)
			(xy 71.176578 -62.168304) (xy 71.133518 -62.17914) (xy 71.092998 -62.197298) (xy 71.056252 -62.222225)
			(xy 71.024399 -62.253161) (xy 71.011034 -62.270894) (xy 70.994544 -62.292818) (xy 70.95636 -62.332204)
			(xy 70.912927 -62.365714) (xy 70.865143 -62.392657) (xy 70.813992 -62.412478) (xy 70.76053 -62.424768)
			(xy 70.705858 -62.429274) (xy 70.651105 -62.425902) (xy 70.597399 -62.414723) (xy 70.545848 -62.395966)
			(xy 70.497516 -62.370018) (xy 70.453399 -62.337415) (xy 70.414406 -62.298829) (xy 70.381343 -62.255056)
			(xy 70.35489 -62.206999) (xy 70.335593 -62.155648) (xy 70.323851 -62.102062) (xy 70.319905 -62.047347)
			(xy 69.50347 -62.047347) (xy 69.506927 -62.054803) (xy 69.522772 -62.108278) (xy 69.530664 -62.163489)
			(xy 69.530433 -62.219261) (xy 69.522086 -62.274405) (xy 69.505799 -62.327747) (xy 69.48192 -62.378149)
			(xy 69.450957 -62.424538) (xy 69.413571 -62.465924) (xy 69.370558 -62.501427) (xy 69.322835 -62.53029)
			(xy 69.271418 -62.551897) (xy 69.217403 -62.565789) (xy 69.161941 -62.571668) (xy 69.106214 -62.569411)
			(xy 69.05141 -62.559065) (xy 68.998696 -62.54085) (xy 68.949195 -62.515155) (xy 68.903962 -62.482527)
			(xy 68.863961 -62.443662) (xy 68.830045 -62.399387) (xy 68.802936 -62.350646) (xy 68.792598 -62.324742)
			(xy 68.783535 -62.302495) (xy 68.758454 -62.261536) (xy 68.726128 -62.226015) (xy 68.687708 -62.197195)
			(xy 68.644559 -62.176103) (xy 68.598218 -62.163487) (xy 68.550332 -62.159798) (xy 68.526406 -62.161928)
			(xy 68.515523 -62.163115) (xy 68.493665 -62.164384) (xy 68.482718 -62.164468) (xy 68.461389 -62.164921)
			(xy 68.419317 -62.171961) (xy 68.379013 -62.185932) (xy 68.341609 -62.206439) (xy 68.308158 -62.232907)
			(xy 68.279598 -62.264592) (xy 68.256732 -62.300602) (xy 68.240205 -62.339927) (xy 68.230479 -62.38146)
			(xy 68.228718 -62.40272) (xy 68.228718 -62.402974) (xy 68.227759 -62.426211) (xy 68.233337 -62.472378)
			(xy 68.247224 -62.516759) (xy 68.268957 -62.557871) (xy 68.297809 -62.594341) (xy 68.332816 -62.624951)
			(xy 68.372809 -62.648679) (xy 68.416453 -62.664732) (xy 68.439284 -62.669166) (xy 68.466802 -62.674333)
			(xy 68.520024 -62.691719) (xy 68.570134 -62.716698) (xy 68.616054 -62.748733) (xy 68.656799 -62.787135)
			(xy 68.691493 -62.831081) (xy 68.719392 -62.879625) (xy 68.739895 -62.931726) (xy 68.752563 -62.986264)
			(xy 68.757124 -63.042069) (xy 68.753479 -63.09794) (xy 68.741706 -63.152679) (xy 68.72206 -63.205109)
			(xy 68.694961 -63.254104) (xy 68.660992 -63.298612) (xy 68.620882 -63.337678) (xy 68.575493 -63.370461)
			(xy 68.525799 -63.396258) (xy 68.50573 -63.40318) (xy 74.846783 -63.40318) (xy 74.849479 -63.348379)
			(xy 74.859998 -63.294529) (xy 74.878122 -63.242741) (xy 74.903478 -63.194084) (xy 74.935543 -63.149561)
			(xy 74.973656 -63.110091) (xy 75.01703 -63.076488) (xy 75.06477 -63.049445) (xy 75.115892 -63.02952)
			(xy 75.169341 -63.017125) (xy 75.224014 -63.012513) (xy 75.278785 -63.015782) (xy 75.332522 -63.026863)
			(xy 75.384117 -63.045528) (xy 75.408536 -63.05804) (xy 75.428973 -63.068519) (xy 75.472702 -63.082555)
			(xy 75.518242 -63.088503) (xy 75.564109 -63.08617) (xy 75.60881 -63.075632) (xy 75.65089 -63.057231)
			(xy 75.688977 -63.031568) (xy 75.721832 -62.999477) (xy 75.748385 -62.962004) (xy 75.76777 -62.92037)
			(xy 75.774042 -62.898274) (xy 75.781371 -62.872132) (xy 75.802376 -62.822068) (xy 75.830266 -62.775488)
			(xy 75.864479 -62.733332) (xy 75.904323 -62.696454) (xy 75.948993 -62.665596) (xy 75.997587 -62.641384)
			(xy 76.049123 -62.624306) (xy 76.102559 -62.614708) (xy 76.156817 -62.612782) (xy 76.210799 -62.618569)
			(xy 76.263416 -62.631951) (xy 76.313604 -62.652657) (xy 76.360349 -62.68027) (xy 76.402707 -62.714232)
			(xy 76.439821 -62.753856) (xy 76.470944 -62.798342) (xy 76.480249 -62.816742) (xy 78.685986 -62.816742)
			(xy 78.68765 -62.762357) (xy 78.697023 -62.708759) (xy 78.713915 -62.657037) (xy 78.737983 -62.608239)
			(xy 78.76874 -62.563356) (xy 78.805561 -62.523297) (xy 78.8477 -62.488875) (xy 78.894301 -62.460789)
			(xy 78.94442 -62.439608) (xy 78.997039 -62.425762) (xy 79.051092 -62.419531) (xy 79.105482 -62.421043)
			(xy 79.159105 -62.430266) (xy 79.210874 -62.447013) (xy 79.259739 -62.470946) (xy 79.304708 -62.501577)
			(xy 79.34487 -62.538286) (xy 79.379409 -62.580328) (xy 79.407626 -62.626851) (xy 79.428947 -62.676911)
			(xy 79.44294 -62.729491) (xy 79.449321 -62.783526) (xy 79.447961 -62.83792) (xy 79.438888 -62.891569)
			(xy 79.422285 -62.943385) (xy 79.398489 -62.992316) (xy 79.383636 -63.015114) (xy 79.371029 -63.034611)
			(xy 79.352398 -63.077134) (xy 79.3418 -63.122333) (xy 79.339588 -63.168705) (xy 79.345834 -63.214708)
			(xy 79.360331 -63.258811) (xy 79.382598 -63.299548) (xy 79.396844 -63.317882) (xy 79.413655 -63.339275)
			(xy 79.441609 -63.385954) (xy 79.462649 -63.436131) (xy 79.476347 -63.488788) (xy 79.482426 -63.542856)
			(xy 79.480763 -63.59724) (xy 79.471392 -63.650836) (xy 79.454501 -63.702557) (xy 79.430435 -63.751354)
			(xy 79.399681 -63.796238) (xy 79.362863 -63.836298) (xy 79.320727 -63.870721) (xy 79.274129 -63.89881)
			(xy 79.224014 -63.919994) (xy 79.171397 -63.933845) (xy 79.117346 -63.94008) (xy 79.062958 -63.938574)
			(xy 79.009335 -63.929357) (xy 78.957565 -63.912616) (xy 78.908698 -63.888691) (xy 78.863726 -63.858066)
			(xy 78.82356 -63.821364) (xy 78.789015 -63.779328) (xy 78.760792 -63.732811) (xy 78.739463 -63.682757)
			(xy 78.725461 -63.63018) (xy 78.71907 -63.576148) (xy 78.720419 -63.521755) (xy 78.729481 -63.468106)
			(xy 78.746072 -63.416288) (xy 78.769856 -63.367353) (xy 78.784704 -63.344552) (xy 78.79734 -63.325073)
			(xy 78.815964 -63.282545) (xy 78.826556 -63.237342) (xy 78.828764 -63.190967) (xy 78.822513 -63.144962)
			(xy 78.808012 -63.100857) (xy 78.785743 -63.060119) (xy 78.771496 -63.041784) (xy 78.754762 -63.020327)
			(xy 78.726806 -62.973648) (xy 78.705765 -62.92347) (xy 78.692066 -62.870812) (xy 78.685986 -62.816742)
			(xy 76.480249 -62.816742) (xy 76.495444 -62.846791) (xy 76.512828 -62.898224) (xy 76.522744 -62.951602)
			(xy 76.524992 -63.005848) (xy 76.519526 -63.059863) (xy 76.506458 -63.112559) (xy 76.48605 -63.162869)
			(xy 76.472796 -63.186564) (xy 76.461506 -63.20697) (xy 76.445744 -63.250856) (xy 76.438251 -63.296881)
			(xy 76.43928 -63.3435) (xy 76.448794 -63.389149) (xy 76.466476 -63.432297) (xy 76.491732 -63.471496)
			(xy 76.50734 -63.488824) (xy 76.525882 -63.50917) (xy 76.557528 -63.55421) (xy 76.582371 -63.603332)
			(xy 76.599895 -63.655514) (xy 76.609736 -63.709673) (xy 76.61169 -63.764684) (xy 76.605715 -63.819405)
			(xy 76.591937 -63.872699) (xy 76.570642 -63.923459) (xy 76.55687 -63.947294) (xy 76.545891 -63.966484)
			(xy 76.529994 -64.007733) (xy 76.521481 -64.051112) (xy 76.52061 -64.09531) (xy 76.527408 -64.138991)
			(xy 76.541668 -64.180834) (xy 76.562961 -64.219575) (xy 76.576428 -64.237108) (xy 76.593093 -64.258569)
			(xy 76.620725 -64.305356) (xy 76.641442 -64.355588) (xy 76.654825 -64.408251) (xy 76.660603 -64.46228)
			(xy 76.65866 -64.516583) (xy 76.649034 -64.57006) (xy 76.631922 -64.621632) (xy 76.607667 -64.670256)
			(xy 76.576762 -64.714948) (xy 76.558648 -64.735202) (xy 76.542963 -64.753) (xy 76.517771 -64.793188)
			(xy 76.500472 -64.837353) (xy 76.491668 -64.883961) (xy 76.491663 -64.931392) (xy 76.500459 -64.978002)
			(xy 76.51775 -65.02217) (xy 76.542935 -65.062363) (xy 76.558648 -65.080134) (xy 76.577082 -65.100754)
			(xy 76.60842 -65.146327) (xy 76.632851 -65.195947) (xy 76.649861 -65.248575) (xy 76.659096 -65.303107)
			(xy 76.66036 -65.3584) (xy 76.653629 -65.413297) (xy 76.639042 -65.466648) (xy 76.616906 -65.517333)
			(xy 76.587685 -65.564291) (xy 76.55199 -65.606539) (xy 76.551286 -65.607162) (xy 79.038831 -65.607162)
			(xy 79.044955 -65.551975) (xy 79.059011 -65.498258) (xy 79.080704 -65.447145) (xy 79.109575 -65.399715)
			(xy 79.145014 -65.356969) (xy 79.186274 -65.319811) (xy 79.232483 -65.289024) (xy 79.282666 -65.265259)
			(xy 79.335763 -65.249017) (xy 79.390654 -65.240641) (xy 79.446179 -65.240309) (xy 79.501166 -65.248026)
			(xy 79.554454 -65.263631) (xy 79.604918 -65.286793) (xy 79.651493 -65.317023) (xy 79.693195 -65.353685)
			(xy 79.71155 -65.37452) (xy 79.722277 -65.386409) (xy 79.748429 -65.40487) (xy 79.778356 -65.416235)
			(xy 79.81017 -65.419787) (xy 79.841867 -65.415303) (xy 79.871447 -65.403065) (xy 79.884524 -65.393824)
			(xy 79.907034 -65.37756) (xy 79.955762 -65.350927) (xy 80.007834 -65.331637) (xy 80.062153 -65.320098)
			(xy 80.11757 -65.316552) (xy 80.172917 -65.321075) (xy 80.227023 -65.333571) (xy 80.278748 -65.353776)
			(xy 80.326998 -65.381264) (xy 80.370755 -65.415454) (xy 80.409095 -65.455625) (xy 80.441209 -65.500928)
			(xy 80.466418 -65.550407) (xy 80.484191 -65.603017) (xy 80.494152 -65.657647) (xy 80.49609 -65.713144)
			(xy 80.489965 -65.768336) (xy 80.475906 -65.822058) (xy 80.45421 -65.873175) (xy 80.425335 -65.920608)
			(xy 80.389891 -65.963356) (xy 80.348626 -66.000516) (xy 80.302411 -66.031304) (xy 80.252222 -66.055068)
			(xy 80.199119 -66.071309) (xy 80.144224 -66.079682) (xy 80.088694 -66.080011) (xy 80.033702 -66.072289)
			(xy 79.980411 -66.056679) (xy 79.929944 -66.033511) (xy 79.883368 -66.003273) (xy 79.841665 -65.966605)
			(xy 79.82331 -65.945766) (xy 79.812615 -65.933844) (xy 79.786457 -65.915373) (xy 79.756522 -65.904006)
			(xy 79.724698 -65.900458) (xy 79.692994 -65.904954) (xy 79.663411 -65.91721) (xy 79.650336 -65.926462)
			(xy 79.627835 -65.942734) (xy 79.579111 -65.969362) (xy 79.527041 -65.988647) (xy 79.472727 -66.000183)
			(xy 79.417315 -66.003727) (xy 79.361973 -65.999202) (xy 79.307872 -65.986706) (xy 79.256153 -65.966501)
			(xy 79.207908 -65.939014) (xy 79.164155 -65.904826) (xy 79.125819 -65.864658) (xy 79.093708 -65.819359)
			(xy 79.068501 -65.769884) (xy 79.05073 -65.717279) (xy 79.04077 -65.662654) (xy 79.038831 -65.607162)
			(xy 76.551286 -65.607162) (xy 76.510569 -65.643191) (xy 76.464291 -65.673479) (xy 76.414126 -65.696768)
			(xy 76.361123 -65.712571) (xy 76.306394 -65.720556) (xy 76.251086 -65.720556) (xy 76.196357 -65.712571)
			(xy 76.143354 -65.696768) (xy 76.093189 -65.673479) (xy 76.046911 -65.643191) (xy 76.00549 -65.606539)
			(xy 75.969795 -65.564291) (xy 75.940574 -65.517333) (xy 75.918438 -65.466648) (xy 75.903851 -65.413297)
			(xy 75.89712 -65.3584) (xy 75.898384 -65.303107) (xy 75.907619 -65.248575) (xy 75.924629 -65.195947)
			(xy 75.94906 -65.146327) (xy 75.980398 -65.100754) (xy 75.998832 -65.080134) (xy 76.014581 -65.06239)
			(xy 76.039772 -65.02219) (xy 76.057067 -64.978014) (xy 76.065865 -64.931397) (xy 76.065861 -64.883956)
			(xy 76.057054 -64.83734) (xy 76.039751 -64.793168) (xy 76.014552 -64.752973) (xy 75.998832 -64.735202)
			(xy 75.980651 -64.714799) (xy 75.94963 -64.669808) (xy 75.925343 -64.620854) (xy 75.908286 -64.568936)
			(xy 75.898807 -64.515117) (xy 75.8971 -64.460495) (xy 75.903201 -64.406189) (xy 75.916983 -64.353308)
			(xy 75.938167 -64.302932) (xy 75.951842 -64.279272) (xy 75.962852 -64.260099) (xy 75.978745 -64.218845)
			(xy 75.987253 -64.175462) (xy 75.988119 -64.131261) (xy 75.981316 -64.087578) (xy 75.967051 -64.045733)
			(xy 75.945754 -64.006991) (xy 75.932284 -63.989458) (xy 75.914773 -63.9667) (xy 75.88598 -63.91702)
			(xy 75.864952 -63.863589) (xy 75.852164 -63.807611) (xy 75.847904 -63.750349) (xy 75.852269 -63.693095)
			(xy 75.86516 -63.63714) (xy 75.886286 -63.583748) (xy 75.90028 -63.558674) (xy 75.91152 -63.538243)
			(xy 75.927281 -63.494364) (xy 75.934776 -63.448346) (xy 75.933754 -63.401734) (xy 75.924248 -63.35609)
			(xy 75.906578 -63.312944) (xy 75.881337 -63.273744) (xy 75.865736 -63.256414) (xy 75.855918 -63.245858)
			(xy 75.837738 -63.22348) (xy 75.829414 -63.21171) (xy 75.819984 -63.198882) (xy 75.795926 -63.17804)
			(xy 75.767456 -63.163805) (xy 75.736348 -63.157063) (xy 75.704539 -63.158234) (xy 75.674011 -63.167246)
			(xy 75.646665 -63.183537) (xy 75.624205 -63.206092) (xy 75.60803 -63.233506) (xy 75.599148 -63.264072)
			(xy 75.598111 -63.295886) (xy 75.601068 -63.311532) (xy 75.606631 -63.338597) (xy 75.610742 -63.393698)
			(xy 75.606863 -63.448816) (xy 75.595076 -63.502798) (xy 75.575627 -63.554516) (xy 75.548923 -63.602889)
			(xy 75.515522 -63.646905) (xy 75.496166 -63.666624) (xy 75.480322 -63.682882) (xy 75.454116 -63.719947)
			(xy 75.434904 -63.761075) (xy 75.423296 -63.804959) (xy 75.419661 -63.850207) (xy 75.424115 -63.895381)
			(xy 75.436515 -63.939048) (xy 75.456469 -63.979821) (xy 75.483342 -64.016405) (xy 75.499468 -64.032384)
			(xy 75.51908 -64.05161) (xy 75.55315 -64.094683) (xy 75.580691 -64.142197) (xy 75.601133 -64.193169)
			(xy 75.614055 -64.246546) (xy 75.619189 -64.301224) (xy 75.616428 -64.356074) (xy 75.605831 -64.40996)
			(xy 75.587616 -64.46177) (xy 75.562159 -64.510433) (xy 75.529988 -64.554941) (xy 75.491766 -64.594377)
			(xy 75.448283 -64.627923) (xy 75.40044 -64.654888) (xy 75.349225 -64.674713) (xy 75.295695 -64.686988)
			(xy 75.240959 -64.691461) (xy 75.186147 -64.688038) (xy 75.132392 -64.67679) (xy 75.080806 -64.65795)
			(xy 75.032455 -64.631907) (xy 74.988339 -64.599199) (xy 74.949368 -64.560503) (xy 74.91635 -64.516619)
			(xy 74.889965 -64.468453) (xy 74.870761 -64.417002) (xy 74.859133 -64.363328) (xy 74.855323 -64.308542)
			(xy 74.859408 -64.253775) (xy 74.871305 -64.20016) (xy 74.890767 -64.148806) (xy 74.917393 -64.100773)
			(xy 74.950631 -64.057055) (xy 74.969878 -64.037464) (xy 74.985738 -64.021219) (xy 75.011949 -63.984153)
			(xy 75.031165 -63.943024) (xy 75.042774 -63.899136) (xy 75.046408 -63.853885) (xy 75.041952 -63.808707)
			(xy 75.029547 -63.765038) (xy 75.009587 -63.724265) (xy 74.982706 -63.687682) (xy 74.966576 -63.671704)
			(xy 74.946974 -63.652505) (xy 74.912919 -63.609485) (xy 74.885379 -63.56203) (xy 74.86492 -63.511119)
			(xy 74.851966 -63.457803) (xy 74.846783 -63.40318) (xy 68.50573 -63.40318) (xy 68.472869 -63.414514)
			(xy 68.417839 -63.424838) (xy 68.361891 -63.427008) (xy 68.306226 -63.420977) (xy 68.27901 -63.414402)
			(xy 68.255679 -63.408951) (xy 68.207874 -63.405856) (xy 68.160336 -63.411769) (xy 68.114746 -63.426481)
			(xy 68.072718 -63.449471) (xy 68.035739 -63.479925) (xy 68.005118 -63.516766) (xy 67.981938 -63.55869)
			(xy 67.973956 -63.58128) (xy 67.964919 -63.607386) (xy 67.94031 -63.656848) (xy 67.908824 -63.702243)
			(xy 67.871119 -63.742621) (xy 67.827985 -63.777139) (xy 67.780323 -63.805073) (xy 67.729129 -63.825841)
			(xy 67.675476 -63.839007) (xy 67.620484 -63.844297) (xy 67.565305 -63.841599) (xy 67.511092 -63.830971)
			(xy 67.458979 -63.812633) (xy 67.410055 -63.786971) (xy 67.365345 -63.75452) (xy 67.325784 -63.715959)
			(xy 67.292198 -63.672095) (xy 67.26529 -63.623846) (xy 67.245623 -63.57222) (xy 67.233609 -63.518296)
			(xy 67.229498 -63.463204) (xy 60.743725 -63.463204) (xy 60.74076 -63.493254) (xy 60.727656 -63.546402)
			(xy 60.707092 -63.597132) (xy 60.679489 -63.644402) (xy 60.66282 -63.666116) (xy 60.648533 -63.684997)
			(xy 60.626431 -63.726862) (xy 60.612467 -63.772096) (xy 60.607125 -63.819134) (xy 60.61059 -63.866347)
			(xy 60.622742 -63.912102) (xy 60.64316 -63.954813) (xy 60.656724 -63.974218) (xy 60.672518 -63.996581)
			(xy 60.698209 -64.044928) (xy 60.716727 -64.09645) (xy 60.727691 -64.150089) (xy 60.730878 -64.204745)
			(xy 60.730327 -64.2112) (xy 68.010784 -64.2112) (xy 68.014855 -64.155578) (xy 68.026981 -64.101141)
			(xy 68.046904 -64.04905) (xy 68.0742 -64.000415) (xy 68.108286 -63.956272) (xy 68.148435 -63.917563)
			(xy 68.193793 -63.885112) (xy 68.243393 -63.859611) (xy 68.296177 -63.841604) (xy 68.35102 -63.831474)
			(xy 68.406754 -63.829437) (xy 68.462191 -63.835537) (xy 68.516148 -63.849643) (xy 68.567477 -63.871455)
			(xy 68.615083 -63.900509) (xy 68.657951 -63.936184) (xy 68.695168 -63.977721) (xy 68.725941 -64.024234)
			(xy 68.749613 -64.074731) (xy 68.765681 -64.128138) (xy 68.76856 -64.1477) (xy 69.951598 -64.1477)
			(xy 69.955669 -64.092078) (xy 69.967795 -64.037641) (xy 69.987718 -63.98555) (xy 70.015014 -63.936915)
			(xy 70.0491 -63.892772) (xy 70.089249 -63.854063) (xy 70.134607 -63.821612) (xy 70.184207 -63.796111)
			(xy 70.236991 -63.778104) (xy 70.291834 -63.767974) (xy 70.347568 -63.765937) (xy 70.403005 -63.772037)
			(xy 70.456962 -63.786143) (xy 70.508291 -63.807955) (xy 70.555897 -63.837009) (xy 70.598765 -63.872684)
			(xy 70.615775 -63.891668) (xy 71.667622 -63.891668) (xy 71.671693 -63.836046) (xy 71.683819 -63.781609)
			(xy 71.703742 -63.729518) (xy 71.731038 -63.680883) (xy 71.765124 -63.63674) (xy 71.805273 -63.598031)
			(xy 71.850631 -63.56558) (xy 71.900231 -63.540079) (xy 71.953015 -63.522072) (xy 72.007858 -63.511942)
			(xy 72.063592 -63.509905) (xy 72.119029 -63.516005) (xy 72.172986 -63.530111) (xy 72.224315 -63.551923)
			(xy 72.271921 -63.580977) (xy 72.314789 -63.616652) (xy 72.352006 -63.658189) (xy 72.382779 -63.704702)
			(xy 72.406451 -63.755199) (xy 72.422519 -63.808606) (xy 72.430639 -63.863782) (xy 72.431148 -63.891668)
			(xy 72.430639 -63.919554) (xy 72.422519 -63.97473) (xy 72.406451 -64.028137) (xy 72.382779 -64.078634)
			(xy 72.352006 -64.125147) (xy 72.314789 -64.166684) (xy 72.271921 -64.202359) (xy 72.224315 -64.231413)
			(xy 72.172986 -64.253225) (xy 72.119029 -64.267331) (xy 72.063592 -64.273431) (xy 72.007858 -64.271394)
			(xy 71.953015 -64.261264) (xy 71.900231 -64.243257) (xy 71.850631 -64.217756) (xy 71.805273 -64.185305)
			(xy 71.765124 -64.146596) (xy 71.731038 -64.102453) (xy 71.703742 -64.053818) (xy 71.683819 -64.001727)
			(xy 71.671693 -63.94729) (xy 71.667622 -63.891668) (xy 70.615775 -63.891668) (xy 70.635982 -63.914221)
			(xy 70.666755 -63.960734) (xy 70.690427 -64.011231) (xy 70.706495 -64.064638) (xy 70.714615 -64.119814)
			(xy 70.715124 -64.1477) (xy 70.714615 -64.175586) (xy 70.706495 -64.230762) (xy 70.690427 -64.284169)
			(xy 70.666755 -64.334666) (xy 70.635982 -64.381179) (xy 70.598765 -64.422716) (xy 70.555897 -64.458391)
			(xy 70.508291 -64.487445) (xy 70.456962 -64.509257) (xy 70.403005 -64.523363) (xy 70.347568 -64.529463)
			(xy 70.291834 -64.527426) (xy 70.236991 -64.517296) (xy 70.184207 -64.499289) (xy 70.134607 -64.473788)
			(xy 70.089249 -64.441337) (xy 70.0491 -64.402628) (xy 70.015014 -64.358485) (xy 69.987718 -64.30985)
			(xy 69.967795 -64.257759) (xy 69.955669 -64.203322) (xy 69.951598 -64.1477) (xy 68.76856 -64.1477)
			(xy 68.773801 -64.183314) (xy 68.77431 -64.2112) (xy 68.773801 -64.239086) (xy 68.765681 -64.294262)
			(xy 68.749613 -64.347669) (xy 68.725941 -64.398166) (xy 68.695168 -64.444679) (xy 68.657951 -64.486216)
			(xy 68.615083 -64.521891) (xy 68.567477 -64.550945) (xy 68.516148 -64.572757) (xy 68.462191 -64.586863)
			(xy 68.406754 -64.592963) (xy 68.35102 -64.590926) (xy 68.296177 -64.580796) (xy 68.243393 -64.562789)
			(xy 68.193793 -64.537288) (xy 68.148435 -64.504837) (xy 68.108286 -64.466128) (xy 68.0742 -64.421985)
			(xy 68.046904 -64.37335) (xy 68.026981 -64.321259) (xy 68.014855 -64.266822) (xy 68.010784 -64.2112)
			(xy 60.730327 -64.2112) (xy 60.726221 -64.259296) (xy 60.713816 -64.31262) (xy 60.693917 -64.363625)
			(xy 60.666934 -64.411262) (xy 60.633419 -64.454555) (xy 60.594062 -64.492613) (xy 60.54967 -64.524656)
			(xy 60.501154 -64.550026) (xy 60.449511 -64.568202) (xy 60.3958 -64.578811) (xy 60.341124 -64.581635)
			(xy 60.286606 -64.576617) (xy 60.233364 -64.563859) (xy 60.182492 -64.543623) (xy 60.135035 -64.516325)
			(xy 60.091966 -64.482524) (xy 60.054169 -64.442916) (xy 60.022421 -64.398312) (xy 59.997373 -64.349629)
			(xy 59.979539 -64.297867) (xy 59.969286 -64.244087) (xy 59.966824 -64.189393) (xy 56.202952 -64.189393)
			(xy 56.202868 -64.204949) (xy 56.194683 -64.25931) (xy 56.17878 -64.311933) (xy 56.155489 -64.361729)
			(xy 56.125291 -64.407666) (xy 56.088813 -64.448794) (xy 56.04681 -64.484259) (xy 56.00015 -64.513329)
			(xy 55.949802 -64.5354) (xy 55.923434 -64.543178) (xy 55.893428 -64.550815) (xy 55.831867 -64.557401)
			(xy 55.770049 -64.553967) (xy 55.709596 -64.540603) (xy 55.68061 -64.529716) (xy 55.65775 -64.520572)
			(xy 55.633366 -64.520572) (xy 55.616719 -64.521119) (xy 55.584562 -64.529742) (xy 55.55573 -64.546392)
			(xy 55.532188 -64.569935) (xy 55.51554 -64.598767) (xy 55.506918 -64.630925) (xy 55.506366 -64.647572)
			(xy 55.506366 -64.744854) (xy 55.55869 -64.812926) (xy 55.600346 -64.824356) (xy 55.6006 -64.824356)
			(xy 55.627222 -64.832068) (xy 55.678069 -64.854124) (xy 55.725191 -64.883304) (xy 55.767595 -64.918995)
			(xy 55.804389 -64.960445) (xy 55.834799 -65.006782) (xy 55.858185 -65.057031) (xy 55.874055 -65.110135)
			(xy 55.882076 -65.164976) (xy 55.882077 -65.220401) (xy 55.87406 -65.275243) (xy 55.858193 -65.328348)
			(xy 55.83481 -65.378598) (xy 55.804403 -65.424937) (xy 55.767611 -65.466389) (xy 55.725209 -65.502082)
			(xy 55.67809 -65.531265) (xy 55.627244 -65.553324) (xy 55.6006 -65.560956) (xy 55.600346 -65.560956)
			(xy 55.55869 -65.572386) (xy 55.506366 -65.640458) (xy 55.506366 -65.759838) (xy 55.506951 -65.777598)
			(xy 55.516749 -65.811739) (xy 55.5356 -65.841844) (xy 55.562035 -65.865567) (xy 55.57774 -65.873884)
			(xy 55.602306 -65.886377) (xy 55.647879 -65.917367) (xy 55.688525 -65.954586) (xy 55.723399 -65.99726)
			(xy 55.751778 -66.044504) (xy 55.762906 -66.069718) (xy 55.773526 -66.096429) (xy 55.787518 -66.15218)
			(xy 55.792985 -66.209399) (xy 55.7898 -66.266791) (xy 55.778037 -66.323054) (xy 55.757963 -66.376915)
			(xy 55.730031 -66.427152) (xy 55.712868 -66.45021) (xy 55.70014 -66.468836) (xy 55.680779 -66.509578)
			(xy 55.668916 -66.553099) (xy 55.664923 -66.598031) (xy 55.668927 -66.642962) (xy 55.6808 -66.68648)
			(xy 55.700171 -66.727217) (xy 55.712868 -66.745866) (xy 55.730181 -66.769164) (xy 55.758295 -66.819944)
			(xy 55.77839 -66.874398) (xy 55.79 -66.931268) (xy 55.792284 -66.977623) (xy 56.496284 -66.977623)
			(xy 56.49836 -66.92237) (xy 56.508391 -66.867996) (xy 56.526169 -66.81564) (xy 56.55132 -66.766399)
			(xy 56.583316 -66.721305) (xy 56.621488 -66.681304) (xy 56.665036 -66.647233) (xy 56.713046 -66.619807)
			(xy 56.764514 -66.5996) (xy 56.818359 -66.587036) (xy 56.873455 -66.582378) (xy 56.90108 -66.58356)
			(xy 56.918234 -66.58399) (xy 56.951777 -66.576831) (xy 56.982203 -66.560999) (xy 57.007315 -66.537638)
			(xy 57.025302 -66.508433) (xy 57.03062 -66.49212) (xy 57.040949 -66.459205) (xy 57.071744 -66.397482)
			(xy 57.091834 -66.369438) (xy 57.105393 -66.350401) (xy 57.126125 -66.308524) (xy 57.138854 -66.263562)
			(xy 57.143148 -66.21703) (xy 57.138865 -66.170498) (xy 57.126147 -66.125533) (xy 57.105424 -66.083651)
			(xy 57.091834 -66.064638) (xy 57.07445 -66.040418) (xy 57.046566 -65.987729) (xy 57.027222 -65.931341)
			(xy 57.01689 -65.872631) (xy 57.01582 -65.813027) (xy 57.02404 -65.753984) (xy 57.032144 -65.725294)
			(xy 57.036292 -65.710056) (xy 57.037763 -65.678519) (xy 57.03143 -65.647589) (xy 57.017683 -65.619167)
			(xy 56.997367 -65.595001) (xy 56.97173 -65.576575) (xy 56.957214 -65.570354) (xy 56.931738 -65.559698)
			(xy 56.883859 -65.532189) (xy 56.840446 -65.498064) (xy 56.802408 -65.458037) (xy 56.770538 -65.412943)
			(xy 56.745502 -65.363725) (xy 56.727824 -65.311412) (xy 56.717874 -65.257097) (xy 56.715858 -65.201915)
			(xy 56.72182 -65.147018) (xy 56.735635 -65.093555) (xy 56.757013 -65.042642) (xy 56.785509 -64.995343)
			(xy 56.820526 -64.952648) (xy 56.861333 -64.915447) (xy 56.907078 -64.884518) (xy 56.956804 -64.860508)
			(xy 57.009472 -64.843918) (xy 57.063982 -64.835095) (xy 57.119194 -64.834224) (xy 57.173955 -64.841322)
			(xy 57.227121 -64.856242) (xy 57.27758 -64.878671) (xy 57.324277 -64.90814) (xy 57.366238 -64.944035)
			(xy 57.402586 -64.985605) (xy 57.43256 -65.031981) (xy 57.455534 -65.082193) (xy 57.471029 -65.135194)
			(xy 57.47872 -65.189875) (xy 57.478447 -65.245094) (xy 57.470215 -65.299696) (xy 57.462674 -65.32626)
			(xy 57.458564 -65.341508) (xy 57.457083 -65.373041) (xy 57.463407 -65.403968) (xy 57.477147 -65.432389)
			(xy 57.497457 -65.456554) (xy 57.52309 -65.474979) (xy 57.537604 -65.4812) (xy 57.562523 -65.491521)
			(xy 57.609386 -65.518222) (xy 57.65202 -65.55126) (xy 57.689572 -65.589976) (xy 57.721295 -65.633597)
			(xy 57.746555 -65.681253) (xy 57.764848 -65.731993) (xy 57.775809 -65.784804) (xy 57.779219 -65.838632)
			(xy 57.775011 -65.892404) (xy 57.763268 -65.945047) (xy 57.744224 -65.995509) (xy 57.71826 -66.042785)
			(xy 57.70245 -66.064638) (xy 57.688822 -66.083627) (xy 57.668096 -66.125517) (xy 57.655377 -66.17049)
			(xy 57.651093 -66.21703) (xy 57.655388 -66.26357) (xy 57.668118 -66.308539) (xy 57.688853 -66.350425)
			(xy 57.70245 -66.369438) (xy 57.718321 -66.391435) (xy 57.744362 -66.439016) (xy 57.763398 -66.489806)
			(xy 57.775048 -66.542781) (xy 57.778064 -66.583305) (xy 58.482324 -66.583305) (xy 58.486212 -66.528943)
			(xy 58.4978 -66.475689) (xy 58.51685 -66.424627) (xy 58.542975 -66.376796) (xy 58.558938 -66.354706)
			(xy 58.572526 -66.335689) (xy 58.593256 -66.293806) (xy 58.605981 -66.24884) (xy 58.610271 -66.202305)
			(xy 58.605982 -66.15577) (xy 58.593259 -66.110803) (xy 58.572531 -66.068919) (xy 58.558938 -66.049906)
			(xy 58.543061 -66.027831) (xy 58.516976 -65.980125) (xy 58.49793 -65.929198) (xy 58.486307 -65.876082)
			(xy 58.482344 -65.821854) (xy 58.486121 -65.767613) (xy 58.497562 -65.714458) (xy 58.516434 -65.663466)
			(xy 58.542355 -65.61567) (xy 58.574801 -65.57204) (xy 58.613112 -65.533458) (xy 58.656514 -65.500707)
			(xy 58.704127 -65.47445) (xy 58.754985 -65.45522) (xy 58.808058 -65.443407) (xy 58.862272 -65.439249)
			(xy 58.916526 -65.442831) (xy 58.969722 -65.45408) (xy 59.020781 -65.472769) (xy 59.06867 -65.498518)
			(xy 59.112417 -65.530806) (xy 59.151137 -65.568979) (xy 59.184044 -65.612263) (xy 59.210471 -65.65978)
			(xy 59.229884 -65.710569) (xy 59.236356 -65.736978) (xy 59.240059 -65.751285) (xy 59.252984 -65.777847)
			(xy 59.271679 -65.800718) (xy 59.29514 -65.818668) (xy 59.322104 -65.830732) (xy 59.351122 -65.836262)
			(xy 59.365896 -65.836038) (xy 59.39283 -65.835183) (xy 59.446476 -65.840311) (xy 59.498866 -65.852938)
			(xy 59.548958 -65.872814) (xy 59.595753 -65.899542) (xy 59.63832 -65.93259) (xy 59.675813 -65.9713)
			(xy 59.707483 -66.014902) (xy 59.732702 -66.062528) (xy 59.750966 -66.113229) (xy 59.761913 -66.165996)
			(xy 59.765324 -66.219778) (xy 59.761131 -66.273505) (xy 59.749418 -66.326108) (xy 59.730418 -66.376537)
			(xy 59.704509 -66.423791) (xy 59.68873 -66.445638) (xy 59.675098 -66.464625) (xy 59.654366 -66.506515)
			(xy 59.641643 -66.551489) (xy 59.637357 -66.59803) (xy 59.641654 -66.644571) (xy 59.654388 -66.689542)
			(xy 59.67513 -66.731426) (xy 59.68873 -66.750438) (xy 59.70454 -66.772475) (xy 59.730572 -66.82005)
			(xy 59.749602 -66.870834) (xy 59.761246 -66.923801) (xy 59.765269 -66.977884) (xy 59.76159 -67.031991)
			(xy 59.750284 -67.085031) (xy 59.731578 -67.135935) (xy 59.70585 -67.183676) (xy 59.673619 -67.22729)
			(xy 59.635534 -67.265899) (xy 59.592364 -67.298724) (xy 59.544979 -67.325102) (xy 59.494336 -67.344502)
			(xy 59.441455 -67.356532) (xy 59.387403 -67.36095) (xy 59.360308 -67.359784) (xy 59.343153 -67.359311)
			(xy 59.309604 -67.366477) (xy 59.279175 -67.382318) (xy 59.254063 -67.40569) (xy 59.236082 -67.434905)
			(xy 59.230768 -67.451224) (xy 59.222526 -67.477831) (xy 59.199443 -67.52852) (xy 59.169234 -67.575313)
			(xy 59.13254 -67.617215) (xy 59.090143 -67.653335) (xy 59.042943 -67.682905) (xy 58.991945 -67.705296)
			(xy 58.938232 -67.720033) (xy 58.882948 -67.726801) (xy 58.827266 -67.725457) (xy 58.772373 -67.716029)
			(xy 58.719434 -67.698718) (xy 58.669575 -67.673892) (xy 58.623857 -67.642079) (xy 58.583252 -67.603955)
			(xy 58.548623 -67.560331) (xy 58.520706 -67.512135) (xy 58.500096 -67.460391) (xy 58.48723 -67.4062)
			(xy 58.482382 -67.350714) (xy 58.485655 -67.295113) (xy 58.49698 -67.240579) (xy 58.516115 -67.188272)
			(xy 58.542654 -67.139304) (xy 58.558938 -67.116706) (xy 58.572526 -67.097689) (xy 58.593256 -67.055806)
			(xy 58.605981 -67.01084) (xy 58.610271 -66.964305) (xy 58.605982 -66.91777) (xy 58.593259 -66.872803)
			(xy 58.572531 -66.830919) (xy 58.558938 -66.811906) (xy 58.54298 -66.789812) (xy 58.516854 -66.741982)
			(xy 58.497802 -66.69092) (xy 58.486214 -66.637666) (xy 58.482324 -66.583305) (xy 57.778064 -66.583305)
			(xy 57.779074 -66.596872) (xy 57.775396 -66.650988) (xy 57.764088 -66.704036) (xy 57.745378 -66.754948)
			(xy 57.719643 -66.802695) (xy 57.687404 -66.846315) (xy 57.64931 -66.884927) (xy 57.60613 -66.917752)
			(xy 57.558734 -66.944128) (xy 57.50808 -66.963524) (xy 57.455188 -66.975547) (xy 57.401127 -66.979955)
			(xy 57.374028 -66.978784) (xy 57.356873 -66.97833) (xy 57.323326 -66.98549) (xy 57.292897 -67.001326)
			(xy 57.267784 -67.024695) (xy 57.249803 -67.053907) (xy 57.244488 -67.070224) (xy 57.236292 -67.096633)
			(xy 57.213431 -67.146977) (xy 57.183541 -67.193494) (xy 57.147248 -67.235207) (xy 57.105312 -67.271243)
			(xy 57.058613 -67.300847) (xy 57.008128 -67.323398) (xy 56.954917 -67.338424) (xy 56.900094 -67.345609)
			(xy 56.844808 -67.344804) (xy 56.790217 -67.336025) (xy 56.737466 -67.319455) (xy 56.68766 -67.295443)
			(xy 56.641843 -67.264492) (xy 56.600975 -67.227249) (xy 56.565912 -67.184496) (xy 56.53739 -67.137129)
			(xy 56.516005 -67.086139) (xy 56.502207 -67.032597) (xy 56.496284 -66.977623) (xy 55.792284 -66.977623)
			(xy 55.792857 -66.98924) (xy 55.786896 -67.046977) (xy 55.772254 -67.103142) (xy 55.749269 -67.156441)
			(xy 55.718473 -67.20564) (xy 55.699914 -67.227958) (xy 55.667402 -67.265804) (xy 55.670958 -67.365372)
			(xy 56.379872 -68.074286) (xy 60.22213 -68.074286) (xy 60.243672 -68.073837) (xy 60.286138 -68.066577)
			(xy 60.326771 -68.052254) (xy 60.364403 -68.031279) (xy 60.397954 -68.004253) (xy 60.426463 -67.971951)
			(xy 60.449112 -67.935302) (xy 60.465249 -67.895356) (xy 60.474414 -67.853259) (xy 60.476341 -67.810219)
			(xy 60.474098 -67.78879) (xy 60.470238 -67.762925) (xy 60.468799 -67.710648) (xy 60.474516 -67.658665)
			(xy 60.487283 -67.607951) (xy 60.506859 -67.559457) (xy 60.532879 -67.514093) (xy 60.54852 -67.493134)
			(xy 60.561253 -67.474508) (xy 60.580622 -67.433764) (xy 60.592493 -67.390241) (xy 60.596493 -67.345305)
			(xy 60.592495 -67.300369) (xy 60.580626 -67.256845) (xy 60.561258 -67.2161) (xy 60.54852 -67.197478)
			(xy 60.531879 -67.175095) (xy 60.504583 -67.126459) (xy 60.48466 -67.074366) (xy 60.472533 -67.019928)
			(xy 60.468461 -66.964305) (xy 60.472531 -66.908681) (xy 60.484657 -66.854243) (xy 60.504579 -66.80215)
			(xy 60.531874 -66.753513) (xy 60.54852 -66.731134) (xy 60.561253 -66.712508) (xy 60.580622 -66.671764)
			(xy 60.592493 -66.628241) (xy 60.596493 -66.583305) (xy 60.592495 -66.538369) (xy 60.580626 -66.494845)
			(xy 60.561258 -66.4541) (xy 60.54852 -66.435478) (xy 60.531879 -66.413095) (xy 60.504583 -66.364459)
			(xy 60.48466 -66.312366) (xy 60.472533 -66.257928) (xy 60.468461 -66.202305) (xy 60.472531 -66.146681)
			(xy 60.484657 -66.092243) (xy 60.504579 -66.04015) (xy 60.531874 -65.991513) (xy 60.54852 -65.969134)
			(xy 60.561253 -65.950508) (xy 60.580622 -65.909764) (xy 60.592493 -65.866241) (xy 60.596493 -65.821305)
			(xy 60.592495 -65.776369) (xy 60.580626 -65.732845) (xy 60.561258 -65.6921) (xy 60.54852 -65.673478)
			(xy 60.532889 -65.652498) (xy 60.506905 -65.607089) (xy 60.487368 -65.558556) (xy 60.474646 -65.507809)
			(xy 60.468976 -65.455799) (xy 60.469272 -65.429638) (xy 60.470486 -65.402542) (xy 60.479626 -65.34908)
			(xy 60.496248 -65.297453) (xy 60.520018 -65.248701) (xy 60.550454 -65.203809) (xy 60.586944 -65.163681)
			(xy 60.628751 -65.129129) (xy 60.675031 -65.100847) (xy 60.724851 -65.079408) (xy 60.777207 -65.065244)
			(xy 60.831041 -65.05864) (xy 60.885267 -65.05973) (xy 60.938792 -65.068492) (xy 60.990536 -65.084748)
			(xy 61.039455 -65.108172) (xy 61.084562 -65.13829) (xy 61.105034 -65.15608) (xy 61.126648 -65.176168)
			(xy 61.164024 -65.221827) (xy 61.193917 -65.2727) (xy 61.215614 -65.327572) (xy 61.222636 -65.356232)
			(xy 61.232796 -65.40119) (xy 61.269372 -65.42913) (xy 61.281425 -65.437752) (xy 61.3085 -65.449779)
			(xy 61.337613 -65.455276) (xy 61.35243 -65.455038) (xy 61.379535 -65.454293) (xy 61.433503 -65.459546)
			(xy 61.486183 -65.472387) (xy 61.536514 -65.492556) (xy 61.583484 -65.519648) (xy 61.626145 -65.553116)
			(xy 61.663637 -65.592287) (xy 61.695207 -65.636371) (xy 61.720218 -65.684481) (xy 61.738166 -65.735647)
			(xy 61.748689 -65.788839) (xy 61.750451 -65.821881) (xy 62.454785 -65.821881) (xy 62.458559 -65.76763)
			(xy 62.469999 -65.714464) (xy 62.488871 -65.663461) (xy 62.514795 -65.615655) (xy 62.547245 -65.572014)
			(xy 62.585562 -65.533423) (xy 62.628971 -65.500665) (xy 62.676592 -65.474401) (xy 62.727459 -65.455167)
			(xy 62.780542 -65.44335) (xy 62.834766 -65.43919) (xy 62.88903 -65.442772) (xy 62.942237 -65.454023)
			(xy 62.993306 -65.472715) (xy 63.041204 -65.498469) (xy 63.084959 -65.530764) (xy 63.123685 -65.568945)
			(xy 63.156598 -65.612237) (xy 63.183029 -65.659765) (xy 63.202444 -65.710564) (xy 63.208916 -65.736978)
			(xy 63.212562 -65.751302) (xy 63.225495 -65.777869) (xy 63.244201 -65.800742) (xy 63.267673 -65.818691)
			(xy 63.294649 -65.830749) (xy 63.323677 -65.836269) (xy 63.338456 -65.836038) (xy 63.365392 -65.835214)
			(xy 63.419037 -65.840337) (xy 63.471428 -65.85296) (xy 63.52152 -65.872831) (xy 63.568317 -65.899556)
			(xy 63.610886 -65.932602) (xy 63.648379 -65.97131) (xy 63.680051 -66.014911) (xy 63.70527 -66.062536)
			(xy 63.723535 -66.113236) (xy 63.734482 -66.166002) (xy 63.737892 -66.219784) (xy 63.733698 -66.273511)
			(xy 63.721983 -66.326112) (xy 63.702981 -66.37654) (xy 63.67707 -66.423792) (xy 63.66129 -66.445638)
			(xy 63.64766 -66.464626) (xy 63.626931 -66.506516) (xy 63.61421 -66.551489) (xy 63.609925 -66.59803)
			(xy 63.614221 -66.64457) (xy 63.626953 -66.689541) (xy 63.647691 -66.731426) (xy 63.66129 -66.750438)
			(xy 63.677151 -66.77252) (xy 63.703227 -66.820224) (xy 63.722265 -66.871148) (xy 63.733881 -66.924258)
			(xy 63.737838 -66.97848) (xy 63.734057 -67.032714) (xy 63.722614 -67.085862) (xy 63.703741 -67.136846)
			(xy 63.67782 -67.184635) (xy 63.645377 -67.228259) (xy 63.607069 -67.266835) (xy 63.563671 -67.299581)
			(xy 63.516064 -67.325834) (xy 63.465212 -67.345062) (xy 63.412145 -67.356875) (xy 63.357939 -67.361034)
			(xy 63.303691 -67.357454) (xy 63.250501 -67.346208) (xy 63.199447 -67.327525) (xy 63.151562 -67.301782)
			(xy 63.107818 -67.269501) (xy 63.0691 -67.231336) (xy 63.036192 -67.18806) (xy 63.009763 -67.140551)
			(xy 62.990347 -67.089771) (xy 62.983872 -67.063366) (xy 62.980274 -67.049029) (xy 62.967328 -67.022462)
			(xy 62.948612 -66.999591) (xy 62.92513 -66.981645) (xy 62.898147 -66.96959) (xy 62.869113 -66.964073)
			(xy 62.854332 -66.964306) (xy 62.827397 -66.965069) (xy 62.773757 -66.959945) (xy 62.721372 -66.947323)
			(xy 62.671285 -66.927453) (xy 62.624494 -66.900731) (xy 62.58193 -66.867689) (xy 62.544439 -66.828986)
			(xy 62.51277 -66.785391) (xy 62.487551 -66.737772) (xy 62.469286 -66.687078) (xy 62.458338 -66.634318)
			(xy 62.454925 -66.580543) (xy 62.459114 -66.526822) (xy 62.470823 -66.474225) (xy 62.489819 -66.4238)
			(xy 62.515722 -66.376551) (xy 62.531498 -66.354706) (xy 62.545088 -66.33569) (xy 62.565821 -66.293808)
			(xy 62.578548 -66.248841) (xy 62.582839 -66.202305) (xy 62.57855 -66.155769) (xy 62.565825 -66.110801)
			(xy 62.545093 -66.068918) (xy 62.531498 -66.049906) (xy 62.515531 -66.027893) (xy 62.489436 -65.980179)
			(xy 62.470382 -65.929244) (xy 62.458753 -65.876119) (xy 62.454785 -65.821881) (xy 61.750451 -65.821881)
			(xy 61.751576 -65.842984) (xy 61.746768 -65.896993) (xy 61.734363 -65.949777) (xy 61.714609 -66.000274)
			(xy 61.687906 -66.047465) (xy 61.671708 -66.06921) (xy 61.658978 -66.087836) (xy 61.639614 -66.128577)
			(xy 61.627749 -66.172099) (xy 61.623756 -66.217031) (xy 61.62776 -66.261962) (xy 61.639636 -66.305481)
			(xy 61.65901 -66.346218) (xy 61.671708 -66.364866) (xy 61.688025 -66.38676) (xy 61.714894 -66.434294)
			(xy 61.73471 -66.485174) (xy 61.747069 -66.538359) (xy 61.751719 -66.592763) (xy 61.748563 -66.647274)
			(xy 61.737667 -66.700779) (xy 61.719252 -66.752182) (xy 61.693697 -66.800435) (xy 61.661522 -66.844551)
			(xy 61.623386 -66.883628) (xy 61.580067 -66.916869) (xy 61.532451 -66.943592) (xy 61.481511 -66.963253)
			(xy 61.428288 -66.97545) (xy 61.37387 -66.979933) (xy 61.346588 -66.978784) (xy 61.329406 -66.978309)
			(xy 61.295802 -66.985469) (xy 61.265336 -67.001352) (xy 61.240224 -67.024802) (xy 61.222296 -67.054111)
			(xy 61.217048 -67.070478) (xy 61.212984 -67.083432) (xy 61.202196 -67.114038) (xy 61.171803 -67.171368)
			(xy 61.152532 -67.197478) (xy 61.139798 -67.216103) (xy 61.120427 -67.256846) (xy 61.108556 -67.300369)
			(xy 61.104557 -67.345305) (xy 61.108557 -67.39024) (xy 61.12043 -67.433763) (xy 61.139803 -67.474505)
			(xy 61.152532 -67.493134) (xy 61.169067 -67.515352) (xy 61.196212 -67.563626) (xy 61.216071 -67.615325)
			(xy 61.222636 -67.642232) (xy 61.232796 -67.686936) (xy 61.269372 -67.71513) (xy 61.281425 -67.723752)
			(xy 61.3085 -67.735779) (xy 61.337613 -67.741276) (xy 61.35243 -67.741038) (xy 61.378548 -67.740283)
			(xy 61.430579 -67.745063) (xy 61.481471 -67.756898) (xy 61.530272 -67.775566) (xy 61.576069 -67.800719)
			(xy 61.597286 -67.815968) (xy 61.619242 -67.832882) (xy 61.658496 -67.872008) (xy 61.691673 -67.916403)
			(xy 61.718075 -67.965133) (xy 61.728096 -67.990974) (xy 61.733853 -68.00537) (xy 61.751237 -68.031032)
			(xy 61.774292 -68.05175) (xy 61.801658 -68.066304) (xy 61.831725 -68.073837) (xy 61.847222 -68.074286)
			(xy 62.3951 -68.074286) (xy 62.461648 -68.02628) (xy 62.474602 -67.987164) (xy 62.483917 -67.960664)
			(xy 62.509225 -67.910518) (xy 62.541611 -67.864624) (xy 62.580375 -67.823973) (xy 62.624679 -67.789443)
			(xy 62.673565 -67.761781) (xy 62.725979 -67.741584) (xy 62.780787 -67.729289) (xy 62.836806 -67.725161)
			(xy 62.892825 -67.729289) (xy 62.947633 -67.741584) (xy 63.000047 -67.761781) (xy 63.048933 -67.789443)
			(xy 63.093237 -67.823973) (xy 63.132001 -67.864624) (xy 63.164387 -67.910518) (xy 63.189695 -67.960664)
			(xy 63.19901 -67.987164) (xy 63.20447 -68.00213) (xy 63.221641 -68.028952) (xy 63.244927 -68.050677)
			(xy 63.272874 -68.065946) (xy 63.303736 -68.073807) (xy 63.31966 -68.074286) (xy 64.236092 -68.074286)
			(xy 64.258119 -68.073834) (xy 64.301518 -68.066272) (xy 64.342963 -68.051338) (xy 64.381211 -68.02948)
			(xy 64.415116 -68.001353) (xy 64.443663 -67.9678) (xy 64.465994 -67.929827) (xy 64.481442 -67.888571)
			(xy 64.489543 -67.845269) (xy 64.490055 -67.801219) (xy 64.487044 -67.779392) (xy 64.482205 -67.752459)
			(xy 64.479385 -67.697811) (xy 64.484403 -67.64332) (xy 64.497158 -67.590107) (xy 64.517387 -67.539263)
			(xy 64.544676 -67.491831) (xy 64.578462 -67.448787) (xy 64.618054 -67.411014) (xy 64.662639 -67.379286)
			(xy 64.7113 -67.354257) (xy 64.763038 -67.336439) (xy 64.816792 -67.326198) (xy 64.871458 -67.323745)
			(xy 64.925913 -67.32913) (xy 64.97904 -67.342243) (xy 65.029747 -67.362814) (xy 65.076993 -67.39042)
			(xy 65.119809 -67.424496) (xy 65.157316 -67.464341) (xy 65.188742 -67.509138) (xy 65.213444 -67.557966)
			(xy 65.230913 -67.609823) (xy 65.236344 -67.636644) (xy 65.240013 -67.653485) (xy 65.255061 -67.684479)
			(xy 65.277844 -67.710324) (xy 65.306706 -67.72914) (xy 65.339547 -67.739558) (xy 65.35674 -67.740784)
			(xy 65.384908 -67.742364) (xy 65.440352 -67.752785) (xy 65.493659 -67.771251) (xy 65.543669 -67.797361)
			(xy 65.589291 -67.830545) (xy 65.629534 -67.870082) (xy 65.663521 -67.91511) (xy 65.690512 -67.964649)
			(xy 65.700656 -67.990974) (xy 65.706414 -68.005366) (xy 65.723801 -68.031019) (xy 65.746857 -68.051727)
			(xy 65.774224 -68.066269) (xy 65.804288 -68.073788) (xy 65.819782 -68.074286) (xy 65.930272 -68.074286)
			(xy 66.008504 -68.152518) (xy 66.024896 -68.168243) (xy 66.062176 -68.194187) (xy 66.103475 -68.21309)
			(xy 66.147476 -68.224349) (xy 66.192778 -68.227606) (xy 66.237937 -68.222757) (xy 66.281515 -68.209956)
			(xy 66.322123 -68.189611) (xy 66.358466 -68.162371) (xy 66.389388 -68.129104) (xy 66.413903 -68.090868)
			(xy 66.431229 -68.048884) (xy 66.436494 -68.026788) (xy 66.442745 -68.000157) (xy 66.461833 -67.948894)
			(xy 66.488032 -67.900874) (xy 66.504058 -67.878706) (xy 66.517656 -67.859695) (xy 66.538393 -67.817812)
			(xy 66.551122 -67.772843) (xy 66.555414 -67.726305) (xy 66.551124 -67.679767) (xy 66.538397 -67.634797)
			(xy 66.517661 -67.592913) (xy 66.504058 -67.573906) (xy 66.487974 -67.55166) (xy 66.461679 -67.503474)
			(xy 66.442564 -67.452015) (xy 66.431023 -67.398348) (xy 66.427296 -67.343581) (xy 66.431459 -67.288845)
			(xy 66.443426 -67.235271) (xy 66.46295 -67.183966) (xy 66.489628 -67.135991) (xy 66.522908 -67.092335)
			(xy 66.542158 -67.072764) (xy 66.559176 -67.056254) (xy 66.601848 -66.96202) (xy 66.574162 -66.883534)
			(xy 66.562986 -66.868294) (xy 66.552064 -66.8528) (xy 66.542321 -66.839016) (xy 66.516978 -66.816736)
			(xy 66.486678 -66.801885) (xy 66.453544 -66.795501) (xy 66.419895 -66.798032) (xy 66.388089 -66.809301)
			(xy 66.360352 -66.828518) (xy 66.349118 -66.841116) (xy 66.331219 -66.86163) (xy 66.290595 -66.897874)
			(xy 66.245231 -66.927974) (xy 66.196048 -66.951317) (xy 66.144045 -66.96743) (xy 66.09028 -66.975985)
			(xy 66.035844 -66.976809) (xy 65.981845 -66.969884) (xy 65.929379 -66.955351) (xy 65.879512 -66.933506)
			(xy 65.856104 -66.919602) (xy 65.837264 -66.908464) (xy 65.796668 -66.892122) (xy 65.753874 -66.88297)
			(xy 65.710144 -66.881278) (xy 65.666771 -66.887097) (xy 65.625034 -66.900255) (xy 65.586165 -66.920363)
			(xy 65.551312 -66.946827) (xy 65.536064 -66.962528) (xy 65.517127 -66.982204) (xy 65.474614 -67.01648)
			(xy 65.427649 -67.044344) (xy 65.377191 -67.065227) (xy 65.324271 -67.078703) (xy 65.26997 -67.084496)
			(xy 65.215398 -67.082487) (xy 65.16167 -67.072718) (xy 65.109884 -67.055389) (xy 65.061098 -67.030852)
			(xy 65.016308 -66.999611) (xy 64.976431 -66.962302) (xy 64.94228 -66.919689) (xy 64.914554 -66.872642)
			(xy 64.893819 -66.822123) (xy 64.880499 -66.769163) (xy 64.877188 -66.742056) (xy 64.873124 -66.702178)
			(xy 64.768984 -66.58229) (xy 64.730122 -66.572384) (xy 64.703226 -66.565109) (xy 64.651736 -66.543827)
			(xy 64.60389 -66.515281) (xy 64.560706 -66.480079) (xy 64.523101 -66.438968) (xy 64.491877 -66.392825)
			(xy 64.467698 -66.34263) (xy 64.451078 -66.289452) (xy 64.442371 -66.234422) (xy 64.441762 -66.178711)
			(xy 64.449263 -66.123503) (xy 64.464716 -66.069974) (xy 64.487792 -66.019263) (xy 64.517999 -65.972447)
			(xy 64.554695 -65.930524) (xy 64.597099 -65.894386) (xy 64.64431 -65.8648) (xy 64.695322 -65.842397)
			(xy 64.749051 -65.827653) (xy 64.804352 -65.820882) (xy 64.860051 -65.822228) (xy 64.887602 -65.826386)
			(xy 64.963294 -65.772792) (xy 64.97574 -65.73012) (xy 64.98463 -65.70345) (xy 64.989887 -65.687776)
			(xy 64.993052 -65.65488) (xy 64.987671 -65.622273) (xy 64.974104 -65.592139) (xy 64.953259 -65.566494)
			(xy 64.94018 -65.556384) (xy 64.918349 -65.539935) (xy 64.879176 -65.501814) (xy 64.845844 -65.458493)
			(xy 64.819036 -65.410858) (xy 64.799301 -65.359884) (xy 64.787043 -65.306616) (xy 64.782513 -65.252144)
			(xy 64.785803 -65.197583) (xy 64.796847 -65.14405) (xy 64.815417 -65.092641) (xy 64.841135 -65.044409)
			(xy 64.873473 -65.00034) (xy 64.911769 -64.961339) (xy 64.95524 -64.928202) (xy 65.002995 -64.901608)
			(xy 65.054056 -64.882102) (xy 65.107378 -64.870083) (xy 65.161871 -64.865797) (xy 65.216416 -64.869333)
			(xy 65.269899 -64.880616) (xy 65.321224 -64.899417) (xy 65.369341 -64.925351) (xy 65.413263 -64.957887)
			(xy 65.452093 -64.996358) (xy 65.485034 -65.039976) (xy 65.511413 -65.08785) (xy 65.53069 -65.138999)
			(xy 65.54247 -65.192374) (xy 65.546511 -65.246885) (xy 65.542731 -65.301415) (xy 65.531207 -65.354846)
			(xy 65.522094 -65.380616) (xy 65.516833 -65.396264) (xy 65.513664 -65.429112) (xy 65.519052 -65.46167)
			(xy 65.532632 -65.491747) (xy 65.553493 -65.517318) (xy 65.566544 -65.527428) (xy 65.589326 -65.544653)
			(xy 65.629996 -65.584748) (xy 65.664237 -65.630455) (xy 65.691285 -65.680755) (xy 65.710535 -65.734524)
			(xy 65.721558 -65.790561) (xy 65.724107 -65.847615) (xy 65.718126 -65.904412) (xy 65.703748 -65.959684)
			(xy 65.681294 -66.012196) (xy 65.651265 -66.060775) (xy 65.614333 -66.104337) (xy 65.593214 -66.123566)
			(xy 65.577137 -66.13816) (xy 65.549728 -66.171833) (xy 65.528445 -66.209675) (xy 65.513907 -66.250586)
			(xy 65.506537 -66.293373) (xy 65.506092 -66.315082) (xy 65.506594 -66.331345) (xy 65.514835 -66.362812)
			(xy 65.530761 -66.391174) (xy 65.553337 -66.41459) (xy 65.581099 -66.431541) (xy 65.596516 -66.436748)
			(xy 65.612232 -66.440962) (xy 65.644737 -66.44215) (xy 65.676484 -66.435073) (xy 65.705407 -66.420192)
			(xy 65.729623 -66.398476) (xy 65.73901 -66.385186) (xy 65.754217 -66.363015) (xy 65.789868 -66.322772)
			(xy 65.830815 -66.287932) (xy 65.876247 -66.259186) (xy 65.925265 -66.237101) (xy 65.976897 -66.222116)
			(xy 66.030122 -66.214528) (xy 66.083884 -66.214486) (xy 66.137121 -66.221991) (xy 66.188777 -66.236896)
			(xy 66.237828 -66.258904) (xy 66.283305 -66.28758) (xy 66.324306 -66.322356) (xy 66.36002 -66.362543)
			(xy 66.37528 -66.384678) (xy 66.39179 -66.40957) (xy 66.44386 -66.439542) (xy 66.504058 -66.443098)
			(xy 66.558922 -66.419222) (xy 66.57848 -66.396108) (xy 66.585286 -66.388148) (xy 66.599644 -66.372899)
			(xy 66.607182 -66.365628) (xy 66.624454 -66.349118) (xy 66.641472 -66.312542) (xy 66.647384 -66.298759)
			(xy 66.653277 -66.26936) (xy 66.652162 -66.239397) (xy 66.644101 -66.210517) (xy 66.637154 -66.197226)
			(xy 66.609468 -66.147442) (xy 66.586608 -66.130932) (xy 66.564072 -66.114126) (xy 66.523723 -66.074981)
			(xy 66.489559 -66.030336) (xy 66.462319 -65.98116) (xy 66.442593 -65.928518) (xy 66.430809 -65.87355)
			(xy 66.427222 -65.817448) (xy 66.431911 -65.761427) (xy 66.444772 -65.706701) (xy 66.465529 -65.654457)
			(xy 66.49373 -65.605825) (xy 66.528765 -65.561861) (xy 66.569875 -65.523516) (xy 66.592704 -65.507108)
			(xy 66.61658 -65.490598) (xy 66.65214 -65.428622) (xy 66.659438 -65.414949) (xy 66.667859 -65.385131)
			(xy 66.668849 -65.354162) (xy 66.662348 -65.323867) (xy 66.65595 -65.30975) (xy 66.644063 -65.284385)
			(xy 66.627023 -65.231025) (xy 66.617969 -65.175746) (xy 66.617095 -65.119738) (xy 66.624421 -65.064204)
			(xy 66.639788 -65.010338) (xy 66.662867 -64.959298) (xy 66.693161 -64.912182) (xy 66.730019 -64.870002)
			(xy 66.772649 -64.833664) (xy 66.820134 -64.803951) (xy 66.871453 -64.781501) (xy 66.925504 -64.766796)
			(xy 66.981124 -64.760153) (xy 67.037117 -64.761715) (xy 67.09228 -64.771447) (xy 67.145427 -64.789141)
			(xy 67.195416 -64.814416) (xy 67.241171 -64.846729) (xy 67.28171 -64.885385) (xy 67.299332 -64.90716)
			(xy 67.313813 -64.924942) (xy 67.348031 -64.955466) (xy 67.387169 -64.979357) (xy 67.429959 -64.995839)
			(xy 67.475011 -65.004378) (xy 67.520863 -65.004697) (xy 67.56603 -64.996785) (xy 67.609044 -64.9809)
			(xy 67.629024 -64.969644) (xy 67.652797 -64.956142) (xy 67.703354 -64.935334) (xy 67.756363 -64.921956)
			(xy 67.810739 -64.916281) (xy 67.865368 -64.918427) (xy 67.919132 -64.928349) (xy 67.970929 -64.945843)
			(xy 68.019698 -64.970552) (xy 68.06444 -65.00197) (xy 68.10424 -65.039452) (xy 68.138282 -65.082232)
			(xy 68.165868 -65.129434) (xy 68.186434 -65.180089) (xy 68.190277 -65.195627) (xy 68.657908 -65.195627)
			(xy 68.662267 -65.14088) (xy 68.674429 -65.087323) (xy 68.694144 -65.036063) (xy 68.721003 -64.988159)
			(xy 68.754453 -64.9446) (xy 68.793802 -64.906286) (xy 68.838237 -64.874009) (xy 68.88684 -64.848436)
			(xy 68.938607 -64.830095) (xy 68.992469 -64.819365) (xy 69.047313 -64.816467) (xy 69.102006 -64.821462)
			(xy 69.155418 -64.834246) (xy 69.206446 -64.854555) (xy 69.254034 -64.881969) (xy 69.297202 -64.915923)
			(xy 69.300464 -64.919352) (xy 71.234298 -64.919352) (xy 71.238369 -64.86373) (xy 71.250495 -64.809293)
			(xy 71.270418 -64.757202) (xy 71.297714 -64.708567) (xy 71.3318 -64.664424) (xy 71.371949 -64.625715)
			(xy 71.417307 -64.593264) (xy 71.466907 -64.567763) (xy 71.519691 -64.549756) (xy 71.574534 -64.539626)
			(xy 71.630268 -64.537589) (xy 71.685705 -64.543689) (xy 71.739662 -64.557795) (xy 71.790991 -64.579607)
			(xy 71.838597 -64.608661) (xy 71.881465 -64.644336) (xy 71.918682 -64.685873) (xy 71.949455 -64.732386)
			(xy 71.973127 -64.782883) (xy 71.989195 -64.83629) (xy 71.997315 -64.891466) (xy 71.997824 -64.919352)
			(xy 71.997315 -64.947238) (xy 71.989195 -65.002414) (xy 71.973127 -65.055821) (xy 71.949455 -65.106318)
			(xy 71.918682 -65.152831) (xy 71.881465 -65.194368) (xy 71.838597 -65.230043) (xy 71.790991 -65.259097)
			(xy 71.739662 -65.280909) (xy 71.685705 -65.295015) (xy 71.630268 -65.301115) (xy 71.574534 -65.299078)
			(xy 71.519691 -65.288948) (xy 71.466907 -65.270941) (xy 71.417307 -65.24544) (xy 71.371949 -65.212989)
			(xy 71.3318 -65.17428) (xy 71.297714 -65.130137) (xy 71.270418 -65.081502) (xy 71.250495 -65.029411)
			(xy 71.238369 -64.974974) (xy 71.234298 -64.919352) (xy 69.300464 -64.919352) (xy 69.335055 -64.955714)
			(xy 69.366813 -65.000521) (xy 69.39182 -65.049418) (xy 69.409558 -65.101395) (xy 69.419662 -65.155379)
			(xy 69.421922 -65.210252) (xy 69.416292 -65.264884) (xy 69.402888 -65.318143) (xy 69.381988 -65.368931)
			(xy 69.368416 -65.392808) (xy 69.357015 -65.413061) (xy 69.341013 -65.456692) (xy 69.333206 -65.502504)
			(xy 69.333854 -65.548972) (xy 69.342936 -65.594548) (xy 69.36015 -65.637715) (xy 69.384922 -65.677035)
			(xy 69.416426 -65.711199) (xy 69.43471 -65.725548) (xy 69.455735 -65.741828) (xy 69.493436 -65.779328)
			(xy 69.525565 -65.8217) (xy 69.5515 -65.868123) (xy 69.570738 -65.917696) (xy 69.582907 -65.969461)
			(xy 69.587771 -66.022414) (xy 69.585236 -66.075529) (xy 69.575351 -66.127778) (xy 69.558307 -66.178148)
			(xy 69.534434 -66.225664) (xy 69.504196 -66.269406) (xy 69.468177 -66.308525) (xy 69.447918 -66.32575)
			(xy 69.430789 -66.340409) (xy 69.401517 -66.374692) (xy 69.378746 -66.413598) (xy 69.363191 -66.455909)
			(xy 69.355338 -66.500299) (xy 69.355434 -66.545379) (xy 69.363475 -66.589736) (xy 69.37921 -66.63198)
			(xy 69.39026 -66.651632) (xy 69.404166 -66.676167) (xy 69.425456 -66.728388) (xy 69.438832 -66.783172)
			(xy 69.444002 -66.839328) (xy 69.440854 -66.895634) (xy 69.429456 -66.950864) (xy 69.420232 -66.977514)
			(xy 69.415053 -66.992979) (xy 69.411905 -67.02543) (xy 69.417099 -67.057617) (xy 69.430295 -67.087431)
			(xy 69.450629 -67.112917) (xy 69.476766 -67.132406) (xy 69.506996 -67.14462) (xy 69.523102 -67.147186)
			(xy 69.535551 -67.148883) (xy 69.560208 -67.153716) (xy 69.572378 -67.156838) (xy 69.595415 -67.162407)
			(xy 69.642672 -67.165937) (xy 69.689763 -67.160637) (xy 69.735052 -67.146691) (xy 69.776968 -67.124583)
			(xy 69.814053 -67.095083) (xy 69.845021 -67.059213) (xy 69.857366 -67.038982) (xy 69.871501 -67.015439)
			(xy 69.905584 -66.972382) (xy 69.945488 -66.934657) (xy 69.990389 -66.903042) (xy 70.039358 -66.878192)
			(xy 70.091385 -66.86062) (xy 70.145393 -66.850688) (xy 70.200267 -66.848603) (xy 70.254874 -66.854407)
			(xy 70.308084 -66.86798) (xy 70.358798 -66.889042) (xy 70.405969 -66.917157) (xy 70.427596 -66.93408)
			(xy 70.446133 -66.948413) (xy 70.48734 -66.970712) (xy 70.531932 -66.98509) (xy 70.578404 -66.99106)
			(xy 70.625182 -66.988421) (xy 70.670687 -66.977261) (xy 70.71338 -66.957959) (xy 70.732904 -66.945002)
			(xy 70.757343 -66.928662) (xy 70.810139 -66.902815) (xy 70.866273 -66.885364) (xy 70.924419 -66.876722)
			(xy 70.983202 -66.877094) (xy 71.012304 -66.881248) (xy 71.035758 -66.884522) (xy 71.083094 -66.883321)
			(xy 71.129387 -66.873372) (xy 71.173037 -66.85502) (xy 71.212532 -66.8289) (xy 71.246505 -66.795916)
			(xy 71.273779 -66.757209) (xy 71.293412 -66.71412) (xy 71.299578 -66.691256) (xy 71.306361 -66.665553)
			(xy 71.326099 -66.616195) (xy 71.3525 -66.570057) (xy 71.368412 -66.548762) (xy 71.377634 -66.536072)
			(xy 71.390154 -66.507319) (xy 71.395289 -66.476382) (xy 71.392729 -66.445126) (xy 71.382628 -66.415437)
			(xy 71.365596 -66.389105) (xy 71.354442 -66.378074) (xy 71.332892 -66.357353) (xy 71.295897 -66.310396)
			(xy 71.280782 -66.284602) (xy 71.269075 -66.264752) (xy 71.239741 -66.229219) (xy 71.20448 -66.199558)
			(xy 71.164448 -66.176744) (xy 71.120957 -66.161523) (xy 71.075435 -66.154396) (xy 71.029373 -66.155595)
			(xy 70.984284 -66.165082) (xy 70.962774 -66.17335) (xy 70.937256 -66.18333) (xy 70.884107 -66.196655)
			(xy 70.829598 -66.20224) (xy 70.774851 -66.199973) (xy 70.720992 -66.189898) (xy 70.669127 -66.172223)
			(xy 70.620323 -66.147312) (xy 70.575584 -66.115677) (xy 70.535829 -66.077968) (xy 70.501877 -66.034961)
			(xy 70.474425 -65.98754) (xy 70.454037 -65.93668) (xy 70.441134 -65.883427) (xy 70.43598 -65.828876)
			(xy 70.438681 -65.774149) (xy 70.449181 -65.720371) (xy 70.467266 -65.668647) (xy 70.492562 -65.620042)
			(xy 70.52455 -65.575555) (xy 70.562572 -65.5361) (xy 70.605847 -65.502489) (xy 70.653484 -65.475413)
			(xy 70.704503 -65.455428) (xy 70.757856 -65.442946) (xy 70.812446 -65.438224) (xy 70.867151 -65.441358)
			(xy 70.920844 -65.452283) (xy 70.972423 -65.470777) (xy 71.020826 -65.496457) (xy 71.065059 -65.528796)
			(xy 71.104212 -65.567129) (xy 71.13748 -65.610668) (xy 71.14828 -65.629263) (xy 72.38684 -65.629263)
			(xy 72.390261 -65.573267) (xy 72.401847 -65.518376) (xy 72.421349 -65.465774) (xy 72.448344 -65.416596)
			(xy 72.482251 -65.371902) (xy 72.522338 -65.332656) (xy 72.567742 -65.299705) (xy 72.617482 -65.273759)
			(xy 72.670485 -65.255378) (xy 72.72561 -65.244959) (xy 72.781666 -65.242727) (xy 72.809608 -65.245234)
			(xy 72.831816 -65.247227) (xy 72.876299 -65.244191) (xy 72.91957 -65.233439) (xy 72.9603 -65.215299)
			(xy 72.997238 -65.190328) (xy 73.029251 -65.159294) (xy 73.055357 -65.123149) (xy 73.074753 -65.083002)
			(xy 73.086844 -65.040086) (xy 73.091259 -64.995718) (xy 73.090024 -64.973454) (xy 73.08846 -64.946027)
			(xy 73.092219 -64.891223) (xy 73.103802 -64.837525) (xy 73.122969 -64.786044) (xy 73.149322 -64.737845)
			(xy 73.182316 -64.693925) (xy 73.22127 -64.655192) (xy 73.265378 -64.622448) (xy 73.313726 -64.59637)
			(xy 73.365315 -64.577498) (xy 73.419079 -64.566221) (xy 73.473903 -64.562773) (xy 73.528655 -64.567226)
			(xy 73.582203 -64.579487) (xy 73.633437 -64.599303) (xy 73.681299 -64.626263) (xy 73.724798 -64.659811)
			(xy 73.763035 -64.699252) (xy 73.795219 -64.74377) (xy 73.820683 -64.792444) (xy 73.838902 -64.844268)
			(xy 73.849498 -64.898169) (xy 73.852252 -64.953033) (xy 73.847107 -65.007725) (xy 73.83417 -65.061113)
			(xy 73.813708 -65.112092) (xy 73.786144 -65.15961) (xy 73.752049 -65.202681) (xy 73.712128 -65.240416)
			(xy 73.667206 -65.272034) (xy 73.618214 -65.296881) (xy 73.566163 -65.314443) (xy 73.512132 -65.324356)
			(xy 73.457238 -65.326416) (xy 73.429876 -65.323974) (xy 73.407662 -65.322059) (xy 73.363183 -65.325081)
			(xy 73.319914 -65.335821) (xy 73.279185 -65.35395) (xy 73.242246 -65.378912) (xy 73.210232 -65.409938)
			(xy 73.184126 -65.446077) (xy 73.164729 -65.486218) (xy 73.152639 -65.52913) (xy 73.148225 -65.573492)
			(xy 73.14946 -65.595754) (xy 73.150222 -65.612518) (xy 73.151379 -65.634011) (xy 73.159961 -65.676184)
			(xy 73.175523 -65.71631) (xy 73.197621 -65.753241) (xy 73.225622 -65.785923) (xy 73.258728 -65.813423)
			(xy 73.295992 -65.834955) (xy 73.33635 -65.849904) (xy 73.378649 -65.857842) (xy 73.400158 -65.858644)
			(xy 73.427964 -65.85965) (xy 73.48288 -65.868577) (xy 73.535917 -65.885389) (xy 73.585948 -65.909727)
			(xy 73.631912 -65.941075) (xy 73.672835 -65.978769) (xy 73.707847 -66.022008) (xy 73.736205 -66.069876)
			(xy 73.757308 -66.121355) (xy 73.770709 -66.175354) (xy 73.776121 -66.230727) (xy 73.773432 -66.286299)
			(xy 73.762698 -66.340891) (xy 73.744146 -66.393343) (xy 73.71817 -66.442544) (xy 73.685322 -66.48745)
			(xy 73.646298 -66.527106) (xy 73.601927 -66.560672) (xy 73.55315 -66.587436) (xy 73.501003 -66.606829)
			(xy 73.446591 -66.61844) (xy 73.391069 -66.622023) (xy 73.335616 -66.617501) (xy 73.281409 -66.604971)
			(xy 73.229597 -66.584699) (xy 73.18128 -66.557114) (xy 73.137483 -66.522802) (xy 73.099136 -66.482491)
			(xy 73.067052 -66.437037) (xy 73.041912 -66.387403) (xy 73.02425 -66.334644) (xy 73.014441 -66.279879)
			(xy 73.013062 -66.25209) (xy 73.011914 -66.230596) (xy 73.003332 -66.188422) (xy 72.98777 -66.148295)
			(xy 72.965671 -66.111363) (xy 72.937669 -66.07868) (xy 72.904562 -66.05118) (xy 72.867296 -66.029648)
			(xy 72.826936 -66.014701) (xy 72.784635 -66.006765) (xy 72.763126 -66.005964) (xy 72.735087 -66.005)
			(xy 72.67972 -65.995958) (xy 72.626274 -65.978905) (xy 72.575903 -65.954208) (xy 72.529692 -65.922399)
			(xy 72.488638 -65.884165) (xy 72.453627 -65.84033) (xy 72.425414 -65.79184) (xy 72.404608 -65.739741)
			(xy 72.391656 -65.685156) (xy 72.38684 -65.629263) (xy 71.14828 -65.629263) (xy 71.151242 -65.634362)
			(xy 71.162936 -65.654221) (xy 71.19227 -65.689758) (xy 71.227532 -65.71942) (xy 71.267567 -65.742236)
			(xy 71.31106 -65.757456) (xy 71.356585 -65.764581) (xy 71.402649 -65.763378) (xy 71.44774 -65.753885)
			(xy 71.46925 -65.745614) (xy 71.495161 -65.735637) (xy 71.549038 -65.722246) (xy 71.604288 -65.716806)
			(xy 71.659743 -65.719431) (xy 71.714232 -65.730066) (xy 71.766604 -65.748487) (xy 71.815753 -65.774303)
			(xy 71.860641 -65.806971) (xy 71.90032 -65.8458) (xy 71.933952 -65.889971) (xy 71.960827 -65.938549)
			(xy 71.980377 -65.99051) (xy 71.99219 -66.044756) (xy 71.996015 -66.100141) (xy 71.991772 -66.155495)
			(xy 71.979551 -66.20965) (xy 71.959609 -66.261462) (xy 71.932369 -66.309837) (xy 71.915782 -66.3321)
			(xy 71.9066 -66.344817) (xy 71.894076 -66.373561) (xy 71.888936 -66.404491) (xy 71.891488 -66.435741)
			(xy 71.90158 -66.465426) (xy 71.918603 -66.491757) (xy 71.929752 -66.502788) (xy 71.949297 -66.521527)
			(xy 71.983366 -66.563612) (xy 72.011142 -66.610092) (xy 72.032067 -66.660032) (xy 72.04572 -66.712429)
			(xy 72.051827 -66.76623) (xy 72.050265 -66.820354) (xy 72.041065 -66.873714) (xy 72.024413 -66.925236)
			(xy 72.000642 -66.973886) (xy 71.970232 -67.018686) (xy 71.933792 -67.058736) (xy 71.892055 -67.093231)
			(xy 71.845859 -67.121477) (xy 71.796134 -67.142908) (xy 71.743878 -67.157092) (xy 71.690142 -67.163744)
			(xy 71.636005 -67.162731) (xy 71.609204 -67.15887) (xy 71.58575 -67.155591) (xy 71.538414 -67.15679)
			(xy 71.492119 -67.166738) (xy 71.448468 -67.185091) (xy 71.408972 -67.211212) (xy 71.375 -67.244197)
			(xy 71.347726 -67.282906) (xy 71.328095 -67.325997) (xy 71.32193 -67.348862) (xy 71.314877 -67.375365)
			(xy 71.294316 -67.426206) (xy 71.266687 -67.473579) (xy 71.232562 -67.516509) (xy 71.192642 -67.554111)
			(xy 71.14775 -67.58561) (xy 71.09881 -67.610359) (xy 71.046832 -67.627846) (xy 70.992886 -67.637712)
			(xy 70.938083 -67.639753) (xy 70.883553 -67.633928) (xy 70.830418 -67.620356) (xy 70.779773 -67.599316)
			(xy 70.732662 -67.571243) (xy 70.71106 -67.554348) (xy 70.692486 -67.540065) (xy 70.651289 -67.51776)
			(xy 70.606705 -67.503375) (xy 70.56024 -67.497397) (xy 70.513466 -67.500028) (xy 70.467965 -67.511179)
			(xy 70.425275 -67.530472) (xy 70.405752 -67.543426) (xy 70.382788 -67.558845) (xy 70.333336 -67.583621)
			(xy 70.280825 -67.601001) (xy 70.226356 -67.610619) (xy 70.171069 -67.612275) (xy 70.116122 -67.605934)
			(xy 70.089268 -67.599306) (xy 70.066247 -67.593661) (xy 70.018982 -67.590139) (xy 69.971884 -67.595449)
			(xy 69.926589 -67.609407) (xy 69.884672 -67.631527) (xy 69.847586 -67.661041) (xy 69.816622 -67.696925)
			(xy 69.80428 -67.717162) (xy 69.790035 -67.740779) (xy 69.75576 -67.783988) (xy 69.715619 -67.821811)
			(xy 69.670451 -67.85346) (xy 69.621195 -67.878274) (xy 69.56888 -67.895737) (xy 69.514595 -67.905484)
			(xy 69.459472 -67.907313) (xy 69.404661 -67.901185) (xy 69.351303 -67.887228) (xy 69.300512 -67.865733)
			(xy 69.253344 -67.837148) (xy 69.210785 -67.802069) (xy 69.173721 -67.761227) (xy 69.142924 -67.715473)
			(xy 69.119037 -67.665761) (xy 69.102558 -67.613128) (xy 69.093829 -67.55867) (xy 69.093034 -67.503523)
			(xy 69.096128 -67.476116) (xy 69.098442 -67.45476) (xy 69.0968 -67.411842) (xy 69.087964 -67.36981)
			(xy 69.072186 -67.329863) (xy 69.049915 -67.293138) (xy 69.021787 -67.26068) (xy 68.988601 -67.233415)
			(xy 68.951303 -67.212118) (xy 68.931282 -67.204336) (xy 68.906313 -67.194666) (xy 68.859078 -67.169458)
			(xy 68.815832 -67.137892) (xy 68.777424 -67.10059) (xy 68.744609 -67.058284) (xy 68.718032 -67.011805)
			(xy 68.698214 -66.962067) (xy 68.685546 -66.910046) (xy 68.680276 -66.856765) (xy 68.682508 -66.803271)
			(xy 68.692197 -66.750614) (xy 68.709154 -66.699829) (xy 68.733046 -66.651914) (xy 68.763402 -66.60781)
			(xy 68.799626 -66.568384) (xy 68.82003 -66.551048) (xy 68.837165 -66.536397) (xy 68.866434 -66.502111)
			(xy 68.889201 -66.463203) (xy 68.904753 -66.420891) (xy 68.912605 -66.3765) (xy 68.912509 -66.331421)
			(xy 68.904469 -66.287064) (xy 68.888736 -66.244818) (xy 68.877688 -66.225166) (xy 68.863343 -66.199798)
			(xy 68.841601 -66.145731) (xy 68.828333 -66.088987) (xy 68.823846 -66.030885) (xy 68.828246 -65.972777)
			(xy 68.84143 -65.916014) (xy 68.863091 -65.861914) (xy 68.877434 -65.836546) (xy 68.888789 -65.816268)
			(xy 68.904801 -65.772644) (xy 68.912617 -65.726837) (xy 68.911976 -65.680373) (xy 68.902901 -65.634799)
			(xy 68.885692 -65.591633) (xy 68.860924 -65.552315) (xy 68.829422 -65.518154) (xy 68.81114 -65.503806)
			(xy 68.789435 -65.486978) (xy 68.750667 -65.448078) (xy 68.717876 -65.404021) (xy 68.69174 -65.355718)
			(xy 68.672798 -65.304167) (xy 68.661443 -65.250433) (xy 68.657908 -65.195627) (xy 68.190277 -65.195627)
			(xy 68.199559 -65.233162) (xy 68.204973 -65.287564) (xy 68.202567 -65.342183) (xy 68.192388 -65.395898)
			(xy 68.174646 -65.447611) (xy 68.149704 -65.496261) (xy 68.118073 -65.540853) (xy 68.080401 -65.580473)
			(xy 68.037458 -65.61431) (xy 67.990126 -65.64167) (xy 67.939373 -65.661994) (xy 67.886238 -65.674865)
			(xy 67.83181 -65.680019) (xy 67.777204 -65.677352) (xy 67.723537 -65.666916) (xy 67.67191 -65.648927)
			(xy 67.62338 -65.623753) (xy 67.57894 -65.591909) (xy 67.5395 -65.554048) (xy 67.522344 -65.532762)
			(xy 67.507849 -65.514967) (xy 67.4736 -65.484421) (xy 67.434427 -65.460514) (xy 67.391602 -65.44402)
			(xy 67.346513 -65.435474) (xy 67.300622 -65.435155) (xy 67.255418 -65.443071) (xy 67.212367 -65.458967)
			(xy 67.192398 -65.470278) (xy 67.129914 -65.580006) (xy 67.145154 -65.640204) (xy 67.157496 -65.664035)
			(xy 67.176107 -65.714372) (xy 67.187472 -65.766822) (xy 67.191365 -65.820347) (xy 67.187711 -65.87389)
			(xy 67.176581 -65.92639) (xy 67.158194 -65.976809) (xy 67.132916 -66.02415) (xy 67.117468 -66.046096)
			(xy 67.104635 -66.064456) (xy 67.084955 -66.104691) (xy 67.072638 -66.147754) (xy 67.068065 -66.19231)
			(xy 67.071379 -66.236977) (xy 67.082476 -66.280371) (xy 67.101012 -66.321145) (xy 67.126413 -66.358036)
			(xy 67.141852 -66.374264) (xy 67.160696 -66.394027) (xy 67.193111 -66.43797) (xy 67.218928 -66.486088)
			(xy 67.237617 -66.537396) (xy 67.248797 -66.590845) (xy 67.252239 -66.645342) (xy 67.247872 -66.699773)
			(xy 67.235787 -66.753024) (xy 67.216229 -66.804008) (xy 67.189599 -66.85168) (xy 67.156441 -66.895066)
			(xy 67.13728 -66.914522) (xy 67.120262 -66.931032) (xy 67.07759 -67.025266) (xy 67.105276 -67.103752)
			(xy 67.116452 -67.118992) (xy 67.131678 -67.140395) (xy 67.156744 -67.186555) (xy 67.175246 -67.235715)
			(xy 67.181476 -67.261232) (xy 67.191636 -67.305936) (xy 67.228212 -67.33413) (xy 67.240266 -67.342748)
			(xy 67.267342 -67.354767) (xy 67.296453 -67.360254) (xy 67.31127 -67.360038) (xy 67.33943 -67.35927)
			(xy 67.395467 -67.36503) (xy 67.450047 -67.378968) (xy 67.501984 -67.400781) (xy 67.550148 -67.429996)
			(xy 67.593492 -67.465977) (xy 67.631073 -67.507941) (xy 67.662073 -67.554975) (xy 67.685819 -67.606058)
			(xy 67.701795 -67.660077) (xy 67.709651 -67.715858) (xy 67.709219 -67.772188) (xy 67.700507 -67.827843)
			(xy 67.683705 -67.88161) (xy 67.659178 -67.932322) (xy 67.627459 -67.978876) (xy 67.589238 -68.020258)
			(xy 67.545348 -68.055569) (xy 67.496741 -68.084041) (xy 67.444475 -68.105055) (xy 67.389687 -68.118154)
			(xy 67.333569 -68.123053) (xy 67.305428 -68.121784) (xy 67.288272 -68.121315) (xy 67.254718 -68.128461)
			(xy 67.224286 -68.144298) (xy 67.199181 -68.16768) (xy 67.181223 -68.19691) (xy 67.175888 -68.213224)
			(xy 67.167955 -68.239007) (xy 67.145829 -68.288204) (xy 67.116985 -68.333788) (xy 67.082001 -68.374849)
			(xy 67.062096 -68.393056) (xy 67.050831 -68.403575) (xy 67.033299 -68.428913) (xy 67.022353 -68.457717)
			(xy 67.018632 -68.488304) (xy 67.022355 -68.518891) (xy 67.033302 -68.547694) (xy 67.050837 -68.573031)
			(xy 67.062096 -68.583556) (xy 67.069805 -68.590437) (xy 67.084546 -68.604924) (xy 67.09156 -68.612512)
			(xy 67.108324 -68.6308) (xy 67.205352 -68.677282) (xy 67.358006 -68.677282)
		)
		(stroke
			(width 0)
			(type solid)
		)
		(fill yes)
		(layer "In6.Cu")
		(net "PV_VDDR_NODE1")
	)
	(gr_poly
		(pts
			(xy 173.7487 -201.56678) (xy 173.765354 -201.566285) (xy 173.797526 -201.557664) (xy 173.826371 -201.541009)
			(xy 173.849921 -201.517455) (xy 173.866572 -201.488608) (xy 173.875188 -201.456434) (xy 173.8757 -201.43978)
			(xy 173.8757 -200.021698) (xy 174.35576 -199.541638) (xy 177.918618 -199.541638) (xy 182.815992 -194.644264)
			(xy 182.834026 -194.579748) (xy 182.825898 -194.547744) (xy 182.819645 -194.520334) (xy 182.814324 -194.464368)
			(xy 182.817277 -194.408226) (xy 182.828438 -194.353126) (xy 182.847565 -194.300262) (xy 182.874246 -194.250777)
			(xy 182.890668 -194.227958) (xy 182.900439 -194.213932) (xy 182.912868 -194.182102) (xy 182.916408 -194.148116)
			(xy 182.910807 -194.114408) (xy 182.90413 -194.098672) (xy 182.884572 -194.056762) (xy 182.87873 -194.050666)
			(xy 182.854854 -194.023742) (xy 182.829962 -193.992754) (xy 182.702454 -194.051936) (xy 182.685944 -194.069208)
			(xy 182.666847 -194.088508) (xy 182.624162 -194.122061) (xy 182.577157 -194.149232) (xy 182.526778 -194.169476)
			(xy 182.500524 -194.176396) (xy 182.479294 -194.182088) (xy 182.43905 -194.19975) (xy 182.402439 -194.224064)
			(xy 182.37055 -194.254307) (xy 182.344331 -194.289579) (xy 182.324563 -194.328832) (xy 182.311834 -194.370898)
			(xy 182.306521 -194.414525) (xy 182.30723 -194.436492) (xy 182.30817 -194.46434) (xy 182.302939 -194.519813)
			(xy 182.289694 -194.573935) (xy 182.268718 -194.625555) (xy 182.240457 -194.673575) (xy 182.205512 -194.716974)
			(xy 182.164626 -194.754829) (xy 182.118668 -194.786333) (xy 182.068617 -194.810818) (xy 182.015537 -194.827763)
			(xy 181.960557 -194.836807) (xy 181.904846 -194.837758) (xy 181.849589 -194.830595) (xy 181.795962 -194.815471)
			(xy 181.745104 -194.792708) (xy 181.698099 -194.76279) (xy 181.655945 -194.726352) (xy 181.619539 -194.684171)
			(xy 181.589656 -194.637143) (xy 181.566931 -194.586269) (xy 181.551848 -194.53263) (xy 181.544726 -194.477368)
			(xy 181.545719 -194.421658) (xy 181.554804 -194.366685) (xy 181.571788 -194.313617) (xy 181.596311 -194.263584)
			(xy 181.62785 -194.217651) (xy 181.665735 -194.176793) (xy 181.70916 -194.14188) (xy 181.757201 -194.113655)
			(xy 181.808837 -194.092718) (xy 181.835806 -194.085718) (xy 181.85703 -194.080022) (xy 181.897263 -194.062356)
			(xy 181.933861 -194.038038) (xy 181.965736 -194.007794) (xy 181.99194 -193.972521) (xy 182.011693 -193.933271)
			(xy 182.024407 -193.89121) (xy 182.029705 -193.84759) (xy 182.0291 -193.825622) (xy 182.028141 -193.797446)
			(xy 182.033529 -193.741329) (xy 182.047116 -193.686616) (xy 182.068607 -193.634497) (xy 182.097533 -193.586109)
			(xy 182.133265 -193.542504) (xy 182.175025 -193.504632) (xy 182.221903 -193.473318) (xy 182.272879 -193.449243)
			(xy 182.326843 -193.432932) (xy 182.38262 -193.424739) (xy 182.438995 -193.424844) (xy 182.494741 -193.433244)
			(xy 182.548644 -193.449755) (xy 182.599531 -193.474019) (xy 182.623206 -193.489326) (xy 182.64174 -193.501282)
			(xy 182.681996 -193.519292) (xy 182.724758 -193.530074) (xy 182.76874 -193.533305) (xy 182.812619 -193.528885)
			(xy 182.855074 -193.51695) (xy 182.875174 -193.507868) (xy 182.895683 -193.487034) (xy 182.941769 -193.451068)
			(xy 182.992684 -193.422344) (xy 183.0473 -193.401499) (xy 183.104406 -193.388994) (xy 183.162736 -193.385108)
			(xy 183.191912 -193.386964) (xy 183.214243 -193.379959) (xy 183.256064 -193.358961) (xy 183.293331 -193.330658)
			(xy 183.324782 -193.296006) (xy 183.349352 -193.256179) (xy 183.366212 -193.212526) (xy 183.374789 -193.166522)
			(xy 183.3753 -193.143124) (xy 183.3753 -175.42256) (xy 183.352212 -175.437791) (xy 183.302556 -175.462155)
			(xy 183.249905 -175.479099) (xy 183.195359 -175.48827) (xy 183.140062 -175.489475) (xy 183.085169 -175.48269)
			(xy 183.031829 -175.468056) (xy 182.981159 -175.445879) (xy 182.934218 -175.416624) (xy 182.89199 -175.380903)
			(xy 182.855356 -175.339462) (xy 182.825085 -175.293171) (xy 182.80181 -175.242996) (xy 182.786017 -175.189987)
			(xy 182.778037 -175.135255) (xy 182.778037 -175.079945) (xy 182.786017 -175.025213) (xy 182.80181 -174.972204)
			(xy 182.825085 -174.922029) (xy 182.855356 -174.875738) (xy 182.89199 -174.834297) (xy 182.934218 -174.798576)
			(xy 182.981159 -174.769321) (xy 183.031829 -174.747144) (xy 183.085169 -174.73251) (xy 183.140062 -174.725725)
			(xy 183.195359 -174.72693) (xy 183.249905 -174.736101) (xy 183.302556 -174.753045) (xy 183.352212 -174.777409)
			(xy 183.3753 -174.79264) (xy 183.3753 -170.90517) (xy 177.74666 -165.27653) (xy 177.73142 -165.27653)
			(xy 176.396396 -163.941506) (xy 174.4853 -163.941506) (xy 170.99407 -160.450276) (xy 170.99407 -158.53918)
			(xy 170.9928 -158.53791) (xy 170.9928 -155.323286) (xy 170.68038 -155.010866) (xy 169.040048 -155.010866)
			(xy 167.949686 -156.101228) (xy 168.495019 -156.101228) (xy 168.497892 -156.046571) (xy 168.508545 -155.992885)
			(xy 168.526761 -155.941272) (xy 168.552164 -155.892792) (xy 168.584234 -155.848439) (xy 168.622313 -155.809124)
			(xy 168.665619 -155.775654) (xy 168.713263 -155.748715) (xy 168.764267 -155.72886) (xy 168.817586 -155.716497)
			(xy 168.872123 -155.71188) (xy 168.926761 -155.715104) (xy 168.980378 -155.726101) (xy 169.031872 -155.744647)
			(xy 169.080189 -155.770361) (xy 169.124335 -155.802716) (xy 169.163405 -155.841046) (xy 169.196597 -155.884566)
			(xy 169.223229 -155.932382) (xy 169.242756 -155.983513) (xy 169.254776 -156.036909) (xy 169.259043 -156.091475)
			(xy 169.257726 -156.118814) (xy 169.256775 -156.14083) (xy 169.261523 -156.184635) (xy 169.273754 -156.226965)
			(xy 169.293099 -156.266552) (xy 169.318981 -156.302211) (xy 169.350624 -156.332873) (xy 169.38708 -156.35762)
			(xy 169.427256 -156.37571) (xy 169.46995 -156.386602) (xy 169.513883 -156.38997) (xy 169.535856 -156.388308)
			(xy 169.563145 -156.386191) (xy 169.617817 -156.388716) (xy 169.671568 -156.399028) (xy 169.723293 -156.416914)
			(xy 169.771932 -156.442008) (xy 169.816486 -156.473795) (xy 169.856041 -156.511622) (xy 169.889784 -156.554713)
			(xy 169.917024 -156.602184) (xy 169.937201 -156.65306) (xy 169.949901 -156.706296) (xy 169.954864 -156.760802)
			(xy 169.951987 -156.815457) (xy 169.94133 -156.86914) (xy 169.923111 -156.920749) (xy 169.897704 -156.969226)
			(xy 169.865632 -157.013574) (xy 169.827551 -157.052885) (xy 169.784244 -157.08635) (xy 169.736599 -157.113284)
			(xy 169.685595 -157.133134) (xy 169.632277 -157.145491) (xy 169.577741 -157.150103) (xy 169.523106 -157.146874)
			(xy 169.469492 -157.135872) (xy 169.418001 -157.117322) (xy 169.369689 -157.091604) (xy 169.325548 -157.059247)
			(xy 169.286483 -157.020914) (xy 169.253297 -156.977392) (xy 169.22667 -156.929575) (xy 169.207149 -156.878444)
			(xy 169.195135 -156.825048) (xy 169.190874 -156.770484) (xy 169.192194 -156.743146) (xy 169.193162 -156.721131)
			(xy 169.188408 -156.677327) (xy 169.176173 -156.634998) (xy 169.156824 -156.595412) (xy 169.13094 -156.559755)
			(xy 169.099296 -156.529094) (xy 169.06284 -156.504347) (xy 169.022663 -156.486256) (xy 168.97997 -156.475363)
			(xy 168.936037 -156.471992) (xy 168.914064 -156.473652) (xy 168.88678 -156.475826) (xy 168.832105 -156.473304)
			(xy 168.778352 -156.462995) (xy 168.726623 -156.445112) (xy 168.677981 -156.42002) (xy 168.633423 -156.388235)
			(xy 168.593865 -156.35041) (xy 168.560117 -156.307319) (xy 168.532873 -156.259849) (xy 168.512691 -156.208973)
			(xy 168.499986 -156.155735) (xy 168.495019 -156.101228) (xy 167.949686 -156.101228) (xy 165.609524 -158.44139)
			(xy 167.156382 -158.44139) (xy 167.160453 -158.385768) (xy 167.172579 -158.331331) (xy 167.192502 -158.27924)
			(xy 167.219798 -158.230605) (xy 167.253884 -158.186462) (xy 167.294033 -158.147753) (xy 167.339391 -158.115302)
			(xy 167.388991 -158.089801) (xy 167.441775 -158.071794) (xy 167.496618 -158.061664) (xy 167.552352 -158.059627)
			(xy 167.607789 -158.065727) (xy 167.661746 -158.079833) (xy 167.713075 -158.101645) (xy 167.760681 -158.130699)
			(xy 167.803549 -158.166374) (xy 167.840766 -158.207911) (xy 167.871539 -158.254424) (xy 167.895211 -158.304921)
			(xy 167.911279 -158.358328) (xy 167.919399 -158.413504) (xy 167.919908 -158.44139) (xy 167.919399 -158.469276)
			(xy 167.911279 -158.524452) (xy 167.895211 -158.577859) (xy 167.871539 -158.628356) (xy 167.840766 -158.674869)
			(xy 167.803549 -158.716406) (xy 167.760681 -158.752081) (xy 167.756183 -158.754826) (xy 168.162222 -158.754826)
			(xy 168.166293 -158.699204) (xy 168.178419 -158.644767) (xy 168.198342 -158.592676) (xy 168.225638 -158.544041)
			(xy 168.259724 -158.499898) (xy 168.299873 -158.461189) (xy 168.345231 -158.428738) (xy 168.394831 -158.403237)
			(xy 168.447615 -158.38523) (xy 168.502458 -158.3751) (xy 168.558192 -158.373063) (xy 168.613629 -158.379163)
			(xy 168.667586 -158.393269) (xy 168.718915 -158.415081) (xy 168.766521 -158.444135) (xy 168.809389 -158.47981)
			(xy 168.846606 -158.521347) (xy 168.877379 -158.56786) (xy 168.901051 -158.618357) (xy 168.917119 -158.671764)
			(xy 168.925239 -158.72694) (xy 168.925748 -158.754826) (xy 168.925239 -158.782712) (xy 168.917119 -158.837888)
			(xy 168.901051 -158.891295) (xy 168.877379 -158.941792) (xy 168.846606 -158.988305) (xy 168.809389 -159.029842)
			(xy 168.766521 -159.065517) (xy 168.718915 -159.094571) (xy 168.667586 -159.116383) (xy 168.613629 -159.130489)
			(xy 168.558192 -159.136589) (xy 168.502458 -159.134552) (xy 168.447615 -159.124422) (xy 168.394831 -159.106415)
			(xy 168.345231 -159.080914) (xy 168.299873 -159.048463) (xy 168.259724 -159.009754) (xy 168.225638 -158.965611)
			(xy 168.198342 -158.916976) (xy 168.178419 -158.864885) (xy 168.166293 -158.810448) (xy 168.162222 -158.754826)
			(xy 167.756183 -158.754826) (xy 167.713075 -158.781135) (xy 167.661746 -158.802947) (xy 167.607789 -158.817053)
			(xy 167.552352 -158.823153) (xy 167.496618 -158.821116) (xy 167.441775 -158.810986) (xy 167.388991 -158.792979)
			(xy 167.339391 -158.767478) (xy 167.294033 -158.735027) (xy 167.253884 -158.696318) (xy 167.219798 -158.652175)
			(xy 167.192502 -158.60354) (xy 167.172579 -158.551449) (xy 167.160453 -158.497012) (xy 167.156382 -158.44139)
			(xy 165.609524 -158.44139) (xy 165.54577 -158.505144) (xy 163.902898 -158.505144) (xy 163.87933 -158.505661)
			(xy 163.833002 -158.514356) (xy 163.789073 -158.531448) (xy 163.749051 -158.556351) (xy 163.714309 -158.588208)
			(xy 163.68604 -158.625928) (xy 163.665214 -158.668215) (xy 163.652547 -158.713617) (xy 163.649914 -158.737046)
			(xy 163.64839 -158.75254) (xy 163.647882 -158.756096) (xy 163.647374 -158.764732) (xy 163.646729 -158.782206)
			(xy 163.653891 -158.816419) (xy 163.670063 -158.847408) (xy 163.681664 -158.86049) (xy 163.756594 -158.939738)
			(xy 163.799012 -158.946596) (xy 163.825795 -158.951451) (xy 163.877727 -158.967752) (xy 163.926816 -158.991265)
			(xy 163.972067 -159.021514) (xy 164.012562 -159.057884) (xy 164.04748 -159.099639) (xy 164.076111 -159.14593)
			(xy 164.097875 -159.195819) (xy 164.112332 -159.248295) (xy 164.115628 -159.274256) (xy 165.897812 -159.274256)
			(xy 165.901883 -159.218634) (xy 165.914009 -159.164197) (xy 165.933932 -159.112106) (xy 165.961228 -159.063471)
			(xy 165.995314 -159.019328) (xy 166.035463 -158.980619) (xy 166.080821 -158.948168) (xy 166.130421 -158.922667)
			(xy 166.183205 -158.90466) (xy 166.238048 -158.89453) (xy 166.293782 -158.892493) (xy 166.349219 -158.898593)
			(xy 166.403176 -158.912699) (xy 166.454505 -158.934511) (xy 166.502111 -158.963565) (xy 166.544979 -158.99924)
			(xy 166.582196 -159.040777) (xy 166.612969 -159.08729) (xy 166.636641 -159.137787) (xy 166.652709 -159.191194)
			(xy 166.660829 -159.24637) (xy 166.661338 -159.274256) (xy 166.660829 -159.302142) (xy 166.652709 -159.357318)
			(xy 166.636641 -159.410725) (xy 166.612969 -159.461222) (xy 166.582196 -159.507735) (xy 166.544979 -159.549272)
			(xy 166.502111 -159.584947) (xy 166.454505 -159.614001) (xy 166.403176 -159.635813) (xy 166.349219 -159.649919)
			(xy 166.293782 -159.656019) (xy 166.238048 -159.653982) (xy 166.183205 -159.643852) (xy 166.130421 -159.625845)
			(xy 166.080821 -159.600344) (xy 166.035463 -159.567893) (xy 165.995314 -159.529184) (xy 165.961228 -159.485041)
			(xy 165.933932 -159.436406) (xy 165.914009 -159.384315) (xy 165.901883 -159.329878) (xy 165.897812 -159.274256)
			(xy 164.115628 -159.274256) (xy 164.119187 -159.302292) (xy 164.118301 -159.356715) (xy 164.109693 -159.41046)
			(xy 164.093536 -159.462437) (xy 164.07016 -159.511592) (xy 164.040037 -159.556927) (xy 164.00378 -159.597523)
			(xy 163.962123 -159.632556) (xy 163.915911 -159.661316) (xy 163.866083 -159.683219) (xy 163.813648 -159.697822)
			(xy 163.75967 -159.704827) (xy 163.705245 -159.704092) (xy 163.651476 -159.695634) (xy 163.599454 -159.679622)
			(xy 163.550235 -159.656382) (xy 163.504816 -159.626386) (xy 163.464119 -159.590242) (xy 163.42897 -159.548682)
			(xy 163.400081 -159.502551) (xy 163.37804 -159.452784) (xy 163.363291 -159.40039) (xy 163.356136 -159.346432)
			(xy 163.356036 -159.319214) (xy 163.355738 -159.295364) (xy 163.347314 -159.248422) (xy 163.330271 -159.203879)
			(xy 163.305208 -159.163304) (xy 163.273009 -159.128123) (xy 163.234805 -159.099575) (xy 163.191942 -159.078664)
			(xy 163.169092 -159.071818) (xy 163.141251 -159.063635) (xy 163.088249 -159.04001) (xy 163.039442 -159.008624)
			(xy 162.995956 -158.970202) (xy 162.958797 -158.925633) (xy 162.928824 -158.875945) (xy 162.906729 -158.822288)
			(xy 162.893023 -158.765902) (xy 162.889946 -158.737046) (xy 162.887377 -158.713614) (xy 162.874681 -158.668221)
			(xy 162.853834 -158.625947) (xy 162.825552 -158.588241) (xy 162.790804 -158.556394) (xy 162.750781 -158.531498)
			(xy 162.706854 -158.514408) (xy 162.660529 -158.505707) (xy 162.636962 -158.505144) (xy 160.105344 -158.505144)
			(xy 160.083148 -158.505597) (xy 160.039429 -158.513304) (xy 159.997715 -158.528492) (xy 159.959276 -158.550698)
			(xy 159.92528 -158.579246) (xy 159.896763 -158.613268) (xy 159.874593 -158.651729) (xy 159.859444 -158.693456)
			(xy 159.851777 -158.737182) (xy 159.851825 -158.781575) (xy 159.859588 -158.825283) (xy 159.866838 -158.846266)
			(xy 159.876251 -158.873623) (xy 159.887662 -158.93034) (xy 159.890399 -158.988129) (xy 159.88792 -159.016954)
			(xy 159.886092 -159.039027) (xy 159.889187 -159.083206) (xy 159.899891 -159.12618) (xy 159.917882 -159.166648)
			(xy 159.942615 -159.203385) (xy 159.973341 -159.235279) (xy 160.00913 -159.261365) (xy 160.048899 -159.280853)
			(xy 160.052982 -159.28213) (xy 161.388042 -159.28213) (xy 161.392113 -159.226508) (xy 161.404239 -159.172071)
			(xy 161.424162 -159.11998) (xy 161.451458 -159.071345) (xy 161.485544 -159.027202) (xy 161.525693 -158.988493)
			(xy 161.571051 -158.956042) (xy 161.620651 -158.930541) (xy 161.673435 -158.912534) (xy 161.728278 -158.902404)
			(xy 161.784012 -158.900367) (xy 161.839449 -158.906467) (xy 161.893406 -158.920573) (xy 161.944735 -158.942385)
			(xy 161.992341 -158.971439) (xy 162.035209 -159.007114) (xy 162.072426 -159.048651) (xy 162.103199 -159.095164)
			(xy 162.126871 -159.145661) (xy 162.142939 -159.199068) (xy 162.151059 -159.254244) (xy 162.151568 -159.28213)
			(xy 162.151059 -159.310016) (xy 162.142939 -159.365192) (xy 162.126871 -159.418599) (xy 162.103199 -159.469096)
			(xy 162.072426 -159.515609) (xy 162.035209 -159.557146) (xy 161.992341 -159.592821) (xy 161.944735 -159.621875)
			(xy 161.893406 -159.643687) (xy 161.839449 -159.657793) (xy 161.784012 -159.663893) (xy 161.728278 -159.661856)
			(xy 161.673435 -159.651726) (xy 161.620651 -159.633719) (xy 161.571051 -159.608218) (xy 161.525693 -159.575767)
			(xy 161.485544 -159.537058) (xy 161.451458 -159.492915) (xy 161.424162 -159.44428) (xy 161.404239 -159.392189)
			(xy 161.392113 -159.337752) (xy 161.388042 -159.28213) (xy 160.052982 -159.28213) (xy 160.070038 -159.287464)
			(xy 160.096731 -159.295671) (xy 160.147556 -159.318806) (xy 160.194466 -159.349105) (xy 160.236457 -159.385918)
			(xy 160.272633 -159.42846) (xy 160.30222 -159.475821) (xy 160.324586 -159.52699) (xy 160.339253 -159.580873)
			(xy 160.345908 -159.636318) (xy 160.344409 -159.692142) (xy 160.334787 -159.74715) (xy 160.317248 -159.800168)
			(xy 160.292168 -159.850062) (xy 160.260081 -159.895767) (xy 160.221674 -159.936306) (xy 160.177767 -159.970812)
			(xy 160.129298 -159.998548) (xy 160.077304 -160.018922) (xy 160.022895 -160.031497) (xy 159.967234 -160.036007)
			(xy 159.91151 -160.032353) (xy 159.856914 -160.020614) (xy 159.804613 -160.001041) (xy 159.755724 -159.974053)
			(xy 159.711293 -159.940225) (xy 159.672267 -159.900281) (xy 159.639482 -159.855075) (xy 159.613638 -159.805571)
			(xy 159.595287 -159.752829) (xy 159.584822 -159.697975) (xy 159.582465 -159.642182) (xy 159.584898 -159.614362)
			(xy 159.586727 -159.592288) (xy 159.583636 -159.548106) (xy 159.572933 -159.505129) (xy 159.554944 -159.464658)
			(xy 159.530212 -159.427917) (xy 159.499487 -159.396018) (xy 159.463698 -159.369928) (xy 159.423928 -159.350436)
			(xy 159.40278 -159.343852) (xy 159.375577 -159.335455) (xy 159.32383 -159.311724) (xy 159.276181 -159.280571)
			(xy 159.233687 -159.242687) (xy 159.197291 -159.198912) (xy 159.1678 -159.150216) (xy 159.145869 -159.097681)
			(xy 159.131983 -159.042471) (xy 159.126451 -158.985812) (xy 159.129396 -158.928958) (xy 159.140751 -158.873173)
			(xy 159.15005 -158.846266) (xy 159.157227 -158.825266) (xy 159.164965 -158.781571) (xy 159.164997 -158.737195)
			(xy 159.157322 -158.693489) (xy 159.142173 -158.651779) (xy 159.120011 -158.613334) (xy 159.09151 -158.579322)
			(xy 159.057534 -158.550777) (xy 159.019118 -158.528565) (xy 158.977428 -158.513363) (xy 158.933731 -158.505632)
			(xy 158.911544 -158.505144) (xy 157.008068 -158.505144) (xy 156.985546 -158.505632) (xy 156.941208 -158.513576)
			(xy 156.898964 -158.529211) (xy 156.860137 -158.552046) (xy 156.825943 -158.581368) (xy 156.797451 -158.616257)
			(xy 156.775555 -158.655621) (xy 156.76094 -158.698228) (xy 156.754063 -158.742744) (xy 156.755139 -158.787776)
			(xy 156.759148 -158.809944) (xy 156.764277 -158.837598) (xy 156.767306 -158.893758) (xy 156.762058 -158.949755)
			(xy 156.748646 -159.004375) (xy 156.727362 -159.056434) (xy 156.698666 -159.104804) (xy 156.663179 -159.148438)
			(xy 156.621672 -159.18639) (xy 156.575043 -159.217837) (xy 156.524303 -159.242099) (xy 156.470551 -159.258649)
			(xy 156.414952 -159.267129) (xy 156.35871 -159.267355) (xy 156.303045 -159.259322) (xy 156.249161 -159.243204)
			(xy 156.198228 -159.219351) (xy 156.151348 -159.18828) (xy 156.109537 -159.150663) (xy 156.073701 -159.107316)
			(xy 156.044617 -159.059177) (xy 156.022915 -159.007291) (xy 156.009065 -158.952781) (xy 156.003367 -158.896828)
			(xy 156.005945 -158.840645) (xy 156.016742 -158.785449) (xy 156.035525 -158.732436) (xy 156.048202 -158.707328)
			(xy 156.05506 -158.694628) (xy 156.062934 -158.66491) (xy 156.066709 -158.648689) (xy 156.066694 -158.615399)
			(xy 156.058068 -158.583246) (xy 156.041419 -158.554418) (xy 156.017879 -158.530879) (xy 155.989051 -158.51423)
			(xy 155.956897 -158.505605) (xy 155.940252 -158.505144) (xy 155.865322 -158.505144) (xy 154.37739 -159.993076)
			(xy 154.95727 -159.993076) (xy 154.961341 -159.937454) (xy 154.973467 -159.883017) (xy 154.99339 -159.830926)
			(xy 155.020686 -159.782291) (xy 155.054772 -159.738148) (xy 155.094921 -159.699439) (xy 155.140279 -159.666988)
			(xy 155.189879 -159.641487) (xy 155.242663 -159.62348) (xy 155.297506 -159.61335) (xy 155.35324 -159.611313)
			(xy 155.408677 -159.617413) (xy 155.462634 -159.631519) (xy 155.513963 -159.653331) (xy 155.561569 -159.682385)
			(xy 155.576583 -159.69488) (xy 158.098742 -159.69488) (xy 158.102813 -159.639258) (xy 158.114939 -159.584821)
			(xy 158.134862 -159.53273) (xy 158.162158 -159.484095) (xy 158.196244 -159.439952) (xy 158.236393 -159.401243)
			(xy 158.281751 -159.368792) (xy 158.331351 -159.343291) (xy 158.384135 -159.325284) (xy 158.438978 -159.315154)
			(xy 158.494712 -159.313117) (xy 158.550149 -159.319217) (xy 158.604106 -159.333323) (xy 158.655435 -159.355135)
			(xy 158.703041 -159.384189) (xy 158.745909 -159.419864) (xy 158.783126 -159.461401) (xy 158.813899 -159.507914)
			(xy 158.837571 -159.558411) (xy 158.853639 -159.611818) (xy 158.861759 -159.666994) (xy 158.862268 -159.69488)
			(xy 158.861759 -159.722766) (xy 158.853639 -159.777942) (xy 158.837571 -159.831349) (xy 158.813899 -159.881846)
			(xy 158.783126 -159.928359) (xy 158.745909 -159.969896) (xy 158.703041 -160.005571) (xy 158.655435 -160.034625)
			(xy 158.604106 -160.056437) (xy 158.550149 -160.070543) (xy 158.494712 -160.076643) (xy 158.438978 -160.074606)
			(xy 158.384135 -160.064476) (xy 158.331351 -160.046469) (xy 158.281751 -160.020968) (xy 158.236393 -159.988517)
			(xy 158.196244 -159.949808) (xy 158.162158 -159.905665) (xy 158.134862 -159.85703) (xy 158.114939 -159.804939)
			(xy 158.102813 -159.750502) (xy 158.098742 -159.69488) (xy 155.576583 -159.69488) (xy 155.604437 -159.71806)
			(xy 155.641654 -159.759597) (xy 155.672427 -159.80611) (xy 155.696099 -159.856607) (xy 155.712167 -159.910014)
			(xy 155.720287 -159.96519) (xy 155.720796 -159.993076) (xy 155.720287 -160.020962) (xy 155.712167 -160.076138)
			(xy 155.696099 -160.129545) (xy 155.672427 -160.180042) (xy 155.641654 -160.226555) (xy 155.604437 -160.268092)
			(xy 155.561569 -160.303767) (xy 155.513963 -160.332821) (xy 155.462634 -160.354633) (xy 155.438784 -160.360868)
			(xy 160.68878 -160.360868) (xy 160.692851 -160.305246) (xy 160.704977 -160.250809) (xy 160.7249 -160.198718)
			(xy 160.752196 -160.150083) (xy 160.786282 -160.10594) (xy 160.826431 -160.067231) (xy 160.871789 -160.03478)
			(xy 160.921389 -160.009279) (xy 160.974173 -159.991272) (xy 161.029016 -159.981142) (xy 161.08475 -159.979105)
			(xy 161.140187 -159.985205) (xy 161.152806 -159.988504) (xy 164.507924 -159.988504) (xy 164.511995 -159.932882)
			(xy 164.524121 -159.878445) (xy 164.544044 -159.826354) (xy 164.57134 -159.777719) (xy 164.605426 -159.733576)
			(xy 164.645575 -159.694867) (xy 164.690933 -159.662416) (xy 164.740533 -159.636915) (xy 164.793317 -159.618908)
			(xy 164.84816 -159.608778) (xy 164.903894 -159.606741) (xy 164.959331 -159.612841) (xy 165.013288 -159.626947)
			(xy 165.064617 -159.648759) (xy 165.112223 -159.677813) (xy 165.155091 -159.713488) (xy 165.192308 -159.755025)
			(xy 165.223081 -159.801538) (xy 165.246753 -159.852035) (xy 165.262821 -159.905442) (xy 165.270941 -159.960618)
			(xy 165.27145 -159.988504) (xy 165.270941 -160.01639) (xy 165.262821 -160.071566) (xy 165.246753 -160.124973)
			(xy 165.223081 -160.17547) (xy 165.192308 -160.221983) (xy 165.155091 -160.26352) (xy 165.112223 -160.299195)
			(xy 165.064617 -160.328249) (xy 165.013288 -160.350061) (xy 164.959331 -160.364167) (xy 164.903894 -160.370267)
			(xy 164.84816 -160.36823) (xy 164.793317 -160.3581) (xy 164.740533 -160.340093) (xy 164.690933 -160.314592)
			(xy 164.645575 -160.282141) (xy 164.605426 -160.243432) (xy 164.57134 -160.199289) (xy 164.544044 -160.150654)
			(xy 164.524121 -160.098563) (xy 164.511995 -160.044126) (xy 164.507924 -159.988504) (xy 161.152806 -159.988504)
			(xy 161.194144 -159.999311) (xy 161.245473 -160.021123) (xy 161.293079 -160.050177) (xy 161.335947 -160.085852)
			(xy 161.373164 -160.127389) (xy 161.403937 -160.173902) (xy 161.427609 -160.224399) (xy 161.443677 -160.277806)
			(xy 161.451797 -160.332982) (xy 161.452306 -160.360868) (xy 161.45207 -160.373822) (xy 162.498784 -160.373822)
			(xy 162.502855 -160.3182) (xy 162.514981 -160.263763) (xy 162.534904 -160.211672) (xy 162.5622 -160.163037)
			(xy 162.596286 -160.118894) (xy 162.636435 -160.080185) (xy 162.681793 -160.047734) (xy 162.731393 -160.022233)
			(xy 162.784177 -160.004226) (xy 162.83902 -159.994096) (xy 162.894754 -159.992059) (xy 162.950191 -159.998159)
			(xy 163.004148 -160.012265) (xy 163.055477 -160.034077) (xy 163.103083 -160.063131) (xy 163.145951 -160.098806)
			(xy 163.183168 -160.140343) (xy 163.213941 -160.186856) (xy 163.237613 -160.237353) (xy 163.253681 -160.29076)
			(xy 163.261801 -160.345936) (xy 163.26231 -160.373822) (xy 163.262162 -160.38195) (xy 165.790116 -160.38195)
			(xy 165.794187 -160.326328) (xy 165.806313 -160.271891) (xy 165.826236 -160.2198) (xy 165.853532 -160.171165)
			(xy 165.887618 -160.127022) (xy 165.927767 -160.088313) (xy 165.973125 -160.055862) (xy 166.022725 -160.030361)
			(xy 166.075509 -160.012354) (xy 166.130352 -160.002224) (xy 166.186086 -160.000187) (xy 166.241523 -160.006287)
			(xy 166.29548 -160.020393) (xy 166.346809 -160.042205) (xy 166.394415 -160.071259) (xy 166.437283 -160.106934)
			(xy 166.4745 -160.148471) (xy 166.505273 -160.194984) (xy 166.528945 -160.245481) (xy 166.545013 -160.298888)
			(xy 166.553133 -160.354064) (xy 166.553642 -160.38195) (xy 166.553133 -160.409836) (xy 166.545013 -160.465012)
			(xy 166.528945 -160.518419) (xy 166.505273 -160.568916) (xy 166.4745 -160.615429) (xy 166.437283 -160.656966)
			(xy 166.394415 -160.692641) (xy 166.346809 -160.721695) (xy 166.29548 -160.743507) (xy 166.241523 -160.757613)
			(xy 166.186086 -160.763713) (xy 166.130352 -160.761676) (xy 166.075509 -160.751546) (xy 166.022725 -160.733539)
			(xy 165.973125 -160.708038) (xy 165.927767 -160.675587) (xy 165.887618 -160.636878) (xy 165.853532 -160.592735)
			(xy 165.826236 -160.5441) (xy 165.806313 -160.492009) (xy 165.794187 -160.437572) (xy 165.790116 -160.38195)
			(xy 163.262162 -160.38195) (xy 163.261801 -160.401708) (xy 163.253681 -160.456884) (xy 163.237613 -160.510291)
			(xy 163.213941 -160.560788) (xy 163.183168 -160.607301) (xy 163.145951 -160.648838) (xy 163.103083 -160.684513)
			(xy 163.055477 -160.713567) (xy 163.004148 -160.735379) (xy 162.950191 -160.749485) (xy 162.894754 -160.755585)
			(xy 162.83902 -160.753548) (xy 162.784177 -160.743418) (xy 162.731393 -160.725411) (xy 162.681793 -160.69991)
			(xy 162.636435 -160.667459) (xy 162.596286 -160.62875) (xy 162.5622 -160.584607) (xy 162.534904 -160.535972)
			(xy 162.514981 -160.483881) (xy 162.502855 -160.429444) (xy 162.498784 -160.373822) (xy 161.45207 -160.373822)
			(xy 161.451797 -160.388754) (xy 161.443677 -160.44393) (xy 161.427609 -160.497337) (xy 161.403937 -160.547834)
			(xy 161.373164 -160.594347) (xy 161.335947 -160.635884) (xy 161.293079 -160.671559) (xy 161.245473 -160.700613)
			(xy 161.194144 -160.722425) (xy 161.140187 -160.736531) (xy 161.08475 -160.742631) (xy 161.029016 -160.740594)
			(xy 160.974173 -160.730464) (xy 160.921389 -160.712457) (xy 160.871789 -160.686956) (xy 160.826431 -160.654505)
			(xy 160.786282 -160.615796) (xy 160.752196 -160.571653) (xy 160.7249 -160.523018) (xy 160.704977 -160.470927)
			(xy 160.692851 -160.41649) (xy 160.68878 -160.360868) (xy 155.438784 -160.360868) (xy 155.408677 -160.368739)
			(xy 155.35324 -160.374839) (xy 155.297506 -160.372802) (xy 155.242663 -160.362672) (xy 155.189879 -160.344665)
			(xy 155.140279 -160.319164) (xy 155.094921 -160.286713) (xy 155.054772 -160.248004) (xy 155.020686 -160.203861)
			(xy 154.99339 -160.155226) (xy 154.973467 -160.103135) (xy 154.961341 -160.048698) (xy 154.95727 -159.993076)
			(xy 154.37739 -159.993076) (xy 153.514806 -160.85566) (xy 156.267402 -160.85566) (xy 156.271473 -160.800038)
			(xy 156.283599 -160.745601) (xy 156.303522 -160.69351) (xy 156.330818 -160.644875) (xy 156.364904 -160.600732)
			(xy 156.405053 -160.562023) (xy 156.450411 -160.529572) (xy 156.500011 -160.504071) (xy 156.552795 -160.486064)
			(xy 156.607638 -160.475934) (xy 156.663372 -160.473897) (xy 156.718809 -160.479997) (xy 156.772766 -160.494103)
			(xy 156.824095 -160.515915) (xy 156.871701 -160.544969) (xy 156.914569 -160.580644) (xy 156.951786 -160.622181)
			(xy 156.982559 -160.668694) (xy 157.006231 -160.719191) (xy 157.022299 -160.772598) (xy 157.030419 -160.827774)
			(xy 157.030928 -160.85566) (xy 157.030419 -160.883546) (xy 157.022299 -160.938722) (xy 157.006231 -160.992129)
			(xy 156.982559 -161.042626) (xy 156.951786 -161.089139) (xy 156.914569 -161.130676) (xy 156.871701 -161.166351)
			(xy 156.824095 -161.195405) (xy 156.772766 -161.217217) (xy 156.718809 -161.231323) (xy 156.663372 -161.237423)
			(xy 156.607638 -161.235386) (xy 156.552795 -161.225256) (xy 156.500011 -161.207249) (xy 156.450411 -161.181748)
			(xy 156.405053 -161.149297) (xy 156.364904 -161.110588) (xy 156.330818 -161.066445) (xy 156.303522 -161.01781)
			(xy 156.283599 -160.965719) (xy 156.271473 -160.911282) (xy 156.267402 -160.85566) (xy 153.514806 -160.85566)
			(xy 152.94229 -161.428176) (xy 157.735522 -161.428176) (xy 157.739593 -161.372554) (xy 157.751719 -161.318117)
			(xy 157.771642 -161.266026) (xy 157.798938 -161.217391) (xy 157.833024 -161.173248) (xy 157.873173 -161.134539)
			(xy 157.918531 -161.102088) (xy 157.968131 -161.076587) (xy 158.020915 -161.05858) (xy 158.075758 -161.04845)
			(xy 158.131492 -161.046413) (xy 158.186929 -161.052513) (xy 158.240886 -161.066619) (xy 158.292215 -161.088431)
			(xy 158.339821 -161.117485) (xy 158.382689 -161.15316) (xy 158.419906 -161.194697) (xy 158.450679 -161.24121)
			(xy 158.474351 -161.291707) (xy 158.490419 -161.345114) (xy 158.498539 -161.40029) (xy 158.499048 -161.428176)
			(xy 158.498539 -161.456062) (xy 158.490419 -161.511238) (xy 158.474351 -161.564645) (xy 158.450679 -161.615142)
			(xy 158.419906 -161.661655) (xy 158.382689 -161.703192) (xy 158.339821 -161.738867) (xy 158.292215 -161.767921)
			(xy 158.240886 -161.789733) (xy 158.186929 -161.803839) (xy 158.131492 -161.809939) (xy 158.075758 -161.807902)
			(xy 158.020915 -161.797772) (xy 157.968131 -161.779765) (xy 157.918531 -161.754264) (xy 157.873173 -161.721813)
			(xy 157.833024 -161.683104) (xy 157.798938 -161.638961) (xy 157.771642 -161.590326) (xy 157.751719 -161.538235)
			(xy 157.739593 -161.483798) (xy 157.735522 -161.428176) (xy 152.94229 -161.428176) (xy 151.928937 -162.441529)
			(xy 157.228537 -162.441529) (xy 157.228556 -162.386819) (xy 157.236388 -162.332672) (xy 157.251875 -162.280199)
			(xy 157.274698 -162.230477) (xy 157.30439 -162.184524) (xy 157.340341 -162.143284) (xy 157.381814 -162.107602)
			(xy 157.427958 -162.07821) (xy 157.477828 -162.055711) (xy 157.5304 -162.040565) (xy 157.584596 -162.033085)
			(xy 157.639306 -162.033422) (xy 157.693406 -162.041571) (xy 157.745787 -162.057364) (xy 157.795375 -162.080477)
			(xy 157.841154 -162.110436) (xy 157.882183 -162.146627) (xy 157.917622 -162.188308) (xy 157.946745 -162.234623)
			(xy 157.968952 -162.284624) (xy 157.970185 -162.288728) (xy 158.913066 -162.288728) (xy 158.917137 -162.233106)
			(xy 158.929263 -162.178669) (xy 158.949186 -162.126578) (xy 158.976482 -162.077943) (xy 159.010568 -162.0338)
			(xy 159.050717 -161.995091) (xy 159.096075 -161.96264) (xy 159.145675 -161.937139) (xy 159.198459 -161.919132)
			(xy 159.253302 -161.909002) (xy 159.309036 -161.906965) (xy 159.364473 -161.913065) (xy 159.41843 -161.927171)
			(xy 159.469759 -161.948983) (xy 159.517365 -161.978037) (xy 159.560233 -162.013712) (xy 159.59745 -162.055249)
			(xy 159.628223 -162.101762) (xy 159.651895 -162.152259) (xy 159.667963 -162.205666) (xy 159.676083 -162.260842)
			(xy 159.676592 -162.288728) (xy 159.676083 -162.316614) (xy 159.667963 -162.37179) (xy 159.665595 -162.37966)
			(xy 161.789362 -162.37966) (xy 161.793433 -162.324038) (xy 161.805559 -162.269601) (xy 161.825482 -162.21751)
			(xy 161.852778 -162.168875) (xy 161.886864 -162.124732) (xy 161.927013 -162.086023) (xy 161.972371 -162.053572)
			(xy 162.021971 -162.028071) (xy 162.074755 -162.010064) (xy 162.129598 -161.999934) (xy 162.185332 -161.997897)
			(xy 162.240769 -162.003997) (xy 162.294726 -162.018103) (xy 162.346055 -162.039915) (xy 162.393661 -162.068969)
			(xy 162.436529 -162.104644) (xy 162.473746 -162.146181) (xy 162.504519 -162.192694) (xy 162.528191 -162.243191)
			(xy 162.544259 -162.296598) (xy 162.552379 -162.351774) (xy 162.552888 -162.37966) (xy 164.953694 -162.37966)
			(xy 164.957765 -162.324038) (xy 164.969891 -162.269601) (xy 164.989814 -162.21751) (xy 165.01711 -162.168875)
			(xy 165.051196 -162.124732) (xy 165.091345 -162.086023) (xy 165.136703 -162.053572) (xy 165.186303 -162.028071)
			(xy 165.239087 -162.010064) (xy 165.29393 -161.999934) (xy 165.349664 -161.997897) (xy 165.405101 -162.003997)
			(xy 165.459058 -162.018103) (xy 165.510387 -162.039915) (xy 165.557993 -162.068969) (xy 165.600861 -162.104644)
			(xy 165.638078 -162.146181) (xy 165.668851 -162.192694) (xy 165.692523 -162.243191) (xy 165.708591 -162.296598)
			(xy 165.716711 -162.351774) (xy 165.71722 -162.37966) (xy 165.716711 -162.407546) (xy 165.715507 -162.415728)
			(xy 166.031162 -162.415728) (xy 166.035233 -162.360106) (xy 166.047359 -162.305669) (xy 166.067282 -162.253578)
			(xy 166.094578 -162.204943) (xy 166.128664 -162.1608) (xy 166.168813 -162.122091) (xy 166.214171 -162.08964)
			(xy 166.263771 -162.064139) (xy 166.316555 -162.046132) (xy 166.371398 -162.036002) (xy 166.427132 -162.033965)
			(xy 166.482569 -162.040065) (xy 166.536526 -162.054171) (xy 166.587855 -162.075983) (xy 166.635461 -162.105037)
			(xy 166.678329 -162.140712) (xy 166.715546 -162.182249) (xy 166.746319 -162.228762) (xy 166.769991 -162.279259)
			(xy 166.786059 -162.332666) (xy 166.794179 -162.387842) (xy 166.794688 -162.415728) (xy 166.794179 -162.443614)
			(xy 166.786059 -162.49879) (xy 166.769991 -162.552197) (xy 166.746319 -162.602694) (xy 166.715546 -162.649207)
			(xy 166.678329 -162.690744) (xy 166.635461 -162.726419) (xy 166.587855 -162.755473) (xy 166.536526 -162.777285)
			(xy 166.482569 -162.791391) (xy 166.427132 -162.797491) (xy 166.371398 -162.795454) (xy 166.316555 -162.785324)
			(xy 166.263771 -162.767317) (xy 166.214171 -162.741816) (xy 166.168813 -162.709365) (xy 166.128664 -162.670656)
			(xy 166.094578 -162.626513) (xy 166.067282 -162.577878) (xy 166.047359 -162.525787) (xy 166.035233 -162.47135)
			(xy 166.031162 -162.415728) (xy 165.715507 -162.415728) (xy 165.708591 -162.462722) (xy 165.692523 -162.516129)
			(xy 165.668851 -162.566626) (xy 165.638078 -162.613139) (xy 165.600861 -162.654676) (xy 165.557993 -162.690351)
			(xy 165.510387 -162.719405) (xy 165.459058 -162.741217) (xy 165.405101 -162.755323) (xy 165.349664 -162.761423)
			(xy 165.29393 -162.759386) (xy 165.239087 -162.749256) (xy 165.186303 -162.731249) (xy 165.136703 -162.705748)
			(xy 165.091345 -162.673297) (xy 165.051196 -162.634588) (xy 165.01711 -162.590445) (xy 164.989814 -162.54181)
			(xy 164.969891 -162.489719) (xy 164.957765 -162.435282) (xy 164.953694 -162.37966) (xy 162.552888 -162.37966)
			(xy 162.552379 -162.407546) (xy 162.544259 -162.462722) (xy 162.528191 -162.516129) (xy 162.504519 -162.566626)
			(xy 162.473746 -162.613139) (xy 162.436529 -162.654676) (xy 162.393661 -162.690351) (xy 162.346055 -162.719405)
			(xy 162.294726 -162.741217) (xy 162.240769 -162.755323) (xy 162.185332 -162.761423) (xy 162.129598 -162.759386)
			(xy 162.074755 -162.749256) (xy 162.021971 -162.731249) (xy 161.972371 -162.705748) (xy 161.927013 -162.673297)
			(xy 161.886864 -162.634588) (xy 161.852778 -162.590445) (xy 161.825482 -162.54181) (xy 161.805559 -162.489719)
			(xy 161.793433 -162.435282) (xy 161.789362 -162.37966) (xy 159.665595 -162.37966) (xy 159.651895 -162.425197)
			(xy 159.628223 -162.475694) (xy 159.59745 -162.522207) (xy 159.560233 -162.563744) (xy 159.517365 -162.599419)
			(xy 159.469759 -162.628473) (xy 159.41843 -162.650285) (xy 159.364473 -162.664391) (xy 159.309036 -162.670491)
			(xy 159.253302 -162.668454) (xy 159.198459 -162.658324) (xy 159.145675 -162.640317) (xy 159.096075 -162.614816)
			(xy 159.050717 -162.582365) (xy 159.010568 -162.543656) (xy 158.976482 -162.499513) (xy 158.949186 -162.450878)
			(xy 158.929263 -162.398787) (xy 158.917137 -162.34435) (xy 158.913066 -162.288728) (xy 157.970185 -162.288728)
			(xy 157.976824 -162.310826) (xy 157.983573 -162.332775) (xy 158.00377 -162.37401) (xy 158.031041 -162.410948)
			(xy 158.064501 -162.442391) (xy 158.103061 -162.467317) (xy 158.14547 -162.484915) (xy 158.190348 -162.494615)
			(xy 158.236239 -162.4961) (xy 158.259018 -162.493198) (xy 158.286138 -162.489591) (xy 158.340848 -162.489289)
			(xy 158.395041 -162.496804) (xy 158.447604 -162.511983) (xy 158.49746 -162.534514) (xy 158.543586 -162.563935)
			(xy 158.585038 -162.599644) (xy 158.620963 -162.640907) (xy 158.650626 -162.686878) (xy 158.673419 -162.736615)
			(xy 158.688874 -162.789098) (xy 158.696674 -162.84325) (xy 158.696658 -162.897961) (xy 158.688829 -162.952109)
			(xy 158.673345 -163.004583) (xy 158.650525 -163.054307) (xy 158.620836 -163.100262) (xy 158.584888 -163.141505)
			(xy 158.543417 -163.177191) (xy 158.497274 -163.206587) (xy 158.447405 -163.22909) (xy 158.394834 -163.24424)
			(xy 158.340638 -163.251725) (xy 158.285928 -163.251393) (xy 158.231826 -163.243249) (xy 158.179443 -163.227461)
			(xy 158.129852 -163.204352) (xy 158.08407 -163.174397) (xy 158.043036 -163.13821) (xy 158.007592 -163.096533)
			(xy 157.978464 -163.05022) (xy 157.956251 -163.000222) (xy 157.948376 -162.97402) (xy 157.941659 -162.95206)
			(xy 157.921454 -162.910828) (xy 157.894176 -162.873891) (xy 157.860712 -162.842451) (xy 157.822148 -162.817527)
			(xy 157.779736 -162.799931) (xy 157.734855 -162.790232) (xy 157.688962 -162.788747) (xy 157.666182 -162.791648)
			(xy 157.639053 -162.795197) (xy 157.584344 -162.795498) (xy 157.530152 -162.787982) (xy 157.47759 -162.772802)
			(xy 157.427735 -162.750269) (xy 157.38161 -162.720847) (xy 157.340161 -162.685137) (xy 157.304237 -162.643873)
			(xy 157.274576 -162.597901) (xy 157.251786 -162.548164) (xy 157.236334 -162.495681) (xy 157.228537 -162.441529)
			(xy 151.928937 -162.441529) (xy 151.421084 -162.949382) (xy 152.266902 -162.949382) (xy 152.270973 -162.89376)
			(xy 152.283099 -162.839323) (xy 152.303022 -162.787232) (xy 152.330318 -162.738597) (xy 152.364404 -162.694454)
			(xy 152.404553 -162.655745) (xy 152.449911 -162.623294) (xy 152.499511 -162.597793) (xy 152.552295 -162.579786)
			(xy 152.607138 -162.569656) (xy 152.662872 -162.567619) (xy 152.718309 -162.573719) (xy 152.772266 -162.587825)
			(xy 152.823595 -162.609637) (xy 152.871201 -162.638691) (xy 152.914069 -162.674366) (xy 152.951286 -162.715903)
			(xy 152.982059 -162.762416) (xy 153.005731 -162.812913) (xy 153.021799 -162.86632) (xy 153.029919 -162.921496)
			(xy 153.030118 -162.932399) (xy 153.290522 -162.932399) (xy 153.293307 -162.877784) (xy 153.303861 -162.824126)
			(xy 153.321967 -162.772524) (xy 153.347255 -162.724036) (xy 153.379207 -162.679655) (xy 153.417167 -162.640291)
			(xy 153.460359 -162.606749) (xy 153.507896 -162.579717) (xy 153.558807 -162.559749) (xy 153.612046 -162.547253)
			(xy 153.666524 -162.542487) (xy 153.721124 -162.545547) (xy 153.774729 -162.556371) (xy 153.826238 -162.574737)
			(xy 153.874599 -162.600269) (xy 153.918818 -162.632443) (xy 153.938732 -162.651186) (xy 153.95547 -162.666843)
			(xy 153.993532 -162.692373) (xy 154.035551 -162.710673) (xy 154.080168 -162.721153) (xy 154.12594 -162.723472)
			(xy 154.171388 -162.717556) (xy 154.215041 -162.703597) (xy 154.255489 -162.682045) (xy 154.273758 -162.668204)
			(xy 154.295496 -162.651624) (xy 154.342752 -162.624135) (xy 154.393447 -162.603672) (xy 154.446545 -162.590657)
			(xy 154.500957 -162.585355) (xy 154.555568 -162.587875) (xy 154.60926 -162.598166) (xy 154.660934 -162.616016)
			(xy 154.709529 -162.64106) (xy 154.754052 -162.672785) (xy 154.79359 -162.710541) (xy 154.827333 -162.753555)
			(xy 154.854589 -162.800945) (xy 154.874801 -162.851741) (xy 154.887555 -162.904902) (xy 154.892588 -162.959339)
			(xy 154.889799 -163.013937) (xy 154.879244 -163.067578) (xy 154.861139 -163.119163) (xy 154.835856 -163.167635)
			(xy 154.803912 -163.212) (xy 154.765962 -163.251352) (xy 154.722782 -163.284882) (xy 154.675258 -163.311905)
			(xy 154.624363 -163.331866) (xy 154.57114 -163.344357) (xy 154.516678 -163.349123) (xy 154.462095 -163.346064)
			(xy 154.408506 -163.335245) (xy 154.357012 -163.316886) (xy 154.308665 -163.291364) (xy 154.264457 -163.259202)
			(xy 154.244548 -163.240466) (xy 154.227742 -163.224884) (xy 154.189696 -163.199346) (xy 154.147691 -163.181036)
			(xy 154.103085 -163.170547) (xy 154.057322 -163.168217) (xy 154.011881 -163.174121) (xy 153.968233 -163.18807)
			(xy 153.92779 -163.209612) (xy 153.909522 -163.223448) (xy 153.88783 -163.240099) (xy 153.840566 -163.267609)
			(xy 153.78986 -163.288088) (xy 153.736749 -163.301119) (xy 153.682322 -163.306434) (xy 153.627693 -163.303924)
			(xy 153.573983 -163.29364) (xy 153.522291 -163.275793) (xy 153.473676 -163.25075) (xy 153.429135 -163.219022)
			(xy 153.38958 -163.18126) (xy 153.355821 -163.138238) (xy 153.32855 -163.090837) (xy 153.308325 -163.040028)
			(xy 153.295562 -162.986852) (xy 153.290522 -162.932399) (xy 153.030118 -162.932399) (xy 153.030428 -162.949382)
			(xy 153.029919 -162.977268) (xy 153.021799 -163.032444) (xy 153.005731 -163.085851) (xy 152.982059 -163.136348)
			(xy 152.951286 -163.182861) (xy 152.914069 -163.224398) (xy 152.871201 -163.260073) (xy 152.823595 -163.289127)
			(xy 152.772266 -163.310939) (xy 152.718309 -163.325045) (xy 152.662872 -163.331145) (xy 152.607138 -163.329108)
			(xy 152.552295 -163.318978) (xy 152.499511 -163.300971) (xy 152.449911 -163.27547) (xy 152.404553 -163.243019)
			(xy 152.364404 -163.20431) (xy 152.330318 -163.160167) (xy 152.303022 -163.111532) (xy 152.283099 -163.059441)
			(xy 152.270973 -163.005004) (xy 152.266902 -162.949382) (xy 151.421084 -162.949382) (xy 150.934674 -163.435792)
			(xy 163.940742 -163.435792) (xy 163.944813 -163.38017) (xy 163.956939 -163.325733) (xy 163.976862 -163.273642)
			(xy 164.004158 -163.225007) (xy 164.038244 -163.180864) (xy 164.078393 -163.142155) (xy 164.123751 -163.109704)
			(xy 164.173351 -163.084203) (xy 164.226135 -163.066196) (xy 164.280978 -163.056066) (xy 164.336712 -163.054029)
			(xy 164.392149 -163.060129) (xy 164.446106 -163.074235) (xy 164.497435 -163.096047) (xy 164.545041 -163.125101)
			(xy 164.587909 -163.160776) (xy 164.625126 -163.202313) (xy 164.655899 -163.248826) (xy 164.679571 -163.299323)
			(xy 164.695639 -163.35273) (xy 164.703759 -163.407906) (xy 164.704268 -163.435792) (xy 164.703759 -163.463678)
			(xy 164.695639 -163.518854) (xy 164.679571 -163.572261) (xy 164.655899 -163.622758) (xy 164.625126 -163.669271)
			(xy 164.587909 -163.710808) (xy 164.545041 -163.746483) (xy 164.497435 -163.775537) (xy 164.446106 -163.797349)
			(xy 164.392149 -163.811455) (xy 164.336712 -163.817555) (xy 164.280978 -163.815518) (xy 164.226135 -163.805388)
			(xy 164.173351 -163.787381) (xy 164.123751 -163.76188) (xy 164.078393 -163.729429) (xy 164.038244 -163.69072)
			(xy 164.004158 -163.646577) (xy 163.976862 -163.597942) (xy 163.956939 -163.545851) (xy 163.944813 -163.491414)
			(xy 163.940742 -163.435792) (xy 150.934674 -163.435792) (xy 149.872192 -164.498274) (xy 149.857035 -164.51407)
			(xy 149.831837 -164.549865) (xy 149.813152 -164.589451) (xy 149.801533 -164.631655) (xy 149.797324 -164.675227)
			(xy 149.80065 -164.718875) (xy 149.811413 -164.761305) (xy 149.823562 -164.788455) (xy 155.522702 -164.788455)
			(xy 155.524235 -164.732777) (xy 155.533848 -164.677914) (xy 155.551338 -164.625032) (xy 155.576332 -164.575256)
			(xy 155.608299 -164.529643) (xy 155.646559 -164.489164) (xy 155.690299 -164.45468) (xy 155.714192 -164.440362)
			(xy 155.734407 -164.428086) (xy 155.770357 -164.39737) (xy 155.800004 -164.360533) (xy 155.822323 -164.318846)
			(xy 155.836544 -164.27375) (xy 155.842176 -164.226801) (xy 155.839023 -164.17962) (xy 155.827196 -164.133838)
			(xy 155.807103 -164.091034) (xy 155.793694 -164.071554) (xy 155.777841 -164.048657) (xy 155.752161 -163.999242)
			(xy 155.733941 -163.946618) (xy 155.723566 -163.891904) (xy 155.721259 -163.836263) (xy 155.727067 -163.780878)
			(xy 155.740868 -163.726926) (xy 155.762368 -163.675555) (xy 155.79111 -163.627856) (xy 155.826482 -163.584844)
			(xy 155.867734 -163.547433) (xy 155.913987 -163.516419) (xy 155.964259 -163.49246) (xy 156.01748 -163.476067)
			(xy 156.072519 -163.467587) (xy 156.128207 -163.467202) (xy 156.183359 -163.474919) (xy 156.236802 -163.490574)
			(xy 156.2874 -163.513834) (xy 156.334079 -163.544205) (xy 156.375844 -163.581041) (xy 156.411809 -163.623559)
			(xy 156.441208 -163.670856) (xy 156.463417 -163.721924) (xy 156.477963 -163.77568) (xy 156.484538 -163.830979)
			(xy 156.483001 -163.886647) (xy 156.473385 -163.941499) (xy 156.455895 -163.99437) (xy 156.430902 -164.044136)
			(xy 156.398937 -164.089738) (xy 156.360681 -164.130207) (xy 156.316947 -164.164682) (xy 156.293058 -164.178996)
			(xy 156.272794 -164.191193) (xy 156.236845 -164.221923) (xy 156.207202 -164.258774) (xy 156.184888 -164.300472)
			(xy 156.170674 -164.345579) (xy 156.165049 -164.392537) (xy 156.168208 -164.439724) (xy 156.180043 -164.485513)
			(xy 156.200144 -164.528322) (xy 156.213556 -164.547804) (xy 156.229478 -164.570658) (xy 156.255171 -164.620077)
			(xy 156.273403 -164.672708) (xy 156.283788 -164.72743) (xy 156.286104 -164.783081) (xy 156.280303 -164.838477)
			(xy 156.266508 -164.892441) (xy 156.245011 -164.943825) (xy 156.216271 -164.991536) (xy 156.180898 -165.034561)
			(xy 156.16924 -165.045136) (xy 164.176962 -165.045136) (xy 164.181033 -164.989514) (xy 164.193159 -164.935077)
			(xy 164.213082 -164.882986) (xy 164.240378 -164.834351) (xy 164.274464 -164.790208) (xy 164.314613 -164.751499)
			(xy 164.359971 -164.719048) (xy 164.409571 -164.693547) (xy 164.462355 -164.67554) (xy 164.517198 -164.66541)
			(xy 164.572932 -164.663373) (xy 164.628369 -164.669473) (xy 164.682326 -164.683579) (xy 164.733655 -164.705391)
			(xy 164.781261 -164.734445) (xy 164.824129 -164.77012) (xy 164.861346 -164.811657) (xy 164.892119 -164.85817)
			(xy 164.915791 -164.908667) (xy 164.931859 -164.962074) (xy 164.939979 -165.01725) (xy 164.940488 -165.045136)
			(xy 164.939979 -165.073022) (xy 164.931859 -165.128198) (xy 164.915791 -165.181605) (xy 164.892119 -165.232102)
			(xy 164.861346 -165.278615) (xy 164.824129 -165.320152) (xy 164.781261 -165.355827) (xy 164.733655 -165.384881)
			(xy 164.682326 -165.406693) (xy 164.628369 -165.420799) (xy 164.572932 -165.426899) (xy 164.517198 -165.424862)
			(xy 164.462355 -165.414732) (xy 164.409571 -165.396725) (xy 164.359971 -165.371224) (xy 164.314613 -165.338773)
			(xy 164.274464 -165.300064) (xy 164.240378 -165.255921) (xy 164.213082 -165.207286) (xy 164.193159 -165.155195)
			(xy 164.181033 -165.100758) (xy 164.176962 -165.045136) (xy 156.16924 -165.045136) (xy 156.139644 -165.071984)
			(xy 156.093386 -165.10301) (xy 156.043108 -165.12698) (xy 155.989879 -165.143382) (xy 155.934831 -165.15187)
			(xy 155.879133 -165.152262) (xy 155.82397 -165.14455) (xy 155.770516 -165.128899) (xy 155.719905 -165.105639)
			(xy 155.673215 -165.075268) (xy 155.631439 -165.038429) (xy 155.595463 -164.995906) (xy 155.566054 -164.948604)
			(xy 155.543837 -164.897528) (xy 155.529283 -164.843764) (xy 155.522702 -164.788455) (xy 149.823562 -164.788455)
			(xy 149.829293 -164.801261) (xy 149.853761 -164.837559) (xy 149.868636 -164.85362) (xy 149.887781 -164.874304)
			(xy 149.920395 -164.920269) (xy 149.945893 -164.970532) (xy 149.96372 -165.023999) (xy 149.973488 -165.079506)
			(xy 149.974986 -165.135846) (xy 149.968179 -165.191794) (xy 149.953217 -165.246132) (xy 149.930425 -165.297678)
			(xy 149.900299 -165.345311) (xy 149.863494 -165.387994) (xy 149.820811 -165.424799) (xy 149.773178 -165.454925)
			(xy 149.721632 -165.477717) (xy 149.667294 -165.492679) (xy 149.611347 -165.499486) (xy 149.555006 -165.497988)
			(xy 149.499499 -165.48822) (xy 149.446033 -165.470393) (xy 149.39577 -165.444895) (xy 149.349804 -165.412282)
			(xy 149.32914 -165.393116) (xy 149.313033 -165.378305) (xy 149.276732 -165.353878) (xy 149.236784 -165.336029)
			(xy 149.19437 -165.325284) (xy 149.150742 -165.321962) (xy 149.107189 -165.32616) (xy 149.064999 -165.337755)
			(xy 149.025418 -165.356404) (xy 148.989616 -165.381555) (xy 148.973794 -165.396672) (xy 148.700236 -165.67023)
			(xy 148.699728 -165.7223) (xy 148.699062 -165.749294) (xy 148.691057 -165.802695) (xy 148.675603 -165.854433)
			(xy 148.653008 -165.903476) (xy 148.623725 -165.948843) (xy 148.595149 -165.981778) (xy 150.680932 -165.981778)
			(xy 150.681777 -165.926238) (xy 150.690669 -165.871409) (xy 150.707421 -165.81845) (xy 150.731678 -165.768481)
			(xy 150.762926 -165.722559) (xy 150.800506 -165.681656) (xy 150.843621 -165.646636) (xy 150.891361 -165.618242)
			(xy 150.942714 -165.597073) (xy 150.996595 -165.583577) (xy 151.051864 -165.578039) (xy 151.107351 -165.580578)
			(xy 151.161884 -165.591139) (xy 151.214307 -165.609498) (xy 151.263513 -165.635268) (xy 151.30846 -165.667903)
			(xy 151.348198 -165.706713) (xy 151.381886 -165.750877) (xy 151.408811 -165.79946) (xy 151.428404 -165.851435)
			(xy 151.44025 -165.905703) (xy 151.442674 -165.933374) (xy 151.44443 -165.950743) (xy 151.456201 -165.983595)
			(xy 151.476427 -166.012034) (xy 151.503596 -166.033935) (xy 151.53568 -166.047663) (xy 151.55291 -166.050468)
			(xy 151.580366 -166.054574) (xy 151.633785 -166.069682) (xy 151.68445 -166.092374) (xy 151.73129 -166.12217)
			(xy 151.773316 -166.158442) (xy 151.809641 -166.200422) (xy 151.839497 -166.247225) (xy 151.862253 -166.29786)
			(xy 151.877428 -166.35126) (xy 151.884703 -166.406295) (xy 151.883924 -166.461804) (xy 151.875106 -166.516614)
			(xy 151.858437 -166.569566) (xy 151.834267 -166.619543) (xy 151.819102 -166.642796) (xy 151.810233 -166.656865)
			(xy 151.802024 -166.680508) (xy 155.307669 -166.680508) (xy 155.308719 -166.624576) (xy 155.317923 -166.569396)
			(xy 155.335084 -166.516151) (xy 155.359833 -166.465981) (xy 155.391641 -166.419962) (xy 155.429825 -166.379079)
			(xy 155.473569 -166.344207) (xy 155.521935 -166.316095) (xy 155.573886 -166.295344) (xy 155.62831 -166.2824)
			(xy 155.68404 -166.277538) (xy 155.739884 -166.280864) (xy 155.794643 -166.292306) (xy 155.847146 -166.311619)
			(xy 155.896267 -166.33839) (xy 155.940953 -166.372044) (xy 155.980249 -166.411861) (xy 155.996847 -166.434516)
			(xy 160.128202 -166.434516) (xy 160.132273 -166.378894) (xy 160.144399 -166.324457) (xy 160.164322 -166.272366)
			(xy 160.191618 -166.223731) (xy 160.225704 -166.179588) (xy 160.265853 -166.140879) (xy 160.311211 -166.108428)
			(xy 160.360811 -166.082927) (xy 160.413595 -166.06492) (xy 160.468438 -166.05479) (xy 160.524172 -166.052753)
			(xy 160.579609 -166.058853) (xy 160.633566 -166.072959) (xy 160.684895 -166.094771) (xy 160.732501 -166.123825)
			(xy 160.775369 -166.1595) (xy 160.812586 -166.201037) (xy 160.843359 -166.24755) (xy 160.867031 -166.298047)
			(xy 160.871485 -166.31285) (xy 163.849302 -166.31285) (xy 163.853373 -166.257228) (xy 163.865499 -166.202791)
			(xy 163.885422 -166.1507) (xy 163.912718 -166.102065) (xy 163.946804 -166.057922) (xy 163.986953 -166.019213)
			(xy 164.032311 -165.986762) (xy 164.081911 -165.961261) (xy 164.134695 -165.943254) (xy 164.189538 -165.933124)
			(xy 164.245272 -165.931087) (xy 164.300709 -165.937187) (xy 164.354666 -165.951293) (xy 164.405995 -165.973105)
			(xy 164.453601 -166.002159) (xy 164.496469 -166.037834) (xy 164.533686 -166.079371) (xy 164.564459 -166.125884)
			(xy 164.588131 -166.176381) (xy 164.604199 -166.229788) (xy 164.612319 -166.284964) (xy 164.612828 -166.31285)
			(xy 164.612319 -166.340736) (xy 164.604199 -166.395912) (xy 164.588131 -166.449319) (xy 164.564459 -166.499816)
			(xy 164.533686 -166.546329) (xy 164.496469 -166.587866) (xy 164.453601 -166.623541) (xy 164.405995 -166.652595)
			(xy 164.354666 -166.674407) (xy 164.300709 -166.688513) (xy 164.245272 -166.694613) (xy 164.189538 -166.692576)
			(xy 164.134695 -166.682446) (xy 164.081911 -166.664439) (xy 164.032311 -166.638938) (xy 163.986953 -166.606487)
			(xy 163.946804 -166.567778) (xy 163.912718 -166.523635) (xy 163.885422 -166.475) (xy 163.865499 -166.422909)
			(xy 163.853373 -166.368472) (xy 163.849302 -166.31285) (xy 160.871485 -166.31285) (xy 160.883099 -166.351454)
			(xy 160.891219 -166.40663) (xy 160.891728 -166.434516) (xy 160.891219 -166.462402) (xy 160.883099 -166.517578)
			(xy 160.867031 -166.570985) (xy 160.843359 -166.621482) (xy 160.812586 -166.667995) (xy 160.775369 -166.709532)
			(xy 160.732501 -166.745207) (xy 160.684895 -166.774261) (xy 160.633566 -166.796073) (xy 160.579609 -166.810179)
			(xy 160.524172 -166.816279) (xy 160.468438 -166.814242) (xy 160.413595 -166.804112) (xy 160.360811 -166.786105)
			(xy 160.311211 -166.760604) (xy 160.265853 -166.728153) (xy 160.225704 -166.689444) (xy 160.191618 -166.645301)
			(xy 160.164322 -166.596666) (xy 160.144399 -166.544575) (xy 160.132273 -166.490138) (xy 160.128202 -166.434516)
			(xy 155.996847 -166.434516) (xy 156.013311 -166.456988) (xy 156.039431 -166.506457) (xy 156.058051 -166.55921)
			(xy 156.06877 -166.614116) (xy 156.070554 -166.642034) (xy 156.071731 -166.656477) (xy 156.08117 -166.683863)
			(xy 156.097892 -166.707515) (xy 156.120563 -166.725546) (xy 156.147372 -166.736515) (xy 156.17618 -166.739547)
			(xy 156.204685 -166.734401) (xy 156.217874 -166.728394) (xy 156.243163 -166.71643) (xy 156.296356 -166.699105)
			(xy 156.351508 -166.689732) (xy 156.407437 -166.68851) (xy 156.462946 -166.695465) (xy 156.516844 -166.710449)
			(xy 156.567978 -166.733141) (xy 156.615252 -166.763054) (xy 156.657652 -166.799547) (xy 156.694271 -166.84184)
			(xy 156.724324 -166.889024) (xy 156.747167 -166.940091) (xy 156.762311 -166.993945) (xy 156.769431 -167.049433)
			(xy 156.768374 -167.105365) (xy 156.759164 -167.160545) (xy 156.741997 -167.213788) (xy 156.717242 -167.263956)
			(xy 156.685428 -167.309972) (xy 156.647238 -167.350851) (xy 156.60349 -167.385717) (xy 156.55512 -167.413824)
			(xy 156.503166 -167.434568) (xy 156.44874 -167.447506) (xy 156.393008 -167.45236) (xy 156.337165 -167.449026)
			(xy 156.282406 -167.437576) (xy 156.229906 -167.418255) (xy 156.180788 -167.391478) (xy 156.136106 -167.357816)
			(xy 156.096816 -167.317993) (xy 156.06376 -167.272861) (xy 156.037647 -167.223387) (xy 156.019036 -167.170631)
			(xy 156.008326 -167.115723) (xy 156.006546 -167.087804) (xy 156.005342 -167.073363) (xy 155.995912 -167.045976)
			(xy 155.979196 -167.022322) (xy 155.956529 -167.004289) (xy 155.929722 -166.993319) (xy 155.900916 -166.990287)
			(xy 155.872413 -166.995436) (xy 155.859226 -167.001444) (xy 155.833964 -167.013462) (xy 155.780773 -167.03079)
			(xy 155.725623 -167.040168) (xy 155.669694 -167.041395) (xy 155.614185 -167.034444) (xy 155.560286 -167.019465)
			(xy 155.50915 -166.996778) (xy 155.461875 -166.966869) (xy 155.419471 -166.93038) (xy 155.382848 -166.888092)
			(xy 155.352791 -166.84091) (xy 155.329943 -166.789847) (xy 155.314794 -166.735995) (xy 155.307669 -166.680508)
			(xy 151.802024 -166.680508) (xy 151.799329 -166.688271) (xy 151.7969 -166.721427) (xy 151.803111 -166.754086)
			(xy 151.817541 -166.784036) (xy 151.839212 -166.809246) (xy 151.85263 -166.819072) (xy 151.874877 -166.834789)
			(xy 151.915033 -166.871592) (xy 151.949546 -166.913731) (xy 151.977715 -166.960352) (xy 151.998968 -167.010504)
			(xy 152.012872 -167.063169) (xy 152.019144 -167.117277) (xy 152.017657 -167.171726) (xy 152.008441 -167.225411)
			(xy 151.991684 -167.277239) (xy 151.967726 -167.326157) (xy 151.937054 -167.37117) (xy 151.900293 -167.411364)
			(xy 151.858188 -167.44592) (xy 151.811597 -167.474137) (xy 151.761466 -167.495441) (xy 151.708815 -167.509399)
			(xy 151.654714 -167.515726) (xy 151.600263 -167.514295) (xy 151.546569 -167.505135) (xy 151.494724 -167.48843)
			(xy 151.445782 -167.464523) (xy 151.400737 -167.433897) (xy 151.360506 -167.397176) (xy 151.325906 -167.355107)
			(xy 151.297641 -167.308545) (xy 151.276286 -167.258436) (xy 151.262274 -167.205799) (xy 151.255891 -167.151705)
			(xy 151.257267 -167.097252) (xy 151.266373 -167.043549) (xy 151.283024 -166.991687) (xy 151.306881 -166.94272)
			(xy 151.32177 -166.91991) (xy 151.33064 -166.905841) (xy 151.341548 -166.874435) (xy 151.343979 -166.841278)
			(xy 151.337768 -166.808618) (xy 151.323336 -166.778668) (xy 151.301662 -166.753458) (xy 151.288242 -166.743634)
			(xy 151.264857 -166.727005) (xy 151.222862 -166.687903) (xy 151.187195 -166.642954) (xy 151.158663 -166.59317)
			(xy 151.137907 -166.539675) (xy 151.125396 -166.483675) (xy 151.122888 -166.45509) (xy 151.121109 -166.437726)
			(xy 151.109336 -166.40488) (xy 151.089114 -166.376445) (xy 151.061953 -166.354543) (xy 151.029879 -166.340807)
			(xy 151.012652 -166.337996) (xy 150.985185 -166.333854) (xy 150.931739 -166.318726) (xy 150.881053 -166.296005)
			(xy 150.834199 -166.266172) (xy 150.792169 -166.229858) (xy 150.75585 -166.18783) (xy 150.726012 -166.14098)
			(xy 150.703286 -166.090296) (xy 150.688153 -166.036852) (xy 150.680932 -165.981778) (xy 148.595149 -165.981778)
			(xy 148.588338 -165.989628) (xy 148.547554 -166.025017) (xy 148.502188 -166.054302) (xy 148.453146 -166.076898)
			(xy 148.401409 -166.092354) (xy 148.348008 -166.100361) (xy 148.321014 -166.101014) (xy 148.268944 -166.101522)
			(xy 147.65782 -166.712646) (xy 146.943318 -166.712646) (xy 146.799511 -166.856453) (xy 148.827759 -166.856453)
			(xy 148.833344 -166.801324) (xy 148.846844 -166.747583) (xy 148.867975 -166.696359) (xy 148.896292 -166.648731)
			(xy 148.931201 -166.605699) (xy 148.971967 -166.568168) (xy 149.017732 -166.536929) (xy 149.067534 -166.512637)
			(xy 149.120326 -166.495804) (xy 149.174998 -166.486784) (xy 149.2304 -166.485766) (xy 149.285366 -166.492772)
			(xy 149.338741 -166.507654) (xy 149.389402 -166.5301) (xy 149.436284 -166.559637) (xy 149.457664 -166.577264)
			(xy 149.475313 -166.591665) (xy 149.514658 -166.614606) (xy 149.557462 -166.630169) (xy 149.602354 -166.637856)
			(xy 149.647897 -166.63742) (xy 149.692634 -166.628876) (xy 149.735132 -166.612497) (xy 149.774031 -166.588807)
			(xy 149.808087 -166.558564) (xy 149.836208 -166.522737) (xy 149.8473 -166.502842) (xy 149.860783 -166.478237)
			(xy 149.893954 -166.432986) (xy 149.933395 -166.393081) (xy 149.978254 -166.359381) (xy 150.027564 -166.332615)
			(xy 150.080263 -166.313358) (xy 150.135213 -166.302026) (xy 150.191231 -166.298864) (xy 150.247108 -166.303939)
			(xy 150.301639 -166.317143) (xy 150.353649 -166.338189) (xy 150.402016 -166.366626) (xy 150.445697 -166.401839)
			(xy 150.48375 -166.443069) (xy 150.515355 -166.489428) (xy 150.53983 -166.539915) (xy 150.556648 -166.593442)
			(xy 150.565446 -166.648854) (xy 150.566034 -166.704958) (xy 150.558399 -166.760543) (xy 150.542707 -166.814411)
			(xy 150.519295 -166.8654) (xy 150.504398 -166.889176) (xy 150.491866 -166.909261) (xy 150.473756 -166.952996)
			(xy 150.464057 -166.999328) (xy 150.463103 -167.046656) (xy 150.470927 -167.093341) (xy 150.48726 -167.137771)
			(xy 150.511536 -167.178409) (xy 150.542916 -167.21385) (xy 150.561294 -167.228774) (xy 150.582822 -167.246092)
			(xy 150.621137 -167.285898) (xy 150.653312 -167.330812) (xy 150.678674 -167.379897) (xy 150.696691 -167.432126)
			(xy 150.706989 -167.486408) (xy 150.709351 -167.541607) (xy 150.703728 -167.59657) (xy 150.690237 -167.650148)
			(xy 150.669161 -167.70122) (xy 150.640941 -167.748718) (xy 150.606165 -167.791651) (xy 150.565562 -167.82912)
			(xy 150.51998 -167.860341) (xy 150.470371 -167.884663) (xy 150.417774 -167.901577) (xy 150.363288 -167.910729)
			(xy 150.308051 -167.911928) (xy 150.253219 -167.905148) (xy 150.199937 -167.890533) (xy 150.14932 -167.868386)
			(xy 150.102427 -167.839171) (xy 150.060236 -167.803499) (xy 150.023631 -167.762116) (xy 149.993376 -167.715886)
			(xy 149.970104 -167.665776) (xy 149.954302 -167.612835) (xy 149.946299 -167.558167) (xy 149.946264 -167.502918)
			(xy 149.954197 -167.44824) (xy 149.969932 -167.395279) (xy 149.99314 -167.34514) (xy 150.007828 -167.321738)
			(xy 150.020339 -167.301641) (xy 150.038447 -167.257909) (xy 150.048147 -167.211579) (xy 150.049103 -167.164255)
			(xy 150.041281 -167.117572) (xy 150.024953 -167.073144) (xy 150.000681 -167.032507) (xy 149.969307 -166.997065)
			(xy 149.950932 -166.98214) (xy 149.936962 -166.97071) (xy 149.919304 -166.956318) (xy 149.879962 -166.933367)
			(xy 149.837159 -166.917796) (xy 149.792267 -166.910104) (xy 149.746722 -166.910536) (xy 149.701983 -166.919079)
			(xy 149.659484 -166.93546) (xy 149.620584 -166.959153) (xy 149.586531 -166.989401) (xy 149.558414 -167.025234)
			(xy 149.547326 -167.045132) (xy 149.533967 -167.069409) (xy 149.501325 -167.114185) (xy 149.462549 -167.153768)
			(xy 149.418457 -167.187327) (xy 149.369974 -167.214156) (xy 149.318121 -167.23369) (xy 149.263987 -167.245519)
			(xy 149.208712 -167.249394) (xy 149.153458 -167.245233) (xy 149.099386 -167.233125) (xy 149.047634 -167.213322)
			(xy 148.999291 -167.186243) (xy 148.955372 -167.152457) (xy 148.916803 -167.112673) (xy 148.884392 -167.067729)
			(xy 148.858824 -167.01857) (xy 148.840634 -166.96623) (xy 148.830206 -166.911809) (xy 148.827759 -166.856453)
			(xy 146.799511 -166.856453) (xy 146.697446 -166.958518) (xy 146.681419 -166.975279) (xy 146.65513 -167.013476)
			(xy 146.636206 -167.055807) (xy 146.625275 -167.10087) (xy 146.622699 -167.147167) (xy 146.628565 -167.193164)
			(xy 146.642676 -167.237334) (xy 146.664566 -167.278211) (xy 146.693507 -167.314439) (xy 146.72854 -167.344817)
			(xy 146.748246 -167.357044) (xy 146.771616 -167.371347) (xy 146.814374 -167.40561) (xy 146.851785 -167.445642)
			(xy 146.883081 -167.490617) (xy 146.907615 -167.539609) (xy 146.924882 -167.591609) (xy 146.934527 -167.645545)
			(xy 146.936351 -167.700307) (xy 146.930316 -167.754766) (xy 146.916547 -167.807799) (xy 146.895327 -167.858315)
			(xy 146.867093 -167.905273) (xy 146.8501 -167.926766) (xy 146.84248 -167.936164) (xy 146.824192 -167.956738)
			(xy 146.804634 -168.003728) (xy 146.799258 -168.017725) (xy 146.795603 -168.040558) (xy 155.370782 -168.040558)
			(xy 155.374853 -167.984936) (xy 155.386979 -167.930499) (xy 155.406902 -167.878408) (xy 155.434198 -167.829773)
			(xy 155.468284 -167.78563) (xy 155.508433 -167.746921) (xy 155.553791 -167.71447) (xy 155.603391 -167.688969)
			(xy 155.656175 -167.670962) (xy 155.711018 -167.660832) (xy 155.766752 -167.658795) (xy 155.822189 -167.664895)
			(xy 155.876146 -167.679001) (xy 155.927475 -167.700813) (xy 155.975081 -167.729867) (xy 156.017259 -167.764968)
			(xy 166.488616 -167.764968) (xy 166.492687 -167.709346) (xy 166.504813 -167.654909) (xy 166.524736 -167.602818)
			(xy 166.552032 -167.554183) (xy 166.586118 -167.51004) (xy 166.626267 -167.471331) (xy 166.671625 -167.43888)
			(xy 166.721225 -167.413379) (xy 166.774009 -167.395372) (xy 166.828852 -167.385242) (xy 166.884586 -167.383205)
			(xy 166.940023 -167.389305) (xy 166.99398 -167.403411) (xy 167.045309 -167.425223) (xy 167.092915 -167.454277)
			(xy 167.135783 -167.489952) (xy 167.173 -167.531489) (xy 167.203773 -167.578002) (xy 167.227445 -167.628499)
			(xy 167.243513 -167.681906) (xy 167.251633 -167.737082) (xy 167.252142 -167.764968) (xy 167.251633 -167.792854)
			(xy 167.243513 -167.84803) (xy 167.227445 -167.901437) (xy 167.203773 -167.951934) (xy 167.173 -167.998447)
			(xy 167.135783 -168.039984) (xy 167.092915 -168.075659) (xy 167.045309 -168.104713) (xy 166.99398 -168.126525)
			(xy 166.940023 -168.140631) (xy 166.884586 -168.146731) (xy 166.828852 -168.144694) (xy 166.774009 -168.134564)
			(xy 166.721225 -168.116557) (xy 166.671625 -168.091056) (xy 166.626267 -168.058605) (xy 166.586118 -168.019896)
			(xy 166.552032 -167.975753) (xy 166.524736 -167.927118) (xy 166.504813 -167.875027) (xy 166.492687 -167.82059)
			(xy 166.488616 -167.764968) (xy 156.017259 -167.764968) (xy 156.017949 -167.765542) (xy 156.055166 -167.807079)
			(xy 156.085939 -167.853592) (xy 156.109611 -167.904089) (xy 156.125679 -167.957496) (xy 156.133799 -168.012672)
			(xy 156.134308 -168.040558) (xy 156.133799 -168.068444) (xy 156.125679 -168.12362) (xy 156.109611 -168.177027)
			(xy 156.085939 -168.227524) (xy 156.055166 -168.274037) (xy 156.017949 -168.315574) (xy 155.975081 -168.351249)
			(xy 155.927475 -168.380303) (xy 155.876146 -168.402115) (xy 155.822189 -168.416221) (xy 155.766752 -168.422321)
			(xy 155.711018 -168.420284) (xy 155.656175 -168.410154) (xy 155.603391 -168.392147) (xy 155.553791 -168.366646)
			(xy 155.508433 -168.334195) (xy 155.468284 -168.295486) (xy 155.434198 -168.251343) (xy 155.406902 -168.202708)
			(xy 155.386979 -168.150617) (xy 155.374853 -168.09618) (xy 155.370782 -168.040558) (xy 146.795603 -168.040558)
			(xy 146.79452 -168.047325) (xy 146.796837 -168.077212) (xy 146.806079 -168.105729) (xy 146.821734 -168.131293)
			(xy 146.832066 -168.142158) (xy 146.921982 -168.232074) (xy 146.938358 -168.247736) (xy 146.975575 -168.273576)
			(xy 147.016781 -168.292416) (xy 147.060672 -168.303659) (xy 147.105861 -168.30695) (xy 147.150919 -168.302185)
			(xy 147.194419 -168.289514) (xy 147.234988 -168.269339) (xy 147.253452 -168.256204) (xy 147.27545 -168.240361)
			(xy 147.323031 -168.214387) (xy 147.373811 -168.19541) (xy 147.426766 -168.183812) (xy 147.480829 -168.179828)
			(xy 147.534911 -168.183537) (xy 147.587924 -168.194865) (xy 147.6388 -168.213584) (xy 147.686513 -168.239316)
			(xy 147.730103 -168.271543) (xy 147.768692 -168.309617) (xy 147.801503 -168.352769) (xy 147.827874 -168.400132)
			(xy 147.847275 -168.450752) (xy 147.859314 -168.503607) (xy 147.86375 -168.557635) (xy 147.860494 -168.611747)
			(xy 147.849609 -168.664853) (xy 147.840954 -168.690544) (xy 147.833925 -168.711532) (xy 147.826407 -168.755147)
			(xy 147.82656 -168.799405) (xy 147.834379 -168.842967) (xy 147.849627 -168.884516) (xy 147.871843 -168.922794)
			(xy 147.900354 -168.956645) (xy 147.9343 -168.985044) (xy 147.972652 -169.007132) (xy 148.014251 -169.022241)
			(xy 148.057839 -169.029915) (xy 148.079968 -169.030396) (xy 148.148294 -169.030396) (xy 148.164949 -169.029902)
			(xy 148.197124 -169.021282) (xy 148.225972 -169.004627) (xy 148.249526 -168.981074) (xy 148.266181 -168.952226)
			(xy 148.274802 -168.920051) (xy 148.275294 -168.903396) (xy 148.275294 -168.863264) (xy 148.252434 -168.830498)
			(xy 148.23718 -168.807798) (xy 148.212628 -168.758929) (xy 148.195306 -168.707055) (xy 148.185569 -168.653239)
			(xy 148.183615 -168.598584) (xy 148.189486 -168.544211) (xy 148.20306 -168.491232) (xy 148.22406 -168.440735)
			(xy 148.252055 -168.393753) (xy 148.286471 -168.351251) (xy 148.326604 -168.314098) (xy 148.371631 -168.283056)
			(xy 148.420628 -168.258762) (xy 148.472593 -168.241713) (xy 148.526459 -168.232259) (xy 148.581123 -168.230592)
			(xy 148.635466 -168.236749) (xy 148.688372 -168.250601) (xy 148.738758 -168.271867) (xy 148.785591 -168.300108)
			(xy 148.827912 -168.334748) (xy 148.864854 -168.375076) (xy 148.895658 -168.420265) (xy 148.919694 -168.469389)
			(xy 148.93647 -168.521443) (xy 148.945641 -168.575358) (xy 148.94702 -168.630031) (xy 148.940578 -168.68434)
			(xy 148.933916 -168.710864) (xy 148.928414 -168.733489) (xy 148.924795 -168.779905) (xy 148.929691 -168.826204)
			(xy 148.942939 -168.870836) (xy 148.964094 -168.912309) (xy 148.99245 -168.949235) (xy 149.027057 -168.980378)
			(xy 149.066758 -169.004696) (xy 149.110224 -169.021376) (xy 149.156002 -169.02986) (xy 149.17928 -169.030396)
			(xy 151.178514 -169.030396) (xy 151.201165 -169.029898) (xy 151.245748 -169.021865) (xy 151.2882 -169.006054)
			(xy 151.327177 -168.982968) (xy 151.361444 -168.953337) (xy 151.389915 -168.9181) (xy 151.411687 -168.878374)
			(xy 151.426072 -168.835418) (xy 151.432614 -168.790591) (xy 151.431104 -168.745315) (xy 151.421592 -168.701024)
			(xy 151.404378 -168.659121) (xy 151.392636 -168.639744) (xy 151.378299 -168.616382) (xy 151.355743 -168.566427)
			(xy 151.340568 -168.513757) (xy 151.333087 -168.459458) (xy 151.333454 -168.404648) (xy 151.34166 -168.350454)
			(xy 151.357538 -168.297992) (xy 151.38076 -168.248342) (xy 151.410848 -168.202527) (xy 151.447183 -168.161489)
			(xy 151.489017 -168.126073) (xy 151.535488 -168.097009) (xy 151.585641 -168.074895) (xy 151.638442 -168.060185)
			(xy 151.692805 -168.053183) (xy 151.74761 -168.054033) (xy 151.80173 -168.062717) (xy 151.85405 -168.079056)
			(xy 151.903492 -168.102715) (xy 151.949041 -168.133206) (xy 151.989756 -168.169902) (xy 152.024802 -168.212047)
			(xy 152.053455 -168.258773) (xy 152.075126 -168.309119) (xy 152.08937 -168.362047) (xy 152.095892 -168.41647)
			(xy 152.094559 -168.471266) (xy 152.085398 -168.525306) (xy 152.068597 -168.57748) (xy 152.044503 -168.626712)
			(xy 152.013611 -168.67199) (xy 151.976558 -168.71238) (xy 151.934106 -168.747052) (xy 151.887129 -168.775292)
			(xy 151.862028 -168.786302) (xy 151.820118 -168.803828) (xy 151.7777 -168.884092) (xy 151.786844 -168.928796)
			(xy 151.790861 -168.945766) (xy 151.80681 -168.976765) (xy 151.83055 -169.002294) (xy 151.860311 -169.02045)
			(xy 151.893873 -169.029879) (xy 151.911304 -169.030396) (xy 152.173178 -169.030396) (xy 152.196081 -169.029902)
			(xy 152.241143 -169.021685) (xy 152.284006 -169.005531) (xy 152.323283 -168.981962) (xy 152.357704 -168.95174)
			(xy 152.386156 -168.915842) (xy 152.407719 -168.87543) (xy 152.421697 -168.831809) (xy 152.425146 -168.809162)
			(xy 152.429249 -168.781576) (xy 152.444469 -168.727922) (xy 152.467341 -168.677057) (xy 152.497377 -168.630066)
			(xy 152.533937 -168.587949) (xy 152.57624 -168.551607) (xy 152.623385 -168.521812) (xy 152.674367 -168.499202)
			(xy 152.728098 -168.484258) (xy 152.783433 -168.477298) (xy 152.839192 -168.478471) (xy 152.894185 -168.487752)
			(xy 152.94724 -168.504943) (xy 152.997225 -168.529678) (xy 153.043076 -168.561429) (xy 153.083813 -168.599519)
			(xy 153.118569 -168.643135) (xy 153.146602 -168.691349) (xy 153.167314 -168.743131) (xy 153.180264 -168.797377)
			(xy 153.185176 -168.852931) (xy 153.181944 -168.908608) (xy 153.170639 -168.963221) (xy 153.1515 -169.015605)
			(xy 153.124936 -169.064643) (xy 153.10866 -169.087292) (xy 153.099961 -169.099672) (xy 153.088086 -169.127491)
			(xy 153.083096 -169.157324) (xy 153.085272 -169.187493) (xy 153.094491 -169.216302) (xy 153.110234 -169.24213)
			(xy 153.120598 -169.253154) (xy 153.250392 -169.382948) (xy 156.066742 -169.382948) (xy 156.070813 -169.327326)
			(xy 156.082939 -169.272889) (xy 156.102862 -169.220798) (xy 156.130158 -169.172163) (xy 156.164244 -169.12802)
			(xy 156.204393 -169.089311) (xy 156.249751 -169.05686) (xy 156.299351 -169.031359) (xy 156.352135 -169.013352)
			(xy 156.406978 -169.003222) (xy 156.462712 -169.001185) (xy 156.518149 -169.007285) (xy 156.572106 -169.021391)
			(xy 156.623435 -169.043203) (xy 156.671041 -169.072257) (xy 156.713909 -169.107932) (xy 156.751126 -169.149469)
			(xy 156.781899 -169.195982) (xy 156.799532 -169.233596) (xy 167.252394 -169.233596) (xy 167.256465 -169.177974)
			(xy 167.268591 -169.123537) (xy 167.288514 -169.071446) (xy 167.31581 -169.022811) (xy 167.349896 -168.978668)
			(xy 167.390045 -168.939959) (xy 167.435403 -168.907508) (xy 167.485003 -168.882007) (xy 167.537787 -168.864)
			(xy 167.59263 -168.85387) (xy 167.648364 -168.851833) (xy 167.703801 -168.857933) (xy 167.757758 -168.872039)
			(xy 167.809087 -168.893851) (xy 167.856693 -168.922905) (xy 167.899561 -168.95858) (xy 167.936778 -169.000117)
			(xy 167.967551 -169.04663) (xy 167.991223 -169.097127) (xy 168.007291 -169.150534) (xy 168.013809 -169.194824)
			(xy 170.15362 -169.194824) (xy 170.158776 -169.139392) (xy 170.171933 -169.085299) (xy 170.192812 -169.033692)
			(xy 170.220969 -168.985667) (xy 170.255806 -168.942243) (xy 170.296584 -168.904344) (xy 170.342437 -168.872773)
			(xy 170.392391 -168.8482) (xy 170.445386 -168.831149) (xy 170.500296 -168.821979) (xy 170.555956 -168.820888)
			(xy 170.611184 -168.827896) (xy 170.664807 -168.842856) (xy 170.715686 -168.86545) (xy 170.762742 -168.895199)
			(xy 170.804975 -168.93147) (xy 170.841489 -168.973494) (xy 170.871508 -169.020377) (xy 170.894394 -169.071126)
			(xy 170.909663 -169.124662) (xy 170.916989 -169.179848) (xy 170.917108 -169.207688) (xy 170.917367 -169.223223)
			(xy 170.924469 -169.253458) (xy 170.938693 -169.281068) (xy 170.948604 -169.293032) (xy 171.004992 -169.357294)
			(xy 171.015492 -169.36873) (xy 171.040925 -169.386522) (xy 171.069906 -169.397636) (xy 171.085256 -169.399966)
			(xy 171.11283 -169.403764) (xy 171.16655 -169.41833) (xy 171.217582 -169.440549) (xy 171.264843 -169.469949)
			(xy 171.307329 -169.505906) (xy 171.344138 -169.547656) (xy 171.374489 -169.594312) (xy 171.397736 -169.644885)
			(xy 171.413386 -169.698299) (xy 171.421107 -169.75342) (xy 171.420858 -169.790603) (xy 171.928246 -169.790603)
			(xy 171.930517 -169.735322) (xy 171.940751 -169.680949) (xy 171.958734 -169.628626) (xy 171.984087 -169.579449)
			(xy 172.01628 -169.534451) (xy 172.054635 -169.494577) (xy 172.09835 -169.460662) (xy 172.146505 -169.433419)
			(xy 172.198092 -169.41342) (xy 172.252026 -169.401083) (xy 172.307177 -169.396668) (xy 172.362388 -169.400267)
			(xy 172.389546 -169.405554) (xy 172.412944 -169.409953) (xy 172.460533 -169.411034) (xy 172.507492 -169.403241)
			(xy 172.552181 -169.386845) (xy 172.593038 -169.362419) (xy 172.628635 -169.330817) (xy 172.65773 -169.293142)
			(xy 172.679306 -169.250711) (xy 172.686472 -169.228008) (xy 172.69471 -169.201592) (xy 172.717669 -169.15125)
			(xy 172.747662 -169.104752) (xy 172.784057 -169.063077) (xy 172.826092 -169.027097) (xy 172.872885 -168.997567)
			(xy 172.923453 -168.975108) (xy 172.976735 -168.960191) (xy 173.031613 -168.953128) (xy 173.086936 -168.954069)
			(xy 173.141543 -168.962992) (xy 173.194287 -168.979712) (xy 173.244063 -169.003877) (xy 173.289824 -169.034979)
			(xy 173.330612 -169.072367) (xy 173.36557 -169.115256) (xy 173.393965 -169.162746) (xy 173.415201 -169.213839)
			(xy 173.428831 -169.267465) (xy 173.434571 -169.322497) (xy 173.4323 -169.377782) (xy 173.422064 -169.432158)
			(xy 173.40408 -169.484485) (xy 173.378725 -169.533664) (xy 173.34653 -169.578664) (xy 173.308171 -169.61854)
			(xy 173.264453 -169.652456) (xy 173.216294 -169.6797) (xy 173.164704 -169.699699) (xy 173.110766 -169.712036)
			(xy 173.055612 -169.716449) (xy 173.000398 -169.712848) (xy 172.973238 -169.70756) (xy 172.949845 -169.703135)
			(xy 172.902252 -169.702055) (xy 172.855291 -169.709852) (xy 172.810601 -169.726251) (xy 172.769743 -169.750681)
			(xy 172.734145 -169.782288) (xy 172.705051 -169.819967) (xy 172.683477 -169.862402) (xy 172.676312 -169.885106)
			(xy 172.668068 -169.911518) (xy 172.645108 -169.961857) (xy 172.615115 -170.00835) (xy 172.57872 -170.050022)
			(xy 172.536686 -170.085998) (xy 172.489896 -170.115524) (xy 172.43933 -170.13798) (xy 172.386051 -170.152895)
			(xy 172.331176 -170.159955) (xy 172.275856 -170.159013) (xy 172.221253 -170.150089) (xy 172.168513 -170.13337)
			(xy 172.118741 -170.109206) (xy 172.072982 -170.078104) (xy 172.032197 -170.040718) (xy 171.997242 -169.997832)
			(xy 171.968849 -169.950345) (xy 171.947615 -169.899254) (xy 171.933985 -169.845632) (xy 171.928246 -169.790603)
			(xy 171.420858 -169.790603) (xy 171.420734 -169.809078) (xy 171.412276 -169.864091) (xy 171.395913 -169.917291)
			(xy 171.371991 -169.967547) (xy 171.341019 -170.013794) (xy 171.303654 -170.055047) (xy 171.260691 -170.090432)
			(xy 171.213041 -170.119197) (xy 171.161716 -170.140731) (xy 171.107806 -170.154577) (xy 171.052456 -170.160441)
			(xy 170.996842 -170.158198) (xy 170.942144 -170.147896) (xy 170.889524 -170.129753) (xy 170.8401 -170.104156)
			(xy 170.794921 -170.071647) (xy 170.754947 -170.032917) (xy 170.721026 -169.988788) (xy 170.693879 -169.940198)
			(xy 170.674082 -169.888178) (xy 170.662056 -169.833833) (xy 170.659552 -169.806112) (xy 170.657394 -169.782726)
			(xy 170.645424 -169.737315) (xy 170.625313 -169.694876) (xy 170.597746 -169.656856) (xy 170.563661 -169.62455)
			(xy 170.52422 -169.599057) (xy 170.480766 -169.581247) (xy 170.457876 -169.575988) (xy 170.430736 -169.569782)
			(xy 170.378459 -169.550642) (xy 170.329518 -169.524109) (xy 170.284953 -169.490744) (xy 170.24571 -169.451257)
			(xy 170.212622 -169.406487) (xy 170.186392 -169.357383) (xy 170.167576 -169.304989) (xy 170.156574 -169.250416)
			(xy 170.15362 -169.194824) (xy 168.013809 -169.194824) (xy 168.015411 -169.20571) (xy 168.01592 -169.233596)
			(xy 168.015411 -169.261482) (xy 168.007291 -169.316658) (xy 167.991223 -169.370065) (xy 167.967551 -169.420562)
			(xy 167.936778 -169.467075) (xy 167.899561 -169.508612) (xy 167.856693 -169.544287) (xy 167.809087 -169.573341)
			(xy 167.757758 -169.595153) (xy 167.703801 -169.609259) (xy 167.648364 -169.615359) (xy 167.59263 -169.613322)
			(xy 167.537787 -169.603192) (xy 167.485003 -169.585185) (xy 167.435403 -169.559684) (xy 167.390045 -169.527233)
			(xy 167.349896 -169.488524) (xy 167.31581 -169.444381) (xy 167.288514 -169.395746) (xy 167.268591 -169.343655)
			(xy 167.256465 -169.289218) (xy 167.252394 -169.233596) (xy 156.799532 -169.233596) (xy 156.805571 -169.246479)
			(xy 156.821639 -169.299886) (xy 156.829759 -169.355062) (xy 156.830268 -169.382948) (xy 156.829759 -169.410834)
			(xy 156.821639 -169.46601) (xy 156.805571 -169.519417) (xy 156.781899 -169.569914) (xy 156.751126 -169.616427)
			(xy 156.713909 -169.657964) (xy 156.671041 -169.693639) (xy 156.623435 -169.722693) (xy 156.572106 -169.744505)
			(xy 156.518149 -169.758611) (xy 156.462712 -169.764711) (xy 156.406978 -169.762674) (xy 156.352135 -169.752544)
			(xy 156.299351 -169.734537) (xy 156.249751 -169.709036) (xy 156.204393 -169.676585) (xy 156.164244 -169.637876)
			(xy 156.130158 -169.593733) (xy 156.102862 -169.545098) (xy 156.082939 -169.493007) (xy 156.070813 -169.43857)
			(xy 156.066742 -169.382948) (xy 153.250392 -169.382948) (xy 153.336752 -169.469308) (xy 153.336752 -170.308016)
			(xy 153.345896 -170.330876) (xy 153.355936 -170.35711) (xy 153.369074 -170.411723) (xy 153.374059 -170.467672)
			(xy 153.370784 -170.523748) (xy 153.359318 -170.578736) (xy 153.339911 -170.631448) (xy 153.31762 -170.672252)
			(xy 155.804868 -170.672252) (xy 155.808939 -170.61663) (xy 155.821065 -170.562193) (xy 155.840988 -170.510102)
			(xy 155.868284 -170.461467) (xy 155.90237 -170.417324) (xy 155.942519 -170.378615) (xy 155.987877 -170.346164)
			(xy 156.037477 -170.320663) (xy 156.090261 -170.302656) (xy 156.145104 -170.292526) (xy 156.200838 -170.290489)
			(xy 156.256275 -170.296589) (xy 156.310232 -170.310695) (xy 156.357723 -170.330876) (xy 157.138622 -170.330876)
			(xy 157.142693 -170.275254) (xy 157.154819 -170.220817) (xy 157.174742 -170.168726) (xy 157.202038 -170.120091)
			(xy 157.236124 -170.075948) (xy 157.276273 -170.037239) (xy 157.321631 -170.004788) (xy 157.371231 -169.979287)
			(xy 157.424015 -169.96128) (xy 157.478858 -169.95115) (xy 157.534592 -169.949113) (xy 157.590029 -169.955213)
			(xy 157.643986 -169.969319) (xy 157.695315 -169.991131) (xy 157.742921 -170.020185) (xy 157.785789 -170.05586)
			(xy 157.823006 -170.097397) (xy 157.853779 -170.14391) (xy 157.877451 -170.194407) (xy 157.893519 -170.247814)
			(xy 157.901639 -170.30299) (xy 157.901905 -170.317567) (xy 175.568781 -170.317567) (xy 175.572697 -170.262637)
			(xy 175.584471 -170.208841) (xy 175.603856 -170.157297) (xy 175.630452 -170.109076) (xy 175.663704 -170.065179)
			(xy 175.702922 -170.026519) (xy 175.72482 -170.00982) (xy 175.743452 -169.995562) (xy 175.775548 -169.961348)
			(xy 175.800817 -169.921823) (xy 175.818402 -169.87833) (xy 175.827703 -169.832349) (xy 175.828406 -169.785442)
			(xy 175.820486 -169.739203) (xy 175.804212 -169.695203) (xy 175.792638 -169.674794) (xy 175.779001 -169.650873)
			(xy 175.757863 -169.600033) (xy 175.744255 -169.546682) (xy 175.738459 -169.491928) (xy 175.740595 -169.436911)
			(xy 175.750619 -169.382772) (xy 175.768323 -169.330636) (xy 175.793339 -169.281588) (xy 175.825147 -169.236646)
			(xy 175.863086 -169.196745) (xy 175.906368 -169.162712) (xy 175.954094 -169.135257) (xy 176.005271 -169.114948)
			(xy 176.058836 -169.102208) (xy 176.113676 -169.097302) (xy 176.168652 -169.100332) (xy 176.222621 -169.111235)
			(xy 176.274462 -169.129784) (xy 176.323097 -169.155593) (xy 176.367516 -169.188127) (xy 176.406796 -169.22671)
			(xy 176.44012 -169.270539) (xy 176.466797 -169.318704) (xy 176.486272 -169.370204) (xy 176.498139 -169.423969)
			(xy 176.50055 -169.456947) (xy 177.008594 -169.456947) (xy 177.015855 -169.401862) (xy 177.031029 -169.348412)
			(xy 177.053795 -169.297728) (xy 177.083672 -169.250882) (xy 177.120028 -169.208866) (xy 177.162093 -169.172566)
			(xy 177.208979 -169.142752) (xy 177.259693 -169.120054) (xy 177.313163 -169.104952) (xy 177.368258 -169.097764)
			(xy 177.423813 -169.098645) (xy 177.478653 -169.107573) (xy 177.531618 -169.124362) (xy 177.581588 -169.148655)
			(xy 177.627506 -169.17994) (xy 177.6684 -169.217553) (xy 177.703407 -169.2607) (xy 177.731785 -169.308469)
			(xy 177.752934 -169.359849) (xy 177.766407 -169.413752) (xy 177.77192 -169.46904) (xy 177.769354 -169.524543)
			(xy 177.758766 -169.579087) (xy 177.740378 -169.631518) (xy 177.71458 -169.680728) (xy 177.698654 -169.703496)
			(xy 177.68641 -169.721048) (xy 177.667417 -169.759394) (xy 177.655115 -169.80038) (xy 177.649854 -169.842848)
			(xy 177.651781 -169.885597) (xy 177.660842 -169.927419) (xy 177.676781 -169.967132) (xy 177.699148 -170.003614)
			(xy 177.72731 -170.035833) (xy 177.743612 -170.049698) (xy 177.764821 -170.067641) (xy 177.802365 -170.108584)
			(xy 177.807503 -170.116149) (xy 178.278052 -170.116149) (xy 178.282847 -170.061922) (xy 178.295302 -170.008927)
			(xy 178.315164 -169.95824) (xy 178.342029 -169.910891) (xy 178.375352 -169.867842) (xy 178.414455 -169.829967)
			(xy 178.458546 -169.798035) (xy 178.506728 -169.772695) (xy 178.558022 -169.754461) (xy 178.611388 -169.743703)
			(xy 178.665741 -169.74064) (xy 178.719977 -169.745335) (xy 178.772995 -169.757692) (xy 178.823719 -169.777459)
			(xy 178.871117 -169.804236) (xy 178.914228 -169.837479) (xy 178.952176 -169.876512) (xy 178.98419 -169.920543)
			(xy 179.00962 -169.968677) (xy 179.027949 -170.019938) (xy 179.038806 -170.073284) (xy 179.04197 -170.127631)
			(xy 179.037376 -170.181876) (xy 179.025118 -170.234917) (xy 179.005445 -170.285677) (xy 178.978756 -170.333125)
			(xy 178.962558 -170.355006) (xy 178.949151 -170.37322) (xy 178.928382 -170.413393) (xy 178.915052 -170.456608)
			(xy 178.909584 -170.5015) (xy 178.912149 -170.546651) (xy 178.922667 -170.590635) (xy 178.940805 -170.632062)
			(xy 178.96599 -170.669624) (xy 178.981354 -170.686222) (xy 178.999883 -170.706162) (xy 179.031724 -170.750309)
			(xy 179.056965 -170.798533) (xy 179.075096 -170.849855) (xy 179.085748 -170.903234) (xy 179.088704 -170.957585)
			(xy 179.086547 -170.981947) (xy 179.363814 -170.981947) (xy 179.369646 -170.926271) (xy 179.383554 -170.872045)
			(xy 179.405239 -170.820435) (xy 179.434234 -170.772548) (xy 179.469917 -170.729413) (xy 179.511522 -170.691958)
			(xy 179.534566 -170.676062) (xy 179.552594 -170.663574) (xy 179.584437 -170.633422) (xy 179.610634 -170.598253)
			(xy 179.630408 -170.559111) (xy 179.643171 -170.517157) (xy 179.648547 -170.473634) (xy 179.646375 -170.429835)
			(xy 179.636719 -170.387058) (xy 179.619866 -170.346572) (xy 179.60848 -170.327828) (xy 179.593786 -170.303996)
			(xy 179.570883 -170.252905) (xy 179.555694 -170.199016) (xy 179.548545 -170.143486) (xy 179.549589 -170.087506)
			(xy 179.558804 -170.032281) (xy 179.575991 -169.978995) (xy 179.600783 -169.928794) (xy 179.632646 -169.882756)
			(xy 179.670896 -169.84187) (xy 179.714711 -169.807013) (xy 179.763151 -169.778935) (xy 179.815174 -169.758238)
			(xy 179.869664 -169.745368) (xy 179.925449 -169.7406) (xy 179.981333 -169.744038) (xy 180.036114 -169.755606)
			(xy 180.088615 -169.775058) (xy 180.13771 -169.801974) (xy 180.182343 -169.835777) (xy 180.221556 -169.875741)
			(xy 180.254507 -169.921007) (xy 180.280487 -169.970603) (xy 180.29894 -170.023464) (xy 180.309467 -170.078454)
			(xy 180.311845 -170.134393) (xy 180.30602 -170.190078) (xy 180.292119 -170.244314) (xy 180.27044 -170.295935)
			(xy 180.241448 -170.343834) (xy 180.205767 -170.38698) (xy 180.164163 -170.424448) (xy 180.141118 -170.44035)
			(xy 180.123079 -170.452823) (xy 180.091237 -170.482978) (xy 180.065041 -170.518149) (xy 180.045269 -170.557293)
			(xy 180.032507 -170.59925) (xy 180.027133 -170.642774) (xy 180.029306 -170.686575) (xy 180.038963 -170.729353)
			(xy 180.055817 -170.76984) (xy 180.067204 -170.788584) (xy 180.081791 -170.81248) (xy 180.104683 -170.863566)
			(xy 180.119862 -170.91745) (xy 180.127002 -170.972974) (xy 180.12595 -171.028945) (xy 180.116728 -171.084161)
			(xy 180.099535 -171.137436) (xy 180.074739 -171.187626) (xy 180.042874 -171.233653) (xy 180.004623 -171.274528)
			(xy 179.960809 -171.309373) (xy 179.912372 -171.33744) (xy 179.860353 -171.358125) (xy 179.805869 -171.370985)
			(xy 179.750091 -171.375744) (xy 179.694216 -171.372298) (xy 179.639445 -171.360723) (xy 179.586954 -171.341266)
			(xy 179.537871 -171.314346) (xy 179.493249 -171.280541) (xy 179.454048 -171.240577) (xy 179.421109 -171.195312)
			(xy 179.39514 -171.145719) (xy 179.376699 -171.092862) (xy 179.366182 -171.037878) (xy 179.363814 -170.981947)
			(xy 179.086547 -170.981947) (xy 179.083904 -171.011804) (xy 179.071447 -171.06479) (xy 179.051584 -171.115467)
			(xy 179.02472 -171.162807) (xy 178.991399 -171.205847) (xy 178.952299 -171.243714) (xy 178.908213 -171.275639)
			(xy 178.860037 -171.300973) (xy 178.80875 -171.319202) (xy 178.755392 -171.329955) (xy 178.701047 -171.333016)
			(xy 178.646819 -171.32832) (xy 178.593809 -171.315964) (xy 178.543093 -171.296198) (xy 178.495703 -171.269424)
			(xy 178.452599 -171.236186) (xy 178.414657 -171.197159) (xy 178.382648 -171.153134) (xy 178.357221 -171.105007)
			(xy 178.338894 -171.053754) (xy 178.328038 -171.000417) (xy 178.324874 -170.946078) (xy 178.329466 -170.891841)
			(xy 178.341721 -170.838808) (xy 178.361389 -170.788055) (xy 178.388072 -170.740612) (xy 178.404266 -170.718734)
			(xy 178.41763 -170.70049) (xy 178.4384 -170.660324) (xy 178.451732 -170.617115) (xy 178.457204 -170.572229)
			(xy 178.454645 -170.527083) (xy 178.444135 -170.483103) (xy 178.426005 -170.441678) (xy 178.400829 -170.404117)
			(xy 178.38547 -170.387518) (xy 178.366911 -170.3676) (xy 178.335061 -170.323451) (xy 178.309811 -170.275222)
			(xy 178.291672 -170.223894) (xy 178.281013 -170.170508) (xy 178.278052 -170.116149) (xy 177.807503 -170.116149)
			(xy 177.833575 -170.15454) (xy 177.857789 -170.204536) (xy 177.874495 -170.257516) (xy 177.88334 -170.312358)
			(xy 177.884138 -170.367904) (xy 177.87687 -170.422977) (xy 177.861692 -170.476415) (xy 177.838923 -170.527085)
			(xy 177.809046 -170.573918) (xy 177.772692 -170.615922) (xy 177.730631 -170.652209) (xy 177.683751 -170.682012)
			(xy 177.633044 -170.7047) (xy 177.579582 -170.719793) (xy 177.524497 -170.726973) (xy 177.468953 -170.726087)
			(xy 177.414125 -170.717154) (xy 177.361172 -170.700364) (xy 177.311214 -170.67607) (xy 177.265308 -170.644788)
			(xy 177.224425 -170.607178) (xy 177.189429 -170.564036) (xy 177.16106 -170.516275) (xy 177.139919 -170.464904)
			(xy 177.126452 -170.41101) (xy 177.120945 -170.355732) (xy 177.123513 -170.30024) (xy 177.134103 -170.245708)
			(xy 177.15249 -170.193288) (xy 177.178286 -170.144089) (xy 177.19421 -170.121326) (xy 177.206436 -170.103762)
			(xy 177.225435 -170.06542) (xy 177.23774 -170.024436) (xy 177.243005 -169.981969) (xy 177.241081 -169.939221)
			(xy 177.232021 -169.897399) (xy 177.216083 -169.857687) (xy 177.193716 -169.821206) (xy 177.165554 -169.788988)
			(xy 177.149252 -169.775124) (xy 177.12798 -169.757249) (xy 177.090422 -169.716305) (xy 177.059199 -169.670345)
			(xy 177.034973 -169.620343) (xy 177.018255 -169.567355) (xy 177.0094 -169.512504) (xy 177.008594 -169.456947)
			(xy 176.50055 -169.456947) (xy 176.502153 -169.478882) (xy 176.498231 -169.533801) (xy 176.486452 -169.587586)
			(xy 176.467064 -169.639119) (xy 176.440467 -169.687328) (xy 176.407216 -169.731213) (xy 176.368 -169.76986)
			(xy 176.346104 -169.786554) (xy 176.327495 -169.800841) (xy 176.295398 -169.835049) (xy 176.270125 -169.874569)
			(xy 176.252538 -169.918057) (xy 176.243233 -169.964034) (xy 176.242526 -170.010938) (xy 176.250443 -170.057175)
			(xy 176.266713 -170.101172) (xy 176.278286 -170.12158) (xy 176.292031 -170.145443) (xy 176.31318 -170.196289)
			(xy 176.326799 -170.249647) (xy 176.332605 -170.30441) (xy 176.330477 -170.359438) (xy 176.320459 -170.413588)
			(xy 176.30276 -170.465736) (xy 176.277747 -170.514797) (xy 176.24594 -170.559751) (xy 176.208 -170.599666)
			(xy 176.164715 -170.633711) (xy 176.116985 -170.661179) (xy 176.065802 -170.681498) (xy 176.012229 -170.694248)
			(xy 175.95738 -170.699163) (xy 175.902393 -170.69614) (xy 175.848413 -170.685243) (xy 175.79656 -170.666698)
			(xy 175.747913 -170.64089) (xy 175.703481 -170.608357) (xy 175.664189 -170.569772) (xy 175.630852 -170.52594)
			(xy 175.604164 -170.477769) (xy 175.58468 -170.426263) (xy 175.572803 -170.372489) (xy 175.568781 -170.317567)
			(xy 157.901905 -170.317567) (xy 157.902148 -170.330876) (xy 157.901639 -170.358762) (xy 157.893519 -170.413938)
			(xy 157.877451 -170.467345) (xy 157.853779 -170.517842) (xy 157.823006 -170.564355) (xy 157.785789 -170.605892)
			(xy 157.742921 -170.641567) (xy 157.695315 -170.670621) (xy 157.643986 -170.692433) (xy 157.590029 -170.706539)
			(xy 157.534592 -170.712639) (xy 157.478858 -170.710602) (xy 157.424015 -170.700472) (xy 157.371231 -170.682465)
			(xy 157.321631 -170.656964) (xy 157.276273 -170.624513) (xy 157.236124 -170.585804) (xy 157.202038 -170.541661)
			(xy 157.174742 -170.493026) (xy 157.154819 -170.440935) (xy 157.142693 -170.386498) (xy 157.138622 -170.330876)
			(xy 156.357723 -170.330876) (xy 156.361561 -170.332507) (xy 156.409167 -170.361561) (xy 156.452035 -170.397236)
			(xy 156.489252 -170.438773) (xy 156.520025 -170.485286) (xy 156.543697 -170.535783) (xy 156.559765 -170.58919)
			(xy 156.567885 -170.644366) (xy 156.568394 -170.672252) (xy 156.567885 -170.700138) (xy 156.559765 -170.755314)
			(xy 156.543697 -170.808721) (xy 156.520025 -170.859218) (xy 156.489252 -170.905731) (xy 156.452035 -170.947268)
			(xy 156.409167 -170.982943) (xy 156.361561 -171.011997) (xy 156.310232 -171.033809) (xy 156.256275 -171.047915)
			(xy 156.200838 -171.054015) (xy 156.145104 -171.051978) (xy 156.090261 -171.041848) (xy 156.037477 -171.023841)
			(xy 155.987877 -170.99834) (xy 155.942519 -170.965889) (xy 155.90237 -170.92718) (xy 155.868284 -170.883037)
			(xy 155.840988 -170.834402) (xy 155.821065 -170.782311) (xy 155.808939 -170.727874) (xy 155.804868 -170.672252)
			(xy 153.31762 -170.672252) (xy 153.312982 -170.680743) (xy 153.279113 -170.725554) (xy 153.239038 -170.764913)
			(xy 153.193622 -170.797968) (xy 153.14385 -170.824004) (xy 153.090796 -170.842457) (xy 153.03561 -170.852929)
			(xy 152.979485 -170.855192) (xy 152.923635 -170.849198) (xy 152.869268 -170.835077) (xy 152.81756 -170.813134)
			(xy 152.769631 -170.783844) (xy 152.726516 -170.74784) (xy 152.689149 -170.705901) (xy 152.658337 -170.658935)
			(xy 152.634748 -170.607957) (xy 152.618892 -170.554071) (xy 152.611112 -170.498441) (xy 152.611575 -170.442272)
			(xy 152.615392 -170.414442) (xy 152.618292 -170.392904) (xy 152.617569 -170.349454) (xy 152.609467 -170.30676)
			(xy 152.594223 -170.266066) (xy 152.57228 -170.228557) (xy 152.544278 -170.195327) (xy 152.511032 -170.167342)
			(xy 152.473512 -170.145419) (xy 152.45334 -170.137328) (xy 152.438031 -170.131336) (xy 152.4084 -170.117091)
			(xy 152.394158 -170.10888) (xy 152.393904 -170.10888) (xy 152.363932 -170.091608) (xy 147.531836 -170.091608)
			(xy 147.464018 -170.142916) (xy 147.452334 -170.18381) (xy 147.444302 -170.210229) (xy 147.421678 -170.260599)
			(xy 147.392031 -170.307182) (xy 147.355977 -170.349005) (xy 147.314271 -170.385193) (xy 147.267784 -170.414991)
			(xy 147.217487 -170.437777) (xy 147.16443 -170.453074) (xy 147.109723 -170.460562) (xy 147.054507 -170.460086)
			(xy 146.999937 -170.451656) (xy 146.947152 -170.435446) (xy 146.897256 -170.411797) (xy 146.851289 -170.381202)
			(xy 146.810213 -170.3443) (xy 146.774886 -170.301862) (xy 146.746046 -170.254775) (xy 146.724295 -170.204022)
			(xy 146.71675 -170.17746) (xy 146.71073 -170.156613) (xy 146.69258 -170.117202) (xy 146.667995 -170.081449)
			(xy 146.63769 -170.050397) (xy 146.602547 -170.024948) (xy 146.56359 -170.005843) (xy 146.521952 -169.993639)
			(xy 146.478846 -169.988691) (xy 146.457162 -169.9895) (xy 146.429652 -169.990538) (xy 146.37482 -169.985646)
			(xy 146.32126 -169.972926) (xy 146.270084 -169.952641) (xy 146.222354 -169.925213) (xy 146.17906 -169.89121)
			(xy 146.141102 -169.851339) (xy 146.109268 -169.806427) (xy 146.084218 -169.757407) (xy 146.066472 -169.705296)
			(xy 146.056398 -169.651176) (xy 146.054207 -169.596169) (xy 146.059942 -169.541419) (xy 146.073486 -169.488061)
			(xy 146.094557 -169.437203) (xy 146.122717 -169.389901) (xy 146.157382 -169.347137) (xy 146.177254 -169.328084)
			(xy 146.193635 -169.312289) (xy 146.221056 -169.275981) (xy 146.241571 -169.235369) (xy 146.254526 -169.191752)
			(xy 146.259506 -169.146526) (xy 146.256352 -169.101136) (xy 146.245164 -169.057033) (xy 146.226301 -169.015628)
			(xy 146.200366 -168.978244) (xy 146.18462 -168.961816) (xy 144.775428 -167.552624) (xy 144.758931 -167.536807)
			(xy 144.72136 -167.51079) (xy 144.67974 -167.491914) (xy 144.635415 -167.480789) (xy 144.589815 -167.477775)
			(xy 144.544411 -167.482967) (xy 144.500669 -167.496199) (xy 144.459999 -167.517043) (xy 144.423716 -167.544827)
			(xy 144.392988 -167.578655) (xy 144.368809 -167.617434) (xy 144.359884 -167.638476) (xy 144.349614 -167.663109)
			(xy 144.323183 -167.709474) (xy 144.290547 -167.751702) (xy 144.252344 -167.788968) (xy 144.209319 -167.820545)
			(xy 144.162313 -167.845817) (xy 144.112242 -167.86429) (xy 144.060086 -167.875603) (xy 144.006862 -167.879535)
			(xy 143.953609 -167.87601) (xy 143.901368 -167.865097) (xy 143.851158 -167.847008) (xy 143.803959 -167.822097)
			(xy 143.782034 -167.806878) (xy 143.764549 -167.794803) (xy 143.726428 -167.776036) (xy 143.685718 -167.763869)
			(xy 143.643551 -167.758639) (xy 143.601102 -167.760493) (xy 143.559552 -167.769379) (xy 143.520057 -167.78505)
			(xy 143.483718 -167.807069) (xy 143.467328 -167.820594) (xy 143.446149 -167.838256) (xy 143.39967 -167.867931)
			(xy 143.349402 -167.890605) (xy 143.296393 -167.905803) (xy 143.241748 -167.91321) (xy 143.186605 -167.912672)
			(xy 143.132116 -167.904198) (xy 143.079414 -167.887966) (xy 143.029598 -167.864314) (xy 142.983708 -167.833736)
			(xy 142.9427 -167.796868) (xy 142.907427 -167.754479) (xy 142.878626 -167.707452) (xy 142.856897 -167.656769)
			(xy 142.842693 -167.603485) (xy 142.83631 -167.548711) (xy 142.837881 -167.493588) (xy 142.847373 -167.439266)
			(xy 142.864588 -167.386877) (xy 142.889167 -167.337513) (xy 142.920599 -167.292203) (xy 142.958228 -167.251892)
			(xy 143.00127 -167.217419) (xy 143.048827 -167.189503) (xy 143.099908 -167.168726) (xy 143.153448 -167.155521)
			(xy 143.208332 -167.150164) (xy 143.263416 -167.152766) (xy 143.317551 -167.163273) (xy 143.369608 -167.181465)
			(xy 143.418504 -167.206964) (xy 143.441166 -167.222678) (xy 143.458652 -167.23475) (xy 143.496774 -167.253513)
			(xy 143.537484 -167.265678) (xy 143.579649 -167.270906) (xy 143.622098 -167.269053) (xy 143.663647 -167.260169)
			(xy 143.703142 -167.244501) (xy 143.739482 -167.222487) (xy 143.755872 -167.208962) (xy 143.775444 -167.192561)
			(xy 143.818169 -167.164595) (xy 143.864246 -167.142585) (xy 143.912849 -167.126924) (xy 143.963108 -167.117894)
			(xy 144.014123 -167.115656) (xy 144.03959 -167.117522) (xy 144.051528 -167.118538) (xy 144.079214 -167.10787)
			(xy 144.093729 -167.101702) (xy 144.119393 -167.083388) (xy 144.139776 -167.059334) (xy 144.153631 -167.031013)
			(xy 144.160109 -167.000157) (xy 144.158814 -166.968655) (xy 144.149825 -166.938435) (xy 144.133693 -166.911346)
			(xy 144.122902 -166.899844) (xy 143.965168 -166.742364) (xy 142.904718 -166.742364) (xy 142.465552 -166.303452)
			(xy 142.465552 -165.787324) (xy 142.46506 -165.770669) (xy 142.456442 -165.738495) (xy 142.439788 -165.709648)
			(xy 142.416233 -165.686098) (xy 142.387383 -165.669449) (xy 142.355207 -165.660837) (xy 142.338552 -165.660324)
			(xy 142.208758 -165.660324) (xy 142.193264 -165.664388) (xy 142.161924 -165.671797) (xy 142.09776 -165.677219)
			(xy 142.033596 -165.671797) (xy 142.002256 -165.664388) (xy 141.986762 -165.660324) (xy 141.739112 -165.660324)
			(xy 138.843004 -162.764216) (xy 131.14274 -162.764216) (xy 131.019042 -162.87496) (xy 131.010406 -162.915346)
			(xy 131.00409 -162.942475) (xy 130.984652 -162.994673) (xy 130.95783 -163.043489) (xy 130.924195 -163.087887)
			(xy 130.884462 -163.126922) (xy 130.839475 -163.159764) (xy 130.790191 -163.185717) (xy 130.737657 -163.204227)
			(xy 130.68299 -163.214902) (xy 130.627351 -163.217514) (xy 130.571924 -163.212008) (xy 130.517887 -163.198502)
			(xy 130.466388 -163.177282) (xy 130.418522 -163.148799) (xy 130.375306 -163.113658) (xy 130.337659 -163.072608)
			(xy 130.306381 -163.026519) (xy 130.282137 -162.976372) (xy 130.265443 -162.923233) (xy 130.256653 -162.868232)
			(xy 130.255953 -162.812536) (xy 130.26336 -162.757331) (xy 130.278715 -162.70379) (xy 130.301692 -162.65305)
			(xy 130.331802 -162.606191) (xy 130.349752 -162.584892) (xy 130.350006 -162.584638) (xy 130.363976 -162.568382)
			(xy 130.382772 -162.522662) (xy 130.388035 -162.508679) (xy 130.392574 -162.479157) (xy 130.390111 -162.449389)
			(xy 130.380783 -162.421014) (xy 130.365102 -162.395592) (xy 130.354832 -162.38474) (xy 130.078988 -162.108896)
			(xy 123.47448 -162.108896) (xy 122.387598 -163.195778) (xy 128.086327 -163.195778) (xy 128.091756 -163.140859)
			(xy 128.105041 -163.087297) (xy 128.125906 -163.036207) (xy 128.153913 -162.988657) (xy 128.18848 -162.945638)
			(xy 128.228885 -162.908049) (xy 128.274284 -162.876674) (xy 128.32373 -162.852168) (xy 128.376191 -162.835042)
			(xy 128.430572 -162.825654) (xy 128.485739 -162.824199) (xy 128.540539 -162.830708) (xy 128.59383 -162.845045)
			(xy 128.644499 -162.866911) (xy 128.691489 -162.895849) (xy 128.733818 -162.931256) (xy 128.770604 -162.972393)
			(xy 128.80108 -163.018401) (xy 128.824608 -163.06832) (xy 128.840698 -163.121108) (xy 128.849014 -163.175664)
			(xy 128.849382 -163.230848) (xy 128.846072 -163.258246) (xy 128.843338 -163.281112) (xy 128.845268 -163.32712)
			(xy 128.855461 -163.372026) (xy 128.873583 -163.414359) (xy 128.899041 -163.452731) (xy 128.930999 -163.485884)
			(xy 128.968411 -163.512732) (xy 129.01005 -163.532395) (xy 129.054552 -163.544229) (xy 129.077466 -163.546536)
			(xy 129.104928 -163.549266) (xy 129.158739 -163.561495) (xy 129.210227 -163.581351) (xy 129.258317 -163.608417)
			(xy 129.302005 -163.642131) (xy 129.340379 -163.681787) (xy 129.372639 -163.726559) (xy 129.398112 -163.775512)
			(xy 129.416265 -163.827624) (xy 129.42672 -163.881808) (xy 129.429259 -163.936933) (xy 129.423829 -163.991849)
			(xy 129.410543 -164.045409) (xy 129.389678 -164.096496) (xy 129.36167 -164.144044) (xy 129.327103 -164.18706)
			(xy 129.286699 -164.224646) (xy 129.241301 -164.256019) (xy 129.191857 -164.280523) (xy 129.139397 -164.297647)
			(xy 129.085018 -164.307034) (xy 129.029853 -164.308488) (xy 128.975055 -164.301978) (xy 128.921767 -164.28764)
			(xy 128.8711 -164.265774) (xy 128.824113 -164.236835) (xy 128.781786 -164.201429) (xy 128.745002 -164.160293)
			(xy 128.714529 -164.114286) (xy 128.691002 -164.064369) (xy 128.674914 -164.011583) (xy 128.666599 -163.957029)
			(xy 128.666232 -163.901847) (xy 128.669542 -163.87445) (xy 128.672267 -163.851583) (xy 128.670337 -163.805576)
			(xy 128.660143 -163.760672) (xy 128.642022 -163.71834) (xy 128.616566 -163.679969) (xy 128.584609 -163.646816)
			(xy 128.547199 -163.619968) (xy 128.505561 -163.600304) (xy 128.461061 -163.588468) (xy 128.438148 -163.58616)
			(xy 128.410683 -163.583449) (xy 128.356869 -163.571221) (xy 128.305379 -163.551367) (xy 128.257286 -163.524301)
			(xy 128.213596 -163.490587) (xy 128.175219 -163.450931) (xy 128.142956 -163.406158) (xy 128.117481 -163.357204)
			(xy 128.099325 -163.305091) (xy 128.088868 -163.250905) (xy 128.086327 -163.195778) (xy 122.387598 -163.195778)
			(xy 122.371358 -163.212018) (xy 122.36196 -163.241228) (xy 122.353642 -163.265776) (xy 122.331296 -163.312543)
			(xy 122.302823 -163.355853) (xy 122.268747 -163.394908) (xy 122.229697 -163.42899) (xy 122.186391 -163.457469)
			(xy 122.139628 -163.479822) (xy 122.115072 -163.488116) (xy 122.085862 -163.497514) (xy 121.928002 -163.655374)
			(xy 124.357549 -163.655374) (xy 124.362871 -163.600917) (xy 124.375919 -163.547778) (xy 124.396425 -163.497049)
			(xy 124.423969 -163.44977) (xy 124.457986 -163.406912) (xy 124.497777 -163.369354) (xy 124.542526 -163.337867)
			(xy 124.591315 -163.313096) (xy 124.643143 -163.29555) (xy 124.696946 -163.28559) (xy 124.75162 -163.283419)
			(xy 124.806043 -163.289081) (xy 124.859098 -163.302462) (xy 124.909698 -163.323286) (xy 124.956803 -163.351126)
			(xy 124.999447 -163.385411) (xy 125.036755 -163.425437) (xy 125.067961 -163.470382) (xy 125.092426 -163.519326)
			(xy 125.109646 -163.571262) (xy 125.113805 -163.594542) (xy 127.110742 -163.594542) (xy 127.114813 -163.53892)
			(xy 127.126939 -163.484483) (xy 127.146862 -163.432392) (xy 127.174158 -163.383757) (xy 127.208244 -163.339614)
			(xy 127.248393 -163.300905) (xy 127.293751 -163.268454) (xy 127.343351 -163.242953) (xy 127.396135 -163.224946)
			(xy 127.450978 -163.214816) (xy 127.506712 -163.212779) (xy 127.562149 -163.218879) (xy 127.616106 -163.232985)
			(xy 127.667435 -163.254797) (xy 127.715041 -163.283851) (xy 127.757909 -163.319526) (xy 127.795126 -163.361063)
			(xy 127.825899 -163.407576) (xy 127.849571 -163.458073) (xy 127.865639 -163.51148) (xy 127.873759 -163.566656)
			(xy 127.874268 -163.594542) (xy 127.873759 -163.622428) (xy 127.865639 -163.677604) (xy 127.849571 -163.731011)
			(xy 127.825899 -163.781508) (xy 127.795126 -163.828021) (xy 127.757909 -163.869558) (xy 127.715041 -163.905233)
			(xy 127.667435 -163.934287) (xy 127.616106 -163.956099) (xy 127.562149 -163.970205) (xy 127.506712 -163.976305)
			(xy 127.450978 -163.974268) (xy 127.396135 -163.964138) (xy 127.343351 -163.946131) (xy 127.293751 -163.92063)
			(xy 127.248393 -163.888179) (xy 127.208244 -163.84947) (xy 127.174158 -163.805327) (xy 127.146862 -163.756692)
			(xy 127.126939 -163.704601) (xy 127.114813 -163.650164) (xy 127.110742 -163.594542) (xy 125.113805 -163.594542)
			(xy 125.119269 -163.625127) (xy 125.120654 -163.652454) (xy 125.121953 -163.676096) (xy 125.132258 -163.722305)
			(xy 125.15095 -163.765803) (xy 125.177383 -163.805081) (xy 125.210639 -163.838779) (xy 125.249565 -163.865727)
			(xy 125.292813 -163.884991) (xy 125.315726 -163.89096) (xy 125.34223 -163.897765) (xy 125.393091 -163.917952)
			(xy 125.440545 -163.945199) (xy 125.48362 -163.978946) (xy 125.521431 -164.018502) (xy 125.553202 -164.063054)
			(xy 125.578281 -164.111689) (xy 125.596155 -164.163407) (xy 125.606455 -164.21715) (xy 125.608971 -164.271812)
			(xy 125.603651 -164.326273) (xy 125.590605 -164.379415) (xy 125.570099 -164.430148) (xy 125.542555 -164.47743)
			(xy 125.508538 -164.520292) (xy 125.468745 -164.557854) (xy 125.423994 -164.589345) (xy 125.375203 -164.614118)
			(xy 125.323373 -164.631667) (xy 125.269568 -164.641629) (xy 125.214891 -164.643802) (xy 125.160464 -164.63814)
			(xy 125.107405 -164.62476) (xy 125.056802 -164.603936) (xy 125.009693 -164.576096) (xy 124.967046 -164.54181)
			(xy 124.929735 -164.501783) (xy 124.898526 -164.456835) (xy 124.874059 -164.40789) (xy 124.856836 -164.35595)
			(xy 124.847212 -164.302083) (xy 124.845826 -164.274754) (xy 124.844459 -164.251118) (xy 124.83416 -164.204916)
			(xy 124.815476 -164.161423) (xy 124.789054 -164.122147) (xy 124.755811 -164.088449) (xy 124.716897 -164.061496)
			(xy 124.673662 -164.042223) (xy 124.650754 -164.036248) (xy 124.624259 -164.02941) (xy 124.573403 -164.009222)
			(xy 124.525952 -163.981975) (xy 124.482882 -163.948228) (xy 124.445075 -163.908673) (xy 124.413307 -163.864122)
			(xy 124.388231 -163.815489) (xy 124.370361 -163.763773) (xy 124.360063 -163.710033) (xy 124.357549 -163.655374)
			(xy 121.928002 -163.655374) (xy 120.626632 -164.956744) (xy 121.41403 -164.956744) (xy 121.418101 -164.901122)
			(xy 121.430227 -164.846685) (xy 121.45015 -164.794594) (xy 121.477446 -164.745959) (xy 121.511532 -164.701816)
			(xy 121.551681 -164.663107) (xy 121.597039 -164.630656) (xy 121.646639 -164.605155) (xy 121.699423 -164.587148)
			(xy 121.754266 -164.577018) (xy 121.81 -164.574981) (xy 121.865437 -164.581081) (xy 121.919394 -164.595187)
			(xy 121.970723 -164.616999) (xy 122.018329 -164.646053) (xy 122.061197 -164.681728) (xy 122.098414 -164.723265)
			(xy 122.129187 -164.769778) (xy 122.152859 -164.820275) (xy 122.168927 -164.873682) (xy 122.177047 -164.928858)
			(xy 122.177556 -164.956744) (xy 122.177047 -164.98463) (xy 122.168927 -165.039806) (xy 122.152859 -165.093213)
			(xy 122.129187 -165.14371) (xy 122.098414 -165.190223) (xy 122.061197 -165.23176) (xy 122.018329 -165.267435)
			(xy 121.970723 -165.296489) (xy 121.919394 -165.318301) (xy 121.865437 -165.332407) (xy 121.81 -165.338507)
			(xy 121.754266 -165.33647) (xy 121.699423 -165.32634) (xy 121.646639 -165.308333) (xy 121.597039 -165.282832)
			(xy 121.551681 -165.250381) (xy 121.511532 -165.211672) (xy 121.477446 -165.167529) (xy 121.45015 -165.118894)
			(xy 121.430227 -165.066803) (xy 121.418101 -165.012366) (xy 121.41403 -164.956744) (xy 120.626632 -164.956744)
			(xy 120.03532 -165.548056) (xy 120.03532 -166.197788) (xy 120.035813 -166.214443) (xy 120.044433 -166.246618)
			(xy 120.061087 -166.275465) (xy 120.084641 -166.299018) (xy 120.11349 -166.31567) (xy 120.145665 -166.324288)
			(xy 120.16232 -166.324788) (xy 121.789952 -166.324788) (xy 121.860564 -166.270432) (xy 121.864374 -166.25189)
			(xy 121.870238 -166.225612) (xy 121.888366 -166.174916) (xy 121.91344 -166.127271) (xy 121.944961 -166.083623)
			(xy 121.982305 -166.044839) (xy 122.024729 -166.011689) (xy 122.071392 -165.98483) (xy 122.121366 -165.964797)
			(xy 122.17366 -165.951987) (xy 122.227235 -165.946654) (xy 122.281028 -165.948905) (xy 122.333971 -165.958694)
			(xy 122.385012 -165.975827) (xy 122.433138 -165.999964) (xy 122.477394 -166.030626) (xy 122.516901 -166.067204)
			(xy 122.550875 -166.108971) (xy 122.578641 -166.155099) (xy 122.599648 -166.204672) (xy 122.60707 -166.230554)
			(xy 122.618246 -166.27221) (xy 122.686572 -166.324788) (xy 124.322078 -166.324788) (xy 124.34459 -166.324305)
			(xy 124.388908 -166.316372) (xy 124.431134 -166.300751) (xy 124.469946 -166.27793) (xy 124.504126 -166.248626)
			(xy 124.532605 -166.213754) (xy 124.554491 -166.174409) (xy 124.569099 -166.131821) (xy 124.57303 -166.10965)
			(xy 124.577607 -166.082959) (xy 124.593309 -166.031132) (xy 124.616181 -165.982046) (xy 124.645762 -165.936686)
			(xy 124.681459 -165.895964) (xy 124.722554 -165.860696) (xy 124.768222 -165.831593) (xy 124.817545 -165.809238)
			(xy 124.869534 -165.794081) (xy 124.923143 -165.786425) (xy 124.977297 -165.786425) (xy 125.030906 -165.794081)
			(xy 125.082895 -165.809238) (xy 125.132218 -165.831593) (xy 125.177886 -165.860696) (xy 125.218981 -165.895964)
			(xy 125.254678 -165.936686) (xy 125.284259 -165.982046) (xy 125.307131 -166.031132) (xy 125.322833 -166.082959)
			(xy 125.32741 -166.10965) (xy 125.331338 -166.131819) (xy 125.345966 -166.174394) (xy 125.367863 -166.213727)
			(xy 125.396346 -166.248589) (xy 125.430523 -166.277889) (xy 125.469327 -166.300712) (xy 125.511543 -166.316345)
			(xy 125.555853 -166.324297) (xy 125.578362 -166.324788) (xy 126.059946 -166.324788) (xy 126.081893 -166.324329)
			(xy 126.125136 -166.316792) (xy 126.166439 -166.301933) (xy 126.204573 -166.280195) (xy 126.238402 -166.252224)
			(xy 126.266918 -166.218854) (xy 126.289273 -166.181079) (xy 126.304801 -166.140023) (xy 126.31304 -166.096908)
			(xy 126.313744 -166.053019) (xy 126.306892 -166.009663) (xy 126.30023 -165.988746) (xy 126.291682 -165.962227)
			(xy 126.281485 -165.907453) (xy 126.279362 -165.851778) (xy 126.28536 -165.796387) (xy 126.299349 -165.742456)
			(xy 126.321033 -165.691134) (xy 126.349951 -165.643511) (xy 126.385488 -165.6006) (xy 126.426887 -165.563314)
			(xy 126.473269 -165.532445) (xy 126.523648 -165.50865) (xy 126.576951 -165.492434) (xy 126.632046 -165.484144)
			(xy 126.687761 -165.483954) (xy 126.742912 -165.49187) (xy 126.796324 -165.507722) (xy 126.846863 -165.531174)
			(xy 126.893454 -165.561727) (xy 126.914656 -165.579806) (xy 126.930899 -165.593655) (xy 126.967095 -165.616275)
			(xy 127.006562 -165.632528) (xy 127.04819 -165.641957) (xy 127.090808 -165.644297) (xy 127.133218 -165.639481)
			(xy 127.174227 -165.627646) (xy 127.212681 -165.609124) (xy 127.247499 -165.584436) (xy 127.26289 -165.569646)
			(xy 127.359664 -165.472872) (xy 127.493776 -165.472872) (xy 127.515953 -165.472383) (xy 127.559631 -165.464671)
			(xy 127.601308 -165.449495) (xy 127.639718 -165.427314) (xy 127.673695 -165.398804) (xy 127.702207 -165.364828)
			(xy 127.724389 -165.32642) (xy 127.739568 -165.284744) (xy 127.747282 -165.241065) (xy 127.747297 -165.196711)
			(xy 127.739614 -165.153028) (xy 127.732536 -165.132004) (xy 127.723697 -165.106342) (xy 127.712536 -165.053226)
			(xy 127.709017 -164.999065) (xy 127.713212 -164.944951) (xy 127.725035 -164.891979) (xy 127.744247 -164.841218)
			(xy 127.770461 -164.793692) (xy 127.803147 -164.750362) (xy 127.841645 -164.712104) (xy 127.885178 -164.679689)
			(xy 127.932866 -164.653772) (xy 127.983747 -164.634877) (xy 128.036792 -164.623385) (xy 128.09093 -164.619528)
			(xy 128.145068 -164.623385) (xy 128.198113 -164.634877) (xy 128.248994 -164.653772) (xy 128.296682 -164.679689)
			(xy 128.340215 -164.712104) (xy 128.378713 -164.750362) (xy 128.411399 -164.793692) (xy 128.437613 -164.841218)
			(xy 128.456825 -164.891979) (xy 128.468648 -164.944951) (xy 128.472843 -164.999065) (xy 128.469324 -165.053226)
			(xy 128.459709 -165.098984) (xy 130.539234 -165.098984) (xy 130.543305 -165.043362) (xy 130.555431 -164.988925)
			(xy 130.575354 -164.936834) (xy 130.60265 -164.888199) (xy 130.636736 -164.844056) (xy 130.676885 -164.805347)
			(xy 130.722243 -164.772896) (xy 130.771843 -164.747395) (xy 130.824627 -164.729388) (xy 130.87947 -164.719258)
			(xy 130.935204 -164.717221) (xy 130.990641 -164.723321) (xy 131.044598 -164.737427) (xy 131.095927 -164.759239)
			(xy 131.11781 -164.772594) (xy 135.566402 -164.772594) (xy 135.570473 -164.716972) (xy 135.582599 -164.662535)
			(xy 135.602522 -164.610444) (xy 135.629818 -164.561809) (xy 135.663904 -164.517666) (xy 135.704053 -164.478957)
			(xy 135.749411 -164.446506) (xy 135.799011 -164.421005) (xy 135.851795 -164.402998) (xy 135.906638 -164.392868)
			(xy 135.962372 -164.390831) (xy 136.017809 -164.396931) (xy 136.071766 -164.411037) (xy 136.123095 -164.432849)
			(xy 136.169413 -164.461117) (xy 138.144773 -164.461117) (xy 138.152842 -164.406102) (xy 138.168811 -164.352841)
			(xy 138.192343 -164.302462) (xy 138.222938 -164.256032) (xy 138.259948 -164.214535) (xy 138.302591 -164.17885)
			(xy 138.349961 -164.149733) (xy 138.401057 -164.127801) (xy 138.454795 -164.113518) (xy 138.510037 -164.107187)
			(xy 138.565613 -164.108942) (xy 138.620346 -164.118746) (xy 138.673076 -164.13639) (xy 138.722686 -164.161502)
			(xy 138.768125 -164.19355) (xy 138.808431 -164.231854) (xy 138.825986 -164.253418) (xy 138.840591 -164.2712)
			(xy 138.875066 -164.30167) (xy 138.914462 -164.325439) (xy 138.957492 -164.34173) (xy 139.002752 -164.350011)
			(xy 139.048762 -164.350011) (xy 139.094022 -164.34173) (xy 139.137052 -164.325439) (xy 139.176448 -164.30167)
			(xy 139.210923 -164.2712) (xy 139.225528 -164.253418) (xy 139.243106 -164.231866) (xy 139.283413 -164.193551)
			(xy 139.328856 -164.161493) (xy 139.378471 -164.136371) (xy 139.431207 -164.118718) (xy 139.485947 -164.108908)
			(xy 139.541532 -164.107148) (xy 139.596783 -164.113475) (xy 139.65053 -164.127757) (xy 139.701635 -164.149689)
			(xy 139.749015 -164.178808) (xy 139.791666 -164.214496) (xy 139.828684 -164.255997) (xy 139.859285 -164.302433)
			(xy 139.882822 -164.35282) (xy 139.898794 -164.406089) (xy 139.906864 -164.461113) (xy 139.906862 -164.516725)
			(xy 139.898786 -164.571748) (xy 139.882808 -164.625016) (xy 139.859267 -164.6754) (xy 139.828661 -164.721832)
			(xy 139.791639 -164.763331) (xy 139.748984 -164.799015) (xy 139.701602 -164.828129) (xy 139.650495 -164.850056)
			(xy 139.596746 -164.864332) (xy 139.541494 -164.870654) (xy 139.48591 -164.868888) (xy 139.43117 -164.859072)
			(xy 139.378436 -164.841414) (xy 139.328824 -164.816287) (xy 139.283384 -164.784225) (xy 139.243081 -164.745906)
			(xy 139.225528 -164.724334) (xy 139.210942 -164.706521) (xy 139.176489 -164.675991) (xy 139.137096 -164.652171)
			(xy 139.094054 -164.635845) (xy 139.048774 -164.627545) (xy 139.00274 -164.627545) (xy 138.95746 -164.635845)
			(xy 138.914418 -164.652171) (xy 138.875025 -164.675991) (xy 138.840572 -164.706521) (xy 138.825986 -164.724334)
			(xy 138.808457 -164.745918) (xy 138.768154 -164.784226) (xy 138.722718 -164.816278) (xy 138.67311 -164.841395)
			(xy 138.620382 -164.859045) (xy 138.565651 -164.868854) (xy 138.510075 -164.870614) (xy 138.454832 -164.864289)
			(xy 138.401093 -164.850011) (xy 138.349995 -164.828084) (xy 138.302621 -164.798972) (xy 138.259976 -164.763291)
			(xy 138.222961 -164.721798) (xy 138.192361 -164.675372) (xy 138.168825 -164.624995) (xy 138.15285 -164.571735)
			(xy 138.144776 -164.516721) (xy 138.144773 -164.461117) (xy 136.169413 -164.461117) (xy 136.170701 -164.461903)
			(xy 136.213569 -164.497578) (xy 136.250786 -164.539115) (xy 136.281559 -164.585628) (xy 136.305231 -164.636125)
			(xy 136.321299 -164.689532) (xy 136.329419 -164.744708) (xy 136.329928 -164.772594) (xy 136.329419 -164.80048)
			(xy 136.321299 -164.855656) (xy 136.305231 -164.909063) (xy 136.281559 -164.95956) (xy 136.250786 -165.006073)
			(xy 136.213569 -165.04761) (xy 136.170701 -165.083285) (xy 136.123095 -165.112339) (xy 136.071766 -165.134151)
			(xy 136.017809 -165.148257) (xy 135.962372 -165.154357) (xy 135.906638 -165.15232) (xy 135.851795 -165.14219)
			(xy 135.799011 -165.124183) (xy 135.749411 -165.098682) (xy 135.704053 -165.066231) (xy 135.663904 -165.027522)
			(xy 135.629818 -164.983379) (xy 135.602522 -164.934744) (xy 135.582599 -164.882653) (xy 135.570473 -164.828216)
			(xy 135.566402 -164.772594) (xy 131.11781 -164.772594) (xy 131.143533 -164.788293) (xy 131.186401 -164.823968)
			(xy 131.223618 -164.865505) (xy 131.254391 -164.912018) (xy 131.278063 -164.962515) (xy 131.294131 -165.015922)
			(xy 131.302251 -165.071098) (xy 131.30276 -165.098984) (xy 131.302251 -165.12687) (xy 131.294131 -165.182046)
			(xy 131.278063 -165.235453) (xy 131.272976 -165.246304) (xy 132.083046 -165.246304) (xy 132.087117 -165.190682)
			(xy 132.099243 -165.136245) (xy 132.119166 -165.084154) (xy 132.146462 -165.035519) (xy 132.180548 -164.991376)
			(xy 132.220697 -164.952667) (xy 132.266055 -164.920216) (xy 132.315655 -164.894715) (xy 132.368439 -164.876708)
			(xy 132.423282 -164.866578) (xy 132.479016 -164.864541) (xy 132.534453 -164.870641) (xy 132.58841 -164.884747)
			(xy 132.639739 -164.906559) (xy 132.687345 -164.935613) (xy 132.730213 -164.971288) (xy 132.76743 -165.012825)
			(xy 132.798203 -165.059338) (xy 132.821875 -165.109835) (xy 132.837943 -165.163242) (xy 132.846063 -165.218418)
			(xy 132.846572 -165.246304) (xy 132.846063 -165.27419) (xy 132.837943 -165.329366) (xy 132.821875 -165.382773)
			(xy 132.798203 -165.43327) (xy 132.76743 -165.479783) (xy 132.730213 -165.52132) (xy 132.687345 -165.556995)
			(xy 132.639739 -165.586049) (xy 132.58841 -165.607861) (xy 132.534453 -165.621967) (xy 132.479016 -165.628067)
			(xy 132.423282 -165.62603) (xy 132.368439 -165.6159) (xy 132.315655 -165.597893) (xy 132.266055 -165.572392)
			(xy 132.220697 -165.539941) (xy 132.180548 -165.501232) (xy 132.146462 -165.457089) (xy 132.119166 -165.408454)
			(xy 132.099243 -165.356363) (xy 132.087117 -165.301926) (xy 132.083046 -165.246304) (xy 131.272976 -165.246304)
			(xy 131.254391 -165.28595) (xy 131.223618 -165.332463) (xy 131.186401 -165.374) (xy 131.143533 -165.409675)
			(xy 131.095927 -165.438729) (xy 131.044598 -165.460541) (xy 130.990641 -165.474647) (xy 130.935204 -165.480747)
			(xy 130.87947 -165.47871) (xy 130.824627 -165.46858) (xy 130.771843 -165.450573) (xy 130.722243 -165.425072)
			(xy 130.676885 -165.392621) (xy 130.636736 -165.353912) (xy 130.60265 -165.309769) (xy 130.575354 -165.261134)
			(xy 130.555431 -165.209043) (xy 130.543305 -165.154606) (xy 130.539234 -165.098984) (xy 128.459709 -165.098984)
			(xy 128.458163 -165.106342) (xy 128.449324 -165.132004) (xy 128.442161 -165.153008) (xy 128.434454 -165.196709)
			(xy 128.434453 -165.241083) (xy 128.442159 -165.284784) (xy 128.457339 -165.326482) (xy 128.47953 -165.364909)
			(xy 128.508059 -165.398898) (xy 128.542057 -165.427416) (xy 128.580491 -165.449595) (xy 128.622194 -165.464761)
			(xy 128.665896 -165.472454) (xy 128.688084 -165.472872) (xy 130.082798 -165.472872) (xy 130.432424 -165.822376)
			(xy 139.630402 -165.822376) (xy 139.634473 -165.766754) (xy 139.646599 -165.712317) (xy 139.666522 -165.660226)
			(xy 139.693818 -165.611591) (xy 139.727904 -165.567448) (xy 139.768053 -165.528739) (xy 139.813411 -165.496288)
			(xy 139.863011 -165.470787) (xy 139.915795 -165.45278) (xy 139.970638 -165.44265) (xy 140.026372 -165.440613)
			(xy 140.081809 -165.446713) (xy 140.135766 -165.460819) (xy 140.187095 -165.482631) (xy 140.234701 -165.511685)
			(xy 140.277569 -165.54736) (xy 140.314786 -165.588897) (xy 140.345559 -165.63541) (xy 140.369231 -165.685907)
			(xy 140.385299 -165.739314) (xy 140.393419 -165.79449) (xy 140.393928 -165.822376) (xy 140.393419 -165.850262)
			(xy 140.385299 -165.905438) (xy 140.369231 -165.958845) (xy 140.345559 -166.009342) (xy 140.314786 -166.055855)
			(xy 140.277569 -166.097392) (xy 140.234701 -166.133067) (xy 140.187095 -166.162121) (xy 140.135766 -166.183933)
			(xy 140.081809 -166.198039) (xy 140.026372 -166.204139) (xy 139.970638 -166.202102) (xy 139.915795 -166.191972)
			(xy 139.863011 -166.173965) (xy 139.813411 -166.148464) (xy 139.768053 -166.116013) (xy 139.727904 -166.077304)
			(xy 139.693818 -166.033161) (xy 139.666522 -165.984526) (xy 139.646599 -165.932435) (xy 139.634473 -165.877998)
			(xy 139.630402 -165.822376) (xy 130.432424 -165.822376) (xy 130.81 -166.19982) (xy 130.827117 -166.216184)
			(xy 130.866224 -166.242879) (xy 130.909595 -166.261877) (xy 130.955732 -166.272523) (xy 131.003042 -166.274447)
			(xy 131.049892 -166.267585) (xy 131.094663 -166.252173) (xy 131.135809 -166.228743) (xy 131.15417 -166.21379)
			(xy 131.175147 -166.196579) (xy 131.221045 -166.16764) (xy 131.27058 -166.145497) (xy 131.322754 -166.130596)
			(xy 131.376512 -166.123238) (xy 131.430771 -166.123571) (xy 131.484434 -166.131589) (xy 131.536421 -166.14713)
			(xy 131.58568 -166.169881) (xy 131.631219 -166.199381) (xy 131.672119 -166.235037) (xy 131.707553 -166.276128)
			(xy 131.736808 -166.321826) (xy 131.759293 -166.371207) (xy 131.774553 -166.423276) (xy 131.782282 -166.476983)
			(xy 131.78282 -166.504112) (xy 131.783316 -166.520765) (xy 131.79194 -166.552935) (xy 131.808596 -166.581776)
			(xy 131.832149 -166.605324) (xy 131.860995 -166.621973) (xy 131.893167 -166.630588) (xy 131.90982 -166.631112)
			(xy 132.89153 -166.631112) (xy 132.914661 -166.630601) (xy 132.96016 -166.622226) (xy 133.003392 -166.605758)
			(xy 133.042932 -166.58174) (xy 133.077474 -166.550965) (xy 133.105878 -166.514448) (xy 133.127207 -166.473396)
			(xy 133.140757 -166.429162) (xy 133.146081 -166.383206) (xy 133.145022 -166.360094) (xy 133.14371 -166.332956)
			(xy 133.147856 -166.278783) (xy 133.159644 -166.225745) (xy 133.178836 -166.174916) (xy 133.205043 -166.127324)
			(xy 133.237737 -166.08393) (xy 133.276255 -166.045612) (xy 133.319819 -166.013145) (xy 133.367548 -165.987186)
			(xy 133.418476 -165.968259) (xy 133.471574 -165.956748) (xy 133.525768 -165.952885) (xy 133.579962 -165.956748)
			(xy 133.63306 -165.968259) (xy 133.683988 -165.987186) (xy 133.731717 -166.013145) (xy 133.775281 -166.045612)
			(xy 133.813799 -166.08393) (xy 133.846493 -166.127324) (xy 133.8727 -166.174916) (xy 133.891892 -166.225745)
			(xy 133.90368 -166.278783) (xy 133.907826 -166.332956) (xy 133.906514 -166.360094) (xy 133.905473 -166.383207)
			(xy 133.910782 -166.429163) (xy 133.924322 -166.473399) (xy 133.945646 -166.514452) (xy 133.97405 -166.550968)
			(xy 134.008594 -166.581738) (xy 134.048138 -166.605747) (xy 134.091374 -166.622201) (xy 134.136875 -166.630556)
			(xy 134.160006 -166.631112) (xy 135.710168 -166.631112) (xy 135.907526 -166.433754) (xy 135.916162 -166.40048)
			(xy 135.923601 -166.373823) (xy 135.945118 -166.322833) (xy 135.973774 -166.275486) (xy 136.008968 -166.232776)
			(xy 136.049964 -166.195597) (xy 136.095899 -166.164729) (xy 136.145812 -166.140821) (xy 136.198655 -166.124373)
			(xy 136.253319 -166.115731) (xy 136.308659 -166.115076) (xy 136.363512 -166.122422) (xy 136.41673 -166.137614)
			(xy 136.467194 -166.160334) (xy 136.513848 -166.190106) (xy 136.555712 -166.226304) (xy 136.591907 -166.268169)
			(xy 136.621676 -166.314825) (xy 136.626046 -166.324534) (xy 137.393678 -166.324534) (xy 137.397749 -166.268912)
			(xy 137.409875 -166.214475) (xy 137.429798 -166.162384) (xy 137.457094 -166.113749) (xy 137.49118 -166.069606)
			(xy 137.531329 -166.030897) (xy 137.576687 -165.998446) (xy 137.626287 -165.972945) (xy 137.679071 -165.954938)
			(xy 137.733914 -165.944808) (xy 137.789648 -165.942771) (xy 137.845085 -165.948871) (xy 137.899042 -165.962977)
			(xy 137.950371 -165.984789) (xy 137.997977 -166.013843) (xy 138.040845 -166.049518) (xy 138.078062 -166.091055)
			(xy 138.108835 -166.137568) (xy 138.132507 -166.188065) (xy 138.148575 -166.241472) (xy 138.156695 -166.296648)
			(xy 138.157204 -166.324534) (xy 138.156695 -166.35242) (xy 138.148575 -166.407596) (xy 138.132507 -166.461003)
			(xy 138.108835 -166.5115) (xy 138.078062 -166.558013) (xy 138.040845 -166.59955) (xy 137.997977 -166.635225)
			(xy 137.950371 -166.664279) (xy 137.899042 -166.686091) (xy 137.845085 -166.700197) (xy 137.789648 -166.706297)
			(xy 137.733914 -166.70426) (xy 137.679071 -166.69413) (xy 137.626287 -166.676123) (xy 137.576687 -166.650622)
			(xy 137.531329 -166.618171) (xy 137.49118 -166.579462) (xy 137.457094 -166.535319) (xy 137.429798 -166.486684)
			(xy 137.409875 -166.434593) (xy 137.397749 -166.380156) (xy 137.393678 -166.324534) (xy 136.626046 -166.324534)
			(xy 136.644393 -166.365291) (xy 136.659582 -166.418509) (xy 136.666925 -166.473363) (xy 136.666267 -166.528702)
			(xy 136.657622 -166.583366) (xy 136.641171 -166.636208) (xy 136.61726 -166.686119) (xy 136.58639 -166.732053)
			(xy 136.549209 -166.773046) (xy 136.506496 -166.808239) (xy 136.459148 -166.836892) (xy 136.408157 -166.858405)
			(xy 136.38149 -166.865808) (xy 136.348216 -166.874444) (xy 135.968486 -167.25392) (xy 131.41198 -167.25392)
			(xy 131.395862 -167.254387) (xy 131.364656 -167.262462) (xy 131.336477 -167.278116) (xy 131.313132 -167.300344)
			(xy 131.296118 -167.327722) (xy 131.286524 -167.358496) (xy 131.285234 -167.37457) (xy 131.283591 -167.399723)
			(xy 131.274498 -167.449303) (xy 131.258944 -167.49725) (xy 131.2372 -167.542726) (xy 131.223766 -167.564054)
			(xy 131.211593 -167.583656) (xy 131.193792 -167.626221) (xy 131.183963 -167.6713) (xy 131.182427 -167.717412)
			(xy 131.189235 -167.763044) (xy 131.204164 -167.8067) (xy 131.226723 -167.846946) (xy 131.241038 -167.865044)
			(xy 131.258574 -167.886966) (xy 131.265924 -167.89908) (xy 134.212328 -167.89908) (xy 134.216399 -167.843458)
			(xy 134.228525 -167.789021) (xy 134.248448 -167.73693) (xy 134.275744 -167.688295) (xy 134.30983 -167.644152)
			(xy 134.349979 -167.605443) (xy 134.395337 -167.572992) (xy 134.444937 -167.547491) (xy 134.497721 -167.529484)
			(xy 134.552564 -167.519354) (xy 134.608298 -167.517317) (xy 134.663735 -167.523417) (xy 134.717692 -167.537523)
			(xy 134.769021 -167.559335) (xy 134.816627 -167.588389) (xy 134.859495 -167.624064) (xy 134.896712 -167.665601)
			(xy 134.927485 -167.712114) (xy 134.951157 -167.762611) (xy 134.967225 -167.816018) (xy 134.975345 -167.871194)
			(xy 134.975854 -167.89908) (xy 134.975345 -167.926966) (xy 134.967225 -167.982142) (xy 134.951157 -168.035549)
			(xy 134.927485 -168.086046) (xy 134.896712 -168.132559) (xy 134.859495 -168.174096) (xy 134.816627 -168.209771)
			(xy 134.769021 -168.238825) (xy 134.717692 -168.260637) (xy 134.663735 -168.274743) (xy 134.608298 -168.280843)
			(xy 134.552564 -168.278806) (xy 134.497721 -168.268676) (xy 134.444937 -168.250669) (xy 134.395337 -168.225168)
			(xy 134.349979 -168.192717) (xy 134.30983 -168.154008) (xy 134.275744 -168.109865) (xy 134.248448 -168.06123)
			(xy 134.228525 -168.009139) (xy 134.216399 -167.954702) (xy 134.212328 -167.89908) (xy 131.265924 -167.89908)
			(xy 131.287694 -167.934959) (xy 131.309466 -167.986702) (xy 131.323421 -168.041076) (xy 131.329257 -168.096909)
			(xy 131.326848 -168.152994) (xy 131.316246 -168.20812) (xy 131.29768 -168.261098) (xy 131.27155 -168.310783)
			(xy 131.238422 -168.356102) (xy 131.199011 -168.396078) (xy 131.154166 -168.429846) (xy 131.104858 -168.456678)
			(xy 131.052149 -168.475995) (xy 130.997179 -168.487379) (xy 130.941134 -168.490584) (xy 130.885224 -168.485542)
			(xy 130.830657 -168.472361) (xy 130.77861 -168.451326) (xy 130.730208 -168.422891) (xy 130.686495 -168.38767)
			(xy 130.648416 -168.346423) (xy 130.616792 -168.300041) (xy 130.592307 -168.249526) (xy 130.575489 -168.195968)
			(xy 130.5667 -168.140523) (xy 130.566132 -168.08439) (xy 130.573796 -168.028779) (xy 130.589527 -167.974891)
			(xy 130.612985 -167.92389) (xy 130.627882 -167.900096) (xy 130.640062 -167.880494) (xy 130.657875 -167.837927)
			(xy 130.667715 -167.792845) (xy 130.669259 -167.746727) (xy 130.662456 -167.701087) (xy 130.647529 -167.657424)
			(xy 130.624969 -167.617171) (xy 130.61061 -167.599106) (xy 130.593619 -167.577874) (xy 130.565189 -167.531518)
			(xy 130.54363 -167.481595) (xy 130.529378 -167.429116) (xy 130.522723 -167.375146) (xy 130.523799 -167.320777)
			(xy 130.532584 -167.267112) (xy 130.548901 -167.215239) (xy 130.572418 -167.166208) (xy 130.60266 -167.121013)
			(xy 130.620516 -167.100504) (xy 130.62077 -167.10025) (xy 130.635248 -167.083994) (xy 130.654806 -167.037004)
			(xy 130.660176 -167.023009) (xy 130.6649 -166.993416) (xy 130.66257 -166.963539) (xy 130.653315 -166.935037)
			(xy 130.637649 -166.90949) (xy 130.627374 -166.898574) (xy 129.82448 -166.09568) (xy 128.900936 -166.09568)
			(xy 128.826768 -166.169848) (xy 128.826768 -166.22268) (xy 128.826265 -166.249919) (xy 128.818479 -166.30384)
			(xy 128.803102 -166.356104) (xy 128.780446 -166.405649) (xy 128.750973 -166.451468) (xy 128.715282 -166.492628)
			(xy 128.674098 -166.528292) (xy 128.62826 -166.557734) (xy 128.5787 -166.580357) (xy 128.526425 -166.595699)
			(xy 128.4725 -166.603449) (xy 128.41802 -166.603449) (xy 128.364095 -166.595699) (xy 128.31182 -166.580357)
			(xy 128.26226 -166.557734) (xy 128.216422 -166.528292) (xy 128.175238 -166.492628) (xy 128.139547 -166.451468)
			(xy 128.110074 -166.405649) (xy 128.087418 -166.356104) (xy 128.072041 -166.30384) (xy 128.064255 -166.249919)
			(xy 128.063752 -166.22268) (xy 128.063752 -166.169848) (xy 127.989584 -166.09568) (xy 127.670306 -166.09568)
			(xy 127.653688 -166.09622) (xy 127.621582 -166.10481) (xy 127.592788 -166.121408) (xy 127.580644 -166.132764)
			(xy 126.765558 -166.948104) (xy 122.679714 -166.948104) (xy 122.549412 -167.078152) (xy 122.256296 -167.078152)
			(xy 122.233053 -167.078672) (xy 122.187343 -167.087125) (xy 122.143931 -167.103748) (xy 122.104266 -167.127988)
			(xy 122.069669 -167.159035) (xy 122.041294 -167.195856) (xy 122.020088 -167.237222) (xy 122.006756 -167.281755)
			(xy 122.001743 -167.327969) (xy 122.005217 -167.374325) (xy 122.010678 -167.396922) (xy 122.0172 -167.423539)
			(xy 122.023434 -167.477984) (xy 122.021812 -167.532761) (xy 122.012369 -167.586743) (xy 121.995298 -167.638817)
			(xy 121.970951 -167.687912) (xy 121.941796 -167.73017) (xy 122.731782 -167.73017) (xy 122.735853 -167.674548)
			(xy 122.747979 -167.620111) (xy 122.767902 -167.56802) (xy 122.795198 -167.519385) (xy 122.829284 -167.475242)
			(xy 122.869433 -167.436533) (xy 122.914791 -167.404082) (xy 122.964391 -167.378581) (xy 123.017175 -167.360574)
			(xy 123.072018 -167.350444) (xy 123.127752 -167.348407) (xy 123.183189 -167.354507) (xy 123.237146 -167.368613)
			(xy 123.288475 -167.390425) (xy 123.336081 -167.419479) (xy 123.378949 -167.455154) (xy 123.416166 -167.496691)
			(xy 123.446939 -167.543204) (xy 123.470611 -167.593701) (xy 123.486679 -167.647108) (xy 123.492287 -167.685212)
			(xy 125.50597 -167.685212) (xy 125.510041 -167.62959) (xy 125.522167 -167.575153) (xy 125.54209 -167.523062)
			(xy 125.569386 -167.474427) (xy 125.603472 -167.430284) (xy 125.643621 -167.391575) (xy 125.688979 -167.359124)
			(xy 125.738579 -167.333623) (xy 125.791363 -167.315616) (xy 125.846206 -167.305486) (xy 125.90194 -167.303449)
			(xy 125.957377 -167.309549) (xy 126.011334 -167.323655) (xy 126.062663 -167.345467) (xy 126.110269 -167.374521)
			(xy 126.153137 -167.410196) (xy 126.190354 -167.451733) (xy 126.221127 -167.498246) (xy 126.244799 -167.548743)
			(xy 126.260867 -167.60215) (xy 126.268987 -167.657326) (xy 126.269496 -167.685212) (xy 126.268987 -167.713098)
			(xy 126.260867 -167.768274) (xy 126.244799 -167.821681) (xy 126.221127 -167.872178) (xy 126.190354 -167.918691)
			(xy 126.153137 -167.960228) (xy 126.110269 -167.995903) (xy 126.062663 -168.024957) (xy 126.011334 -168.046769)
			(xy 125.957377 -168.060875) (xy 125.90194 -168.066975) (xy 125.846206 -168.064938) (xy 125.791363 -168.054808)
			(xy 125.738579 -168.036801) (xy 125.688979 -168.0113) (xy 125.643621 -167.978849) (xy 125.603472 -167.94014)
			(xy 125.569386 -167.895997) (xy 125.54209 -167.847362) (xy 125.522167 -167.795271) (xy 125.510041 -167.740834)
			(xy 125.50597 -167.685212) (xy 123.492287 -167.685212) (xy 123.494799 -167.702284) (xy 123.495308 -167.73017)
			(xy 123.494799 -167.758056) (xy 123.486679 -167.813232) (xy 123.470611 -167.866639) (xy 123.446939 -167.917136)
			(xy 123.416166 -167.963649) (xy 123.378949 -168.005186) (xy 123.336081 -168.040861) (xy 123.288475 -168.069915)
			(xy 123.237146 -168.091727) (xy 123.183189 -168.105833) (xy 123.127752 -168.111933) (xy 123.072018 -168.109896)
			(xy 123.017175 -168.099766) (xy 122.964391 -168.081759) (xy 122.914791 -168.056258) (xy 122.869433 -168.023807)
			(xy 122.829284 -167.985098) (xy 122.795198 -167.940955) (xy 122.767902 -167.89232) (xy 122.747979 -167.840229)
			(xy 122.735853 -167.785792) (xy 122.731782 -167.73017) (xy 121.941796 -167.73017) (xy 121.93983 -167.733019)
			(xy 121.902574 -167.773207) (xy 121.85995 -167.807651) (xy 121.812836 -167.835641) (xy 121.762202 -167.856601)
			(xy 121.70909 -167.8701) (xy 121.654592 -167.875859) (xy 121.599832 -167.873761) (xy 121.545935 -167.863848)
			(xy 121.494011 -167.846325) (xy 121.445129 -167.821552) (xy 121.400296 -167.790038) (xy 121.360433 -167.752434)
			(xy 121.326361 -167.709512) (xy 121.298783 -167.662156) (xy 121.278264 -167.611342) (xy 121.265228 -167.558114)
			(xy 121.259944 -167.503568) (xy 121.262519 -167.448828) (xy 121.2729 -167.395019) (xy 121.290875 -167.34325)
			(xy 121.303034 -167.31869) (xy 121.312596 -167.299226) (xy 121.325672 -167.257882) (xy 121.331538 -167.214917)
			(xy 121.330024 -167.171581) (xy 121.321175 -167.129131) (xy 121.305245 -167.0888) (xy 121.2827 -167.051759)
			(xy 121.254192 -167.019084) (xy 121.220551 -166.991723) (xy 121.182752 -166.970472) (xy 121.141894 -166.955948)
			(xy 121.099163 -166.948571) (xy 121.077482 -166.948104) (xy 120.16232 -166.948104) (xy 120.145664 -166.948596)
			(xy 120.113485 -166.957214) (xy 120.084634 -166.973868) (xy 120.061077 -166.997422) (xy 120.04442 -167.02627)
			(xy 120.035798 -167.058448) (xy 120.03532 -167.075104) (xy 120.03532 -168.319823) (xy 124.108451 -168.319823)
			(xy 124.113306 -168.265331) (xy 124.125893 -168.212092) (xy 124.145954 -168.161195) (xy 124.173077 -168.113685)
			(xy 124.206707 -168.070536) (xy 124.246155 -168.032631) (xy 124.290611 -168.000748) (xy 124.339165 -167.97554)
			(xy 124.390821 -167.957525) (xy 124.44452 -167.947071) (xy 124.499162 -167.944392) (xy 124.553626 -167.949545)
			(xy 124.606796 -167.962422) (xy 124.657582 -167.98276) (xy 124.704944 -168.010143) (xy 124.747909 -168.044008)
			(xy 124.785598 -168.083662) (xy 124.817238 -168.128291) (xy 124.84218 -168.176982) (xy 124.859914 -168.228735)
			(xy 124.870075 -168.282491) (xy 124.871734 -168.309798) (xy 124.873152 -168.332163) (xy 124.882963 -168.375888)
			(xy 124.90029 -168.417215) (xy 124.924594 -168.454864) (xy 124.955123 -168.487668) (xy 124.990931 -168.514611)
			(xy 125.030908 -168.534858) (xy 125.073816 -168.547782) (xy 125.118326 -168.552983) (xy 125.14072 -168.552114)
			(xy 125.168049 -168.55098) (xy 125.222555 -168.555545) (xy 125.27585 -168.567846) (xy 125.326842 -168.587632)
			(xy 125.374486 -168.614496) (xy 125.417806 -168.647889) (xy 125.455914 -168.687126) (xy 125.488028 -168.731402)
			(xy 125.51349 -168.779811) (xy 125.531778 -168.831359) (xy 125.542518 -168.88499) (xy 125.54549 -168.939606)
			(xy 125.543238 -168.964864) (xy 125.937262 -168.964864) (xy 125.941333 -168.909242) (xy 125.953459 -168.854805)
			(xy 125.973382 -168.802714) (xy 126.000678 -168.754079) (xy 126.034764 -168.709936) (xy 126.074913 -168.671227)
			(xy 126.120271 -168.638776) (xy 126.169871 -168.613275) (xy 126.222655 -168.595268) (xy 126.277498 -168.585138)
			(xy 126.333232 -168.583101) (xy 126.388669 -168.589201) (xy 126.442626 -168.603307) (xy 126.493955 -168.625119)
			(xy 126.541561 -168.654173) (xy 126.584429 -168.689848) (xy 126.621646 -168.731385) (xy 126.652419 -168.777898)
			(xy 126.676091 -168.828395) (xy 126.692159 -168.881802) (xy 126.700279 -168.936978) (xy 126.700788 -168.964864)
			(xy 126.700279 -168.99275) (xy 126.692159 -169.047926) (xy 126.676091 -169.101333) (xy 126.669456 -169.115486)
			(xy 127.695196 -169.115486) (xy 127.699267 -169.059864) (xy 127.711393 -169.005427) (xy 127.731316 -168.953336)
			(xy 127.758612 -168.904701) (xy 127.792698 -168.860558) (xy 127.832847 -168.821849) (xy 127.878205 -168.789398)
			(xy 127.927805 -168.763897) (xy 127.980589 -168.74589) (xy 128.035432 -168.73576) (xy 128.091166 -168.733723)
			(xy 128.146603 -168.739823) (xy 128.20056 -168.753929) (xy 128.251889 -168.775741) (xy 128.299495 -168.804795)
			(xy 128.342363 -168.84047) (xy 128.37958 -168.882007) (xy 128.410353 -168.92852) (xy 128.434025 -168.979017)
			(xy 128.450093 -169.032424) (xy 128.458213 -169.0876) (xy 128.458569 -169.107104) (xy 131.393182 -169.107104)
			(xy 131.397253 -169.051482) (xy 131.409379 -168.997045) (xy 131.429302 -168.944954) (xy 131.456598 -168.896319)
			(xy 131.490684 -168.852176) (xy 131.530833 -168.813467) (xy 131.576191 -168.781016) (xy 131.625791 -168.755515)
			(xy 131.678575 -168.737508) (xy 131.733418 -168.727378) (xy 131.789152 -168.725341) (xy 131.844589 -168.731441)
			(xy 131.898546 -168.745547) (xy 131.949875 -168.767359) (xy 131.997481 -168.796413) (xy 132.040349 -168.832088)
			(xy 132.04871 -168.84142) (xy 133.331202 -168.84142) (xy 133.335273 -168.785798) (xy 133.347399 -168.731361)
			(xy 133.367322 -168.67927) (xy 133.394618 -168.630635) (xy 133.428704 -168.586492) (xy 133.468853 -168.547783)
			(xy 133.514211 -168.515332) (xy 133.563811 -168.489831) (xy 133.616595 -168.471824) (xy 133.671438 -168.461694)
			(xy 133.727172 -168.459657) (xy 133.782609 -168.465757) (xy 133.836566 -168.479863) (xy 133.887895 -168.501675)
			(xy 133.935501 -168.530729) (xy 133.978369 -168.566404) (xy 134.015586 -168.607941) (xy 134.046359 -168.654454)
			(xy 134.070031 -168.704951) (xy 134.086099 -168.758358) (xy 134.093987 -168.811956) (xy 143.170654 -168.811956)
			(xy 143.174725 -168.756334) (xy 143.186851 -168.701897) (xy 143.206774 -168.649806) (xy 143.23407 -168.601171)
			(xy 143.268156 -168.557028) (xy 143.308305 -168.518319) (xy 143.353663 -168.485868) (xy 143.403263 -168.460367)
			(xy 143.456047 -168.44236) (xy 143.51089 -168.43223) (xy 143.566624 -168.430193) (xy 143.622061 -168.436293)
			(xy 143.676018 -168.450399) (xy 143.727347 -168.472211) (xy 143.774953 -168.501265) (xy 143.817821 -168.53694)
			(xy 143.855038 -168.578477) (xy 143.885811 -168.62499) (xy 143.909483 -168.675487) (xy 143.925551 -168.728894)
			(xy 143.933671 -168.78407) (xy 143.93418 -168.811956) (xy 143.933671 -168.839842) (xy 143.925551 -168.895018)
			(xy 143.909483 -168.948425) (xy 143.885811 -168.998922) (xy 143.855038 -169.045435) (xy 143.817821 -169.086972)
			(xy 143.774953 -169.122647) (xy 143.727347 -169.151701) (xy 143.676018 -169.173513) (xy 143.622061 -169.187619)
			(xy 143.566624 -169.193719) (xy 143.51089 -169.191682) (xy 143.456047 -169.181552) (xy 143.403263 -169.163545)
			(xy 143.353663 -169.138044) (xy 143.308305 -169.105593) (xy 143.268156 -169.066884) (xy 143.23407 -169.022741)
			(xy 143.206774 -168.974106) (xy 143.186851 -168.922015) (xy 143.174725 -168.867578) (xy 143.170654 -168.811956)
			(xy 134.093987 -168.811956) (xy 134.094219 -168.813534) (xy 134.094728 -168.84142) (xy 134.094219 -168.869306)
			(xy 134.086099 -168.924482) (xy 134.070031 -168.977889) (xy 134.046359 -169.028386) (xy 134.015586 -169.074899)
			(xy 133.978369 -169.116436) (xy 133.935501 -169.152111) (xy 133.887895 -169.181165) (xy 133.836566 -169.202977)
			(xy 133.782609 -169.217083) (xy 133.727172 -169.223183) (xy 133.671438 -169.221146) (xy 133.616595 -169.211016)
			(xy 133.563811 -169.193009) (xy 133.514211 -169.167508) (xy 133.468853 -169.135057) (xy 133.428704 -169.096348)
			(xy 133.394618 -169.052205) (xy 133.367322 -169.00357) (xy 133.347399 -168.951479) (xy 133.335273 -168.897042)
			(xy 133.331202 -168.84142) (xy 132.04871 -168.84142) (xy 132.077566 -168.873625) (xy 132.108339 -168.920138)
			(xy 132.132011 -168.970635) (xy 132.148079 -169.024042) (xy 132.156199 -169.079218) (xy 132.156708 -169.107104)
			(xy 132.156199 -169.13499) (xy 132.148079 -169.190166) (xy 132.132011 -169.243573) (xy 132.108339 -169.29407)
			(xy 132.077566 -169.340583) (xy 132.040349 -169.38212) (xy 131.997481 -169.417795) (xy 131.949875 -169.446849)
			(xy 131.898546 -169.468661) (xy 131.844589 -169.482767) (xy 131.789152 -169.488867) (xy 131.733418 -169.48683)
			(xy 131.678575 -169.4767) (xy 131.625791 -169.458693) (xy 131.576191 -169.433192) (xy 131.530833 -169.400741)
			(xy 131.490684 -169.362032) (xy 131.456598 -169.317889) (xy 131.429302 -169.269254) (xy 131.409379 -169.217163)
			(xy 131.397253 -169.162726) (xy 131.393182 -169.107104) (xy 128.458569 -169.107104) (xy 128.458722 -169.115486)
			(xy 128.458213 -169.143372) (xy 128.450093 -169.198548) (xy 128.434025 -169.251955) (xy 128.410353 -169.302452)
			(xy 128.37958 -169.348965) (xy 128.342363 -169.390502) (xy 128.299495 -169.426177) (xy 128.251889 -169.455231)
			(xy 128.20056 -169.477043) (xy 128.146603 -169.491149) (xy 128.091166 -169.497249) (xy 128.035432 -169.495212)
			(xy 127.980589 -169.485082) (xy 127.927805 -169.467075) (xy 127.878205 -169.441574) (xy 127.832847 -169.409123)
			(xy 127.792698 -169.370414) (xy 127.758612 -169.326271) (xy 127.731316 -169.277636) (xy 127.711393 -169.225545)
			(xy 127.699267 -169.171108) (xy 127.695196 -169.115486) (xy 126.669456 -169.115486) (xy 126.652419 -169.15183)
			(xy 126.621646 -169.198343) (xy 126.584429 -169.23988) (xy 126.541561 -169.275555) (xy 126.493955 -169.304609)
			(xy 126.442626 -169.326421) (xy 126.388669 -169.340527) (xy 126.333232 -169.346627) (xy 126.277498 -169.34459)
			(xy 126.222655 -169.33446) (xy 126.169871 -169.316453) (xy 126.120271 -169.290952) (xy 126.074913 -169.258501)
			(xy 126.034764 -169.219792) (xy 126.000678 -169.175649) (xy 125.973382 -169.127014) (xy 125.953459 -169.074923)
			(xy 125.941333 -169.020486) (xy 125.937262 -168.964864) (xy 125.543238 -168.964864) (xy 125.540632 -168.994086)
			(xy 125.528044 -169.047314) (xy 125.507984 -169.098199) (xy 125.480863 -169.145698) (xy 125.447237 -169.188838)
			(xy 125.407796 -169.226733) (xy 125.363348 -169.258608) (xy 125.314803 -169.283809) (xy 125.263157 -169.30182)
			(xy 125.209468 -169.312271) (xy 125.154838 -169.314949) (xy 125.100384 -169.309797) (xy 125.047225 -169.296923)
			(xy 124.996449 -169.276589) (xy 124.949096 -169.249213) (xy 124.906138 -169.215356) (xy 124.868456 -169.175711)
			(xy 124.836821 -169.131092) (xy 124.811881 -169.082412) (xy 124.794149 -169.03067) (xy 124.783987 -168.976926)
			(xy 124.782326 -168.949624) (xy 124.780931 -168.927256) (xy 124.771121 -168.883527) (xy 124.753794 -168.842197)
			(xy 124.729488 -168.804545) (xy 124.698956 -168.771739) (xy 124.663144 -168.744796) (xy 124.623162 -168.724551)
			(xy 124.580249 -168.71163) (xy 124.535736 -168.706436) (xy 124.51334 -168.707308) (xy 124.486007 -168.708479)
			(xy 124.43149 -168.703922) (xy 124.378183 -168.691626) (xy 124.327178 -168.671843) (xy 124.27952 -168.644979)
			(xy 124.236188 -168.611584) (xy 124.198068 -168.572344) (xy 124.165943 -168.528063) (xy 124.140471 -168.479647)
			(xy 124.122174 -168.42809) (xy 124.111427 -168.374449) (xy 124.108451 -168.319823) (xy 120.03532 -168.319823)
			(xy 120.03532 -169.858675) (xy 121.373904 -169.858675) (xy 121.375446 -169.802583) (xy 121.385186 -169.747322)
			(xy 121.402915 -169.694083) (xy 121.42825 -169.644015) (xy 121.460644 -169.598197) (xy 121.4994 -169.557617)
			(xy 121.543681 -169.523152) (xy 121.592532 -169.495543) (xy 121.6449 -169.475386) (xy 121.699655 -169.463117)
			(xy 121.755617 -169.458999) (xy 121.811579 -169.463122) (xy 121.866333 -169.475396) (xy 121.918699 -169.495558)
			(xy 121.943368 -169.508932) (xy 121.963153 -169.519573) (xy 122.00555 -169.534416) (xy 122.049896 -169.541582)
			(xy 122.094811 -169.540846) (xy 122.138898 -169.532233) (xy 122.180787 -169.51601) (xy 122.219175 -169.492681)
			(xy 122.252868 -169.462971) (xy 122.267218 -169.445686) (xy 122.285002 -169.423981) (xy 122.325924 -169.385588)
			(xy 122.372028 -169.353602) (xy 122.42232 -169.328714) (xy 122.475714 -169.311459) (xy 122.531059 -169.302209)
			(xy 122.587163 -169.301166) (xy 122.642814 -169.30835) (xy 122.696813 -169.323606) (xy 122.747995 -169.346607)
			(xy 122.795257 -169.376856) (xy 122.837579 -169.4137) (xy 122.87405 -169.456345) (xy 122.902912 -169.502328)
			(xy 136.734802 -169.502328) (xy 136.738873 -169.446706) (xy 136.750999 -169.392269) (xy 136.770922 -169.340178)
			(xy 136.798218 -169.291543) (xy 136.832304 -169.2474) (xy 136.872453 -169.208691) (xy 136.917811 -169.17624)
			(xy 136.967411 -169.150739) (xy 137.020195 -169.132732) (xy 137.075038 -169.122602) (xy 137.130772 -169.120565)
			(xy 137.186209 -169.126665) (xy 137.240166 -169.140771) (xy 137.291495 -169.162583) (xy 137.339101 -169.191637)
			(xy 137.381969 -169.227312) (xy 137.419186 -169.268849) (xy 137.449959 -169.315362) (xy 137.473631 -169.365859)
			(xy 137.489699 -169.419266) (xy 137.497819 -169.474442) (xy 137.498328 -169.502328) (xy 137.497819 -169.530214)
			(xy 137.489699 -169.58539) (xy 137.473631 -169.638797) (xy 137.449959 -169.689294) (xy 137.419186 -169.735807)
			(xy 137.381969 -169.777344) (xy 137.339101 -169.813019) (xy 137.291495 -169.842073) (xy 137.240166 -169.863885)
			(xy 137.186209 -169.877991) (xy 137.130772 -169.884091) (xy 137.075038 -169.882054) (xy 137.020195 -169.871924)
			(xy 136.967411 -169.853917) (xy 136.917811 -169.828416) (xy 136.872453 -169.795965) (xy 136.832304 -169.757256)
			(xy 136.798218 -169.713113) (xy 136.770922 -169.664478) (xy 136.750999 -169.612387) (xy 136.738873 -169.55795)
			(xy 136.734802 -169.502328) (xy 122.902912 -169.502328) (xy 122.903881 -169.503871) (xy 122.92643 -169.555254)
			(xy 122.941211 -169.609386) (xy 122.947904 -169.665098) (xy 122.946366 -169.72119) (xy 122.93663 -169.776452)
			(xy 122.918906 -169.829692) (xy 122.893575 -169.879762) (xy 122.861185 -169.925583) (xy 122.822433 -169.966165)
			(xy 122.778155 -170.000635) (xy 122.729307 -170.028249) (xy 122.676941 -170.048411) (xy 122.622187 -170.060686)
			(xy 122.566226 -170.06481) (xy 122.510264 -170.060694) (xy 122.455509 -170.048426) (xy 122.40314 -170.028271)
			(xy 122.37847 -170.0149) (xy 122.358668 -170.004292) (xy 122.316275 -169.989442) (xy 122.271933 -169.982271)
			(xy 122.227021 -169.983001) (xy 122.182936 -169.991609) (xy 122.141048 -170.007829) (xy 122.102661 -170.031155)
			(xy 122.068969 -170.060862) (xy 122.05462 -170.078146) (xy 122.03679 -170.099814) (xy 121.995867 -170.138207)
			(xy 121.949762 -170.170193) (xy 121.899471 -170.195081) (xy 121.846076 -170.212335) (xy 121.79073 -170.221582)
			(xy 121.734627 -170.222625) (xy 121.678975 -170.215439) (xy 121.624977 -170.20018) (xy 121.573795 -170.177177)
			(xy 121.526534 -170.146927) (xy 121.484214 -170.11008) (xy 121.447746 -170.067433) (xy 121.417917 -170.019905)
			(xy 121.395371 -169.96852) (xy 121.380594 -169.914388) (xy 121.373904 -169.858675) (xy 120.03532 -169.858675)
			(xy 120.03532 -170.402504) (xy 125.717044 -170.402504) (xy 125.721115 -170.346882) (xy 125.733241 -170.292445)
			(xy 125.753164 -170.240354) (xy 125.78046 -170.191719) (xy 125.814546 -170.147576) (xy 125.854695 -170.108867)
			(xy 125.900053 -170.076416) (xy 125.949653 -170.050915) (xy 126.002437 -170.032908) (xy 126.05728 -170.022778)
			(xy 126.113014 -170.020741) (xy 126.168451 -170.026841) (xy 126.222408 -170.040947) (xy 126.273737 -170.062759)
			(xy 126.321343 -170.091813) (xy 126.364211 -170.127488) (xy 126.401428 -170.169025) (xy 126.432201 -170.215538)
			(xy 126.455873 -170.266035) (xy 126.471941 -170.319442) (xy 126.480061 -170.374618) (xy 126.480357 -170.39082)
			(xy 127.662938 -170.39082) (xy 127.667009 -170.335198) (xy 127.679135 -170.280761) (xy 127.699058 -170.22867)
			(xy 127.726354 -170.180035) (xy 127.76044 -170.135892) (xy 127.800589 -170.097183) (xy 127.845947 -170.064732)
			(xy 127.895547 -170.039231) (xy 127.948331 -170.021224) (xy 128.003174 -170.011094) (xy 128.058908 -170.009057)
			(xy 128.114345 -170.015157) (xy 128.168302 -170.029263) (xy 128.219631 -170.051075) (xy 128.267237 -170.080129)
			(xy 128.310105 -170.115804) (xy 128.347322 -170.157341) (xy 128.378095 -170.203854) (xy 128.401767 -170.254351)
			(xy 128.417835 -170.307758) (xy 128.425955 -170.362934) (xy 128.426464 -170.39082) (xy 128.425955 -170.418706)
			(xy 128.417835 -170.473882) (xy 128.401767 -170.527289) (xy 128.378095 -170.577786) (xy 128.347322 -170.624299)
			(xy 128.310105 -170.665836) (xy 128.267237 -170.701511) (xy 128.219631 -170.730565) (xy 128.168302 -170.752377)
			(xy 128.114345 -170.766483) (xy 128.058908 -170.772583) (xy 128.003174 -170.770546) (xy 127.948331 -170.760416)
			(xy 127.895547 -170.742409) (xy 127.845947 -170.716908) (xy 127.800589 -170.684457) (xy 127.76044 -170.645748)
			(xy 127.726354 -170.601605) (xy 127.699058 -170.55297) (xy 127.679135 -170.500879) (xy 127.667009 -170.446442)
			(xy 127.662938 -170.39082) (xy 126.480357 -170.39082) (xy 126.48057 -170.402504) (xy 126.480061 -170.43039)
			(xy 126.471941 -170.485566) (xy 126.455873 -170.538973) (xy 126.432201 -170.58947) (xy 126.401428 -170.635983)
			(xy 126.364211 -170.67752) (xy 126.321343 -170.713195) (xy 126.273737 -170.742249) (xy 126.222408 -170.764061)
			(xy 126.168451 -170.778167) (xy 126.113014 -170.784267) (xy 126.05728 -170.78223) (xy 126.002437 -170.7721)
			(xy 125.949653 -170.754093) (xy 125.900053 -170.728592) (xy 125.854695 -170.696141) (xy 125.814546 -170.657432)
			(xy 125.78046 -170.613289) (xy 125.753164 -170.564654) (xy 125.733241 -170.512563) (xy 125.721115 -170.458126)
			(xy 125.717044 -170.402504) (xy 120.03532 -170.402504) (xy 120.03532 -170.43019) (xy 120.569228 -170.964098)
			(xy 122.147074 -170.964098) (xy 122.151145 -170.908476) (xy 122.163271 -170.854039) (xy 122.183194 -170.801948)
			(xy 122.21049 -170.753313) (xy 122.244576 -170.70917) (xy 122.284725 -170.670461) (xy 122.330083 -170.63801)
			(xy 122.379683 -170.612509) (xy 122.432467 -170.594502) (xy 122.48731 -170.584372) (xy 122.543044 -170.582335)
			(xy 122.598481 -170.588435) (xy 122.652438 -170.602541) (xy 122.703767 -170.624353) (xy 122.751373 -170.653407)
			(xy 122.794241 -170.689082) (xy 122.831458 -170.730619) (xy 122.862231 -170.777132) (xy 122.885903 -170.827629)
			(xy 122.901971 -170.881036) (xy 122.910091 -170.936212) (xy 122.9106 -170.964098) (xy 122.910091 -170.991984)
			(xy 122.901971 -171.04716) (xy 122.885903 -171.100567) (xy 122.862231 -171.151064) (xy 122.834204 -171.193426)
			(xy 130.992659 -171.193426) (xy 130.993957 -171.138402) (xy 131.003149 -171.084136) (xy 131.020045 -171.031754)
			(xy 131.044293 -170.982344) (xy 131.07539 -170.936931) (xy 131.11269 -170.896459) (xy 131.155419 -170.861768)
			(xy 131.178808 -170.847258) (xy 131.197826 -170.835418) (xy 131.231691 -170.806095) (xy 131.259889 -170.771288)
			(xy 131.281549 -170.732076) (xy 131.295998 -170.689674) (xy 131.302789 -170.645396) (xy 131.301712 -170.600613)
			(xy 131.2928 -170.556713) (xy 131.27633 -170.515054) (xy 131.25281 -170.476929) (xy 131.238244 -170.459908)
			(xy 131.22028 -170.439051) (xy 131.189915 -170.393141) (xy 131.166462 -170.343343) (xy 131.15041 -170.290691)
			(xy 131.142091 -170.236279) (xy 131.141678 -170.181237) (xy 131.14918 -170.126706) (xy 131.16444 -170.07382)
			(xy 131.187143 -170.023676) (xy 131.216817 -169.977314) (xy 131.252845 -169.935699) (xy 131.294479 -169.899693)
			(xy 131.340856 -169.870045) (xy 131.391013 -169.847369) (xy 131.443907 -169.832137) (xy 131.498442 -169.824665)
			(xy 131.553484 -169.825107) (xy 131.607892 -169.833456) (xy 131.660535 -169.849536) (xy 131.71032 -169.873015)
			(xy 131.756214 -169.903406) (xy 131.797265 -169.940076) (xy 131.832619 -169.982265) (xy 131.852618 -170.014646)
			(xy 134.117332 -170.014646) (xy 134.121403 -169.959024) (xy 134.133529 -169.904587) (xy 134.153452 -169.852496)
			(xy 134.180748 -169.803861) (xy 134.214834 -169.759718) (xy 134.254983 -169.721009) (xy 134.300341 -169.688558)
			(xy 134.349941 -169.663057) (xy 134.402725 -169.64505) (xy 134.457568 -169.63492) (xy 134.513302 -169.632883)
			(xy 134.568739 -169.638983) (xy 134.622696 -169.653089) (xy 134.674025 -169.674901) (xy 134.721631 -169.703955)
			(xy 134.764499 -169.73963) (xy 134.801716 -169.781167) (xy 134.832489 -169.82768) (xy 134.856161 -169.878177)
			(xy 134.872229 -169.931584) (xy 134.880349 -169.98676) (xy 134.880858 -170.014646) (xy 134.880349 -170.042532)
			(xy 134.872229 -170.097708) (xy 134.856161 -170.151115) (xy 134.832489 -170.201612) (xy 134.801716 -170.248125)
			(xy 134.764499 -170.289662) (xy 134.721631 -170.325337) (xy 134.674025 -170.354391) (xy 134.622696 -170.376203)
			(xy 134.595932 -170.3832) (xy 139.643864 -170.3832) (xy 139.647935 -170.327578) (xy 139.660061 -170.273141)
			(xy 139.679984 -170.22105) (xy 139.70728 -170.172415) (xy 139.741366 -170.128272) (xy 139.781515 -170.089563)
			(xy 139.826873 -170.057112) (xy 139.876473 -170.031611) (xy 139.929257 -170.013604) (xy 139.9841 -170.003474)
			(xy 140.039834 -170.001437) (xy 140.095271 -170.007537) (xy 140.149228 -170.021643) (xy 140.200557 -170.043455)
			(xy 140.248163 -170.072509) (xy 140.259515 -170.081956) (xy 143.170654 -170.081956) (xy 143.174725 -170.026334)
			(xy 143.186851 -169.971897) (xy 143.206774 -169.919806) (xy 143.23407 -169.871171) (xy 143.268156 -169.827028)
			(xy 143.308305 -169.788319) (xy 143.353663 -169.755868) (xy 143.403263 -169.730367) (xy 143.456047 -169.71236)
			(xy 143.51089 -169.70223) (xy 143.566624 -169.700193) (xy 143.622061 -169.706293) (xy 143.676018 -169.720399)
			(xy 143.727347 -169.742211) (xy 143.774953 -169.771265) (xy 143.817821 -169.80694) (xy 143.855038 -169.848477)
			(xy 143.885811 -169.89499) (xy 143.909483 -169.945487) (xy 143.925551 -169.998894) (xy 143.933671 -170.05407)
			(xy 143.93418 -170.081956) (xy 143.933671 -170.109842) (xy 143.925551 -170.165018) (xy 143.909483 -170.218425)
			(xy 143.885811 -170.268922) (xy 143.855038 -170.315435) (xy 143.817821 -170.356972) (xy 143.774953 -170.392647)
			(xy 143.727347 -170.421701) (xy 143.676018 -170.443513) (xy 143.622061 -170.457619) (xy 143.566624 -170.463719)
			(xy 143.51089 -170.461682) (xy 143.456047 -170.451552) (xy 143.403263 -170.433545) (xy 143.353663 -170.408044)
			(xy 143.308305 -170.375593) (xy 143.268156 -170.336884) (xy 143.23407 -170.292741) (xy 143.206774 -170.244106)
			(xy 143.186851 -170.192015) (xy 143.174725 -170.137578) (xy 143.170654 -170.081956) (xy 140.259515 -170.081956)
			(xy 140.291031 -170.108184) (xy 140.328248 -170.149721) (xy 140.359021 -170.196234) (xy 140.382693 -170.246731)
			(xy 140.398761 -170.300138) (xy 140.406881 -170.355314) (xy 140.40739 -170.3832) (xy 140.406881 -170.411086)
			(xy 140.398761 -170.466262) (xy 140.382693 -170.519669) (xy 140.359021 -170.570166) (xy 140.328248 -170.616679)
			(xy 140.291031 -170.658216) (xy 140.248163 -170.693891) (xy 140.200557 -170.722945) (xy 140.149228 -170.744757)
			(xy 140.095271 -170.758863) (xy 140.039834 -170.764963) (xy 139.9841 -170.762926) (xy 139.929257 -170.752796)
			(xy 139.876473 -170.734789) (xy 139.826873 -170.709288) (xy 139.781515 -170.676837) (xy 139.741366 -170.638128)
			(xy 139.70728 -170.593985) (xy 139.679984 -170.54535) (xy 139.660061 -170.493259) (xy 139.647935 -170.438822)
			(xy 139.643864 -170.3832) (xy 134.595932 -170.3832) (xy 134.568739 -170.390309) (xy 134.513302 -170.396409)
			(xy 134.457568 -170.394372) (xy 134.402725 -170.384242) (xy 134.349941 -170.366235) (xy 134.300341 -170.340734)
			(xy 134.254983 -170.308283) (xy 134.214834 -170.269574) (xy 134.180748 -170.225431) (xy 134.153452 -170.176796)
			(xy 134.133529 -170.124705) (xy 134.121403 -170.070268) (xy 134.117332 -170.014646) (xy 131.852618 -170.014646)
			(xy 131.861543 -170.029097) (xy 131.883437 -170.0796) (xy 131.897845 -170.132725) (xy 131.904469 -170.187369)
			(xy 131.903171 -170.242398) (xy 131.893979 -170.296669) (xy 131.877082 -170.349056) (xy 131.852832 -170.39847)
			(xy 131.821732 -170.443887) (xy 131.784428 -170.484363) (xy 131.741695 -170.519057) (xy 131.718304 -170.533568)
			(xy 131.699347 -170.545501) (xy 131.665485 -170.574812) (xy 131.637286 -170.609605) (xy 131.615624 -170.648804)
			(xy 131.601171 -170.691193) (xy 131.594372 -170.73546) (xy 131.595441 -170.780233) (xy 131.604343 -170.824125)
			(xy 131.620802 -170.865777) (xy 131.644309 -170.903898) (xy 131.658868 -170.920918) (xy 131.676814 -170.941787)
			(xy 131.707173 -170.987696) (xy 131.73062 -171.037491) (xy 131.746668 -171.090139) (xy 131.754983 -171.144546)
			(xy 131.755392 -171.199584) (xy 131.747888 -171.254109) (xy 131.732626 -171.30699) (xy 131.709922 -171.357128)
			(xy 131.680249 -171.403484) (xy 131.644223 -171.445093) (xy 131.632674 -171.45508) (xy 136.710418 -171.45508)
			(xy 136.714489 -171.399458) (xy 136.726615 -171.345021) (xy 136.746538 -171.29293) (xy 136.773834 -171.244295)
			(xy 136.80792 -171.200152) (xy 136.848069 -171.161443) (xy 136.893427 -171.128992) (xy 136.943027 -171.103491)
			(xy 136.995811 -171.085484) (xy 137.050654 -171.075354) (xy 137.106388 -171.073317) (xy 137.161825 -171.079417)
			(xy 137.215782 -171.093523) (xy 137.267111 -171.115335) (xy 137.314717 -171.144389) (xy 137.357585 -171.180064)
			(xy 137.394802 -171.221601) (xy 137.425575 -171.268114) (xy 137.449247 -171.318611) (xy 137.465315 -171.372018)
			(xy 137.473435 -171.427194) (xy 137.473944 -171.45508) (xy 137.473435 -171.482966) (xy 137.465315 -171.538142)
			(xy 137.449247 -171.591549) (xy 137.425575 -171.642046) (xy 137.394802 -171.688559) (xy 137.357585 -171.730096)
			(xy 137.314717 -171.765771) (xy 137.267111 -171.794825) (xy 137.215782 -171.816637) (xy 137.161825 -171.830743)
			(xy 137.106388 -171.836843) (xy 137.050654 -171.834806) (xy 136.995811 -171.824676) (xy 136.943027 -171.806669)
			(xy 136.893427 -171.781168) (xy 136.848069 -171.748717) (xy 136.80792 -171.710008) (xy 136.773834 -171.665865)
			(xy 136.746538 -171.61723) (xy 136.726615 -171.565139) (xy 136.714489 -171.510702) (xy 136.710418 -171.45508)
			(xy 131.632674 -171.45508) (xy 131.60259 -171.481094) (xy 131.556216 -171.510738) (xy 131.506063 -171.533409)
			(xy 131.453173 -171.548638) (xy 131.398643 -171.556108) (xy 131.343605 -171.555663) (xy 131.289203 -171.547314)
			(xy 131.236565 -171.531233) (xy 131.186785 -171.507755) (xy 131.140896 -171.477366) (xy 131.09985 -171.440698)
			(xy 131.0645 -171.398512) (xy 131.035579 -171.351684) (xy 131.013688 -171.301185) (xy 130.999282 -171.248065)
			(xy 130.992659 -171.193426) (xy 122.834204 -171.193426) (xy 122.831458 -171.197577) (xy 122.794241 -171.239114)
			(xy 122.751373 -171.274789) (xy 122.703767 -171.303843) (xy 122.652438 -171.325655) (xy 122.598481 -171.339761)
			(xy 122.543044 -171.345861) (xy 122.48731 -171.343824) (xy 122.432467 -171.333694) (xy 122.379683 -171.315687)
			(xy 122.330083 -171.290186) (xy 122.284725 -171.257735) (xy 122.244576 -171.219026) (xy 122.21049 -171.174883)
			(xy 122.183194 -171.126248) (xy 122.163271 -171.074157) (xy 122.151145 -171.01972) (xy 122.147074 -170.964098)
			(xy 120.569228 -170.964098) (xy 121.299478 -171.694348) (xy 121.310382 -171.704628) (xy 121.335949 -171.72025)
			(xy 121.364452 -171.729485) (xy 121.394322 -171.731827) (xy 121.423916 -171.727146) (xy 121.437908 -171.72178)
			(xy 121.484898 -171.702222) (xy 121.505472 -171.683934) (xy 121.51487 -171.676314) (xy 121.53739 -171.658611)
			(xy 121.586695 -171.629453) (xy 121.639805 -171.607993) (xy 121.695526 -171.594713) (xy 121.752606 -171.589912)
			(xy 121.809762 -171.593698) (xy 121.86571 -171.605986) (xy 121.919193 -171.626499) (xy 121.969008 -171.654777)
			(xy 122.014036 -171.690184) (xy 122.053265 -171.731925) (xy 122.085813 -171.77906) (xy 122.098816 -171.804584)
			(xy 122.10711 -171.820298) (xy 122.13085 -171.846716) (xy 122.160961 -171.865553) (xy 122.195103 -171.875343)
			(xy 122.212862 -171.875958) (xy 124.118624 -171.875958) (xy 124.141219 -171.875465) (xy 124.185695 -171.867474)
			(xy 124.22806 -171.851748) (xy 124.266978 -171.828782) (xy 124.301224 -171.799299) (xy 124.329721 -171.764228)
			(xy 124.35157 -171.724672) (xy 124.366084 -171.681877) (xy 124.372806 -171.63719) (xy 124.372624 -171.614592)
			(xy 124.372298 -171.586764) (xy 124.378737 -171.531486) (xy 124.39314 -171.47773) (xy 124.415202 -171.426638)
			(xy 124.444454 -171.379295) (xy 124.480275 -171.336704) (xy 124.521905 -171.299772) (xy 124.56846 -171.26928)
			(xy 124.618952 -171.245877) (xy 124.672308 -171.23006) (xy 124.727397 -171.222164) (xy 124.783048 -171.222358)
			(xy 124.838081 -171.230636) (xy 124.891326 -171.246823) (xy 124.941654 -171.270576) (xy 124.987996 -171.30139)
			(xy 125.029369 -171.338611) (xy 125.064893 -171.381449) (xy 125.093816 -171.428994) (xy 125.115523 -171.480238)
			(xy 125.129552 -171.534092) (xy 125.135607 -171.589414) (xy 125.134904 -171.608496) (xy 127.104138 -171.608496)
			(xy 127.108209 -171.552874) (xy 127.120335 -171.498437) (xy 127.140258 -171.446346) (xy 127.167554 -171.397711)
			(xy 127.20164 -171.353568) (xy 127.241789 -171.314859) (xy 127.287147 -171.282408) (xy 127.336747 -171.256907)
			(xy 127.389531 -171.2389) (xy 127.444374 -171.22877) (xy 127.500108 -171.226733) (xy 127.555545 -171.232833)
			(xy 127.609502 -171.246939) (xy 127.660831 -171.268751) (xy 127.708437 -171.297805) (xy 127.751305 -171.33348)
			(xy 127.788522 -171.375017) (xy 127.819295 -171.42153) (xy 127.842967 -171.472027) (xy 127.859035 -171.525434)
			(xy 127.867155 -171.58061) (xy 127.867664 -171.608496) (xy 127.867155 -171.636382) (xy 127.859035 -171.691558)
			(xy 127.842967 -171.744965) (xy 127.819295 -171.795462) (xy 127.788522 -171.841975) (xy 127.751305 -171.883512)
			(xy 127.708437 -171.919187) (xy 127.660831 -171.948241) (xy 127.609502 -171.970053) (xy 127.555545 -171.984159)
			(xy 127.500108 -171.990259) (xy 127.444374 -171.988222) (xy 127.389531 -171.978092) (xy 127.336747 -171.960085)
			(xy 127.287147 -171.934584) (xy 127.241789 -171.902133) (xy 127.20164 -171.863424) (xy 127.167554 -171.819281)
			(xy 127.140258 -171.770646) (xy 127.120335 -171.718555) (xy 127.108209 -171.664118) (xy 127.104138 -171.608496)
			(xy 125.134904 -171.608496) (xy 125.133559 -171.645028) (xy 125.123451 -171.699753) (xy 125.105498 -171.75243)
			(xy 125.093222 -171.777406) (xy 125.086278 -171.791901) (xy 125.079173 -171.823237) (xy 125.080138 -171.855354)
			(xy 125.089113 -171.886206) (xy 125.105527 -171.913829) (xy 125.11659 -171.925488) (xy 125.177296 -171.98594)
			(xy 125.784356 -171.98594) (xy 125.8189 -171.958762) (xy 125.84141 -171.941753) (xy 125.890447 -171.913854)
			(xy 125.943057 -171.893479) (xy 125.998094 -171.881074) (xy 126.054358 -171.876909) (xy 126.110622 -171.881074)
			(xy 126.165659 -171.893479) (xy 126.218269 -171.913854) (xy 126.267306 -171.941753) (xy 126.289816 -171.958762)
			(xy 126.32436 -171.98594) (xy 126.57074 -171.98594) (xy 126.57074 -172.49267) (xy 128.035302 -172.49267)
			(xy 128.039373 -172.437048) (xy 128.051499 -172.382611) (xy 128.071422 -172.33052) (xy 128.098718 -172.281885)
			(xy 128.132804 -172.237742) (xy 128.172953 -172.199033) (xy 128.218311 -172.166582) (xy 128.267911 -172.141081)
			(xy 128.320695 -172.123074) (xy 128.375538 -172.112944) (xy 128.431272 -172.110907) (xy 128.486709 -172.117007)
			(xy 128.540666 -172.131113) (xy 128.591995 -172.152925) (xy 128.639601 -172.181979) (xy 128.682469 -172.217654)
			(xy 128.719686 -172.259191) (xy 128.729972 -172.274738) (xy 131.28701 -172.274738) (xy 131.291081 -172.219116)
			(xy 131.303207 -172.164679) (xy 131.32313 -172.112588) (xy 131.350426 -172.063953) (xy 131.384512 -172.01981)
			(xy 131.424661 -171.981101) (xy 131.470019 -171.94865) (xy 131.519619 -171.923149) (xy 131.572403 -171.905142)
			(xy 131.627246 -171.895012) (xy 131.68298 -171.892975) (xy 131.738417 -171.899075) (xy 131.792374 -171.913181)
			(xy 131.843703 -171.934993) (xy 131.891309 -171.964047) (xy 131.934177 -171.999722) (xy 131.971394 -172.041259)
			(xy 132.002167 -172.087772) (xy 132.025839 -172.138269) (xy 132.041907 -172.191676) (xy 132.050027 -172.246852)
			(xy 132.050536 -172.274738) (xy 132.050027 -172.302624) (xy 132.041907 -172.3578) (xy 132.025839 -172.411207)
			(xy 132.002167 -172.461704) (xy 131.979663 -172.495718) (xy 133.374382 -172.495718) (xy 133.378453 -172.440096)
			(xy 133.390579 -172.385659) (xy 133.410502 -172.333568) (xy 133.437798 -172.284933) (xy 133.471884 -172.24079)
			(xy 133.512033 -172.202081) (xy 133.557391 -172.16963) (xy 133.606991 -172.144129) (xy 133.659775 -172.126122)
			(xy 133.714618 -172.115992) (xy 133.770352 -172.113955) (xy 133.825789 -172.120055) (xy 133.879746 -172.134161)
			(xy 133.931075 -172.155973) (xy 133.978681 -172.185027) (xy 134.021549 -172.220702) (xy 134.058766 -172.262239)
			(xy 134.089539 -172.308752) (xy 134.113211 -172.359249) (xy 134.129279 -172.412656) (xy 134.137399 -172.467832)
			(xy 134.137908 -172.495718) (xy 134.137399 -172.523604) (xy 134.132756 -172.555154) (xy 135.068562 -172.555154)
			(xy 135.072633 -172.499532) (xy 135.084759 -172.445095) (xy 135.104682 -172.393004) (xy 135.131978 -172.344369)
			(xy 135.166064 -172.300226) (xy 135.206213 -172.261517) (xy 135.251571 -172.229066) (xy 135.301171 -172.203565)
			(xy 135.353955 -172.185558) (xy 135.408798 -172.175428) (xy 135.464532 -172.173391) (xy 135.519969 -172.179491)
			(xy 135.573926 -172.193597) (xy 135.625255 -172.215409) (xy 135.672861 -172.244463) (xy 135.715729 -172.280138)
			(xy 135.752946 -172.321675) (xy 135.783719 -172.368188) (xy 135.807391 -172.418685) (xy 135.823459 -172.472092)
			(xy 135.831579 -172.527268) (xy 135.832088 -172.555154) (xy 135.831579 -172.58304) (xy 135.823459 -172.638216)
			(xy 135.807391 -172.691623) (xy 135.783719 -172.74212) (xy 135.752946 -172.788633) (xy 135.715729 -172.83017)
			(xy 135.672861 -172.865845) (xy 135.625255 -172.894899) (xy 135.573926 -172.916711) (xy 135.519969 -172.930817)
			(xy 135.464532 -172.936917) (xy 135.408798 -172.93488) (xy 135.353955 -172.92475) (xy 135.301171 -172.906743)
			(xy 135.251571 -172.881242) (xy 135.206213 -172.848791) (xy 135.166064 -172.810082) (xy 135.131978 -172.765939)
			(xy 135.104682 -172.717304) (xy 135.084759 -172.665213) (xy 135.072633 -172.610776) (xy 135.068562 -172.555154)
			(xy 134.132756 -172.555154) (xy 134.129279 -172.57878) (xy 134.113211 -172.632187) (xy 134.089539 -172.682684)
			(xy 134.058766 -172.729197) (xy 134.021549 -172.770734) (xy 133.978681 -172.806409) (xy 133.931075 -172.835463)
			(xy 133.879746 -172.857275) (xy 133.825789 -172.871381) (xy 133.770352 -172.877481) (xy 133.714618 -172.875444)
			(xy 133.659775 -172.865314) (xy 133.606991 -172.847307) (xy 133.557391 -172.821806) (xy 133.512033 -172.789355)
			(xy 133.471884 -172.750646) (xy 133.437798 -172.706503) (xy 133.410502 -172.657868) (xy 133.390579 -172.605777)
			(xy 133.378453 -172.55134) (xy 133.374382 -172.495718) (xy 131.979663 -172.495718) (xy 131.971394 -172.508217)
			(xy 131.934177 -172.549754) (xy 131.891309 -172.585429) (xy 131.843703 -172.614483) (xy 131.792374 -172.636295)
			(xy 131.738417 -172.650401) (xy 131.68298 -172.656501) (xy 131.627246 -172.654464) (xy 131.572403 -172.644334)
			(xy 131.519619 -172.626327) (xy 131.470019 -172.600826) (xy 131.424661 -172.568375) (xy 131.384512 -172.529666)
			(xy 131.350426 -172.485523) (xy 131.32313 -172.436888) (xy 131.303207 -172.384797) (xy 131.291081 -172.33036)
			(xy 131.28701 -172.274738) (xy 128.729972 -172.274738) (xy 128.750459 -172.305704) (xy 128.774131 -172.356201)
			(xy 128.790199 -172.409608) (xy 128.798319 -172.464784) (xy 128.798828 -172.49267) (xy 128.798319 -172.520556)
			(xy 128.790199 -172.575732) (xy 128.774131 -172.629139) (xy 128.750459 -172.679636) (xy 128.719686 -172.726149)
			(xy 128.682469 -172.767686) (xy 128.639601 -172.803361) (xy 128.591995 -172.832415) (xy 128.540666 -172.854227)
			(xy 128.486709 -172.868333) (xy 128.431272 -172.874433) (xy 128.375538 -172.872396) (xy 128.320695 -172.862266)
			(xy 128.267911 -172.844259) (xy 128.218311 -172.818758) (xy 128.172953 -172.786307) (xy 128.132804 -172.747598)
			(xy 128.098718 -172.703455) (xy 128.071422 -172.65482) (xy 128.051499 -172.602729) (xy 128.039373 -172.548292)
			(xy 128.035302 -172.49267) (xy 126.57074 -172.49267) (xy 126.57074 -172.73524) (xy 126.774194 -172.938948)
			(xy 126.78993 -172.95405) (xy 126.825579 -172.979171) (xy 126.864997 -172.997832) (xy 126.907023 -173.009483)
			(xy 126.950422 -173.013783) (xy 126.993917 -173.010604) (xy 127.03623 -173.00004) (xy 127.076115 -172.982401)
			(xy 127.1124 -172.958207) (xy 127.128524 -172.94352) (xy 127.149241 -172.924553) (xy 127.195214 -172.892285)
			(xy 127.245419 -172.867104) (xy 127.298774 -172.849553) (xy 127.354124 -172.840012) (xy 127.410275 -172.838685)
			(xy 127.466015 -172.845603) (xy 127.520138 -172.860616) (xy 127.571477 -172.883398) (xy 127.618922 -172.913459)
			(xy 127.661449 -172.950149) (xy 127.698139 -172.992676) (xy 127.728201 -173.040121) (xy 127.750984 -173.09146)
			(xy 127.765996 -173.145583) (xy 127.772914 -173.201322) (xy 127.771589 -173.257474) (xy 127.762047 -173.312824)
			(xy 127.744497 -173.366178) (xy 127.719316 -173.416384) (xy 127.687049 -173.462358) (xy 127.66802 -173.483016)
			(xy 127.653345 -173.499143) (xy 127.629182 -173.535434) (xy 127.611568 -173.575318) (xy 127.602411 -173.612048)
			(xy 128.261362 -173.612048) (xy 128.265433 -173.556426) (xy 128.277559 -173.501989) (xy 128.297482 -173.449898)
			(xy 128.324778 -173.401263) (xy 128.358864 -173.35712) (xy 128.399013 -173.318411) (xy 128.444371 -173.28596)
			(xy 128.493971 -173.260459) (xy 128.546755 -173.242452) (xy 128.601598 -173.232322) (xy 128.657332 -173.230285)
			(xy 128.712769 -173.236385) (xy 128.766726 -173.250491) (xy 128.818055 -173.272303) (xy 128.865661 -173.301357)
			(xy 128.908529 -173.337032) (xy 128.945746 -173.378569) (xy 128.976519 -173.425082) (xy 129.000191 -173.475579)
			(xy 129.016259 -173.528986) (xy 129.024379 -173.584162) (xy 129.024888 -173.612048) (xy 129.024379 -173.639934)
			(xy 129.016259 -173.69511) (xy 129.000191 -173.748517) (xy 128.976519 -173.799014) (xy 128.945746 -173.845527)
			(xy 128.908529 -173.887064) (xy 128.865661 -173.922739) (xy 128.818055 -173.951793) (xy 128.766726 -173.973605)
			(xy 128.712769 -173.987711) (xy 128.657332 -173.993811) (xy 128.601598 -173.991774) (xy 128.546755 -173.981644)
			(xy 128.493971 -173.963637) (xy 128.444371 -173.938136) (xy 128.399013 -173.905685) (xy 128.358864 -173.866976)
			(xy 128.324778 -173.822833) (xy 128.297482 -173.774198) (xy 128.277559 -173.722107) (xy 128.265433 -173.66767)
			(xy 128.261362 -173.612048) (xy 127.602411 -173.612048) (xy 127.601021 -173.617622) (xy 127.597851 -173.661107)
			(xy 127.60215 -173.704494) (xy 127.613793 -173.74651) (xy 127.632437 -173.785922) (xy 127.657535 -173.821574)
			(xy 127.672592 -173.837346) (xy 127.849884 -174.014638) (xy 127.849884 -174.232824) (xy 128.476248 -174.859188)
			(xy 128.938528 -174.859188) (xy 129.321814 -175.24222) (xy 130.453892 -175.24222) (xy 130.607308 -175.088804)
			(xy 130.917188 -175.088804) (xy 130.939331 -175.08835) (xy 130.982954 -175.08072) (xy 131.024591 -175.065639)
			(xy 131.062981 -175.043562) (xy 131.096959 -175.015159) (xy 131.125493 -174.981293) (xy 131.147719 -174.94299)
			(xy 131.162963 -174.901411) (xy 131.170763 -174.857818) (xy 131.170881 -174.813534) (xy 131.167632 -174.791624)
			(xy 131.166616 -174.785528) (xy 131.162697 -174.76341) (xy 131.148112 -174.720928) (xy 131.126287 -174.681671)
			(xy 131.097902 -174.646862) (xy 131.06384 -174.617584) (xy 131.025162 -174.59475) (xy 130.983072 -174.579069)
			(xy 130.938882 -174.57103) (xy 130.916426 -174.57039) (xy 130.888903 -174.569794) (xy 130.834458 -174.561656)
			(xy 130.781748 -174.545778) (xy 130.731867 -174.522488) (xy 130.685852 -174.49227) (xy 130.644658 -174.455753)
			(xy 130.60914 -174.413693) (xy 130.580037 -174.366965) (xy 130.557952 -174.316539) (xy 130.543344 -174.263463)
			(xy 130.536517 -174.208838) (xy 130.537613 -174.153799) (xy 130.546608 -174.099489) (xy 130.563316 -174.047035)
			(xy 130.587389 -173.997528) (xy 130.618329 -173.951995) (xy 130.655492 -173.911382) (xy 130.698107 -173.876533)
			(xy 130.745288 -173.84817) (xy 130.796056 -173.826883) (xy 130.849356 -173.813115) (xy 130.904082 -173.80715)
			(xy 130.959097 -173.809114) (xy 131.013258 -173.818964) (xy 131.065442 -173.836498) (xy 131.114563 -173.861349)
			(xy 131.137406 -173.876716) (xy 131.156118 -173.889278) (xy 131.196977 -173.908287) (xy 131.24055 -173.919785)
			(xy 131.285468 -173.923413) (xy 131.330321 -173.919055) (xy 131.373701 -173.90685) (xy 131.414246 -173.887179)
			(xy 131.450682 -173.860662) (xy 131.481867 -173.828129) (xy 131.494784 -173.80966) (xy 131.510208 -173.787324)
			(xy 131.546365 -173.746838) (xy 131.587894 -173.711885) (xy 131.633958 -173.683171) (xy 131.683626 -173.661276)
			(xy 131.735897 -173.646641) (xy 131.789714 -173.639562) (xy 131.843991 -173.640182) (xy 131.897632 -173.648488)
			(xy 131.949554 -173.664313) (xy 131.99871 -173.687338) (xy 132.044106 -173.717096) (xy 132.084826 -173.752988)
			(xy 132.120048 -173.79429) (xy 132.149061 -173.840166) (xy 132.171279 -173.889691) (xy 132.186253 -173.941865)
			(xy 132.193682 -173.995635) (xy 132.193415 -174.049915) (xy 132.185458 -174.103609) (xy 132.16997 -174.155633)
			(xy 132.147266 -174.204937) (xy 132.117803 -174.250526) (xy 132.11199 -174.257208) (xy 133.504176 -174.257208)
			(xy 133.508247 -174.201586) (xy 133.520373 -174.147149) (xy 133.540296 -174.095058) (xy 133.567592 -174.046423)
			(xy 133.601678 -174.00228) (xy 133.641827 -173.963571) (xy 133.687185 -173.93112) (xy 133.736785 -173.905619)
			(xy 133.789569 -173.887612) (xy 133.844412 -173.877482) (xy 133.900146 -173.875445) (xy 133.955583 -173.881545)
			(xy 134.00954 -173.895651) (xy 134.060869 -173.917463) (xy 134.108475 -173.946517) (xy 134.151343 -173.982192)
			(xy 134.18856 -174.023729) (xy 134.219333 -174.070242) (xy 134.243005 -174.120739) (xy 134.259073 -174.174146)
			(xy 134.267193 -174.229322) (xy 134.267702 -174.257208) (xy 134.267193 -174.285094) (xy 134.259073 -174.34027)
			(xy 134.243005 -174.393677) (xy 134.219333 -174.444174) (xy 134.18856 -174.490687) (xy 134.151343 -174.532224)
			(xy 134.108475 -174.567899) (xy 134.060869 -174.596953) (xy 134.00954 -174.618765) (xy 133.955583 -174.632871)
			(xy 133.900146 -174.638971) (xy 133.844412 -174.636934) (xy 133.789569 -174.626804) (xy 133.736785 -174.608797)
			(xy 133.687185 -174.583296) (xy 133.641827 -174.550845) (xy 133.601678 -174.512136) (xy 133.567592 -174.467993)
			(xy 133.540296 -174.419358) (xy 133.520373 -174.367267) (xy 133.508247 -174.31283) (xy 133.504176 -174.257208)
			(xy 132.11199 -174.257208) (xy 132.082177 -174.291478) (xy 132.041105 -174.326968) (xy 132.018532 -174.342044)
			(xy 131.999347 -174.354947) (xy 131.965588 -174.38653) (xy 131.938103 -174.423701) (xy 131.9178 -174.465234)
			(xy 131.905351 -174.509755) (xy 131.901167 -174.555795) (xy 131.905386 -174.601831) (xy 131.91109 -174.624238)
			(xy 131.917786 -174.650021) (xy 131.924802 -174.702824) (xy 131.924417 -174.756091) (xy 131.916639 -174.808788)
			(xy 131.901618 -174.859894) (xy 131.891024 -174.884334) (xy 131.881957 -174.905551) (xy 131.870804 -174.950319)
			(xy 131.867917 -174.996364) (xy 131.873391 -175.042175) (xy 131.887046 -175.086244) (xy 131.908433 -175.127123)
			(xy 131.936849 -175.163469) (xy 131.97136 -175.194088) (xy 132.010832 -175.217973) (xy 132.053968 -175.234338)
			(xy 132.09935 -175.242647) (xy 132.122418 -175.243236) (xy 134.573518 -175.243236) (xy 134.643368 -175.18634)
			(xy 134.652512 -175.14189) (xy 134.658483 -175.115256) (xy 134.677018 -175.063918) (xy 134.702679 -175.015745)
			(xy 134.734942 -174.97172) (xy 134.77315 -174.932741) (xy 134.816522 -174.899604) (xy 134.864173 -174.872986)
			(xy 134.91513 -174.853429) (xy 134.968355 -174.841333) (xy 135.02276 -174.836944) (xy 135.077235 -174.840352)
			(xy 135.130668 -174.851488) (xy 135.18197 -174.870124) (xy 135.230092 -174.89588) (xy 135.274054 -174.92823)
			(xy 135.312957 -174.966515) (xy 135.346008 -175.009952) (xy 135.372533 -175.057655) (xy 135.382762 -175.082962)
			(xy 135.388662 -175.097123) (xy 135.406129 -175.122333) (xy 135.429107 -175.142646) (xy 135.45627 -175.156888)
			(xy 135.486046 -175.164235) (xy 135.50138 -175.16475) (xy 140.254736 -175.16475) (xy 140.7668 -175.676814)
			(xy 140.777469 -175.686859) (xy 140.802392 -175.702259) (xy 140.830166 -175.711581) (xy 140.859332 -175.714338)
			(xy 140.888361 -175.710383) (xy 140.902182 -175.705516) (xy 140.923695 -175.69761) (xy 140.968139 -175.686405)
			(xy 140.990828 -175.683164) (xy 141.034516 -175.677576) (xy 141.071346 -175.639984) (xy 141.08237 -175.62805)
			(xy 141.098515 -175.599869) (xy 141.107003 -175.56852) (xy 141.107281 -175.536043) (xy 141.099332 -175.504552)
			(xy 141.083671 -175.476099) (xy 141.07287 -175.463962) (xy 141.03985 -175.42891) (xy 140.997686 -175.421798)
			(xy 140.970563 -175.416761) (xy 140.918037 -175.399905) (xy 140.868487 -175.375659) (xy 140.822946 -175.344528)
			(xy 140.782365 -175.307162) (xy 140.747589 -175.264339) (xy 140.719345 -175.216954) (xy 140.698222 -175.165994)
			(xy 140.68466 -175.112523) (xy 140.678941 -175.057656) (xy 140.681186 -175.002537) (xy 140.691348 -174.948317)
			(xy 140.709214 -174.896126) (xy 140.734412 -174.847053) (xy 140.766416 -174.802121) (xy 140.804559 -174.762269)
			(xy 140.825982 -174.744888) (xy 140.844254 -174.730005) (xy 140.875454 -174.694693) (xy 140.899608 -174.654233)
			(xy 140.915887 -174.610013) (xy 140.923732 -174.563549) (xy 140.922875 -174.516436) (xy 140.913345 -174.470288)
			(xy 140.895469 -174.426689) (xy 140.86986 -174.387135) (xy 140.837395 -174.352981) (xy 140.818616 -174.338742)
			(xy 140.796776 -174.32237) (xy 140.757558 -174.284406) (xy 140.724148 -174.241242) (xy 140.697229 -174.193758)
			(xy 140.677348 -174.142924) (xy 140.664912 -174.089777) (xy 140.660174 -174.035399) (xy 140.663231 -173.980902)
			(xy 140.674021 -173.927396) (xy 140.692322 -173.875972) (xy 140.717764 -173.82768) (xy 140.749825 -173.783506)
			(xy 140.787852 -173.744349) (xy 140.809218 -173.727364) (xy 140.827523 -173.712568) (xy 140.858828 -173.677426)
			(xy 140.883133 -173.637124) (xy 140.899608 -173.593039) (xy 140.907691 -173.546675) (xy 140.907105 -173.499615)
			(xy 140.897871 -173.453466) (xy 140.880305 -173.409804) (xy 140.855005 -173.37012) (xy 140.822835 -173.335767)
			(xy 140.804138 -173.321472) (xy 140.782117 -173.304737) (xy 140.742679 -173.265959) (xy 140.709255 -173.221893)
			(xy 140.682546 -173.173461) (xy 140.66311 -173.12168) (xy 140.651357 -173.067634) (xy 140.647532 -173.012458)
			(xy 140.651716 -172.957308) (xy 140.66382 -172.903341) (xy 140.683591 -172.851687) (xy 140.710615 -172.80343)
			(xy 140.744325 -172.759581) (xy 140.784014 -172.721061) (xy 140.80617 -172.704506) (xy 140.82494 -172.690277)
			(xy 140.857344 -172.656099) (xy 140.882901 -172.616539) (xy 140.900737 -172.572949) (xy 140.910243 -172.526821)
			(xy 140.911093 -172.479732) (xy 140.903258 -172.433291) (xy 140.887006 -172.389086) (xy 140.862893 -172.34863)
			(xy 140.831744 -172.313304) (xy 140.813536 -172.29836) (xy 140.792591 -172.281424) (xy 140.755214 -172.242638)
			(xy 140.723664 -172.198982) (xy 140.698568 -172.151321) (xy 140.680424 -172.100605) (xy 140.669593 -172.047842)
			(xy 140.666291 -171.994079) (xy 140.670584 -171.940387) (xy 140.682385 -171.887831) (xy 140.701461 -171.837458)
			(xy 140.727431 -171.790269) (xy 140.759781 -171.747201) (xy 140.797866 -171.709111) (xy 140.819124 -171.69257)
			(xy 140.837626 -171.678015) (xy 140.869395 -171.643282) (xy 140.894225 -171.603293) (xy 140.911266 -171.559415)
			(xy 140.919936 -171.51315) (xy 140.919939 -171.466079) (xy 140.911274 -171.419813) (xy 140.894238 -171.375933)
			(xy 140.869413 -171.335941) (xy 140.837648 -171.301204) (xy 140.819124 -171.286678) (xy 140.797003 -171.269445)
			(xy 140.757578 -171.22957) (xy 140.724414 -171.184353) (xy 140.698227 -171.134769) (xy 140.67958 -171.081886)
			(xy 140.668874 -171.026843) (xy 140.666342 -170.970826) (xy 140.672036 -170.915041) (xy 140.685834 -170.860691)
			(xy 140.70744 -170.808946) (xy 140.736387 -170.760921) (xy 140.772053 -170.71765) (xy 140.813668 -170.680067)
			(xy 140.860337 -170.64898) (xy 140.911053 -170.625059) (xy 140.964724 -170.608819) (xy 141.020195 -170.600611)
			(xy 141.076269 -170.600611) (xy 141.13174 -170.608819) (xy 141.185411 -170.625059) (xy 141.236127 -170.64898)
			(xy 141.282796 -170.680067) (xy 141.324411 -170.71765) (xy 141.360077 -170.760921) (xy 141.389024 -170.808946)
			(xy 141.41063 -170.860691) (xy 141.424428 -170.915041) (xy 141.430122 -170.970826) (xy 141.42759 -171.026843)
			(xy 141.416884 -171.081886) (xy 141.398237 -171.134769) (xy 141.37205 -171.184353) (xy 141.338886 -171.22957)
			(xy 141.299461 -171.269445) (xy 141.27734 -171.286678) (xy 141.258844 -171.301234) (xy 141.227089 -171.335967)
			(xy 141.202271 -171.375954) (xy 141.18524 -171.419826) (xy 141.176577 -171.466083) (xy 141.17658 -171.513145)
			(xy 141.185248 -171.559402) (xy 141.202284 -171.603272) (xy 141.227106 -171.643256) (xy 141.258866 -171.677985)
			(xy 141.27734 -171.69257) (xy 141.299021 -171.709449) (xy 141.33777 -171.748403) (xy 141.370529 -171.792513)
			(xy 141.39662 -171.840867) (xy 141.415504 -171.892465) (xy 141.426789 -171.946238) (xy 141.430242 -172.001074)
			(xy 141.425792 -172.055837) (xy 141.413531 -172.109396) (xy 141.393712 -172.160642) (xy 141.366745 -172.208513)
			(xy 141.33319 -172.252021) (xy 141.293738 -172.290263) (xy 141.271752 -172.306742) (xy 141.252975 -172.32097)
			(xy 141.22056 -172.355149) (xy 141.194991 -172.394713) (xy 141.177145 -172.438307) (xy 141.167632 -172.484443)
			(xy 141.166776 -172.531541) (xy 141.174607 -172.577991) (xy 141.190857 -172.622206) (xy 141.214971 -172.662672)
			(xy 141.246124 -172.698006) (xy 141.264386 -172.712888) (xy 141.285194 -172.729707) (xy 141.322351 -172.768201)
			(xy 141.353768 -172.811508) (xy 141.378829 -172.858778) (xy 141.397042 -172.909085) (xy 141.408051 -172.961442)
			(xy 141.411639 -173.014824) (xy 141.407737 -173.068184) (xy 141.39642 -173.120476) (xy 141.377911 -173.170675)
			(xy 141.352573 -173.217797) (xy 141.320902 -173.260918) (xy 141.283518 -173.299193) (xy 141.262608 -173.315884)
			(xy 141.244306 -173.330679) (xy 141.213006 -173.365818) (xy 141.188707 -173.406116) (xy 141.172238 -173.450198)
			(xy 141.164161 -173.496557) (xy 141.164752 -173.54361) (xy 141.17399 -173.589752) (xy 141.191561 -173.633406)
			(xy 141.216864 -173.673081) (xy 141.249036 -173.707424) (xy 141.267688 -173.721776) (xy 141.28928 -173.738181)
			(xy 141.328047 -173.776095) (xy 141.361055 -173.819117) (xy 141.387637 -173.86638) (xy 141.407257 -173.916931)
			(xy 141.419521 -173.969751) (xy 141.424181 -174.023776) (xy 141.421142 -174.077916) (xy 141.410467 -174.131081)
			(xy 141.39237 -174.182197) (xy 141.367217 -174.230235) (xy 141.335513 -174.274227) (xy 141.297899 -174.313286)
			(xy 141.276832 -174.33036) (xy 141.258555 -174.345243) (xy 141.227343 -174.380556) (xy 141.203179 -174.42102)
			(xy 141.192957 -174.448776) (xy 142.720625 -174.448776) (xy 142.728139 -174.394984) (xy 142.743205 -174.342801)
			(xy 142.765519 -174.293282) (xy 142.794629 -174.247428) (xy 142.829948 -174.206165) (xy 142.870761 -174.170327)
			(xy 142.916244 -174.140639) (xy 142.965477 -174.117701) (xy 142.991332 -174.10938) (xy 143.012663 -174.102428)
			(xy 143.05264 -174.082072) (xy 143.088422 -174.055014) (xy 143.118899 -174.022095) (xy 143.143123 -173.984337)
			(xy 143.160342 -173.942912) (xy 143.170022 -173.899108) (xy 143.171418 -173.876716) (xy 143.171926 -173.86935)
			(xy 143.17275 -173.846553) (xy 143.167297 -173.801269) (xy 143.153844 -173.757688) (xy 143.132824 -173.717209)
			(xy 143.104914 -173.681135) (xy 143.071009 -173.650625) (xy 143.032201 -173.626662) (xy 143.011144 -173.61789)
			(xy 142.986278 -173.607676) (xy 142.939507 -173.581174) (xy 142.896918 -173.548371) (xy 142.859354 -173.509916)
			(xy 142.827559 -173.466569) (xy 142.802161 -173.419189) (xy 142.783664 -173.368715) (xy 142.772434 -173.316143)
			(xy 142.768692 -173.262516) (xy 142.772513 -173.208895) (xy 142.783822 -173.15634) (xy 142.802394 -173.105893)
			(xy 142.827862 -173.058551) (xy 142.859722 -173.015252) (xy 142.897343 -172.976852) (xy 142.939981 -172.944112)
			(xy 142.986791 -172.91768) (xy 143.011652 -172.907452) (xy 143.033021 -172.898568) (xy 143.072329 -172.874151)
			(xy 143.106568 -172.843022) (xy 143.134606 -172.80621) (xy 143.155518 -172.764931) (xy 143.168612 -172.720548)
			(xy 143.173455 -172.674528) (xy 143.17218 -172.65142) (xy 143.170868 -172.630509) (xy 143.172271 -172.588631)
			(xy 143.174974 -172.567854) (xy 143.17767 -172.545633) (xy 143.176163 -172.5009) (xy 143.166845 -172.457124)
			(xy 143.150004 -172.415655) (xy 143.126159 -172.377778) (xy 143.096049 -172.344663) (xy 143.060604 -172.317333)
			(xy 143.02092 -172.296634) (xy 142.999714 -172.28947) (xy 142.973922 -172.280777) (xy 142.924841 -172.257264)
			(xy 142.8796 -172.227014) (xy 142.839116 -172.190642) (xy 142.804212 -172.148886) (xy 142.775596 -172.102594)
			(xy 142.75385 -172.052704) (xy 142.739414 -172.000231) (xy 142.732581 -171.946239) (xy 142.733491 -171.891824)
			(xy 142.742124 -171.83809) (xy 142.758306 -171.786129) (xy 142.781708 -171.736994) (xy 142.811855 -171.691684)
			(xy 142.848135 -171.651118) (xy 142.889812 -171.61612) (xy 142.936039 -171.587399) (xy 142.985879 -171.56554)
			(xy 143.038319 -171.550984) (xy 143.065246 -171.547028) (xy 143.081772 -171.54436) (xy 143.112691 -171.531557)
			(xy 143.139222 -171.51116) (xy 143.159542 -171.48457) (xy 143.172255 -171.453614) (xy 143.176489 -171.420418)
			(xy 143.17472 -171.403772) (xy 143.171445 -171.376664) (xy 143.171822 -171.322062) (xy 143.17998 -171.268072)
			(xy 143.195751 -171.215795) (xy 143.218814 -171.166301) (xy 143.248696 -171.120601) (xy 143.284788 -171.079626)
			(xy 143.326353 -171.044216) (xy 143.372541 -171.015092) (xy 143.422409 -170.992851) (xy 143.474938 -170.977945)
			(xy 143.529056 -170.97068) (xy 143.583657 -170.971204) (xy 143.637626 -170.979506) (xy 143.689859 -170.995417)
			(xy 143.739291 -171.018612) (xy 143.784912 -171.048616) (xy 143.825789 -171.084818) (xy 143.861089 -171.126477)
			(xy 143.890089 -171.172743) (xy 143.912197 -171.222671) (xy 143.926962 -171.27524) (xy 143.934082 -171.329377)
			(xy 143.933412 -171.383976) (xy 143.924965 -171.437922) (xy 143.908915 -171.490113) (xy 143.885588 -171.539483)
			(xy 143.855461 -171.585023) (xy 143.81915 -171.625804) (xy 143.777397 -171.660991) (xy 143.731053 -171.689867)
			(xy 143.681067 -171.711842) (xy 143.628458 -171.726466) (xy 143.60144 -171.730416) (xy 143.584925 -171.733134)
			(xy 143.554014 -171.745933) (xy 143.527488 -171.766321) (xy 143.507168 -171.7929) (xy 143.494449 -171.823844)
			(xy 143.490204 -171.857029) (xy 143.491966 -171.873672) (xy 143.49514 -171.900062) (xy 143.495009 -171.953215)
			(xy 143.491712 -171.97959) (xy 143.488982 -172.001807) (xy 143.490495 -172.046542) (xy 143.49982 -172.09032)
			(xy 143.516667 -172.131789) (xy 143.540516 -172.169666) (xy 143.57063 -172.202781) (xy 143.606078 -172.23011)
			(xy 143.645765 -172.250809) (xy 143.666972 -172.257974) (xy 143.693238 -172.26669) (xy 143.743096 -172.290706)
			(xy 143.788962 -172.321674) (xy 143.829872 -172.358943) (xy 143.864969 -172.401731) (xy 143.893516 -172.44914)
			(xy 143.914915 -172.500177) (xy 143.928716 -172.553769) (xy 143.933571 -172.598951) (xy 146.085613 -172.598951)
			(xy 146.091421 -172.54171) (xy 146.105759 -172.48599) (xy 146.1283 -172.433054) (xy 146.158533 -172.384102)
			(xy 146.195774 -172.340245) (xy 146.217132 -172.320966) (xy 146.233818 -172.305831) (xy 146.261994 -172.270683)
			(xy 146.283537 -172.231122) (xy 146.297771 -172.188383) (xy 146.304252 -172.143804) (xy 146.302777 -172.098781)
			(xy 146.293392 -172.054723) (xy 146.27639 -172.013007) (xy 146.252303 -171.974941) (xy 146.237452 -171.958)
			(xy 146.219328 -171.937441) (xy 146.188465 -171.892152) (xy 146.1644 -171.842914) (xy 146.147627 -171.790739)
			(xy 146.138492 -171.736701) (xy 146.137182 -171.681912) (xy 146.143725 -171.627499) (xy 146.157986 -171.574582)
			(xy 146.179671 -171.52425) (xy 146.208335 -171.477538) (xy 146.243387 -171.435409) (xy 146.284106 -171.398728)
			(xy 146.329655 -171.36825) (xy 146.379095 -171.344603) (xy 146.431411 -171.328273) (xy 146.485524 -171.319596)
			(xy 146.540323 -171.318751) (xy 146.594678 -171.325755) (xy 146.647472 -171.340464) (xy 146.697618 -171.362575)
			(xy 146.744085 -171.391633) (xy 146.785916 -171.427041) (xy 146.822251 -171.46807) (xy 146.83641 -171.489624)
			(xy 152.200608 -171.489624) (xy 152.204679 -171.434002) (xy 152.216805 -171.379565) (xy 152.236728 -171.327474)
			(xy 152.264024 -171.278839) (xy 152.29811 -171.234696) (xy 152.338259 -171.195987) (xy 152.383617 -171.163536)
			(xy 152.433217 -171.138035) (xy 152.486001 -171.120028) (xy 152.540844 -171.109898) (xy 152.596578 -171.107861)
			(xy 152.652015 -171.113961) (xy 152.705972 -171.128067) (xy 152.757301 -171.149879) (xy 152.804907 -171.178933)
			(xy 152.847775 -171.214608) (xy 152.884992 -171.256145) (xy 152.915765 -171.302658) (xy 152.939437 -171.353155)
			(xy 152.955505 -171.406562) (xy 152.963625 -171.461738) (xy 152.964134 -171.489624) (xy 154.723336 -171.489624)
			(xy 154.727407 -171.434002) (xy 154.739533 -171.379565) (xy 154.759456 -171.327474) (xy 154.786752 -171.278839)
			(xy 154.820838 -171.234696) (xy 154.860987 -171.195987) (xy 154.906345 -171.163536) (xy 154.955945 -171.138035)
			(xy 155.008729 -171.120028) (xy 155.063572 -171.109898) (xy 155.119306 -171.107861) (xy 155.174743 -171.113961)
			(xy 155.2287 -171.128067) (xy 155.280029 -171.149879) (xy 155.327635 -171.178933) (xy 155.370503 -171.214608)
			(xy 155.40772 -171.256145) (xy 155.438493 -171.302658) (xy 155.462165 -171.353155) (xy 155.478233 -171.406562)
			(xy 155.486353 -171.461738) (xy 155.486862 -171.489624) (xy 155.486353 -171.51751) (xy 155.478233 -171.572686)
			(xy 155.462165 -171.626093) (xy 155.438493 -171.67659) (xy 155.40772 -171.723103) (xy 155.370503 -171.76464)
			(xy 155.327635 -171.800315) (xy 155.280029 -171.829369) (xy 155.2287 -171.851181) (xy 155.213595 -171.85513)
			(xy 169.289982 -171.85513) (xy 169.294053 -171.799508) (xy 169.306179 -171.745071) (xy 169.326102 -171.69298)
			(xy 169.353398 -171.644345) (xy 169.387484 -171.600202) (xy 169.427633 -171.561493) (xy 169.472991 -171.529042)
			(xy 169.522591 -171.503541) (xy 169.575375 -171.485534) (xy 169.630218 -171.475404) (xy 169.685952 -171.473367)
			(xy 169.741389 -171.479467) (xy 169.795346 -171.493573) (xy 169.846675 -171.515385) (xy 169.894281 -171.544439)
			(xy 169.937149 -171.580114) (xy 169.974366 -171.621651) (xy 170.005139 -171.668164) (xy 170.028811 -171.718661)
			(xy 170.044879 -171.772068) (xy 170.052999 -171.827244) (xy 170.053508 -171.85513) (xy 170.052999 -171.883016)
			(xy 170.044879 -171.938192) (xy 170.028811 -171.991599) (xy 170.005139 -172.042096) (xy 169.974366 -172.088609)
			(xy 169.940747 -172.12613) (xy 180.83307 -172.12613) (xy 180.836358 -172.070508) (xy 180.8477 -172.015956)
			(xy 180.866856 -171.963633) (xy 180.893419 -171.914654) (xy 180.926823 -171.870058) (xy 180.966358 -171.830795)
			(xy 181.011184 -171.797701) (xy 181.060346 -171.771477) (xy 181.1128 -171.752684) (xy 181.167429 -171.741719)
			(xy 181.223072 -171.738816) (xy 181.278546 -171.744038) (xy 181.33267 -171.757273) (xy 181.384294 -171.778239)
			(xy 181.43232 -171.80649) (xy 181.475725 -171.841426) (xy 181.513588 -171.882305) (xy 181.545102 -171.928255)
			(xy 181.569598 -171.9783) (xy 181.586554 -172.031376) (xy 181.595611 -172.086354) (xy 181.595978 -172.107553)
			(xy 182.103211 -172.107553) (xy 182.109111 -172.052642) (xy 182.122866 -171.999156) (xy 182.14419 -171.948212)
			(xy 182.172636 -171.900875) (xy 182.20761 -171.858135) (xy 182.248382 -171.820883) (xy 182.294098 -171.7899)
			(xy 182.343804 -171.765832) (xy 182.396462 -171.749183) (xy 182.450969 -171.7403) (xy 182.506188 -171.739369)
			(xy 182.560964 -171.74641) (xy 182.614152 -171.761275) (xy 182.664641 -171.783654) (xy 182.711376 -171.813079)
			(xy 182.75338 -171.848935) (xy 182.789775 -171.890473) (xy 182.8198 -171.936824) (xy 182.842828 -171.98702)
			(xy 182.858379 -172.040012) (xy 182.866125 -172.094693) (xy 182.865907 -172.149919) (xy 182.857728 -172.204537)
			(xy 182.84176 -172.257404) (xy 182.818335 -172.307417) (xy 182.787944 -172.353529) (xy 182.751222 -172.394778)
			(xy 182.730394 -172.412914) (xy 182.713432 -172.42786) (xy 182.684495 -172.462585) (xy 182.662158 -172.501881)
			(xy 182.647125 -172.544509) (xy 182.639871 -172.589125) (xy 182.640623 -172.63432) (xy 182.64936 -172.678668)
			(xy 182.665804 -172.720772) (xy 182.689438 -172.759303) (xy 182.719515 -172.793045) (xy 182.736998 -172.807376)
			(xy 182.758431 -172.824793) (xy 182.796524 -172.864779) (xy 182.828454 -172.90984) (xy 182.853552 -172.959034)
			(xy 182.871296 -173.011333) (xy 182.881313 -173.065643) (xy 182.883395 -173.120831) (xy 182.877498 -173.175742)
			(xy 182.863745 -173.229229) (xy 182.842424 -173.280174) (xy 182.81398 -173.327512) (xy 182.779008 -173.370255)
			(xy 182.738238 -173.407508) (xy 182.692523 -173.438494) (xy 182.642818 -173.462565) (xy 182.590162 -173.479217)
			(xy 182.535655 -173.488103) (xy 182.480436 -173.489037) (xy 182.425659 -173.482) (xy 182.37247 -173.467138)
			(xy 182.321979 -173.444763) (xy 182.275242 -173.415341) (xy 182.233236 -173.379488) (xy 182.196838 -173.337953)
			(xy 182.166809 -173.291603) (xy 182.143777 -173.241409) (xy 182.128222 -173.188418) (xy 182.120471 -173.133738)
			(xy 182.120685 -173.078511) (xy 182.128859 -173.023893) (xy 182.144824 -172.971024) (xy 182.168244 -172.921009)
			(xy 182.198631 -172.874894) (xy 182.235349 -172.833642) (xy 182.256176 -172.815504) (xy 182.273215 -172.800645)
			(xy 182.302144 -172.765903) (xy 182.324473 -172.726592) (xy 182.339496 -172.683952) (xy 182.346741 -172.639327)
			(xy 182.345979 -172.594124) (xy 182.337234 -172.549768) (xy 182.320782 -172.507659) (xy 182.297141 -172.469123)
			(xy 182.267058 -172.435376) (xy 182.249572 -172.421042) (xy 182.228163 -172.403595) (xy 182.190071 -172.363607)
			(xy 182.158144 -172.318545) (xy 182.133047 -172.26935) (xy 182.115306 -172.217051) (xy 182.105291 -172.16274)
			(xy 182.103211 -172.107553) (xy 181.595978 -172.107553) (xy 181.596575 -172.142065) (xy 181.589425 -172.197323)
			(xy 181.574314 -172.250954) (xy 181.551564 -172.301816) (xy 181.521658 -172.348829) (xy 181.503828 -172.370242)
			(xy 181.488798 -172.388513) (xy 181.465042 -172.429418) (xy 181.449268 -172.474013) (xy 181.44202 -172.520758)
			(xy 181.443551 -172.568036) (xy 181.453806 -172.614215) (xy 181.472432 -172.657696) (xy 181.498784 -172.696979)
			(xy 181.531952 -172.730706) (xy 181.551072 -172.744638) (xy 181.57365 -172.760965) (xy 181.614265 -172.799108)
			(xy 181.648901 -172.842753) (xy 181.67682 -172.890971) (xy 181.697429 -172.942737) (xy 181.71029 -172.99695)
			(xy 181.71513 -173.052457) (xy 181.711845 -173.108078) (xy 181.700505 -173.162629) (xy 181.681351 -173.214952)
			(xy 181.654791 -173.263932) (xy 181.62139 -173.308528) (xy 181.581857 -173.347792) (xy 181.537035 -173.380888)
			(xy 181.487875 -173.407114) (xy 181.435424 -173.42591) (xy 181.380796 -173.436878) (xy 181.325154 -173.439785)
			(xy 181.269681 -173.434567) (xy 181.215557 -173.421337) (xy 181.163933 -173.400375) (xy 181.115906 -173.372128)
			(xy 181.072498 -173.337196) (xy 181.034633 -173.296322) (xy 181.003115 -173.250376) (xy 180.978615 -173.200334)
			(xy 180.961654 -173.14726) (xy 180.952592 -173.092284) (xy 180.951623 -173.036575) (xy 180.958766 -172.981317)
			(xy 180.973871 -172.927686) (xy 180.996615 -172.876822) (xy 181.026515 -172.829806) (xy 181.044342 -172.808392)
			(xy 181.059451 -172.790182) (xy 181.083207 -172.749265) (xy 181.098978 -172.704658) (xy 181.106219 -172.657901)
			(xy 181.10468 -172.610613) (xy 181.094414 -172.564426) (xy 181.075775 -172.520939) (xy 181.049408 -172.481653)
			(xy 181.016225 -172.447927) (xy 180.997098 -172.433996) (xy 180.974545 -172.417631) (xy 180.93393 -172.379486)
			(xy 180.899295 -172.33584) (xy 180.871376 -172.28762) (xy 180.850768 -172.235853) (xy 180.837908 -172.181638)
			(xy 180.83307 -172.12613) (xy 169.940747 -172.12613) (xy 169.937149 -172.130146) (xy 169.894281 -172.165821)
			(xy 169.846675 -172.194875) (xy 169.795346 -172.216687) (xy 169.741389 -172.230793) (xy 169.685952 -172.236893)
			(xy 169.630218 -172.234856) (xy 169.575375 -172.224726) (xy 169.522591 -172.206719) (xy 169.472991 -172.181218)
			(xy 169.427633 -172.148767) (xy 169.387484 -172.110058) (xy 169.353398 -172.065915) (xy 169.326102 -172.01728)
			(xy 169.306179 -171.965189) (xy 169.294053 -171.910752) (xy 169.289982 -171.85513) (xy 155.213595 -171.85513)
			(xy 155.174743 -171.865287) (xy 155.119306 -171.871387) (xy 155.063572 -171.86935) (xy 155.008729 -171.85922)
			(xy 154.955945 -171.841213) (xy 154.906345 -171.815712) (xy 154.860987 -171.783261) (xy 154.820838 -171.744552)
			(xy 154.786752 -171.700409) (xy 154.759456 -171.651774) (xy 154.739533 -171.599683) (xy 154.727407 -171.545246)
			(xy 154.723336 -171.489624) (xy 152.964134 -171.489624) (xy 152.963625 -171.51751) (xy 152.955505 -171.572686)
			(xy 152.939437 -171.626093) (xy 152.915765 -171.67659) (xy 152.884992 -171.723103) (xy 152.847775 -171.76464)
			(xy 152.804907 -171.800315) (xy 152.757301 -171.829369) (xy 152.705972 -171.851181) (xy 152.652015 -171.865287)
			(xy 152.596578 -171.871387) (xy 152.540844 -171.86935) (xy 152.486001 -171.85922) (xy 152.433217 -171.841213)
			(xy 152.383617 -171.815712) (xy 152.338259 -171.783261) (xy 152.29811 -171.744552) (xy 152.264024 -171.700409)
			(xy 152.236728 -171.651774) (xy 152.216805 -171.599683) (xy 152.204679 -171.545246) (xy 152.200608 -171.489624)
			(xy 146.83641 -171.489624) (xy 146.852341 -171.513875) (xy 146.875569 -171.563515) (xy 146.891455 -171.615966)
			(xy 146.899673 -171.670152) (xy 146.900053 -171.724955) (xy 146.892589 -171.779249) (xy 146.877433 -171.831917)
			(xy 146.854897 -171.881874) (xy 146.825446 -171.928093) (xy 146.789685 -171.969622) (xy 146.769328 -171.987972)
			(xy 146.752701 -172.003168) (xy 146.724528 -172.038306) (xy 146.702986 -172.077858) (xy 146.688749 -172.120586)
			(xy 146.682262 -172.165155) (xy 146.683729 -172.210169) (xy 146.693104 -172.25422) (xy 146.710093 -172.295931)
			(xy 146.734164 -172.333997) (xy 146.749008 -172.350938) (xy 146.767501 -172.371804) (xy 146.798771 -172.417964)
			(xy 146.822994 -172.468183) (xy 146.839653 -172.521391) (xy 146.848395 -172.576457) (xy 146.849034 -172.632209)
			(xy 146.841555 -172.68746) (xy 146.826119 -172.741036) (xy 146.803054 -172.791797) (xy 146.788378 -172.815504)
			(xy 146.776952 -172.83413) (xy 146.759916 -172.874364) (xy 146.750014 -172.916919) (xy 146.747538 -172.96054)
			(xy 146.75256 -173.003942) (xy 146.764932 -173.045846) (xy 146.78429 -173.085015) (xy 146.810063 -173.120295)
			(xy 146.825462 -173.135798) (xy 146.845166 -173.155443) (xy 146.879171 -173.199481) (xy 146.906421 -173.247991)
			(xy 146.926337 -173.299943) (xy 146.938499 -173.354237) (xy 146.940114 -173.375828) (xy 148.477222 -173.375828)
			(xy 148.481293 -173.320206) (xy 148.493419 -173.265769) (xy 148.513342 -173.213678) (xy 148.540638 -173.165043)
			(xy 148.574724 -173.1209) (xy 148.614873 -173.082191) (xy 148.660231 -173.04974) (xy 148.709831 -173.024239)
			(xy 148.762615 -173.006232) (xy 148.817458 -172.996102) (xy 148.873192 -172.994065) (xy 148.928629 -173.000165)
			(xy 148.982586 -173.014271) (xy 149.033915 -173.036083) (xy 149.081521 -173.065137) (xy 149.124389 -173.100812)
			(xy 149.161606 -173.142349) (xy 149.192379 -173.188862) (xy 149.192884 -173.189939) (xy 152.202789 -173.189939)
			(xy 152.207621 -173.135592) (xy 152.22015 -173.082488) (xy 152.240118 -173.031711) (xy 152.26712 -172.984299)
			(xy 152.300602 -172.941219) (xy 152.339883 -172.903351) (xy 152.384159 -172.871467) (xy 152.408128 -172.85843)
			(xy 152.428672 -172.847075) (xy 152.465578 -172.818079) (xy 152.496538 -172.782805) (xy 152.520502 -172.74245)
			(xy 152.536657 -172.698384) (xy 152.544454 -172.652102) (xy 152.543628 -172.605176) (xy 152.539446 -172.582078)
			(xy 152.534432 -172.555255) (xy 152.53122 -172.500781) (xy 152.535805 -172.446406) (xy 152.548093 -172.393239)
			(xy 152.567832 -172.342366) (xy 152.59462 -172.294826) (xy 152.62791 -172.251588) (xy 152.667022 -172.213536)
			(xy 152.711158 -172.181447) (xy 152.759417 -172.155976) (xy 152.810813 -172.137642) (xy 152.864298 -172.126821)
			(xy 152.918778 -172.123732) (xy 152.973143 -172.128439) (xy 153.026282 -172.140847) (xy 153.077111 -172.1607)
			(xy 153.124591 -172.187595) (xy 153.167753 -172.220982) (xy 153.205716 -172.26018) (xy 153.237706 -172.304388)
			(xy 153.263069 -172.352704) (xy 153.281287 -172.404141) (xy 153.291988 -172.45765) (xy 153.294954 -172.512138)
			(xy 153.290125 -172.566492) (xy 153.277598 -172.619603) (xy 153.25763 -172.670386) (xy 153.230628 -172.717806)
			(xy 153.197144 -172.760893) (xy 153.157861 -172.798768) (xy 153.113581 -172.830658) (xy 153.08961 -172.843698)
			(xy 153.069059 -172.855043) (xy 153.032151 -172.884038) (xy 153.001188 -172.919313) (xy 152.977224 -172.95967)
			(xy 152.96107 -173.003739) (xy 152.953276 -173.050023) (xy 152.954107 -173.096952) (xy 152.958292 -173.12005)
			(xy 152.963231 -173.146886) (xy 152.966437 -173.201353) (xy 152.961848 -173.255721) (xy 152.949557 -173.308881)
			(xy 152.929816 -173.359746) (xy 152.903027 -173.407278) (xy 152.869737 -173.450508) (xy 152.830626 -173.488551)
			(xy 152.786493 -173.520633) (xy 152.738238 -173.546097) (xy 152.686846 -173.564425) (xy 152.633367 -173.575241)
			(xy 152.578893 -173.578325) (xy 152.524535 -173.573614) (xy 152.471403 -173.561205) (xy 152.420582 -173.541349)
			(xy 152.37311 -173.514454) (xy 152.329955 -173.481068) (xy 152.291999 -173.441872) (xy 152.260016 -173.397667)
			(xy 152.23466 -173.349355) (xy 152.216447 -173.297923) (xy 152.205751 -173.24442) (xy 152.202789 -173.189939)
			(xy 149.192884 -173.189939) (xy 149.216051 -173.239359) (xy 149.232119 -173.292766) (xy 149.240239 -173.347942)
			(xy 149.240748 -173.375828) (xy 149.240239 -173.403714) (xy 149.232119 -173.45889) (xy 149.216051 -173.512297)
			(xy 149.192379 -173.562794) (xy 149.161606 -173.609307) (xy 149.124389 -173.650844) (xy 149.081521 -173.686519)
			(xy 149.033915 -173.715573) (xy 148.982586 -173.737385) (xy 148.928629 -173.751491) (xy 148.873192 -173.757591)
			(xy 148.817458 -173.755554) (xy 148.762615 -173.745424) (xy 148.709831 -173.727417) (xy 148.660231 -173.701916)
			(xy 148.614873 -173.669465) (xy 148.574724 -173.630756) (xy 148.540638 -173.586613) (xy 148.513342 -173.537978)
			(xy 148.493419 -173.485887) (xy 148.481293 -173.43145) (xy 148.477222 -173.375828) (xy 146.940114 -173.375828)
			(xy 146.942648 -173.409721) (xy 146.938696 -173.46522) (xy 146.926727 -173.519557) (xy 146.906995 -173.57158)
			(xy 146.879918 -173.620186) (xy 146.846069 -173.664345) (xy 146.806167 -173.703121) (xy 146.761058 -173.735691)
			(xy 146.711696 -173.761366) (xy 146.65913 -173.779602) (xy 146.604473 -173.790011) (xy 146.548884 -173.792372)
			(xy 146.493541 -173.786637) (xy 146.439617 -173.772926) (xy 146.388256 -173.75153) (xy 146.340547 -173.722903)
			(xy 146.297499 -173.687652) (xy 146.260027 -173.646523) (xy 146.228925 -173.600389) (xy 146.204851 -173.550227)
			(xy 146.188316 -173.497101) (xy 146.179671 -173.442138) (xy 146.179099 -173.386501) (xy 146.186612 -173.331371)
			(xy 146.20205 -173.277917) (xy 146.225088 -173.227271) (xy 146.239738 -173.203616) (xy 146.251141 -173.184977)
			(xy 146.268177 -173.144746) (xy 146.278081 -173.102194) (xy 146.280559 -173.058576) (xy 146.275541 -173.015176)
			(xy 146.263172 -172.973274) (xy 146.243818 -172.934106) (xy 146.21805 -172.898825) (xy 146.202654 -172.883322)
			(xy 146.182296 -172.862991) (xy 146.147365 -172.817273) (xy 146.119694 -172.766828) (xy 146.099911 -172.712801)
			(xy 146.088464 -172.656416) (xy 146.085613 -172.598951) (xy 143.933571 -172.598951) (xy 143.934629 -172.608793)
			(xy 143.932532 -172.664095) (xy 143.922467 -172.718513) (xy 143.904645 -172.770906) (xy 143.879442 -172.820175)
			(xy 143.847385 -172.865285) (xy 143.809147 -172.905292) (xy 143.765531 -172.939354) (xy 143.717452 -172.966758)
			(xy 143.691864 -172.977302) (xy 143.670517 -172.986235) (xy 143.631211 -173.010643) (xy 143.596971 -173.041764)
			(xy 143.568931 -173.078568) (xy 143.548015 -173.119839) (xy 143.534916 -173.164215) (xy 143.530065 -173.210229)
			(xy 143.531336 -173.233334) (xy 143.532179 -173.246336) (xy 143.532304 -173.272394) (xy 143.53159 -173.285404)
			(xy 143.530707 -173.3082) (xy 143.536169 -173.353488) (xy 143.549632 -173.397073) (xy 143.570661 -173.437552)
			(xy 143.598582 -173.473626) (xy 143.632495 -173.504134) (xy 143.671312 -173.528095) (xy 143.692372 -173.536864)
			(xy 143.718004 -173.547554) (xy 143.766192 -173.575156) (xy 143.809869 -173.609453) (xy 143.848112 -173.649719)
			(xy 143.880115 -173.695104) (xy 143.9052 -173.744648) (xy 143.922837 -173.797306) (xy 143.932655 -173.851964)
			(xy 143.934445 -173.907468) (xy 143.92817 -173.962645) (xy 143.913962 -174.01633) (xy 143.892122 -174.067388)
			(xy 143.863111 -174.114741) (xy 143.827542 -174.157388) (xy 143.786166 -174.194427) (xy 143.739857 -174.225078)
			(xy 143.689595 -174.248691) (xy 143.663162 -174.257208) (xy 143.641834 -174.264167) (xy 143.601858 -174.284522)
			(xy 143.566076 -174.311579) (xy 143.535599 -174.344497) (xy 143.511375 -174.382254) (xy 143.494154 -174.423678)
			(xy 143.484473 -174.46748) (xy 143.483076 -174.489872) (xy 143.480536 -174.521368) (xy 143.47824 -174.54359)
			(xy 143.480602 -174.5882) (xy 143.490733 -174.631708) (xy 143.499044 -174.651113) (xy 146.054207 -174.651113)
			(xy 146.060334 -174.597065) (xy 146.074076 -174.544436) (xy 146.095156 -174.494294) (xy 146.123145 -174.447654)
			(xy 146.157476 -174.405463) (xy 146.197452 -174.368577) (xy 146.242263 -174.337745) (xy 146.290999 -174.31359)
			(xy 146.342673 -174.296604) (xy 146.396235 -174.287131) (xy 146.4506 -174.285363) (xy 146.504664 -174.291336)
			(xy 146.557332 -174.304929) (xy 146.607535 -174.325865) (xy 146.654254 -174.353721) (xy 146.696542 -174.387932)
			(xy 146.733542 -174.427803) (xy 146.764502 -174.472525) (xy 146.788796 -174.521192) (xy 146.805929 -174.572817)
			(xy 146.815555 -174.626352) (xy 146.817478 -174.680712) (xy 146.815048 -174.707804) (xy 146.813084 -174.730904)
			(xy 146.816566 -174.777129) (xy 146.828363 -174.821881) (xy 148.726384 -174.821881) (xy 148.728297 -174.766714)
			(xy 148.738141 -174.712399) (xy 148.755711 -174.66007) (xy 148.780639 -174.61082) (xy 148.812405 -174.565677)
			(xy 148.850347 -174.525583) (xy 148.89367 -174.491377) (xy 148.941472 -174.463772) (xy 148.992753 -174.443345)
			(xy 149.046443 -174.430522) (xy 149.10142 -174.425572) (xy 149.156537 -174.428597) (xy 149.210642 -174.439534)
			(xy 149.262606 -174.458155) (xy 149.278307 -174.466504) (xy 152.20264 -174.466504) (xy 152.206711 -174.410882)
			(xy 152.218837 -174.356445) (xy 152.23876 -174.304354) (xy 152.266056 -174.255719) (xy 152.300142 -174.211576)
			(xy 152.340291 -174.172867) (xy 152.385649 -174.140416) (xy 152.435249 -174.114915) (xy 152.488033 -174.096908)
			(xy 152.542876 -174.086778) (xy 152.59861 -174.084741) (xy 152.654047 -174.090841) (xy 152.708004 -174.104947)
			(xy 152.759333 -174.126759) (xy 152.806939 -174.155813) (xy 152.849807 -174.191488) (xy 152.887024 -174.233025)
			(xy 152.917797 -174.279538) (xy 152.941469 -174.330035) (xy 152.957537 -174.383442) (xy 152.959164 -174.394498)
			(xy 154.697765 -174.394498) (xy 154.703685 -174.33853) (xy 154.717761 -174.284039) (xy 154.739689 -174.232206)
			(xy 154.768992 -174.184157) (xy 154.805034 -174.140932) (xy 154.8257 -174.121826) (xy 154.837232 -174.110975)
			(xy 154.854936 -174.08473) (xy 154.865628 -174.054933) (xy 154.86865 -174.02342) (xy 154.863815 -173.992134)
			(xy 154.851421 -173.963004) (xy 154.84221 -173.950122) (xy 154.826291 -173.928613) (xy 154.800136 -173.881928)
			(xy 154.780761 -173.832045) (xy 154.768545 -173.779945) (xy 154.76373 -173.726649) (xy 154.766408 -173.673204)
			(xy 154.776527 -173.620656) (xy 154.79389 -173.570038) (xy 154.818155 -173.522343) (xy 154.848846 -173.478506)
			(xy 154.885361 -173.439387) (xy 154.926984 -173.405754) (xy 154.972898 -173.378267) (xy 155.022202 -173.357464)
			(xy 155.04795 -173.350174) (xy 155.068463 -173.344322) (xy 155.1073 -173.326681) (xy 155.142645 -173.302802)
			(xy 155.173505 -173.273355) (xy 155.199014 -173.239168) (xy 155.218455 -173.2012) (xy 155.231281 -173.160519)
			(xy 155.237133 -173.118267) (xy 155.236926 -173.096936) (xy 155.236649 -173.06933) (xy 155.242936 -173.014485)
			(xy 155.257063 -172.961119) (xy 155.278735 -172.910347) (xy 155.307499 -172.863229) (xy 155.342754 -172.820749)
			(xy 155.383764 -172.783795) (xy 155.429672 -172.753137) (xy 155.47952 -172.729417) (xy 155.532267 -172.713129)
			(xy 155.58681 -172.704615) (xy 155.642011 -172.704051) (xy 155.696717 -172.71145) (xy 155.749785 -172.726657)
			(xy 155.800106 -172.749355) (xy 155.846631 -172.779069) (xy 155.863798 -172.793914) (xy 174.649382 -172.793914)
			(xy 174.653453 -172.738292) (xy 174.665579 -172.683855) (xy 174.685502 -172.631764) (xy 174.712798 -172.583129)
			(xy 174.746884 -172.538986) (xy 174.787033 -172.500277) (xy 174.832391 -172.467826) (xy 174.881991 -172.442325)
			(xy 174.934775 -172.424318) (xy 174.989618 -172.414188) (xy 175.045352 -172.412151) (xy 175.100789 -172.418251)
			(xy 175.154746 -172.432357) (xy 175.206075 -172.454169) (xy 175.253681 -172.483223) (xy 175.296549 -172.518898)
			(xy 175.333766 -172.560435) (xy 175.364539 -172.606948) (xy 175.388211 -172.657445) (xy 175.404279 -172.710852)
			(xy 175.412399 -172.766028) (xy 175.412908 -172.793914) (xy 175.412399 -172.8218) (xy 175.404279 -172.876976)
			(xy 175.388211 -172.930383) (xy 175.364539 -172.98088) (xy 175.333766 -173.027393) (xy 175.296549 -173.06893)
			(xy 175.253681 -173.104605) (xy 175.206075 -173.133659) (xy 175.154746 -173.155471) (xy 175.100789 -173.169577)
			(xy 175.045352 -173.175677) (xy 174.989618 -173.17364) (xy 174.934775 -173.16351) (xy 174.881991 -173.145503)
			(xy 174.832391 -173.120002) (xy 174.787033 -173.087551) (xy 174.746884 -173.048842) (xy 174.712798 -173.004699)
			(xy 174.685502 -172.956064) (xy 174.665579 -172.903973) (xy 174.653453 -172.849536) (xy 174.649382 -172.793914)
			(xy 155.863798 -172.793914) (xy 155.888387 -172.815178) (xy 155.924502 -172.85693) (xy 155.954222 -172.903451)
			(xy 155.976926 -172.95377) (xy 155.99214 -173.006836) (xy 155.999546 -173.06154) (xy 155.998989 -173.116741)
			(xy 155.990482 -173.171286) (xy 155.974201 -173.224034) (xy 155.950487 -173.273885) (xy 155.919835 -173.319798)
			(xy 155.882886 -173.360812) (xy 155.84041 -173.396073) (xy 155.793296 -173.424842) (xy 155.742527 -173.446521)
			(xy 155.71597 -173.45406) (xy 155.69548 -173.459986) (xy 155.656647 -173.477617) (xy 155.621304 -173.501486)
			(xy 155.590444 -173.530923) (xy 155.564932 -173.565099) (xy 155.545487 -173.603056) (xy 155.544172 -173.607222)
			(xy 160.717736 -173.607222) (xy 160.721807 -173.5516) (xy 160.733933 -173.497163) (xy 160.753856 -173.445072)
			(xy 160.781152 -173.396437) (xy 160.815238 -173.352294) (xy 160.855387 -173.313585) (xy 160.900745 -173.281134)
			(xy 160.950345 -173.255633) (xy 161.003129 -173.237626) (xy 161.057972 -173.227496) (xy 161.113706 -173.225459)
			(xy 161.169143 -173.231559) (xy 161.2231 -173.245665) (xy 161.274429 -173.267477) (xy 161.322035 -173.296531)
			(xy 161.364903 -173.332206) (xy 161.40212 -173.373743) (xy 161.432893 -173.420256) (xy 161.456565 -173.470753)
			(xy 161.472633 -173.52416) (xy 161.480753 -173.579336) (xy 161.481262 -173.607222) (xy 161.480753 -173.635108)
			(xy 161.472633 -173.690284) (xy 161.456565 -173.743691) (xy 161.432893 -173.794188) (xy 161.40212 -173.840701)
			(xy 161.364903 -173.882238) (xy 161.322035 -173.917913) (xy 161.274429 -173.946967) (xy 161.2231 -173.968779)
			(xy 161.169143 -173.982885) (xy 161.113706 -173.988985) (xy 161.057972 -173.986948) (xy 161.003129 -173.976818)
			(xy 160.950345 -173.958811) (xy 160.900745 -173.93331) (xy 160.855387 -173.900859) (xy 160.815238 -173.86215)
			(xy 160.781152 -173.818007) (xy 160.753856 -173.769372) (xy 160.733933 -173.717281) (xy 160.721807 -173.662844)
			(xy 160.717736 -173.607222) (xy 155.544172 -173.607222) (xy 155.532653 -173.643727) (xy 155.526792 -173.68597)
			(xy 155.526994 -173.707298) (xy 155.527348 -173.735066) (xy 155.52099 -173.790233) (xy 155.506707 -173.843897)
			(xy 155.4848 -173.894925) (xy 155.455732 -173.942241) (xy 155.420114 -173.984846) (xy 155.39974 -174.003716)
			(xy 155.388262 -174.014621) (xy 155.37055 -174.040849) (xy 155.359848 -174.070633) (xy 155.356816 -174.102136)
			(xy 155.36164 -174.133415) (xy 155.374024 -174.16254) (xy 155.38323 -174.17542) (xy 155.403478 -174.203244)
			(xy 155.434653 -174.264586) (xy 155.445206 -174.29734) (xy 155.451983 -174.318553) (xy 155.471973 -174.358344)
			(xy 155.498597 -174.39404) (xy 155.531037 -174.424545) (xy 155.5683 -174.448926) (xy 155.609244 -174.466434)
			(xy 155.652613 -174.476534) (xy 155.674822 -174.478188) (xy 155.701926 -174.480123) (xy 155.755222 -174.490714)
			(xy 155.806476 -174.508758) (xy 155.854653 -174.533891) (xy 155.898776 -174.565604) (xy 155.937954 -174.603256)
			(xy 155.971395 -174.646085) (xy 155.998421 -174.693225) (xy 156.018487 -174.743722) (xy 156.031186 -174.796555)
			(xy 156.036261 -174.850655) (xy 156.03361 -174.904929) (xy 156.023287 -174.958277) (xy 156.005499 -175.009621)
			(xy 156.002653 -175.015144) (xy 156.395672 -175.015144) (xy 156.399743 -174.959522) (xy 156.411869 -174.905085)
			(xy 156.431792 -174.852994) (xy 156.459088 -174.804359) (xy 156.493174 -174.760216) (xy 156.533323 -174.721507)
			(xy 156.578681 -174.689056) (xy 156.628281 -174.663555) (xy 156.681065 -174.645548) (xy 156.735908 -174.635418)
			(xy 156.791642 -174.633381) (xy 156.847079 -174.639481) (xy 156.901036 -174.653587) (xy 156.952365 -174.675399)
			(xy 156.999971 -174.704453) (xy 157.036654 -174.734981) (xy 162.163435 -174.734981) (xy 162.163993 -174.680424)
			(xy 162.172318 -174.626502) (xy 162.188241 -174.574317) (xy 162.211436 -174.524932) (xy 162.24143 -174.479356)
			(xy 162.277611 -174.438518) (xy 162.298126 -174.42053) (xy 162.316035 -174.40461) (xy 162.346158 -174.367355)
			(xy 162.368764 -174.325114) (xy 162.383051 -174.279385) (xy 162.388514 -174.231787) (xy 162.384959 -174.18401)
			(xy 162.372511 -174.137746) (xy 162.351612 -174.094635) (xy 162.33775 -174.07509) (xy 162.3217 -174.052721)
			(xy 162.295484 -174.004309) (xy 162.2765 -173.952631) (xy 162.265142 -173.898762) (xy 162.261646 -173.843818)
			(xy 162.266085 -173.788943) (xy 162.278367 -173.735277) (xy 162.298236 -173.683933) (xy 162.32528 -173.635979)
			(xy 162.358937 -173.592411) (xy 162.398508 -173.554133) (xy 162.44317 -173.521942) (xy 162.491996 -173.496506)
			(xy 162.543972 -173.478354) (xy 162.598017 -173.467862) (xy 162.653009 -173.465248) (xy 162.707806 -173.470567)
			(xy 162.761269 -173.483708) (xy 162.812287 -173.504399) (xy 162.859801 -173.532208) (xy 162.885037 -173.552358)
			(xy 166.306498 -173.552358) (xy 166.310569 -173.496736) (xy 166.322695 -173.442299) (xy 166.342618 -173.390208)
			(xy 166.369914 -173.341573) (xy 166.404 -173.29743) (xy 166.444149 -173.258721) (xy 166.489507 -173.22627)
			(xy 166.539107 -173.200769) (xy 166.591891 -173.182762) (xy 166.646734 -173.172632) (xy 166.702468 -173.170595)
			(xy 166.757905 -173.176695) (xy 166.811862 -173.190801) (xy 166.863191 -173.212613) (xy 166.910797 -173.241667)
			(xy 166.953665 -173.277342) (xy 166.990882 -173.318879) (xy 167.021655 -173.365392) (xy 167.045327 -173.415889)
			(xy 167.061395 -173.469296) (xy 167.069515 -173.524472) (xy 167.070024 -173.552358) (xy 167.069515 -173.580244)
			(xy 167.061395 -173.63542) (xy 167.045327 -173.688827) (xy 167.021655 -173.739324) (xy 166.990882 -173.785837)
			(xy 166.953665 -173.827374) (xy 166.910797 -173.863049) (xy 166.863191 -173.892103) (xy 166.811862 -173.913915)
			(xy 166.757905 -173.928021) (xy 166.702468 -173.934121) (xy 166.646734 -173.932084) (xy 166.591891 -173.921954)
			(xy 166.539107 -173.903947) (xy 166.489507 -173.878446) (xy 166.444149 -173.845995) (xy 166.404 -173.807286)
			(xy 166.369914 -173.763143) (xy 166.342618 -173.714508) (xy 166.322695 -173.662417) (xy 166.310569 -173.60798)
			(xy 166.306498 -173.552358) (xy 162.885037 -173.552358) (xy 162.902824 -173.56656) (xy 162.940461 -173.60674)
			(xy 162.971931 -173.651912) (xy 162.984688 -173.67631) (xy 162.995607 -173.696834) (xy 163.02363 -173.733919)
			(xy 163.057931 -173.765288) (xy 163.097365 -173.789895) (xy 163.140618 -173.806918) (xy 163.186245 -173.81579)
			(xy 163.232725 -173.816215) (xy 163.255706 -173.812708) (xy 163.282502 -173.80852) (xy 163.336705 -173.806756)
			(xy 163.390611 -173.812686) (xy 163.443134 -173.826191) (xy 163.493215 -173.847) (xy 163.539843 -173.874692)
			(xy 163.58208 -173.908709) (xy 163.619072 -173.948365) (xy 163.650075 -173.992861) (xy 163.674463 -174.041299)
			(xy 163.691744 -174.092704) (xy 163.701571 -174.146038) (xy 163.703744 -174.200226) (xy 163.698221 -174.254175)
			(xy 163.685112 -174.306799) (xy 163.664682 -174.357035) (xy 163.637342 -174.403871) (xy 163.603645 -174.446363)
			(xy 163.564269 -174.483653) (xy 163.520008 -174.514991) (xy 163.471755 -174.539743) (xy 163.420482 -174.557412)
			(xy 163.367224 -174.567641) (xy 163.313054 -174.570223) (xy 163.259064 -174.565106) (xy 163.232592 -174.559214)
			(xy 163.209713 -174.554171) (xy 163.16293 -174.551727) (xy 163.116492 -174.557899) (xy 163.071972 -174.57248)
			(xy 163.030879 -174.594975) (xy 162.994606 -174.624621) (xy 162.964382 -174.660415) (xy 162.941231 -174.701142)
			(xy 162.925939 -174.745422) (xy 162.922301 -174.766478) (xy 168.030142 -174.766478) (xy 168.034213 -174.710856)
			(xy 168.046339 -174.656419) (xy 168.066262 -174.604328) (xy 168.093558 -174.555693) (xy 168.127644 -174.51155)
			(xy 168.167793 -174.472841) (xy 168.213151 -174.44039) (xy 168.262751 -174.414889) (xy 168.315535 -174.396882)
			(xy 168.370378 -174.386752) (xy 168.426112 -174.384715) (xy 168.481549 -174.390815) (xy 168.535506 -174.404921)
			(xy 168.586835 -174.426733) (xy 168.634441 -174.455787) (xy 168.677309 -174.491462) (xy 168.714526 -174.532999)
			(xy 168.745299 -174.579512) (xy 168.768971 -174.630009) (xy 168.785039 -174.683416) (xy 168.793159 -174.738592)
			(xy 168.793668 -174.766478) (xy 168.793159 -174.794364) (xy 168.785039 -174.84954) (xy 168.768971 -174.902947)
			(xy 168.745299 -174.953444) (xy 168.714526 -174.999957) (xy 168.677309 -175.041494) (xy 168.634441 -175.077169)
			(xy 168.586835 -175.106223) (xy 168.535506 -175.128035) (xy 168.481549 -175.142141) (xy 168.426112 -175.148241)
			(xy 168.370378 -175.146204) (xy 168.315535 -175.136074) (xy 168.262751 -175.118067) (xy 168.213151 -175.092566)
			(xy 168.167793 -175.060115) (xy 168.127644 -175.021406) (xy 168.093558 -174.977263) (xy 168.066262 -174.928628)
			(xy 168.046339 -174.876537) (xy 168.034213 -174.8221) (xy 168.030142 -174.766478) (xy 162.922301 -174.766478)
			(xy 162.92195 -174.76851) (xy 162.917374 -174.795409) (xy 162.901632 -174.847649) (xy 162.878608 -174.897113)
			(xy 162.848772 -174.942793) (xy 162.812732 -174.983756) (xy 162.771224 -175.019166) (xy 162.725094 -175.048302)
			(xy 162.675283 -175.070568) (xy 162.622809 -175.08551) (xy 162.568741 -175.092824) (xy 162.514183 -175.09236)
			(xy 162.460247 -175.084129) (xy 162.408034 -175.068296) (xy 162.358609 -175.045187) (xy 162.312981 -175.015271)
			(xy 162.272081 -174.979161) (xy 162.236742 -174.937591) (xy 162.207687 -174.891411) (xy 162.185507 -174.841562)
			(xy 162.170655 -174.789062) (xy 162.163435 -174.734981) (xy 157.036654 -174.734981) (xy 157.042839 -174.740128)
			(xy 157.080056 -174.781665) (xy 157.110829 -174.828178) (xy 157.134501 -174.878675) (xy 157.150569 -174.932082)
			(xy 157.158689 -174.987258) (xy 157.159198 -175.015144) (xy 157.158689 -175.04303) (xy 157.150569 -175.098206)
			(xy 157.134501 -175.151613) (xy 157.110829 -175.20211) (xy 157.080056 -175.248623) (xy 157.042839 -175.29016)
			(xy 156.999971 -175.325835) (xy 156.988814 -175.332644) (xy 166.582342 -175.332644) (xy 166.586413 -175.277022)
			(xy 166.598539 -175.222585) (xy 166.618462 -175.170494) (xy 166.645758 -175.121859) (xy 166.679844 -175.077716)
			(xy 166.719993 -175.039007) (xy 166.765351 -175.006556) (xy 166.814951 -174.981055) (xy 166.867735 -174.963048)
			(xy 166.922578 -174.952918) (xy 166.978312 -174.950881) (xy 167.033749 -174.956981) (xy 167.087706 -174.971087)
			(xy 167.139035 -174.992899) (xy 167.186641 -175.021953) (xy 167.229509 -175.057628) (xy 167.266726 -175.099165)
			(xy 167.297499 -175.145678) (xy 167.321171 -175.196175) (xy 167.337239 -175.249582) (xy 167.345359 -175.304758)
			(xy 167.345868 -175.332644) (xy 167.345359 -175.36053) (xy 167.337239 -175.415706) (xy 167.321171 -175.469113)
			(xy 167.297499 -175.51961) (xy 167.266726 -175.566123) (xy 167.229509 -175.60766) (xy 167.186641 -175.643335)
			(xy 167.139035 -175.672389) (xy 167.087706 -175.694201) (xy 167.033749 -175.708307) (xy 166.978312 -175.714407)
			(xy 166.922578 -175.71237) (xy 166.867735 -175.70224) (xy 166.814951 -175.684233) (xy 166.765351 -175.658732)
			(xy 166.719993 -175.626281) (xy 166.679844 -175.587572) (xy 166.645758 -175.543429) (xy 166.618462 -175.494794)
			(xy 166.598539 -175.442703) (xy 166.586413 -175.388266) (xy 166.582342 -175.332644) (xy 156.988814 -175.332644)
			(xy 156.952365 -175.354889) (xy 156.901036 -175.376701) (xy 156.847079 -175.390807) (xy 156.791642 -175.396907)
			(xy 156.735908 -175.39487) (xy 156.681065 -175.38474) (xy 156.628281 -175.366733) (xy 156.578681 -175.341232)
			(xy 156.533323 -175.308781) (xy 156.493174 -175.270072) (xy 156.459088 -175.225929) (xy 156.431792 -175.177294)
			(xy 156.411869 -175.125203) (xy 156.399743 -175.070766) (xy 156.395672 -175.015144) (xy 156.002653 -175.015144)
			(xy 155.980608 -175.057922) (xy 155.949116 -175.102204) (xy 155.91166 -175.14157) (xy 155.868999 -175.175225)
			(xy 155.821995 -175.202487) (xy 155.771599 -175.222805) (xy 155.71883 -175.235768) (xy 155.69184 -175.238918)
			(xy 155.669867 -175.241609) (xy 155.627263 -175.253624) (xy 155.587385 -175.272838) (xy 155.551438 -175.298668)
			(xy 155.520508 -175.330336) (xy 155.495532 -175.366882) (xy 155.477265 -175.407202) (xy 155.466258 -175.450077)
			(xy 155.462845 -175.494211) (xy 155.46451 -175.516286) (xy 155.466736 -175.544138) (xy 155.464018 -175.599945)
			(xy 155.453194 -175.654759) (xy 155.434496 -175.70741) (xy 155.408321 -175.756773) (xy 155.37523 -175.801793)
			(xy 155.33593 -175.841508) (xy 155.313888 -175.858678) (xy 155.295363 -175.873204) (xy 155.263597 -175.90794)
			(xy 155.238771 -175.947932) (xy 155.221734 -175.991812) (xy 155.213068 -176.038079) (xy 155.213071 -176.08515)
			(xy 155.221742 -176.131416) (xy 155.238784 -176.175294) (xy 155.263615 -176.215283) (xy 155.293785 -176.248267)
			(xy 157.220109 -176.248267) (xy 157.221856 -176.1922) (xy 157.231794 -176.136994) (xy 157.249709 -176.083838)
			(xy 157.275215 -176.033878) (xy 157.307762 -175.988192) (xy 157.346648 -175.947764) (xy 157.391035 -175.913466)
			(xy 157.439965 -175.886038) (xy 157.492385 -175.86607) (xy 157.547163 -175.853994) (xy 157.60312 -175.850069)
			(xy 157.659047 -175.85438) (xy 157.713741 -175.866835) (xy 157.766022 -175.887164) (xy 157.814762 -175.91493)
			(xy 157.85891 -175.949534) (xy 157.897516 -175.990229) (xy 157.929746 -176.036139) (xy 157.954906 -176.086274)
			(xy 157.972454 -176.139552) (xy 157.982011 -176.194826) (xy 157.98337 -176.250903) (xy 157.976504 -176.306575)
			(xy 157.961559 -176.360642) (xy 157.950662 -176.38649) (xy 157.942036 -176.40722) (xy 157.931401 -176.450837)
			(xy 157.928593 -176.495644) (xy 157.9337 -176.540248) (xy 157.946562 -176.583262) (xy 157.96678 -176.623347)
			(xy 157.974116 -176.633124) (xy 169.643042 -176.633124) (xy 169.647113 -176.577502) (xy 169.659239 -176.523065)
			(xy 169.679162 -176.470974) (xy 169.706458 -176.422339) (xy 169.740544 -176.378196) (xy 169.780693 -176.339487)
			(xy 169.826051 -176.307036) (xy 169.875651 -176.281535) (xy 169.928435 -176.263528) (xy 169.983278 -176.253398)
			(xy 170.039012 -176.251361) (xy 170.094449 -176.257461) (xy 170.148406 -176.271567) (xy 170.199735 -176.293379)
			(xy 170.247341 -176.322433) (xy 170.290209 -176.358108) (xy 170.327426 -176.399645) (xy 170.358199 -176.446158)
			(xy 170.381871 -176.496655) (xy 170.397939 -176.550062) (xy 170.406059 -176.605238) (xy 170.406568 -176.633124)
			(xy 170.406059 -176.66101) (xy 170.397939 -176.716186) (xy 170.381871 -176.769593) (xy 170.358199 -176.82009)
			(xy 170.327426 -176.866603) (xy 170.290209 -176.90814) (xy 170.247341 -176.943815) (xy 170.199735 -176.972869)
			(xy 170.148406 -176.994681) (xy 170.094449 -177.008787) (xy 170.039012 -177.014887) (xy 169.983278 -177.01285)
			(xy 169.928435 -177.00272) (xy 169.875651 -176.984713) (xy 169.826051 -176.959212) (xy 169.780693 -176.926761)
			(xy 169.740544 -176.888052) (xy 169.706458 -176.843909) (xy 169.679162 -176.795274) (xy 169.659239 -176.743183)
			(xy 169.647113 -176.688746) (xy 169.643042 -176.633124) (xy 157.974116 -176.633124) (xy 157.993725 -176.659258)
			(xy 158.026559 -176.689877) (xy 158.04515 -176.702466) (xy 158.068414 -176.718126) (xy 158.110558 -176.75512)
			(xy 158.146832 -176.797885) (xy 158.176453 -176.845501) (xy 158.198782 -176.896941) (xy 158.213339 -176.951096)
			(xy 158.21981 -177.006799) (xy 158.218054 -177.062848) (xy 158.208111 -177.118037) (xy 158.190194 -177.171175)
			(xy 158.164689 -177.221117) (xy 158.132147 -177.266786) (xy 158.093269 -177.307198) (xy 158.048892 -177.341481)
			(xy 157.999974 -177.368898) (xy 157.947568 -177.388856) (xy 157.892805 -177.400926) (xy 157.836865 -177.404847)
			(xy 157.780954 -177.400535) (xy 157.726277 -177.388083) (xy 157.674012 -177.367759) (xy 157.625286 -177.340001)
			(xy 157.58115 -177.305408) (xy 157.542555 -177.264725) (xy 157.510333 -177.21883) (xy 157.485178 -177.168711)
			(xy 157.467633 -177.115449) (xy 157.458076 -177.060192) (xy 157.456712 -177.004132) (xy 157.463572 -176.948476)
			(xy 157.478507 -176.894424) (xy 157.489398 -176.868582) (xy 157.49807 -176.84787) (xy 157.508703 -176.804247)
			(xy 157.511508 -176.759434) (xy 157.506396 -176.714825) (xy 157.493528 -176.671808) (xy 157.473302 -176.631721)
			(xy 157.446349 -176.59581) (xy 157.413506 -176.565193) (xy 157.39491 -176.552606) (xy 157.371605 -176.536993)
			(xy 157.32944 -176.499999) (xy 157.293147 -176.457228) (xy 157.263508 -176.409604) (xy 157.241162 -176.358153)
			(xy 157.226591 -176.303985) (xy 157.220109 -176.248267) (xy 155.293785 -176.248267) (xy 155.295385 -176.250016)
			(xy 155.313888 -176.26457) (xy 155.336009 -176.281803) (xy 155.375434 -176.321678) (xy 155.408598 -176.366895)
			(xy 155.434785 -176.416479) (xy 155.453432 -176.469362) (xy 155.464138 -176.524405) (xy 155.46667 -176.580422)
			(xy 155.460976 -176.636207) (xy 155.447178 -176.690557) (xy 155.425572 -176.742302) (xy 155.396625 -176.790327)
			(xy 155.360959 -176.833598) (xy 155.319344 -176.871181) (xy 155.272675 -176.902268) (xy 155.221959 -176.926189)
			(xy 155.168288 -176.942429) (xy 155.112817 -176.950637) (xy 155.056743 -176.950637) (xy 155.001272 -176.942429)
			(xy 154.947601 -176.926189) (xy 154.896885 -176.902268) (xy 154.850216 -176.871181) (xy 154.808601 -176.833598)
			(xy 154.772935 -176.790327) (xy 154.743988 -176.742302) (xy 154.722382 -176.690557) (xy 154.708584 -176.636207)
			(xy 154.70289 -176.580422) (xy 154.705422 -176.524405) (xy 154.716128 -176.469362) (xy 154.734775 -176.416479)
			(xy 154.760962 -176.366895) (xy 154.794126 -176.321678) (xy 154.833551 -176.281803) (xy 154.855672 -176.26457)
			(xy 154.874146 -176.249985) (xy 154.905904 -176.215255) (xy 154.930725 -176.175271) (xy 154.94776 -176.131401)
			(xy 154.956427 -176.085145) (xy 154.95643 -176.038084) (xy 154.947768 -175.991826) (xy 154.930738 -175.947955)
			(xy 154.905921 -175.907968) (xy 154.874167 -175.873234) (xy 154.855672 -175.858678) (xy 154.834307 -175.842046)
			(xy 154.796045 -175.803737) (xy 154.763583 -175.760404) (xy 154.737574 -175.712917) (xy 154.718538 -175.66223)
			(xy 154.70686 -175.609361) (xy 154.702773 -175.555372) (xy 154.706359 -175.501347) (xy 154.717546 -175.448372)
			(xy 154.736111 -175.397511) (xy 154.761679 -175.349785) (xy 154.793737 -175.306152) (xy 154.831642 -175.26749)
			(xy 154.874631 -175.234575) (xy 154.921842 -175.208067) (xy 154.972327 -175.1885) (xy 155.02507 -175.176267)
			(xy 155.079013 -175.171612) (xy 155.133072 -175.174631) (xy 155.15971 -175.179482) (xy 155.174797 -175.182058)
			(xy 155.205367 -175.180781) (xy 155.234752 -175.172254) (xy 155.261258 -175.15697) (xy 155.283358 -175.135809)
			(xy 155.299777 -175.109991) (xy 155.30957 -175.081003) (xy 155.312172 -175.050517) (xy 155.307434 -175.020289)
			(xy 155.30195 -175.006) (xy 155.298161 -174.996759) (xy 155.291426 -174.977954) (xy 155.288488 -174.968408)
			(xy 155.281687 -174.947203) (xy 155.261703 -174.90741) (xy 155.235086 -174.871713) (xy 155.202649 -174.841206)
			(xy 155.165389 -174.816823) (xy 155.124448 -174.799314) (xy 155.08108 -174.789213) (xy 155.058872 -174.78756)
			(xy 155.030798 -174.785585) (xy 154.975663 -174.774291) (xy 154.922784 -174.755022) (xy 154.873309 -174.728195)
			(xy 154.828311 -174.694393) (xy 154.788767 -174.654347) (xy 154.755533 -174.608927) (xy 154.72933 -174.559119)
			(xy 154.710728 -174.506002) (xy 154.70013 -174.450729) (xy 154.697765 -174.394498) (xy 152.959164 -174.394498)
			(xy 152.965657 -174.438618) (xy 152.966166 -174.466504) (xy 152.965657 -174.49439) (xy 152.957537 -174.549566)
			(xy 152.941469 -174.602973) (xy 152.917797 -174.65347) (xy 152.887024 -174.699983) (xy 152.849807 -174.74152)
			(xy 152.806939 -174.777195) (xy 152.759333 -174.806249) (xy 152.708004 -174.828061) (xy 152.654047 -174.842167)
			(xy 152.59861 -174.848267) (xy 152.542876 -174.84623) (xy 152.488033 -174.8361) (xy 152.435249 -174.818093)
			(xy 152.385649 -174.792592) (xy 152.340291 -174.760141) (xy 152.300142 -174.721432) (xy 152.266056 -174.677289)
			(xy 152.23876 -174.628654) (xy 152.218837 -174.576563) (xy 152.206711 -174.522126) (xy 152.20264 -174.466504)
			(xy 149.278307 -174.466504) (xy 149.311344 -174.484072) (xy 149.355837 -174.516742) (xy 149.395157 -174.555484)
			(xy 149.428483 -174.599489) (xy 149.455118 -174.647837) (xy 149.474507 -174.69952) (xy 149.486244 -174.753457)
			(xy 149.488652 -174.780956) (xy 149.490821 -174.804488) (xy 149.502806 -174.850197) (xy 149.523026 -174.892906)
			(xy 149.550786 -174.931146) (xy 149.585129 -174.963603) (xy 149.624876 -174.989159) (xy 149.668659 -175.006935)
			(xy 149.714971 -175.01632) (xy 149.738588 -175.017176) (xy 149.766172 -175.01812) (xy 149.820664 -175.026873)
			(xy 149.873324 -175.043389) (xy 149.923055 -175.067322) (xy 149.968817 -175.098174) (xy 150.009655 -175.135298)
			(xy 150.044715 -175.177921) (xy 150.073267 -175.225152) (xy 150.094713 -175.276004) (xy 150.108605 -175.329417)
			(xy 150.114655 -175.384275) (xy 150.112735 -175.439431) (xy 150.102885 -175.493735) (xy 150.085312 -175.546053)
			(xy 150.060381 -175.595291) (xy 150.028614 -175.640422) (xy 149.990675 -175.680503) (xy 149.947354 -175.714698)
			(xy 149.900784 -175.741584) (xy 152.193242 -175.741584) (xy 152.197313 -175.685962) (xy 152.209439 -175.631525)
			(xy 152.229362 -175.579434) (xy 152.256658 -175.530799) (xy 152.290744 -175.486656) (xy 152.330893 -175.447947)
			(xy 152.376251 -175.415496) (xy 152.425851 -175.389995) (xy 152.478635 -175.371988) (xy 152.533478 -175.361858)
			(xy 152.589212 -175.359821) (xy 152.644649 -175.365921) (xy 152.698606 -175.380027) (xy 152.749935 -175.401839)
			(xy 152.797541 -175.430893) (xy 152.840409 -175.466568) (xy 152.877626 -175.508105) (xy 152.908399 -175.554618)
			(xy 152.932071 -175.605115) (xy 152.948139 -175.658522) (xy 152.956259 -175.713698) (xy 152.956768 -175.741584)
			(xy 152.956259 -175.76947) (xy 152.948139 -175.824646) (xy 152.932071 -175.878053) (xy 152.908399 -175.92855)
			(xy 152.877626 -175.975063) (xy 152.840409 -176.0166) (xy 152.797541 -176.052275) (xy 152.749935 -176.081329)
			(xy 152.698606 -176.103141) (xy 152.644649 -176.117247) (xy 152.589212 -176.123347) (xy 152.533478 -176.12131)
			(xy 152.478635 -176.11118) (xy 152.425851 -176.093173) (xy 152.376251 -176.067672) (xy 152.330893 -176.035221)
			(xy 152.290744 -175.996512) (xy 152.256658 -175.952369) (xy 152.229362 -175.903734) (xy 152.209439 -175.851643)
			(xy 152.197313 -175.797206) (xy 152.193242 -175.741584) (xy 149.900784 -175.741584) (xy 149.899558 -175.742292)
			(xy 149.848283 -175.762709) (xy 149.794601 -175.775523) (xy 149.739633 -175.780466) (xy 149.684526 -175.777435)
			(xy 149.630432 -175.766493) (xy 149.578479 -175.747869) (xy 149.529753 -175.721952) (xy 149.485271 -175.689282)
			(xy 149.445962 -175.650543) (xy 149.412647 -175.606542) (xy 149.386022 -175.558199) (xy 149.366642 -175.506524)
			(xy 149.354912 -175.452594) (xy 149.352508 -175.4251) (xy 149.350318 -175.401571) (xy 149.338329 -175.355868)
			(xy 149.318108 -175.313164) (xy 149.290351 -175.274927) (xy 149.256011 -175.242472) (xy 149.21627 -175.216915)
			(xy 149.172493 -175.199134) (xy 149.126187 -175.189741) (xy 149.102572 -175.18888) (xy 149.074981 -175.188048)
			(xy 149.020479 -175.179301) (xy 148.967806 -175.162791) (xy 148.918063 -175.138861) (xy 148.872289 -175.108011)
			(xy 148.831438 -175.070886) (xy 148.796366 -175.028261) (xy 148.767802 -174.981026) (xy 148.746345 -174.930167)
			(xy 148.732442 -174.876747) (xy 148.726384 -174.821881) (xy 146.828363 -174.821881) (xy 146.828382 -174.821952)
			(xy 146.84814 -174.863886) (xy 146.875184 -174.901535) (xy 146.908613 -174.933648) (xy 146.947318 -174.959158)
			(xy 146.968464 -174.968662) (xy 146.993345 -174.979668) (xy 147.039919 -175.007788) (xy 147.082027 -175.04224)
			(xy 147.118812 -175.082324) (xy 147.14953 -175.127228) (xy 147.173557 -175.17604) (xy 147.190406 -175.227771)
			(xy 147.199734 -175.28137) (xy 147.201353 -175.335752) (xy 147.19523 -175.389811) (xy 147.181489 -175.442453)
			(xy 147.160409 -175.492608) (xy 147.132417 -175.53926) (xy 147.098081 -175.581462) (xy 147.058098 -175.618358)
			(xy 147.013279 -175.649199) (xy 146.964533 -175.67336) (xy 146.912848 -175.690351) (xy 146.859275 -175.699827)
			(xy 146.804898 -175.701595) (xy 146.750822 -175.695621) (xy 146.698143 -175.682025) (xy 146.64793 -175.661082)
			(xy 146.601201 -175.633219) (xy 146.558905 -175.598999) (xy 146.521899 -175.559118) (xy 146.490935 -175.514384)
			(xy 146.46664 -175.465704) (xy 146.449507 -175.414067) (xy 146.439883 -175.36052) (xy 146.437965 -175.306148)
			(xy 146.440398 -175.27905) (xy 146.442438 -175.255954) (xy 146.438948 -175.209723) (xy 146.427121 -175.164893)
			(xy 146.407351 -175.122957) (xy 146.380294 -175.085307) (xy 146.346851 -175.053196) (xy 146.308134 -175.027692)
			(xy 146.286982 -175.018192) (xy 146.262123 -175.00715) (xy 146.215563 -174.979028) (xy 146.173471 -174.944577)
			(xy 146.136699 -174.904496) (xy 146.105994 -174.859598) (xy 146.081979 -174.810793) (xy 146.06514 -174.759071)
			(xy 146.05582 -174.705482) (xy 146.054207 -174.651113) (xy 143.499044 -174.651113) (xy 143.508321 -174.672772)
			(xy 143.532823 -174.710125) (xy 143.563482 -174.742615) (xy 143.599354 -174.769238) (xy 143.639331 -174.789175)
			(xy 143.660622 -174.795942) (xy 143.687326 -174.804284) (xy 143.738096 -174.827787) (xy 143.784891 -174.858451)
			(xy 143.826707 -174.895619) (xy 143.862648 -174.938493) (xy 143.891944 -174.986156) (xy 143.913967 -175.037585)
			(xy 143.928245 -175.091679) (xy 143.934472 -175.147278) (xy 143.932515 -175.20319) (xy 143.922415 -175.258217)
			(xy 143.904389 -175.31118) (xy 143.878824 -175.360943) (xy 143.846266 -175.406441) (xy 143.807415 -175.446697)
			(xy 143.763103 -175.48085) (xy 143.714278 -175.508166) (xy 143.688308 -175.518572) (xy 143.668563 -175.526542)
			(xy 143.631851 -175.548104) (xy 143.599245 -175.575482) (xy 143.571657 -175.60791) (xy 143.549858 -175.644483)
			(xy 143.534458 -175.684176) (xy 143.525888 -175.725881) (xy 143.524387 -175.768431) (xy 143.526764 -175.78959)
			(xy 143.53018 -175.819526) (xy 143.528652 -175.879755) (xy 143.523716 -175.909478) (xy 143.521204 -175.925864)
			(xy 143.523791 -175.958902) (xy 143.534794 -175.990161) (xy 143.553473 -176.017536) (xy 143.578567 -176.03918)
			(xy 143.608387 -176.053637) (xy 143.624554 -176.057306) (xy 143.652032 -176.063055) (xy 143.70502 -176.081591)
			(xy 143.75472 -176.107692) (xy 143.800059 -176.140794) (xy 143.840059 -176.180182) (xy 143.873855 -176.225005)
			(xy 143.900719 -176.274297) (xy 143.920071 -176.326994) (xy 143.931492 -176.381956) (xy 143.934736 -176.438)
			(xy 143.929733 -176.493913) (xy 143.916592 -176.54849) (xy 143.895596 -176.600553) (xy 143.867197 -176.648977)
			(xy 143.83201 -176.692717) (xy 143.790793 -176.73083) (xy 143.744437 -176.762491) (xy 143.693941 -176.787019)
			(xy 143.640397 -176.803883) (xy 143.58496 -176.812719) (xy 143.528826 -176.813337) (xy 143.473208 -176.805723)
			(xy 143.419306 -176.790041) (xy 143.368283 -176.766631) (xy 143.321241 -176.735997) (xy 143.279196 -176.698801)
			(xy 143.243054 -176.655846) (xy 143.213597 -176.608059) (xy 143.19146 -176.556471) (xy 143.17712 -176.502196)
			(xy 143.170889 -176.446406) (xy 143.172899 -176.390305) (xy 143.177514 -176.362614) (xy 143.18001 -176.346227)
			(xy 143.177422 -176.313192) (xy 143.166419 -176.281936) (xy 143.147745 -176.254563) (xy 143.122655 -176.232918)
			(xy 143.092841 -176.218458) (xy 143.076676 -176.214786) (xy 143.049814 -176.209127) (xy 142.99794 -176.191172)
			(xy 142.949176 -176.165968) (xy 142.904527 -176.134034) (xy 142.864916 -176.09603) (xy 142.831162 -176.052742)
			(xy 142.80396 -176.005062) (xy 142.783874 -175.953976) (xy 142.771317 -175.900538) (xy 142.766548 -175.845852)
			(xy 142.769668 -175.791048) (xy 142.78061 -175.737256) (xy 142.799149 -175.685588) (xy 142.824902 -175.637111)
			(xy 142.857338 -175.592825) (xy 142.895786 -175.553646) (xy 142.939453 -175.520382) (xy 142.987437 -175.493721)
			(xy 143.012922 -175.48352) (xy 143.032676 -175.475573) (xy 143.069388 -175.454007) (xy 143.101993 -175.426624)
			(xy 143.12958 -175.394192) (xy 143.151377 -175.357616) (xy 143.166775 -175.31792) (xy 143.175344 -175.276214)
			(xy 143.176843 -175.233662) (xy 143.174466 -175.212502) (xy 143.171606 -175.188271) (xy 143.171353 -175.13948)
			(xy 143.173958 -175.11522) (xy 143.176171 -175.092991) (xy 143.173823 -175.048387) (xy 143.163706 -175.004882)
			(xy 143.146131 -174.96382) (xy 143.12164 -174.926467) (xy 143.090991 -174.893977) (xy 143.055128 -174.867352)
			(xy 143.01516 -174.847414) (xy 142.993872 -174.840646) (xy 142.967977 -174.832444) (xy 142.918585 -174.809851)
			(xy 142.872896 -174.780482) (xy 142.831833 -174.744931) (xy 142.796226 -174.703916) (xy 142.766796 -174.658266)
			(xy 142.744136 -174.608905) (xy 142.728705 -174.556828) (xy 142.720815 -174.50309) (xy 142.720625 -174.448776)
			(xy 141.192957 -174.448776) (xy 141.186891 -174.465246) (xy 141.179038 -174.511716) (xy 141.179889 -174.558838)
			(xy 141.189416 -174.604995) (xy 141.207291 -174.648603) (xy 141.232901 -174.688168) (xy 141.265368 -174.72233)
			(xy 141.284198 -174.736506) (xy 141.306412 -174.753195) (xy 141.346229 -174.791946) (xy 141.380004 -174.836063)
			(xy 141.407021 -174.884612) (xy 141.42671 -174.936567) (xy 141.438654 -174.990829) (xy 141.4426 -175.04625)
			(xy 141.438465 -175.101656) (xy 141.426337 -175.155877) (xy 141.406471 -175.207765) (xy 141.379289 -175.256223)
			(xy 141.345365 -175.300224) (xy 141.305416 -175.33884) (xy 141.283182 -175.355504) (xy 141.264351 -175.369667)
			(xy 141.23181 -175.403736) (xy 141.206103 -175.443218) (xy 141.188111 -175.48676) (xy 141.17845 -175.532872)
			(xy 141.177451 -175.579974) (xy 141.185148 -175.626454) (xy 141.201277 -175.670721) (xy 141.225286 -175.711257)
			(xy 141.256353 -175.746676) (xy 141.274546 -175.76165) (xy 141.29546 -175.778679) (xy 141.332747 -175.817646)
			(xy 141.364174 -175.861475) (xy 141.389116 -175.909294) (xy 141.407074 -175.960148) (xy 141.417692 -176.013025)
			(xy 141.420756 -176.06687) (xy 141.416207 -176.12061) (xy 141.404135 -176.173174) (xy 141.394942 -176.19853)
			(xy 141.390084 -176.212332) (xy 141.386111 -176.241314) (xy 141.388858 -176.270438) (xy 141.39818 -176.298165)
			(xy 141.413584 -176.323034) (xy 141.423644 -176.333658) (xy 142.60576 -177.515774) (xy 143.181578 -177.515774)
			(xy 143.233902 -177.49012) (xy 143.252952 -177.466244) (xy 143.256254 -177.461926) (xy 143.274636 -177.440036)
			(xy 143.316834 -177.401481) (xy 143.364312 -177.369653) (xy 143.416007 -177.345265) (xy 143.470763 -177.328864)
			(xy 143.527353 -177.320815) (xy 143.58451 -177.3213) (xy 143.640955 -177.330307) (xy 143.695424 -177.347635)
			(xy 143.746698 -177.372897) (xy 143.79363 -177.405525) (xy 143.835168 -177.444791) (xy 143.853154 -177.467006)
			(xy 143.871188 -177.49012) (xy 143.92402 -177.515774) (xy 148.074126 -177.515774) (xy 148.09713 -177.515266)
			(xy 148.142383 -177.506968) (xy 148.185405 -177.490664) (xy 148.224792 -177.466888) (xy 148.259261 -177.436414)
			(xy 148.287685 -177.400237) (xy 148.309138 -177.359538) (xy 148.322919 -177.315643) (xy 148.32858 -177.269985)
			(xy 148.325936 -177.224053) (xy 148.321014 -177.201576) (xy 148.314754 -177.173674) (xy 148.309684 -177.116717)
			(xy 148.313168 -177.059641) (xy 148.325127 -177.003723) (xy 148.345293 -176.950215) (xy 148.373216 -176.900314)
			(xy 148.40827 -176.855136) (xy 148.449672 -176.815693) (xy 148.496494 -176.782868) (xy 148.547688 -176.757394)
			(xy 148.57476 -176.748186) (xy 148.596056 -176.740814) (xy 148.635836 -176.719647) (xy 148.671259 -176.691795)
			(xy 148.701212 -176.65813) (xy 148.724757 -176.619709) (xy 148.741155 -176.577737) (xy 148.749891 -176.533531)
			(xy 148.750692 -176.488477) (xy 148.743532 -176.443988) (xy 148.736558 -176.422558) (xy 148.727937 -176.396533)
			(xy 148.717389 -176.342735) (xy 148.714648 -176.287981) (xy 148.71977 -176.233398) (xy 148.732649 -176.180109)
			(xy 148.753021 -176.129212) (xy 148.780467 -176.081754) (xy 148.814421 -176.038712) (xy 148.854185 -176.00097)
			(xy 148.898939 -175.969308) (xy 148.947764 -175.944375) (xy 148.999655 -175.926685) (xy 149.053542 -175.916602)
			(xy 149.108318 -175.914334) (xy 149.162855 -175.919927) (xy 149.21603 -175.933266) (xy 149.266749 -175.954077)
			(xy 149.313969 -175.981931) (xy 149.356716 -176.016256) (xy 149.394113 -176.056344) (xy 149.425388 -176.101371)
			(xy 149.449898 -176.150409) (xy 149.46714 -176.20245) (xy 149.476757 -176.256423) (xy 149.478552 -176.311216)
			(xy 149.472488 -176.365703) (xy 149.45869 -176.418761) (xy 149.437442 -176.469298) (xy 149.409181 -176.516275)
			(xy 149.374488 -176.558725) (xy 149.334079 -176.595774) (xy 149.288784 -176.626659) (xy 149.239536 -176.650745)
			(xy 149.21357 -176.65954) (xy 149.192274 -176.666915) (xy 149.152495 -176.688087) (xy 149.117074 -176.715942)
			(xy 149.087119 -176.749608) (xy 149.063571 -176.788028) (xy 149.047168 -176.829999) (xy 149.038423 -176.874204)
			(xy 149.037611 -176.91926) (xy 149.044757 -176.963752) (xy 149.051772 -176.985168) (xy 149.060374 -177.011264)
			(xy 149.070856 -177.065201) (xy 149.073501 -177.120083) (xy 149.068253 -177.174777) (xy 149.062186 -177.201576)
			(xy 149.057213 -177.22405) (xy 149.05453 -177.269997) (xy 149.060166 -177.315676) (xy 149.073936 -177.359592)
			(xy 149.095391 -177.400311) (xy 149.123828 -177.436499) (xy 149.158318 -177.466974) (xy 149.197733 -177.490739)
			(xy 149.240783 -177.507017) (xy 149.286061 -177.515275) (xy 149.309074 -177.515774) (xy 152.965404 -177.515774)
			(xy 153.166064 -177.716434) (xy 153.892502 -177.716434) (xy 153.896573 -177.660812) (xy 153.908699 -177.606375)
			(xy 153.928622 -177.554284) (xy 153.955918 -177.505649) (xy 153.990004 -177.461506) (xy 154.030153 -177.422797)
			(xy 154.075511 -177.390346) (xy 154.125111 -177.364845) (xy 154.177895 -177.346838) (xy 154.232738 -177.336708)
			(xy 154.288472 -177.334671) (xy 154.343909 -177.340771) (xy 154.397866 -177.354877) (xy 154.449195 -177.376689)
			(xy 154.496801 -177.405743) (xy 154.539669 -177.441418) (xy 154.576886 -177.482955) (xy 154.607659 -177.529468)
			(xy 154.631331 -177.579965) (xy 154.647399 -177.633372) (xy 154.655519 -177.688548) (xy 154.656028 -177.716434)
			(xy 154.655519 -177.74432) (xy 154.647399 -177.799496) (xy 154.631331 -177.852903) (xy 154.607659 -177.9034)
			(xy 154.576886 -177.949913) (xy 154.539669 -177.99145) (xy 154.496801 -178.027125) (xy 154.449195 -178.056179)
			(xy 154.397866 -178.077991) (xy 154.343909 -178.092097) (xy 154.288472 -178.098197) (xy 154.232738 -178.09616)
			(xy 154.177895 -178.08603) (xy 154.125111 -178.068023) (xy 154.075511 -178.042522) (xy 154.030153 -178.010071)
			(xy 153.990004 -177.971362) (xy 153.955918 -177.927219) (xy 153.928622 -177.878584) (xy 153.908699 -177.826493)
			(xy 153.896573 -177.772056) (xy 153.892502 -177.716434) (xy 153.166064 -177.716434) (xy 153.552144 -178.102514)
			(xy 166.370252 -178.102514) (xy 166.374323 -178.046892) (xy 166.386449 -177.992455) (xy 166.406372 -177.940364)
			(xy 166.433668 -177.891729) (xy 166.467754 -177.847586) (xy 166.507903 -177.808877) (xy 166.553261 -177.776426)
			(xy 166.602861 -177.750925) (xy 166.655645 -177.732918) (xy 166.710488 -177.722788) (xy 166.766222 -177.720751)
			(xy 166.821659 -177.726851) (xy 166.864114 -177.73795) (xy 170.990928 -177.73795) (xy 170.995487 -177.558432)
			(xy 171.008081 -177.379298) (xy 171.028683 -177.200907) (xy 171.057253 -177.023618) (xy 171.093734 -176.847786)
			(xy 171.138051 -176.673764) (xy 171.190117 -176.501901) (xy 171.249826 -176.332542) (xy 171.317059 -176.166026)
			(xy 171.391681 -176.002688) (xy 171.473542 -175.842856) (xy 171.562479 -175.686849) (xy 171.658312 -175.534982)
			(xy 171.760849 -175.387558) (xy 171.869885 -175.244874) (xy 171.985202 -175.107215) (xy 172.106566 -174.974858)
			(xy 172.233736 -174.848069) (xy 172.366456 -174.727101) (xy 172.504459 -174.612198) (xy 172.64747 -174.50359)
			(xy 172.7952 -174.401495) (xy 172.947354 -174.306117) (xy 173.103626 -174.217648) (xy 173.263703 -174.136266)
			(xy 173.427264 -174.062134) (xy 173.59398 -173.9954) (xy 173.763517 -173.936199) (xy 173.935535 -173.884648)
			(xy 174.109689 -173.840852) (xy 174.28563 -173.804899) (xy 174.463004 -173.77686) (xy 174.641455 -173.756792)
			(xy 174.820627 -173.744735) (xy 175.000158 -173.740714) (xy 175.179689 -173.744735) (xy 175.358861 -173.756792)
			(xy 175.537312 -173.77686) (xy 175.714686 -173.804899) (xy 175.890627 -173.840852) (xy 176.064781 -173.884648)
			(xy 176.236799 -173.936199) (xy 176.406336 -173.9954) (xy 176.573052 -174.062134) (xy 176.736613 -174.136266)
			(xy 176.89669 -174.217648) (xy 177.052962 -174.306117) (xy 177.205116 -174.401495) (xy 177.352846 -174.50359)
			(xy 177.495857 -174.612198) (xy 177.63386 -174.727101) (xy 177.76658 -174.848069) (xy 177.89375 -174.974858)
			(xy 178.015114 -175.107215) (xy 178.130431 -175.244874) (xy 178.239467 -175.387558) (xy 178.342004 -175.534982)
			(xy 178.437837 -175.686849) (xy 178.526774 -175.842856) (xy 178.608635 -176.002688) (xy 178.683257 -176.166026)
			(xy 178.75049 -176.332542) (xy 178.810199 -176.501901) (xy 178.85634 -176.654206) (xy 179.564282 -176.654206)
			(xy 179.568353 -176.598584) (xy 179.580479 -176.544147) (xy 179.600402 -176.492056) (xy 179.627698 -176.443421)
			(xy 179.661784 -176.399278) (xy 179.701933 -176.360569) (xy 179.747291 -176.328118) (xy 179.796891 -176.302617)
			(xy 179.849675 -176.28461) (xy 179.904518 -176.27448) (xy 179.960252 -176.272443) (xy 180.015689 -176.278543)
			(xy 180.069646 -176.292649) (xy 180.120975 -176.314461) (xy 180.168581 -176.343515) (xy 180.211449 -176.37919)
			(xy 180.248666 -176.420727) (xy 180.279439 -176.46724) (xy 180.303111 -176.517737) (xy 180.319179 -176.571144)
			(xy 180.327299 -176.62632) (xy 180.327808 -176.654206) (xy 180.327299 -176.682092) (xy 180.319179 -176.737268)
			(xy 180.303111 -176.790675) (xy 180.279439 -176.841172) (xy 180.248666 -176.887685) (xy 180.211449 -176.929222)
			(xy 180.168581 -176.964897) (xy 180.120975 -176.993951) (xy 180.069646 -177.015763) (xy 180.015689 -177.029869)
			(xy 179.960252 -177.035969) (xy 179.904518 -177.033932) (xy 179.849675 -177.023802) (xy 179.796891 -177.005795)
			(xy 179.747291 -176.980294) (xy 179.701933 -176.947843) (xy 179.661784 -176.909134) (xy 179.627698 -176.864991)
			(xy 179.600402 -176.816356) (xy 179.580479 -176.764265) (xy 179.568353 -176.709828) (xy 179.564282 -176.654206)
			(xy 178.85634 -176.654206) (xy 178.862265 -176.673764) (xy 178.906582 -176.847786) (xy 178.943063 -177.023618)
			(xy 178.971633 -177.200907) (xy 178.992235 -177.379298) (xy 179.004829 -177.558432) (xy 179.009388 -177.73795)
			(xy 179.005905 -177.917493) (xy 178.994385 -178.0967) (xy 178.974851 -178.27521) (xy 178.947344 -178.452668)
			(xy 178.911918 -178.628715) (xy 178.868644 -178.803) (xy 178.817609 -178.975171) (xy 178.758916 -179.144885)
			(xy 178.692682 -179.311801) (xy 178.61904 -179.475583) (xy 178.538138 -179.635903) (xy 178.450138 -179.792439)
			(xy 178.355216 -179.944878) (xy 178.253564 -180.092914) (xy 178.145385 -180.236249) (xy 178.030895 -180.374596)
			(xy 177.910326 -180.507677) (xy 177.783918 -180.635227) (xy 177.651926 -180.756987) (xy 177.583592 -180.815234)
			(xy 177.560538 -180.835301) (xy 177.51903 -180.880166) (xy 177.483412 -180.929836) (xy 177.454233 -180.983542)
			(xy 177.431944 -181.040453) (xy 177.416891 -181.099691) (xy 177.409305 -181.16034) (xy 177.40884 -181.1909)
			(xy 177.40884 -182.749952) (xy 177.408349 -182.818748) (xy 177.400494 -182.956117) (xy 177.38481 -183.092813)
			(xy 177.361347 -183.228391) (xy 177.334155 -183.345328) (xy 178.908962 -183.345328) (xy 178.913033 -183.289706)
			(xy 178.925159 -183.235269) (xy 178.945082 -183.183178) (xy 178.972378 -183.134543) (xy 179.006464 -183.0904)
			(xy 179.046613 -183.051691) (xy 179.091971 -183.01924) (xy 179.141571 -182.993739) (xy 179.194355 -182.975732)
			(xy 179.249198 -182.965602) (xy 179.304932 -182.963565) (xy 179.360369 -182.969665) (xy 179.414326 -182.983771)
			(xy 179.465655 -183.005583) (xy 179.513261 -183.034637) (xy 179.556129 -183.070312) (xy 179.593346 -183.111849)
			(xy 179.624119 -183.158362) (xy 179.647791 -183.208859) (xy 179.663859 -183.262266) (xy 179.671979 -183.317442)
			(xy 179.672488 -183.345328) (xy 179.671979 -183.373214) (xy 179.663859 -183.42839) (xy 179.647791 -183.481797)
			(xy 179.624119 -183.532294) (xy 179.593346 -183.578807) (xy 179.556129 -183.620344) (xy 179.513261 -183.656019)
			(xy 179.465655 -183.685073) (xy 179.414326 -183.706885) (xy 179.360369 -183.720991) (xy 179.304932 -183.727091)
			(xy 179.249198 -183.725054) (xy 179.194355 -183.714924) (xy 179.141571 -183.696917) (xy 179.091971 -183.671416)
			(xy 179.046613 -183.638965) (xy 179.006464 -183.600256) (xy 178.972378 -183.556113) (xy 178.945082 -183.507478)
			(xy 178.925159 -183.455387) (xy 178.913033 -183.40095) (xy 178.908962 -183.345328) (xy 177.334155 -183.345328)
			(xy 177.330183 -183.362408) (xy 177.291418 -183.494428) (xy 177.24518 -183.624019) (xy 177.191619 -183.750759)
			(xy 177.13091 -183.874235) (xy 177.063251 -183.994043) (xy 176.988863 -184.109794) (xy 176.907988 -184.221109)
			(xy 176.82089 -184.327625) (xy 176.727853 -184.428996) (xy 176.629181 -184.524889) (xy 176.525195 -184.614993)
			(xy 176.416235 -184.699014) (xy 176.302656 -184.776678) (xy 176.184828 -184.84773) (xy 176.063136 -184.911941)
			(xy 175.937977 -184.969099) (xy 175.809759 -185.019018) (xy 175.678901 -185.061537) (xy 175.545828 -185.096516)
			(xy 175.410976 -185.12384) (xy 175.274783 -185.143422) (xy 175.137695 -185.155196) (xy 175.000158 -185.159126)
			(xy 174.862621 -185.155196) (xy 174.725533 -185.143422) (xy 174.58934 -185.12384) (xy 174.454488 -185.096516)
			(xy 174.321415 -185.061537) (xy 174.190557 -185.019018) (xy 174.062339 -184.969099) (xy 173.93718 -184.911941)
			(xy 173.815488 -184.84773) (xy 173.69766 -184.776678) (xy 173.584081 -184.699014) (xy 173.475121 -184.614993)
			(xy 173.371135 -184.524889) (xy 173.272463 -184.428996) (xy 173.179426 -184.327625) (xy 173.092328 -184.221109)
			(xy 173.011453 -184.109794) (xy 172.937065 -183.994043) (xy 172.869406 -183.874235) (xy 172.808697 -183.750759)
			(xy 172.755136 -183.624019) (xy 172.708898 -183.494428) (xy 172.670133 -183.362408) (xy 172.638969 -183.228391)
			(xy 172.615506 -183.092813) (xy 172.599822 -182.956117) (xy 172.591967 -182.818748) (xy 172.591476 -182.749952)
			(xy 172.591476 -181.1909) (xy 172.591006 -181.16034) (xy 172.583413 -181.099693) (xy 172.568357 -181.040456)
			(xy 172.546071 -180.983543) (xy 172.516898 -180.929834) (xy 172.48129 -180.880157) (xy 172.439795 -180.835281)
			(xy 172.416724 -180.815234) (xy 172.34839 -180.756987) (xy 172.216398 -180.635227) (xy 172.08999 -180.507677)
			(xy 171.969421 -180.374596) (xy 171.854931 -180.236249) (xy 171.746752 -180.092914) (xy 171.6451 -179.944878)
			(xy 171.550178 -179.792439) (xy 171.462178 -179.635903) (xy 171.381276 -179.475583) (xy 171.307634 -179.311801)
			(xy 171.2414 -179.144885) (xy 171.182707 -178.975171) (xy 171.131672 -178.803) (xy 171.088398 -178.628715)
			(xy 171.052972 -178.452668) (xy 171.025465 -178.27521) (xy 171.005931 -178.0967) (xy 170.994411 -177.917493)
			(xy 170.990928 -177.73795) (xy 166.864114 -177.73795) (xy 166.875616 -177.740957) (xy 166.926945 -177.762769)
			(xy 166.974551 -177.791823) (xy 167.017419 -177.827498) (xy 167.054636 -177.869035) (xy 167.085409 -177.915548)
			(xy 167.109081 -177.966045) (xy 167.125149 -178.019452) (xy 167.133269 -178.074628) (xy 167.133778 -178.102514)
			(xy 167.133269 -178.1304) (xy 167.125149 -178.185576) (xy 167.109081 -178.238983) (xy 167.085409 -178.28948)
			(xy 167.054636 -178.335993) (xy 167.017419 -178.37753) (xy 166.974551 -178.413205) (xy 166.926945 -178.442259)
			(xy 166.875616 -178.464071) (xy 166.821659 -178.478177) (xy 166.766222 -178.484277) (xy 166.710488 -178.48224)
			(xy 166.655645 -178.47211) (xy 166.602861 -178.454103) (xy 166.553261 -178.428602) (xy 166.507903 -178.396151)
			(xy 166.467754 -178.357442) (xy 166.433668 -178.313299) (xy 166.406372 -178.264664) (xy 166.386449 -178.212573)
			(xy 166.374323 -178.158136) (xy 166.370252 -178.102514) (xy 153.552144 -178.102514) (xy 154.015948 -178.566318)
			(xy 154.029324 -178.578886) (xy 154.061548 -178.596423) (xy 154.097438 -178.604033) (xy 154.11577 -178.603148)
			(xy 154.125168 -178.602386) (xy 154.129232 -178.601878) (xy 154.12974 -178.601878) (xy 154.156395 -178.598575)
			(xy 154.210106 -178.598596) (xy 154.263282 -178.606153) (xy 154.314871 -178.621096) (xy 154.363854 -178.643129)
			(xy 154.409261 -178.671818) (xy 154.450194 -178.706593) (xy 154.485842 -178.746768) (xy 154.515502 -178.791546)
			(xy 154.538585 -178.840044) (xy 154.547062 -178.86553) (xy 154.559508 -178.905154) (xy 154.626564 -178.95443)
			(xy 156.318712 -178.95443) (xy 156.341035 -178.953962) (xy 156.384995 -178.946159) (xy 156.426915 -178.930795)
			(xy 156.465506 -178.908343) (xy 156.499581 -178.879494) (xy 156.52809 -178.845135) (xy 156.550158 -178.806323)
			(xy 156.565105 -178.764252) (xy 156.572471 -178.720217) (xy 156.572712 -178.69789) (xy 156.572913 -178.670459)
			(xy 156.580227 -178.616095) (xy 156.59525 -178.563338) (xy 156.617675 -178.513276) (xy 156.647038 -178.466942)
			(xy 156.682733 -178.425291) (xy 156.724026 -178.389181) (xy 156.770064 -178.359357) (xy 156.8199 -178.336434)
			(xy 156.872504 -178.320884) (xy 156.926793 -178.313028) (xy 156.981647 -178.313028) (xy 157.035936 -178.320884)
			(xy 157.08854 -178.336434) (xy 157.138376 -178.359357) (xy 157.184414 -178.389181) (xy 157.225707 -178.425291)
			(xy 157.261402 -178.466942) (xy 157.290765 -178.513276) (xy 157.31319 -178.563338) (xy 157.328213 -178.616095)
			(xy 157.335527 -178.670459) (xy 157.335728 -178.69789) (xy 157.335975 -178.720215) (xy 157.343341 -178.764247)
			(xy 157.358288 -178.806314) (xy 157.380356 -178.845121) (xy 157.408866 -178.879476) (xy 157.44294 -178.90832)
			(xy 157.48153 -178.930766) (xy 157.523449 -178.946123) (xy 157.567406 -178.95392) (xy 157.589728 -178.95443)
			(xy 163.874196 -178.95443) (xy 163.964112 -178.864768) (xy 164.50183 -179.402486) (xy 166.142922 -179.402486)
			(xy 166.146993 -179.346864) (xy 166.159119 -179.292427) (xy 166.179042 -179.240336) (xy 166.206338 -179.191701)
			(xy 166.240424 -179.147558) (xy 166.280573 -179.108849) (xy 166.325931 -179.076398) (xy 166.375531 -179.050897)
			(xy 166.428315 -179.03289) (xy 166.483158 -179.02276) (xy 166.538892 -179.020723) (xy 166.594329 -179.026823)
			(xy 166.648286 -179.040929) (xy 166.699615 -179.062741) (xy 166.747221 -179.091795) (xy 166.790089 -179.12747)
			(xy 166.827306 -179.169007) (xy 166.858079 -179.21552) (xy 166.881751 -179.266017) (xy 166.897819 -179.319424)
			(xy 166.905939 -179.3746) (xy 166.906448 -179.402486) (xy 166.905939 -179.430372) (xy 166.897819 -179.485548)
			(xy 166.881751 -179.538955) (xy 166.858079 -179.589452) (xy 166.827306 -179.635965) (xy 166.790089 -179.677502)
			(xy 166.747221 -179.713177) (xy 166.699615 -179.742231) (xy 166.648286 -179.764043) (xy 166.594329 -179.778149)
			(xy 166.538892 -179.784249) (xy 166.483158 -179.782212) (xy 166.428315 -179.772082) (xy 166.375531 -179.754075)
			(xy 166.325931 -179.728574) (xy 166.280573 -179.696123) (xy 166.240424 -179.657414) (xy 166.206338 -179.613271)
			(xy 166.179042 -179.564636) (xy 166.159119 -179.512545) (xy 166.146993 -179.458108) (xy 166.142922 -179.402486)
			(xy 164.50183 -179.402486) (xy 164.955982 -179.856638) (xy 165.14826 -179.856638) (xy 166.137844 -180.846222)
			(xy 166.149986 -180.857674) (xy 166.178883 -180.874356) (xy 166.211119 -180.882965) (xy 166.244485 -180.882912)
			(xy 166.276694 -180.874199) (xy 166.305537 -180.857425) (xy 166.317676 -180.845968) (xy 166.356792 -180.806852)
			(xy 166.563294 -180.806852) (xy 166.59352 -180.788818) (xy 166.617699 -180.774954) (xy 166.669188 -180.75362)
			(xy 166.723233 -180.740003) (xy 166.778684 -180.734395) (xy 166.834361 -180.736914) (xy 166.889079 -180.747507)
			(xy 166.941673 -180.765948) (xy 166.991025 -180.791845) (xy 167.036084 -180.824647) (xy 167.075892 -180.863655)
			(xy 167.1096 -180.90804) (xy 167.136492 -180.956857) (xy 167.155995 -181.009067) (xy 167.167695 -181.063559)
			(xy 167.171342 -181.119174) (xy 167.166858 -181.174727) (xy 167.15434 -181.229037) (xy 167.134054 -181.280948)
			(xy 167.106431 -181.329355) (xy 167.072058 -181.373227) (xy 167.052244 -181.39283) (xy 167.03627 -181.408718)
			(xy 167.009643 -181.445054) (xy 166.989841 -181.485517) (xy 166.977484 -181.528838) (xy 166.972961 -181.573659)
			(xy 166.976412 -181.618575) (xy 166.987729 -181.662179) (xy 167.006559 -181.703103) (xy 167.03231 -181.740066)
			(xy 167.047926 -181.756304) (xy 168.36263 -183.071008) (xy 170.466002 -183.071008) (xy 170.470073 -183.015386)
			(xy 170.482199 -182.960949) (xy 170.502122 -182.908858) (xy 170.529418 -182.860223) (xy 170.563504 -182.81608)
			(xy 170.603653 -182.777371) (xy 170.649011 -182.74492) (xy 170.698611 -182.719419) (xy 170.751395 -182.701412)
			(xy 170.806238 -182.691282) (xy 170.861972 -182.689245) (xy 170.917409 -182.695345) (xy 170.971366 -182.709451)
			(xy 171.022695 -182.731263) (xy 171.070301 -182.760317) (xy 171.113169 -182.795992) (xy 171.150386 -182.837529)
			(xy 171.181159 -182.884042) (xy 171.204831 -182.934539) (xy 171.220899 -182.987946) (xy 171.229019 -183.043122)
			(xy 171.229528 -183.071008) (xy 171.229019 -183.098894) (xy 171.220899 -183.15407) (xy 171.204831 -183.207477)
			(xy 171.181159 -183.257974) (xy 171.150386 -183.304487) (xy 171.113169 -183.346024) (xy 171.070301 -183.381699)
			(xy 171.022695 -183.410753) (xy 170.971366 -183.432565) (xy 170.917409 -183.446671) (xy 170.861972 -183.452771)
			(xy 170.806238 -183.450734) (xy 170.751395 -183.440604) (xy 170.698611 -183.422597) (xy 170.649011 -183.397096)
			(xy 170.603653 -183.364645) (xy 170.563504 -183.325936) (xy 170.529418 -183.281793) (xy 170.502122 -183.233158)
			(xy 170.482199 -183.181067) (xy 170.470073 -183.12663) (xy 170.466002 -183.071008) (xy 168.36263 -183.071008)
			(xy 172.056298 -186.764676) (xy 174.499522 -186.764676) (xy 174.503593 -186.709054) (xy 174.515719 -186.654617)
			(xy 174.535642 -186.602526) (xy 174.562938 -186.553891) (xy 174.597024 -186.509748) (xy 174.637173 -186.471039)
			(xy 174.682531 -186.438588) (xy 174.732131 -186.413087) (xy 174.784915 -186.39508) (xy 174.839758 -186.38495)
			(xy 174.895492 -186.382913) (xy 174.950929 -186.389013) (xy 175.004886 -186.403119) (xy 175.056215 -186.424931)
			(xy 175.103821 -186.453985) (xy 175.146689 -186.48966) (xy 175.183906 -186.531197) (xy 175.214679 -186.57771)
			(xy 175.238351 -186.628207) (xy 175.254419 -186.681614) (xy 175.262539 -186.73679) (xy 175.263048 -186.764676)
			(xy 175.262539 -186.792562) (xy 175.254419 -186.847738) (xy 175.238351 -186.901145) (xy 175.214679 -186.951642)
			(xy 175.183906 -186.998155) (xy 175.146689 -187.039692) (xy 175.103821 -187.075367) (xy 175.056215 -187.104421)
			(xy 175.004886 -187.126233) (xy 174.978087 -187.133239) (xy 179.830983 -187.133239) (xy 179.837086 -187.077765)
			(xy 179.851202 -187.023772) (xy 179.873029 -186.972409) (xy 179.902102 -186.924771) (xy 179.937801 -186.881875)
			(xy 179.979365 -186.844633) (xy 180.025909 -186.813839) (xy 180.07644 -186.790151) (xy 180.129882 -186.774073)
			(xy 180.185096 -186.765947) (xy 180.213 -186.765438) (xy 180.240904 -186.765947) (xy 180.296118 -186.774073)
			(xy 180.34956 -186.790151) (xy 180.400091 -186.813839) (xy 180.446635 -186.844633) (xy 180.488199 -186.881875)
			(xy 180.523898 -186.924771) (xy 180.552971 -186.972409) (xy 180.574798 -187.023772) (xy 180.588914 -187.077765)
			(xy 180.595017 -187.133239) (xy 180.592979 -187.18901) (xy 180.582842 -187.243889) (xy 180.564823 -187.296709)
			(xy 180.539305 -187.346341) (xy 180.506833 -187.391729) (xy 180.468098 -187.431906) (xy 180.423926 -187.466014)
			(xy 180.375258 -187.493328) (xy 180.323132 -187.513264) (xy 180.268659 -187.525399) (xy 180.213 -187.529473)
			(xy 180.157341 -187.525399) (xy 180.102868 -187.513264) (xy 180.050742 -187.493328) (xy 180.002074 -187.466014)
			(xy 179.957902 -187.431906) (xy 179.919167 -187.391729) (xy 179.886695 -187.346341) (xy 179.861177 -187.296709)
			(xy 179.843158 -187.243889) (xy 179.833021 -187.18901) (xy 179.830983 -187.133239) (xy 174.978087 -187.133239)
			(xy 174.950929 -187.140339) (xy 174.895492 -187.146439) (xy 174.839758 -187.144402) (xy 174.784915 -187.134272)
			(xy 174.732131 -187.116265) (xy 174.682531 -187.090764) (xy 174.637173 -187.058313) (xy 174.597024 -187.019604)
			(xy 174.562938 -186.975461) (xy 174.535642 -186.926826) (xy 174.515719 -186.874735) (xy 174.503593 -186.820298)
			(xy 174.499522 -186.764676) (xy 172.056298 -186.764676) (xy 173.01464 -187.723018) (xy 173.01464 -188.06795)
			(xy 179.087778 -188.06795) (xy 179.091851 -188.012291) (xy 179.103986 -187.957818) (xy 179.123922 -187.905692)
			(xy 179.151236 -187.857024) (xy 179.185344 -187.812852) (xy 179.225521 -187.774117) (xy 179.270909 -187.741645)
			(xy 179.320541 -187.716127) (xy 179.373361 -187.698108) (xy 179.42824 -187.687971) (xy 179.484011 -187.685933)
			(xy 179.539485 -187.692036) (xy 179.593478 -187.706152) (xy 179.644841 -187.727979) (xy 179.692479 -187.757052)
			(xy 179.735375 -187.792751) (xy 179.772617 -187.834315) (xy 179.803411 -187.880859) (xy 179.827099 -187.93139)
			(xy 179.843177 -187.984832) (xy 179.851303 -188.040046) (xy 179.851812 -188.06795) (xy 179.851303 -188.095854)
			(xy 179.843177 -188.151068) (xy 179.827099 -188.20451) (xy 179.803411 -188.255041) (xy 179.772617 -188.301585)
			(xy 179.735375 -188.343149) (xy 179.692479 -188.378848) (xy 179.644841 -188.407921) (xy 179.593478 -188.429748)
			(xy 179.539485 -188.443864) (xy 179.484011 -188.449967) (xy 179.42824 -188.447929) (xy 179.373361 -188.437792)
			(xy 179.320541 -188.419773) (xy 179.270909 -188.394255) (xy 179.225521 -188.361783) (xy 179.185344 -188.323048)
			(xy 179.151236 -188.278876) (xy 179.123922 -188.230208) (xy 179.103986 -188.178082) (xy 179.091851 -188.123609)
			(xy 179.087778 -188.06795) (xy 173.01464 -188.06795) (xy 173.01464 -194.981322) (xy 172.212762 -195.7832)
			(xy 178.433728 -195.7832) (xy 178.437801 -195.727541) (xy 178.449936 -195.673068) (xy 178.469872 -195.620942)
			(xy 178.497186 -195.572274) (xy 178.531294 -195.528102) (xy 178.571471 -195.489367) (xy 178.616859 -195.456895)
			(xy 178.666491 -195.431377) (xy 178.719311 -195.413358) (xy 178.77419 -195.403221) (xy 178.829961 -195.401183)
			(xy 178.885435 -195.407286) (xy 178.939428 -195.421402) (xy 178.990791 -195.443229) (xy 179.038429 -195.472302)
			(xy 179.081325 -195.508001) (xy 179.118567 -195.549565) (xy 179.149361 -195.596109) (xy 179.173049 -195.64664)
			(xy 179.189127 -195.700082) (xy 179.197253 -195.755296) (xy 179.197762 -195.7832) (xy 179.197253 -195.811104)
			(xy 179.189127 -195.866318) (xy 179.173049 -195.91976) (xy 179.149361 -195.970291) (xy 179.118567 -196.016835)
			(xy 179.081325 -196.058399) (xy 179.038429 -196.094098) (xy 178.990791 -196.123171) (xy 178.939428 -196.144998)
			(xy 178.885435 -196.159114) (xy 178.829961 -196.165217) (xy 178.77419 -196.163179) (xy 178.719311 -196.153042)
			(xy 178.666491 -196.135023) (xy 178.616859 -196.109505) (xy 178.571471 -196.077033) (xy 178.531294 -196.038298)
			(xy 178.497186 -195.994126) (xy 178.469872 -195.945458) (xy 178.449936 -195.893332) (xy 178.437801 -195.838859)
			(xy 178.433728 -195.7832) (xy 172.212762 -195.7832) (xy 171.272962 -196.723) (xy 174.801528 -196.723)
			(xy 174.805601 -196.667341) (xy 174.817736 -196.612868) (xy 174.837672 -196.560742) (xy 174.864986 -196.512074)
			(xy 174.899094 -196.467902) (xy 174.939271 -196.429167) (xy 174.984659 -196.396695) (xy 175.034291 -196.371177)
			(xy 175.087111 -196.353158) (xy 175.14199 -196.343021) (xy 175.197761 -196.340983) (xy 175.253235 -196.347086)
			(xy 175.307228 -196.361202) (xy 175.358591 -196.383029) (xy 175.406229 -196.412102) (xy 175.449125 -196.447801)
			(xy 175.486367 -196.489365) (xy 175.517161 -196.535909) (xy 175.540849 -196.58644) (xy 175.556927 -196.639882)
			(xy 175.565053 -196.695096) (xy 175.565562 -196.723) (xy 175.565053 -196.750904) (xy 175.556927 -196.806118)
			(xy 175.540849 -196.85956) (xy 175.517161 -196.910091) (xy 175.486367 -196.956635) (xy 175.449125 -196.998199)
			(xy 175.406229 -197.033898) (xy 175.358591 -197.062971) (xy 175.307228 -197.084798) (xy 175.287181 -197.090039)
			(xy 177.316383 -197.090039) (xy 177.322486 -197.034565) (xy 177.336602 -196.980572) (xy 177.358429 -196.929209)
			(xy 177.387502 -196.881571) (xy 177.423201 -196.838675) (xy 177.464765 -196.801433) (xy 177.511309 -196.770639)
			(xy 177.56184 -196.746951) (xy 177.615282 -196.730873) (xy 177.670496 -196.722747) (xy 177.6984 -196.722238)
			(xy 177.726304 -196.722747) (xy 177.781518 -196.730873) (xy 177.83496 -196.746951) (xy 177.885491 -196.770639)
			(xy 177.932035 -196.801433) (xy 177.973599 -196.838675) (xy 178.009298 -196.881571) (xy 178.038371 -196.929209)
			(xy 178.060198 -196.980572) (xy 178.074314 -197.034565) (xy 178.080417 -197.090039) (xy 178.078379 -197.14581)
			(xy 178.068242 -197.200689) (xy 178.050223 -197.253509) (xy 178.024705 -197.303141) (xy 177.992233 -197.348529)
			(xy 177.953498 -197.388706) (xy 177.909326 -197.422814) (xy 177.860658 -197.450128) (xy 177.808532 -197.470064)
			(xy 177.754059 -197.482199) (xy 177.6984 -197.486273) (xy 177.642741 -197.482199) (xy 177.588268 -197.470064)
			(xy 177.536142 -197.450128) (xy 177.487474 -197.422814) (xy 177.443302 -197.388706) (xy 177.404567 -197.348529)
			(xy 177.372095 -197.303141) (xy 177.346577 -197.253509) (xy 177.328558 -197.200689) (xy 177.318421 -197.14581)
			(xy 177.316383 -197.090039) (xy 175.287181 -197.090039) (xy 175.253235 -197.098914) (xy 175.197761 -197.105017)
			(xy 175.14199 -197.102979) (xy 175.087111 -197.092842) (xy 175.034291 -197.074823) (xy 174.984659 -197.049305)
			(xy 174.939271 -197.016833) (xy 174.899094 -196.978098) (xy 174.864986 -196.933926) (xy 174.837672 -196.885258)
			(xy 174.817736 -196.833132) (xy 174.805601 -196.778659) (xy 174.801528 -196.723) (xy 171.272962 -196.723)
			(xy 171.03344 -196.962522) (xy 171.03344 -197.63994) (xy 171.034 -197.657406) (xy 171.043473 -197.691031)
			(xy 171.050197 -197.702043) (xy 171.421686 -197.702043) (xy 171.428904 -197.646596) (xy 171.444138 -197.592797)
			(xy 171.467062 -197.541798) (xy 171.497186 -197.494691) (xy 171.533862 -197.452487) (xy 171.576307 -197.416088)
			(xy 171.623611 -197.386275) (xy 171.674759 -197.363687) (xy 171.728657 -197.348806) (xy 171.78415 -197.341953)
			(xy 171.840049 -197.343274) (xy 171.895156 -197.35274) (xy 171.948291 -197.37015) (xy 171.998316 -197.395129)
			(xy 172.044158 -197.427142) (xy 172.060549 -197.4426) (xy 172.714157 -197.4426) (xy 172.720257 -197.387163)
			(xy 172.734363 -197.333206) (xy 172.756175 -197.281877) (xy 172.785229 -197.234271) (xy 172.820904 -197.191403)
			(xy 172.862441 -197.154186) (xy 172.908954 -197.123413) (xy 172.959451 -197.099741) (xy 173.012858 -197.083673)
			(xy 173.068034 -197.075553) (xy 173.09592 -197.075044) (xy 173.123806 -197.075553) (xy 173.178982 -197.083673)
			(xy 173.232389 -197.099741) (xy 173.282886 -197.123413) (xy 173.329399 -197.154186) (xy 173.370936 -197.191403)
			(xy 173.406611 -197.234271) (xy 173.435665 -197.281877) (xy 173.457477 -197.333206) (xy 173.471583 -197.387163)
			(xy 173.477683 -197.4426) (xy 173.475646 -197.498334) (xy 173.465516 -197.553177) (xy 173.447509 -197.605961)
			(xy 173.422008 -197.655561) (xy 173.389557 -197.700919) (xy 173.350848 -197.741068) (xy 173.306705 -197.775154)
			(xy 173.25807 -197.80245) (xy 173.205979 -197.822373) (xy 173.151542 -197.834499) (xy 173.09592 -197.83857)
			(xy 173.040298 -197.834499) (xy 172.985861 -197.822373) (xy 172.93377 -197.80245) (xy 172.885135 -197.775154)
			(xy 172.840992 -197.741068) (xy 172.802283 -197.700919) (xy 172.769832 -197.655561) (xy 172.744331 -197.605961)
			(xy 172.726324 -197.553177) (xy 172.716194 -197.498334) (xy 172.714157 -197.4426) (xy 172.060549 -197.4426)
			(xy 172.084837 -197.465505) (xy 172.119479 -197.509395) (xy 172.147344 -197.557871) (xy 172.167834 -197.609896)
			(xy 172.180511 -197.664355) (xy 172.185102 -197.72008) (xy 172.181509 -197.775879) (xy 172.16981 -197.830556)
			(xy 172.150254 -197.882939) (xy 172.123262 -197.931907) (xy 172.08941 -197.97641) (xy 172.06976 -197.996302)
			(xy 172.057809 -198.008814) (xy 172.040499 -198.038756) (xy 172.031874 -198.07225) (xy 172.032569 -198.106829)
			(xy 172.036994 -198.123556) (xy 172.081952 -198.273924) (xy 172.116242 -198.276972) (xy 172.143768 -198.279942)
			(xy 172.197628 -198.292747) (xy 172.24907 -198.313205) (xy 172.297014 -198.340885) (xy 172.340452 -198.375207)
			(xy 172.378471 -198.415449) (xy 172.410273 -198.460764) (xy 172.435188 -198.510202) (xy 172.44441 -198.536306)
			(xy 172.452152 -198.557772) (xy 172.474066 -198.597789) (xy 172.50277 -198.633253) (xy 172.537344 -198.663023)
			(xy 172.576676 -198.686144) (xy 172.619504 -198.701872) (xy 172.664451 -198.709704) (xy 172.710075 -198.709387)
			(xy 172.754909 -198.700931) (xy 172.797514 -198.684608) (xy 172.817282 -198.673212) (xy 172.841201 -198.659196)
			(xy 172.892227 -198.637522) (xy 172.945851 -198.62346) (xy 173.000947 -198.617306) (xy 173.056353 -198.61919)
			(xy 173.110903 -198.629072) (xy 173.163449 -198.646744) (xy 173.212884 -198.671834) (xy 173.258169 -198.703815)
			(xy 173.298348 -198.742011) (xy 173.332577 -198.78562) (xy 173.360135 -198.833724) (xy 173.380441 -198.885309)
			(xy 173.393069 -198.93929) (xy 173.397752 -198.99453) (xy 173.394392 -199.049866) (xy 173.383059 -199.104133)
			(xy 173.363992 -199.156189) (xy 173.337593 -199.204938) (xy 173.304417 -199.249354) (xy 173.265163 -199.288501)
			(xy 173.220657 -199.321555) (xy 173.171836 -199.347821) (xy 173.119727 -199.366745) (xy 173.065429 -199.377929)
			(xy 173.010084 -199.381138) (xy 172.954857 -199.376304) (xy 172.900911 -199.363528) (xy 172.849382 -199.343081)
			(xy 172.801354 -199.315391) (xy 172.757839 -199.281043) (xy 172.719752 -199.240759) (xy 172.687896 -199.195388)
			(xy 172.662941 -199.145884) (xy 172.653706 -199.119744) (xy 172.646055 -199.098242) (xy 172.624137 -199.058213)
			(xy 172.595424 -199.02274) (xy 172.56084 -198.992964) (xy 172.521495 -198.969842) (xy 172.478654 -198.954115)
			(xy 172.433693 -198.946291) (xy 172.388057 -198.946619) (xy 172.343214 -198.95509) (xy 172.300603 -198.971432)
			(xy 172.280834 -198.982838) (xy 172.256873 -198.996964) (xy 172.205663 -199.01868) (xy 172.151842 -199.032731)
			(xy 172.096551 -199.038817) (xy 172.040963 -199.036811) (xy 171.986255 -199.026755) (xy 171.933587 -199.008862)
			(xy 171.884075 -198.983511) (xy 171.838769 -198.951239) (xy 171.798628 -198.912732) (xy 171.764505 -198.868804)
			(xy 171.737121 -198.820386) (xy 171.717058 -198.768506) (xy 171.70474 -198.714263) (xy 171.700429 -198.658805)
			(xy 171.704216 -198.60331) (xy 171.71602 -198.548952) (xy 171.735592 -198.496885) (xy 171.762517 -198.448211)
			(xy 171.796224 -198.403962) (xy 171.81576 -198.38416) (xy 171.827727 -198.371661) (xy 171.845041 -198.341716)
			(xy 171.853664 -198.308217) (xy 171.852958 -198.273634) (xy 171.848526 -198.256906) (xy 171.803568 -198.106538)
			(xy 171.769278 -198.10349) (xy 171.741475 -198.100514) (xy 171.687101 -198.08748) (xy 171.635212 -198.066648)
			(xy 171.58692 -198.038465) (xy 171.543259 -198.003535) (xy 171.505164 -197.962605) (xy 171.473453 -197.916553)
			(xy 171.448803 -197.866365) (xy 171.431743 -197.813117) (xy 171.422639 -197.757949) (xy 171.421686 -197.702043)
			(xy 171.050197 -197.702043) (xy 171.061677 -197.720846) (xy 171.07408 -197.733158) (xy 171.094389 -197.752616)
			(xy 171.129634 -197.796447) (xy 171.158059 -197.844979) (xy 171.179048 -197.89716) (xy 171.192145 -197.951857)
			(xy 171.197067 -198.007885) (xy 171.193706 -198.064028) (xy 171.182136 -198.119069) (xy 171.162608 -198.171813)
			(xy 171.149518 -198.196708) (xy 171.138641 -198.217516) (xy 171.123942 -198.262103) (xy 171.117688 -198.308632)
			(xy 171.120094 -198.355518) (xy 171.131076 -198.401163) (xy 171.150261 -198.444011) (xy 171.176995 -198.482604)
			(xy 171.210368 -198.515624) (xy 171.229528 -198.529194) (xy 171.252614 -198.545437) (xy 171.294184 -198.583619)
			(xy 171.329677 -198.627509) (xy 171.358317 -198.676149) (xy 171.379481 -198.728476) (xy 171.392705 -198.78335)
			(xy 171.397702 -198.839574) (xy 171.394363 -198.89592) (xy 171.38276 -198.951159) (xy 171.363146 -199.004087)
			(xy 171.33595 -199.053549) (xy 171.301765 -199.098465) (xy 171.261337 -199.137855) (xy 171.215547 -199.17086)
			(xy 171.165395 -199.196761) (xy 171.13885 -199.206358) (xy 171.123864 -199.211438) (xy 171.03344 -199.332596)
			(xy 171.03344 -199.759316) (xy 171.63364 -199.759316) (xy 171.637711 -199.703694) (xy 171.649837 -199.649257)
			(xy 171.66976 -199.597166) (xy 171.697056 -199.548531) (xy 171.731142 -199.504388) (xy 171.771291 -199.465679)
			(xy 171.816649 -199.433228) (xy 171.866249 -199.407727) (xy 171.919033 -199.38972) (xy 171.973876 -199.37959)
			(xy 172.02961 -199.377553) (xy 172.085047 -199.383653) (xy 172.139004 -199.397759) (xy 172.190333 -199.419571)
			(xy 172.237939 -199.448625) (xy 172.280807 -199.4843) (xy 172.318024 -199.525837) (xy 172.348797 -199.57235)
			(xy 172.372469 -199.622847) (xy 172.388537 -199.676254) (xy 172.396657 -199.73143) (xy 172.397166 -199.759316)
			(xy 172.396657 -199.787202) (xy 172.388537 -199.842378) (xy 172.372469 -199.895785) (xy 172.348797 -199.946282)
			(xy 172.318024 -199.992795) (xy 172.280807 -200.034332) (xy 172.237939 -200.070007) (xy 172.190333 -200.099061)
			(xy 172.139004 -200.120873) (xy 172.085047 -200.134979) (xy 172.02961 -200.141079) (xy 171.973876 -200.139042)
			(xy 171.919033 -200.128912) (xy 171.866249 -200.110905) (xy 171.816649 -200.085404) (xy 171.771291 -200.052953)
			(xy 171.731142 -200.014244) (xy 171.697056 -199.970101) (xy 171.66976 -199.921466) (xy 171.649837 -199.869375)
			(xy 171.637711 -199.814938) (xy 171.63364 -199.759316) (xy 171.03344 -199.759316) (xy 171.03344 -200.76922)
			(xy 171.831 -201.56678)
		)
		(stroke
			(width 0)
			(type solid)
		)
		(fill yes)
		(layer "In6.Cu")
		(net "P3V3_NODE1")
	)
	(gr_poly
		(pts
			(xy 99.299776 -151.527256) (xy 99.322978 -151.515827) (xy 99.37176 -151.498635) (xy 99.422417 -151.488192)
			(xy 99.47402 -151.484689) (xy 99.525623 -151.488192) (xy 99.57628 -151.498635) (xy 99.625062 -151.515827)
			(xy 99.648264 -151.527256) (xy 99.675696 -151.541226) (xy 101.545136 -151.541226) (xy 101.560354 -151.540779)
			(xy 101.589925 -151.533567) (xy 101.616948 -151.519562) (xy 101.63989 -151.49956) (xy 101.649022 -151.487378)
			(xy 101.649022 -151.487124) (xy 101.665704 -151.464274) (xy 101.704709 -151.423296) (xy 101.749341 -151.388532)
			(xy 101.798619 -151.360744) (xy 101.851463 -151.340543) (xy 101.906712 -151.328373) (xy 101.963153 -151.3245)
			(xy 102.019547 -151.329009) (xy 102.074655 -151.341802) (xy 102.101142 -151.351742) (xy 102.122249 -151.359555)
			(xy 102.166365 -151.368448) (xy 102.211357 -151.369431) (xy 102.255819 -151.362474) (xy 102.29836 -151.347794)
			(xy 102.337651 -151.325851) (xy 102.372462 -151.29733) (xy 102.401706 -151.263124) (xy 102.424467 -151.224301)
			(xy 102.440034 -151.182076) (xy 102.44792 -151.13777) (xy 102.44836 -151.115268) (xy 102.44836 -149.952964)
			(xy 102.75316 -149.648164) (xy 103.96728 -149.648164) (xy 104.765602 -150.446486) (xy 104.775843 -150.456224)
			(xy 104.799709 -150.471344) (xy 104.826329 -150.480812) (xy 104.854383 -150.484158) (xy 104.868472 -150.483062)
			(xy 104.895063 -150.480769) (xy 104.948398 -150.482748) (xy 105.000937 -150.49214) (xy 105.051654 -150.508763)
			(xy 105.09956 -150.532291) (xy 105.143719 -150.562267) (xy 105.151335 -150.569168) (xy 115.414042 -150.569168)
			(xy 115.418113 -150.513546) (xy 115.430239 -150.459109) (xy 115.450162 -150.407018) (xy 115.477458 -150.358383)
			(xy 115.511544 -150.31424) (xy 115.551693 -150.275531) (xy 115.597051 -150.24308) (xy 115.646651 -150.217579)
			(xy 115.699435 -150.199572) (xy 115.754278 -150.189442) (xy 115.810012 -150.187405) (xy 115.865449 -150.193505)
			(xy 115.919406 -150.207611) (xy 115.970735 -150.229423) (xy 116.018341 -150.258477) (xy 116.061209 -150.294152)
			(xy 116.098426 -150.335689) (xy 116.129199 -150.382202) (xy 116.152871 -150.432699) (xy 116.168939 -150.486106)
			(xy 116.177059 -150.541282) (xy 116.177568 -150.569168) (xy 116.177059 -150.597054) (xy 116.168939 -150.65223)
			(xy 116.152871 -150.705637) (xy 116.129199 -150.756134) (xy 116.098426 -150.802647) (xy 116.061209 -150.844184)
			(xy 116.018341 -150.879859) (xy 115.970735 -150.908913) (xy 115.919406 -150.930725) (xy 115.865449 -150.944831)
			(xy 115.810012 -150.950931) (xy 115.754278 -150.948894) (xy 115.699435 -150.938764) (xy 115.646651 -150.920757)
			(xy 115.597051 -150.895256) (xy 115.551693 -150.862805) (xy 115.511544 -150.824096) (xy 115.477458 -150.779953)
			(xy 115.450162 -150.731318) (xy 115.430239 -150.679227) (xy 115.418113 -150.62479) (xy 115.414042 -150.569168)
			(xy 105.151335 -150.569168) (xy 105.18327 -150.598104) (xy 105.217441 -150.639103) (xy 105.245564 -150.684464)
			(xy 105.267092 -150.733301) (xy 105.281603 -150.784663) (xy 105.288815 -150.837545) (xy 105.288586 -150.890916)
			(xy 105.280922 -150.943735) (xy 105.273856 -150.969472) (xy 105.26775 -150.992247) (xy 105.26312 -151.039167)
			(xy 105.267222 -151.086135) (xy 105.279914 -151.131542) (xy 105.300761 -151.17383) (xy 105.329049 -151.211549)
			(xy 105.363807 -151.243404) (xy 105.403843 -151.268304) (xy 105.447783 -151.285395) (xy 105.494122 -151.294089)
			(xy 105.517696 -151.294592) (xy 107.144058 -151.294592) (xy 107.390692 -151.541226) (xy 108.620306 -151.541226)
			(xy 108.684314 -151.4983) (xy 108.699046 -151.462232) (xy 108.710166 -151.436259) (xy 108.738946 -151.38764)
			(xy 108.774583 -151.343799) (xy 108.816297 -151.305694) (xy 108.863175 -151.274158) (xy 108.914191 -151.249883)
			(xy 108.968231 -151.233398) (xy 109.024111 -151.225064) (xy 109.080609 -151.225064) (xy 109.136489 -151.233398)
			(xy 109.190529 -151.249883) (xy 109.241545 -151.274158) (xy 109.288423 -151.305694) (xy 109.330137 -151.343799)
			(xy 109.365774 -151.38764) (xy 109.394554 -151.436259) (xy 109.405674 -151.462232) (xy 109.420152 -151.498046)
			(xy 109.484668 -151.541226) (xy 118.857268 -151.541226) (xy 118.978426 -151.445214) (xy 118.990364 -151.409654)
			(xy 119.000126 -151.382324) (xy 119.026745 -151.330756) (xy 119.060875 -151.28382) (xy 119.101726 -151.242601)
			(xy 119.148354 -151.208052) (xy 119.173752 -151.194008) (xy 119.193527 -151.182999) (xy 119.229165 -151.155105)
			(xy 119.259303 -151.121344) (xy 119.282989 -151.082781) (xy 119.299476 -151.040635) (xy 119.308242 -150.996236)
			(xy 119.309011 -150.950986) (xy 119.305832 -150.928578) (xy 119.301869 -150.901537) (xy 119.300805 -150.846895)
			(xy 119.307551 -150.792661) (xy 119.321969 -150.739945) (xy 119.343764 -150.689827) (xy 119.372489 -150.643332)
			(xy 119.407557 -150.601414) (xy 119.448248 -150.56493) (xy 119.49373 -150.534628) (xy 119.543072 -150.511129)
			(xy 119.595263 -150.494912) (xy 119.649234 -150.486311) (xy 119.70388 -150.485501) (xy 119.758083 -150.4925)
			(xy 119.810731 -150.507163) (xy 119.860747 -150.529191) (xy 119.907107 -150.558133) (xy 119.948862 -150.593395)
			(xy 119.985155 -150.634256) (xy 120.015245 -150.679879) (xy 120.038515 -150.72933) (xy 120.054489 -150.781595)
			(xy 120.062838 -150.835606) (xy 120.063394 -150.890255) (xy 120.056143 -150.944424) (xy 120.041234 -150.997004)
			(xy 120.018974 -151.046917) (xy 119.989817 -151.093142) (xy 119.954361 -151.134732) (xy 119.913331 -151.170835)
			(xy 119.867569 -151.200712) (xy 119.81801 -151.223751) (xy 119.791988 -151.232108) (xy 119.777874 -151.236752)
			(xy 119.752166 -151.251636) (xy 119.730611 -151.272077) (xy 119.714387 -151.296961) (xy 119.704379 -151.32493)
			(xy 119.701131 -151.354458) (xy 119.704823 -151.383933) (xy 119.709692 -151.39797) (xy 119.713756 -151.409654)
			(xy 119.725694 -151.445214) (xy 119.846852 -151.541226) (xy 120.932702 -151.541226) (xy 121.897648 -150.57628)
			(xy 121.9073 -150.552658) (xy 121.919317 -150.524839) (xy 121.950848 -150.473094) (xy 121.990161 -150.426984)
			(xy 122.036269 -150.387666) (xy 122.088011 -150.356131) (xy 122.115834 -150.344124) (xy 122.139456 -150.334472)
			(xy 123.046998 -149.42693) (xy 123.059444 -149.344634) (xy 123.039886 -149.30755) (xy 123.027749 -149.283503)
			(xy 123.009608 -149.232784) (xy 122.99878 -149.180019) (xy 122.995482 -149.126255) (xy 122.999778 -149.072561)
			(xy 123.011582 -149.020005) (xy 123.030662 -148.969632) (xy 123.056636 -148.922443) (xy 123.088989 -148.879377)
			(xy 123.127077 -148.841288) (xy 123.170144 -148.808935) (xy 123.217333 -148.782961) (xy 123.267706 -148.763882)
			(xy 123.320262 -148.752077) (xy 123.373955 -148.747782) (xy 123.42772 -148.75108) (xy 123.480485 -148.761908)
			(xy 123.531204 -148.780049) (xy 123.555252 -148.792184) (xy 123.592336 -148.811742) (xy 123.674632 -148.799296)
			(xy 124.615702 -147.858226) (xy 124.630742 -147.842554) (xy 124.655778 -147.807064) (xy 124.674417 -147.767834)
			(xy 124.686116 -147.726007) (xy 124.690534 -147.6828) (xy 124.687544 -147.639471) (xy 124.677231 -147.59728)
			(xy 124.659897 -147.557457) (xy 124.636045 -147.52116) (xy 124.60637 -147.489446) (xy 124.571736 -147.463238)
			(xy 124.533151 -147.443298) (xy 124.512578 -147.436332) (xy 124.486041 -147.42747) (xy 124.435695 -147.403068)
			(xy 124.389452 -147.371577) (xy 124.348303 -147.333672) (xy 124.313129 -147.290165) (xy 124.284684 -147.241989)
			(xy 124.263577 -147.190175) (xy 124.250263 -147.135836) (xy 124.245024 -147.080134) (xy 124.247975 -147.024265)
			(xy 124.259051 -146.969425) (xy 124.278016 -146.91679) (xy 124.304462 -146.867488) (xy 124.337823 -146.822576)
			(xy 124.377385 -146.783016) (xy 124.422298 -146.749656) (xy 124.471601 -146.723211) (xy 124.524236 -146.704248)
			(xy 124.579076 -146.693173) (xy 124.634946 -146.690225) (xy 124.690647 -146.695465) (xy 124.744986 -146.708781)
			(xy 124.796799 -146.729889) (xy 124.844975 -146.758335) (xy 124.888481 -146.793511) (xy 124.926385 -146.834662)
			(xy 124.957874 -146.880906) (xy 124.982274 -146.931252) (xy 124.991114 -146.957796) (xy 124.998065 -146.978382)
			(xy 125.01798 -147.016995) (xy 125.044174 -147.051656) (xy 125.075885 -147.081355) (xy 125.112186 -147.105225)
			(xy 125.152019 -147.122571) (xy 125.194223 -147.132886) (xy 125.237567 -147.135869) (xy 125.280786 -147.131434)
			(xy 125.32262 -147.119709) (xy 125.361849 -147.101038) (xy 125.39733 -147.075963) (xy 125.413008 -147.06092)
			(xy 125.78588 -146.688048) (xy 126.852426 -146.688048) (xy 126.885446 -146.66468) (xy 126.907052 -146.649855)
			(xy 126.953516 -146.62563) (xy 127.002858 -146.607992) (xy 127.05415 -146.597275) (xy 127.106426 -146.59368)
			(xy 127.158702 -146.597275) (xy 127.209994 -146.607992) (xy 127.259336 -146.62563) (xy 127.3058 -146.649855)
			(xy 127.327406 -146.66468) (xy 127.360426 -146.688048) (xy 130.76936 -146.688048) (xy 137.59942 -139.857988)
			(xy 137.59942 -137.573258) (xy 137.475468 -137.448798) (xy 137.431272 -137.443718) (xy 137.403701 -137.440067)
			(xy 137.349946 -137.425808) (xy 137.29883 -137.403894) (xy 137.251439 -137.374791) (xy 137.208776 -137.339114)
			(xy 137.171745 -137.297621) (xy 137.141132 -137.25119) (xy 137.117586 -137.200807) (xy 137.101605 -137.147538)
			(xy 137.093529 -137.092513) (xy 137.093528 -137.036898) (xy 137.101603 -136.981873) (xy 137.117582 -136.928604)
			(xy 137.141127 -136.87822) (xy 137.171738 -136.831788) (xy 137.208768 -136.790293) (xy 137.25143 -136.754616)
			(xy 137.29882 -136.725511) (xy 137.349935 -136.703596) (xy 137.40369 -136.689335) (xy 137.431272 -136.685782)
			(xy 137.475468 -136.680702) (xy 137.59942 -136.556242) (xy 137.59942 -135.027162) (xy 137.598998 -135.012177)
			(xy 137.591993 -134.983037) (xy 137.578378 -134.956338) (xy 137.558906 -134.933554) (xy 137.534654 -134.915947)
			(xy 137.50696 -134.904487) (xy 137.492232 -134.901686) (xy 137.491978 -134.901686) (xy 137.465652 -134.897128)
			(xy 137.414525 -134.881614) (xy 137.36606 -134.859124) (xy 137.321206 -134.830095) (xy 137.280837 -134.795095)
			(xy 137.245743 -134.754808) (xy 137.216609 -134.710021) (xy 137.194005 -134.66161) (xy 137.178372 -134.610519)
			(xy 137.170016 -134.557748) (xy 137.1691 -134.504327) (xy 137.171938 -134.47776) (xy 137.172446 -134.474204)
			(xy 137.172954 -134.465822) (xy 137.173523 -134.447793) (xy 137.16575 -134.412587) (xy 137.148431 -134.380965)
			(xy 137.136124 -134.367778) (xy 137.0203 -134.251954) (xy 136.373362 -134.251954) (xy 136.351124 -134.252417)
			(xy 136.307328 -134.260165) (xy 136.265549 -134.275417) (xy 136.227062 -134.297707) (xy 136.193042 -134.326357)
			(xy 136.164528 -134.36049) (xy 136.142391 -134.399065) (xy 136.127304 -134.440904) (xy 136.119731 -134.48473)
			(xy 136.119362 -134.50697) (xy 136.118984 -134.534587) (xy 136.111241 -134.589271) (xy 136.095694 -134.642267)
			(xy 136.072669 -134.692469) (xy 136.042647 -134.738826) (xy 136.006255 -134.78037) (xy 135.964254 -134.816234)
			(xy 135.917521 -134.845668) (xy 135.867032 -134.868056) (xy 135.813844 -134.882932) (xy 135.759066 -134.889983)
			(xy 135.703844 -134.889064) (xy 135.649331 -134.880192) (xy 135.596667 -134.863554) (xy 135.546952 -134.839497)
			(xy 135.501225 -134.808524) (xy 135.460441 -134.771281) (xy 135.425453 -134.728548) (xy 135.396991 -134.681217)
			(xy 135.375651 -134.630277) (xy 135.361877 -134.576792) (xy 135.355959 -134.52188) (xy 135.3566 -134.49427)
			(xy 135.356954 -134.471556) (xy 135.350572 -134.426583) (xy 135.336299 -134.383461) (xy 135.314591 -134.343561)
			(xy 135.286138 -134.308153) (xy 135.251845 -134.278366) (xy 135.212805 -134.255146) (xy 135.170261 -134.239234)
			(xy 135.125565 -134.231135) (xy 135.102854 -134.230618) (xy 134.528306 -134.230618) (xy 134.505814 -134.231126)
			(xy 134.46154 -134.239095) (xy 134.41936 -134.254731) (xy 134.380591 -134.277548) (xy 134.346442 -134.306831)
			(xy 134.31798 -134.341668) (xy 134.296094 -134.38097) (xy 134.281467 -134.423511) (xy 134.274555 -134.467962)
			(xy 134.27456 -134.49046) (xy 134.274718 -134.51759) (xy 134.268292 -134.571461) (xy 134.254299 -134.623878)
			(xy 134.23302 -134.673783) (xy 134.204885 -134.720171) (xy 134.170461 -134.762104) (xy 134.130444 -134.798737)
			(xy 134.08564 -134.82933) (xy 134.036954 -134.853267) (xy 133.985367 -134.870065) (xy 133.93192 -134.879384)
			(xy 133.877693 -134.881037) (xy 133.823778 -134.87499) (xy 133.771264 -134.861365) (xy 133.72121 -134.840438)
			(xy 133.674626 -134.812629) (xy 133.632452 -134.778502) (xy 133.595539 -134.738743) (xy 133.579616 -134.716774)
			(xy 133.5662 -134.698242) (xy 133.533853 -134.665895) (xy 133.496234 -134.639866) (xy 133.454561 -134.620995)
			(xy 133.410183 -134.609895) (xy 133.364533 -134.606923) (xy 133.31909 -134.612176) (xy 133.275322 -134.625483)
			(xy 133.25475 -134.635494) (xy 133.231249 -134.64707) (xy 133.18181 -134.664395) (xy 133.130466 -134.674798)
			(xy 133.078182 -134.678084) (xy 133.025939 -134.674191) (xy 132.974719 -134.663193) (xy 132.925484 -134.645296)
			(xy 132.879158 -134.620835) (xy 132.836611 -134.590271) (xy 132.817362 -134.572502) (xy 132.780024 -134.536942)
			(xy 132.676646 -134.538212) (xy 131.191 -136.023604) (xy 125.255274 -136.023604) (xy 124.61621 -136.662668)
			(xy 124.600546 -136.679022) (xy 124.574698 -136.716201) (xy 124.555855 -136.757375) (xy 124.544611 -136.801238)
			(xy 124.541325 -136.8464) (xy 124.546101 -136.891428) (xy 124.558786 -136.934896) (xy 124.57898 -136.975425)
			(xy 124.606041 -137.01173) (xy 124.639111 -137.04266) (xy 124.657866 -137.055352) (xy 124.681229 -137.071073)
			(xy 124.723491 -137.108286) (xy 124.759824 -137.151308) (xy 124.789437 -137.199203) (xy 124.811687 -137.250931)
			(xy 124.826092 -137.305369) (xy 124.832337 -137.361332) (xy 124.830287 -137.417606) (xy 124.819986 -137.472966)
			(xy 124.801659 -137.526211) (xy 124.775704 -137.576184) (xy 124.742684 -137.621797) (xy 124.703318 -137.662061)
			(xy 124.65846 -137.696101) (xy 124.609085 -137.723176) (xy 124.556267 -137.742698) (xy 124.501152 -137.754243)
			(xy 124.444939 -137.757561) (xy 124.388849 -137.752579) (xy 124.334101 -137.739406) (xy 124.281884 -137.718327)
			(xy 124.257308 -137.704576) (xy 124.227336 -137.687304) (xy 124.02947 -137.687304) (xy 124.012824 -137.687851)
			(xy 123.980669 -137.696474) (xy 123.951841 -137.713124) (xy 123.928303 -137.736668) (xy 123.911661 -137.765501)
			(xy 123.903046 -137.797658) (xy 123.90247 -137.814304) (xy 123.90247 -137.852658) (xy 123.923806 -137.884662)
			(xy 123.938629 -137.907719) (xy 123.962227 -137.957193) (xy 123.965189 -137.966719) (xy 126.653129 -137.966719)
			(xy 126.658852 -137.912247) (xy 126.672304 -137.859154) (xy 126.693209 -137.808529) (xy 126.721138 -137.761414)
			(xy 126.755516 -137.718776) (xy 126.795638 -137.681492) (xy 126.840679 -137.650327) (xy 126.889712 -137.625923)
			(xy 126.941732 -137.608781) (xy 126.995668 -137.599252) (xy 127.050412 -137.597533) (xy 127.104839 -137.603659)
			(xy 127.157831 -137.617504) (xy 127.2083 -137.638784) (xy 127.255207 -137.667062) (xy 127.297588 -137.701755)
			(xy 127.334574 -137.742152) (xy 127.365404 -137.787423) (xy 127.389444 -137.836636) (xy 127.398272 -137.862564)
			(xy 127.405615 -137.88383) (xy 127.426711 -137.923563) (xy 127.454471 -137.958961) (xy 127.48803 -137.98892)
			(xy 127.526339 -138.012503) (xy 127.568201 -138.028973) (xy 127.612308 -138.037817) (xy 127.657284 -138.038758)
			(xy 127.701723 -138.031767) (xy 127.723138 -138.02487) (xy 127.746856 -138.017076) (xy 127.795769 -138.007073)
			(xy 127.84557 -138.003542) (xy 127.895405 -138.006543) (xy 127.919988 -138.0109) (xy 127.935747 -138.013408)
			(xy 127.967586 -138.011449) (xy 127.997942 -138.001647) (xy 128.024914 -137.984614) (xy 128.046811 -137.961418)
			(xy 128.062264 -137.933511) (xy 128.070305 -137.902642) (xy 128.070864 -137.886694) (xy 128.071372 -137.866628)
			(xy 128.072146 -137.844965) (xy 128.06719 -137.801905) (xy 128.054992 -137.760312) (xy 128.035906 -137.721395)
			(xy 128.010488 -137.686286) (xy 127.979475 -137.656005) (xy 127.94377 -137.631431) (xy 127.904409 -137.613279)
			(xy 127.862537 -137.602077) (xy 127.840994 -137.599674) (xy 127.813259 -137.596656) (xy 127.759035 -137.583532)
			(xy 127.7073 -137.562651) (xy 127.659158 -137.53446) (xy 127.615633 -137.499558) (xy 127.577655 -137.458691)
			(xy 127.546032 -137.41273) (xy 127.521439 -137.362653) (xy 127.5044 -137.309529) (xy 127.495278 -137.254491)
			(xy 127.494268 -137.19871) (xy 127.501391 -137.143377) (xy 127.516495 -137.089671) (xy 127.539259 -137.038737)
			(xy 127.569197 -136.991661) (xy 127.605671 -136.949445) (xy 127.647903 -136.912991) (xy 127.694993 -136.883075)
			(xy 127.745938 -136.860335) (xy 127.799651 -136.845255) (xy 127.854987 -136.838158) (xy 127.910767 -136.839194)
			(xy 127.965802 -136.848341) (xy 128.018918 -136.865405) (xy 128.068983 -136.890021) (xy 128.11493 -136.921666)
			(xy 128.155779 -136.959663) (xy 128.19066 -137.003204) (xy 128.218829 -137.05136) (xy 128.239686 -137.103104)
			(xy 128.252785 -137.157334) (xy 128.257849 -137.212893) (xy 128.256792 -137.240772) (xy 128.25596 -137.262435)
			(xy 128.260917 -137.305502) (xy 128.273119 -137.3471) (xy 128.29221 -137.386021) (xy 128.317636 -137.421133)
			(xy 128.348658 -137.451415) (xy 128.384372 -137.475986) (xy 128.423742 -137.494133) (xy 128.465623 -137.505328)
			(xy 128.48717 -137.507726) (xy 128.51452 -137.510633) (xy 128.542805 -137.517414) (xy 130.042507 -137.517414)
			(xy 130.049849 -137.462669) (xy 130.065007 -137.409555) (xy 130.087665 -137.359182) (xy 130.117348 -137.312602)
			(xy 130.153437 -137.270787) (xy 130.195178 -137.234613) (xy 130.241698 -137.204835) (xy 130.292025 -137.182075)
			(xy 130.345108 -137.166809) (xy 130.399837 -137.159355) (xy 130.455069 -137.15987) (xy 130.50965 -137.168343)
			(xy 130.536188 -137.176002) (xy 130.556704 -137.181876) (xy 130.599008 -137.187454) (xy 130.641651 -137.185884)
			(xy 130.683431 -137.17721) (xy 130.723173 -137.161675) (xy 130.759761 -137.139717) (xy 130.792165 -137.111954)
			(xy 130.819474 -137.079166) (xy 130.830574 -137.06094) (xy 130.844844 -137.037287) (xy 130.879174 -136.99401)
			(xy 130.919384 -136.956134) (xy 130.964636 -136.924451) (xy 131.013982 -136.899624) (xy 131.066393 -136.882172)
			(xy 131.120773 -136.872458) (xy 131.175984 -136.870687) (xy 131.230875 -136.876894) (xy 131.284296 -136.890952)
			(xy 131.335133 -136.912564) (xy 131.382322 -136.941281) (xy 131.424878 -136.976501) (xy 131.461911 -137.01749)
			(xy 131.492647 -137.063389) (xy 131.516444 -137.113241) (xy 131.532805 -137.166003) (xy 131.541387 -137.220572)
			(xy 131.542012 -137.275809) (xy 131.534665 -137.330558) (xy 131.519502 -137.383676) (xy 131.496839 -137.434053)
			(xy 131.467148 -137.480636) (xy 131.431052 -137.522452) (xy 131.389303 -137.558625) (xy 131.342776 -137.588402)
			(xy 131.292441 -137.611159) (xy 131.239351 -137.62642) (xy 131.184615 -137.633868) (xy 131.129377 -137.633345)
			(xy 131.074792 -137.624864) (xy 131.048252 -137.6172) (xy 131.027726 -137.611367) (xy 130.985425 -137.605783)
			(xy 130.942786 -137.607348) (xy 130.901008 -137.616016) (xy 130.861267 -137.631545) (xy 130.82468 -137.653497)
			(xy 130.792276 -137.681255) (xy 130.764967 -137.714039) (xy 130.753866 -137.732262) (xy 130.739622 -137.755927)
			(xy 130.705293 -137.799198) (xy 130.665084 -137.837067) (xy 130.619835 -137.868743) (xy 130.570492 -137.893565)
			(xy 130.521342 -137.909929) (xy 131.555673 -137.909929) (xy 131.562352 -137.854888) (xy 131.576929 -137.801393)
			(xy 131.599097 -137.750572) (xy 131.628389 -137.703496) (xy 131.664188 -137.661157) (xy 131.70574 -137.624447)
			(xy 131.752168 -137.594138) (xy 131.802495 -137.570871) (xy 131.855661 -137.555135) (xy 131.910544 -137.547262)
			(xy 131.938268 -137.546842) (xy 131.961602 -137.546433) (xy 132.0075 -137.538011) (xy 132.051091 -137.521351)
			(xy 132.090907 -137.497014) (xy 132.125612 -137.465817) (xy 132.154038 -137.428809) (xy 132.175232 -137.387234)
			(xy 132.18848 -137.342489) (xy 132.193337 -137.296077) (xy 132.192014 -137.272776) (xy 132.190309 -137.24491)
			(xy 132.194022 -137.189207) (xy 132.205815 -137.134641) (xy 132.225435 -137.082376) (xy 132.252463 -137.033528)
			(xy 132.286321 -136.989142) (xy 132.326288 -136.950164) (xy 132.371509 -136.917428) (xy 132.421019 -136.891633)
			(xy 132.473759 -136.873329) (xy 132.528604 -136.862908) (xy 132.584383 -136.860592) (xy 132.639903 -136.86643)
			(xy 132.693979 -136.880298) (xy 132.745457 -136.9019) (xy 132.793236 -136.930774) (xy 132.815076 -136.948164)
			(xy 132.833783 -136.962866) (xy 132.875453 -136.985814) (xy 132.920665 -137.00061) (xy 132.96784 -137.006737)
			(xy 133.015332 -137.003981) (xy 133.061481 -136.992438) (xy 133.104678 -136.972511) (xy 133.143414 -136.944896)
			(xy 133.160262 -136.928098) (xy 133.180625 -136.90762) (xy 133.226373 -136.87238) (xy 133.276911 -136.84444)
			(xy 133.331083 -136.824439) (xy 133.387652 -136.812834) (xy 133.445324 -136.809891) (xy 133.502781 -136.815676)
			(xy 133.558708 -136.830058) (xy 133.611828 -136.852707) (xy 133.660926 -136.883106) (xy 133.683248 -136.901428)
			(xy 133.696154 -136.911655) (xy 133.725841 -136.925866) (xy 133.758177 -136.932007) (xy 133.791006 -136.929666)
			(xy 133.822144 -136.919002) (xy 133.849515 -136.900723) (xy 133.860794 -136.888728) (xy 133.880441 -136.867192)
			(xy 133.925191 -136.829832) (xy 133.975103 -136.799714) (xy 134.029016 -136.777539) (xy 134.085674 -136.763822)
			(xy 134.143759 -136.758882) (xy 134.20192 -136.762836) (xy 134.258802 -136.77559) (xy 134.313083 -136.796848)
			(xy 134.338568 -136.811004) (xy 134.353934 -136.81918) (xy 134.387639 -136.82781) (xy 134.422422 -136.827032)
			(xy 134.455707 -136.816905) (xy 134.48503 -136.798179) (xy 134.497064 -136.785604) (xy 134.515898 -136.765192)
			(xy 134.558453 -136.729506) (xy 134.605733 -136.700367) (xy 134.656739 -136.678391) (xy 134.710391 -136.664043)
			(xy 134.765557 -136.657626) (xy 134.821071 -136.659275) (xy 134.875759 -136.668956) (xy 134.928465 -136.686463)
			(xy 134.978076 -136.711428) (xy 135.023543 -136.743322) (xy 135.063905 -136.781472) (xy 135.098309 -136.82507)
			(xy 135.126028 -136.873197) (xy 135.146476 -136.924833) (xy 135.159222 -136.978889) (xy 135.163995 -137.034222)
			(xy 135.160694 -137.089661) (xy 135.155312 -137.11555) (xy 135.416034 -137.11555) (xy 135.420105 -137.059928)
			(xy 135.432231 -137.005491) (xy 135.452154 -136.9534) (xy 135.47945 -136.904765) (xy 135.513536 -136.860622)
			(xy 135.553685 -136.821913) (xy 135.599043 -136.789462) (xy 135.648643 -136.763961) (xy 135.701427 -136.745954)
			(xy 135.75627 -136.735824) (xy 135.812004 -136.733787) (xy 135.867441 -136.739887) (xy 135.921398 -136.753993)
			(xy 135.972727 -136.775805) (xy 136.020333 -136.804859) (xy 136.063201 -136.840534) (xy 136.100418 -136.882071)
			(xy 136.131191 -136.928584) (xy 136.154863 -136.979081) (xy 136.170931 -137.032488) (xy 136.179051 -137.087664)
			(xy 136.17956 -137.11555) (xy 136.179051 -137.143436) (xy 136.170931 -137.198612) (xy 136.154863 -137.252019)
			(xy 136.131191 -137.302516) (xy 136.100418 -137.349029) (xy 136.063201 -137.390566) (xy 136.020333 -137.426241)
			(xy 135.972727 -137.455295) (xy 135.921398 -137.477107) (xy 135.867441 -137.491213) (xy 135.812004 -137.497313)
			(xy 135.75627 -137.495276) (xy 135.701427 -137.485146) (xy 135.648643 -137.467139) (xy 135.599043 -137.441638)
			(xy 135.553685 -137.409187) (xy 135.513536 -137.370478) (xy 135.47945 -137.326335) (xy 135.452154 -137.2777)
			(xy 135.432231 -137.225609) (xy 135.420105 -137.171172) (xy 135.416034 -137.11555) (xy 135.155312 -137.11555)
			(xy 135.14939 -137.144037) (xy 135.130322 -137.196199) (xy 135.103892 -137.245045) (xy 135.070659 -137.289543)
			(xy 135.031326 -137.328752) (xy 134.986723 -137.361843) (xy 134.937793 -137.388118) (xy 134.885571 -137.407021)
			(xy 134.83116 -137.418152) (xy 134.77571 -137.421276) (xy 134.720393 -137.416328) (xy 134.666377 -137.403411)
			(xy 134.614806 -137.382799) (xy 134.590536 -137.369296) (xy 134.575168 -137.361124) (xy 134.541464 -137.352494)
			(xy 134.506682 -137.35327) (xy 134.473397 -137.363396) (xy 134.444075 -137.382121) (xy 134.43204 -137.394696)
			(xy 134.413775 -137.41441) (xy 134.372743 -137.449112) (xy 134.327249 -137.477715) (xy 134.278192 -137.499654)
			(xy 134.226542 -137.514494) (xy 134.173322 -137.521942) (xy 134.119583 -137.521851) (xy 134.066388 -137.514222)
			(xy 134.014789 -137.499206) (xy 133.965807 -137.477101) (xy 133.92041 -137.448344) (xy 133.899656 -137.431272)
			(xy 133.886747 -137.421049) (xy 133.857061 -137.406837) (xy 133.824726 -137.400697) (xy 133.791897 -137.403036)
			(xy 133.76076 -137.4137) (xy 133.733389 -137.431978) (xy 133.72211 -137.443972) (xy 133.704135 -137.463711)
			(xy 133.663615 -137.49847) (xy 133.618644 -137.52724) (xy 133.570101 -137.549459) (xy 133.518934 -137.564692)
			(xy 133.466143 -137.572642) (xy 133.412759 -137.573153) (xy 133.359825 -137.566216) (xy 133.308376 -137.551967)
			(xy 133.259416 -137.530682) (xy 133.213902 -137.502779) (xy 133.193028 -137.486136) (xy 133.174318 -137.471439)
			(xy 133.132648 -137.44849) (xy 133.087437 -137.433693) (xy 133.040263 -137.427566) (xy 132.992772 -137.430321)
			(xy 132.946622 -137.441864) (xy 132.903426 -137.46179) (xy 132.86469 -137.489404) (xy 132.847842 -137.506202)
			(xy 132.829722 -137.524521) (xy 132.789415 -137.556617) (xy 132.745158 -137.583004) (xy 132.697756 -137.603201)
			(xy 132.648069 -137.616842) (xy 132.596999 -137.62368) (xy 132.571236 -137.624058) (xy 132.547903 -137.62447)
			(xy 132.502004 -137.632892) (xy 132.458414 -137.649551) (xy 132.418597 -137.673888) (xy 132.383892 -137.705084)
			(xy 132.355466 -137.742092) (xy 132.334272 -137.783666) (xy 132.321024 -137.828411) (xy 132.316167 -137.874823)
			(xy 132.31749 -137.898124) (xy 132.319161 -137.925801) (xy 132.315499 -137.981125) (xy 132.303866 -138.035336)
			(xy 132.284507 -138.087292) (xy 132.25783 -138.135898) (xy 132.224398 -138.18013) (xy 132.184914 -138.219055)
			(xy 132.14021 -138.251855) (xy 132.091229 -138.277836) (xy 132.039003 -138.296453) (xy 131.984632 -138.307313)
			(xy 131.929261 -138.310187) (xy 131.874058 -138.305014) (xy 131.820184 -138.291904) (xy 131.768777 -138.271133)
			(xy 131.720918 -138.243138) (xy 131.677617 -138.208509) (xy 131.639785 -138.167976) (xy 131.608219 -138.122393)
			(xy 131.583585 -138.072721) (xy 131.566402 -138.020005) (xy 131.557032 -137.965358) (xy 131.555673 -137.909929)
			(xy 130.521342 -137.909929) (xy 130.518086 -137.911013) (xy 130.463712 -137.920724) (xy 130.408506 -137.922493)
			(xy 130.353622 -137.916285) (xy 130.300206 -137.902228) (xy 130.249374 -137.880617) (xy 130.20219 -137.851904)
			(xy 130.159638 -137.816687) (xy 130.122609 -137.775704) (xy 130.091875 -137.729809) (xy 130.068079 -137.679964)
			(xy 130.051718 -137.627208) (xy 130.043134 -137.572644) (xy 130.042507 -137.517414) (xy 128.542805 -137.517414)
			(xy 128.568007 -137.523456) (xy 128.619099 -137.543825) (xy 128.666737 -137.571317) (xy 128.709936 -137.605364)
			(xy 128.747799 -137.645259) (xy 128.779543 -137.690176) (xy 128.804511 -137.739185) (xy 128.822184 -137.791271)
			(xy 128.832196 -137.845354) (xy 128.834342 -137.900315) (xy 128.828575 -137.955014) (xy 128.815015 -138.008319)
			(xy 128.793944 -138.059125) (xy 128.765797 -138.10638) (xy 128.731158 -138.149105) (xy 128.690745 -138.186414)
			(xy 128.645394 -138.217536) (xy 128.596045 -138.241825) (xy 128.543721 -138.258778) (xy 128.489504 -138.268044)
			(xy 128.462024 -138.269218) (xy 128.437935 -138.270379) (xy 128.39082 -138.280646) (xy 128.346483 -138.299605)
			(xy 128.30651 -138.326576) (xy 128.272333 -138.360594) (xy 128.245176 -138.400441) (xy 128.226011 -138.444689)
			(xy 128.220216 -138.4681) (xy 128.213705 -138.495027) (xy 128.194027 -138.546808) (xy 128.167064 -138.595198)
			(xy 128.133385 -138.639179) (xy 128.093698 -138.677824) (xy 128.048838 -138.710323) (xy 127.999748 -138.735989)
			(xy 127.947462 -138.754285) (xy 127.893079 -138.764824) (xy 127.837744 -138.767385) (xy 127.78262 -138.761914)
			(xy 127.728867 -138.748527) (xy 127.677616 -138.727504) (xy 127.629946 -138.699289) (xy 127.586859 -138.664474)
			(xy 127.549261 -138.623792) (xy 127.517944 -138.5781) (xy 127.493567 -138.528357) (xy 127.484632 -138.502136)
			(xy 127.477284 -138.480872) (xy 127.456189 -138.44114) (xy 127.428429 -138.405741) (xy 127.394871 -138.375783)
			(xy 127.356563 -138.3522) (xy 127.314702 -138.335729) (xy 127.270595 -138.326884) (xy 127.225619 -138.325943)
			(xy 127.181181 -138.332934) (xy 127.159766 -138.33983) (xy 127.133751 -138.348396) (xy 127.079963 -138.358723)
			(xy 127.02525 -138.361254) (xy 126.970738 -138.355935) (xy 126.917546 -138.342877) (xy 126.866768 -138.322348)
			(xy 126.819447 -138.294769) (xy 126.776555 -138.260707) (xy 126.738975 -138.220863) (xy 126.707477 -138.176055)
			(xy 126.68271 -138.127203) (xy 126.665182 -138.075312) (xy 126.655254 -138.021449) (xy 126.653129 -137.966719)
			(xy 123.965189 -137.966719) (xy 123.978502 -138.009534) (xy 123.987118 -138.063666) (xy 123.987899 -138.118474)
			(xy 123.980829 -138.17283) (xy 123.966052 -138.225614) (xy 123.943874 -138.27574) (xy 123.91475 -138.322177)
			(xy 123.879281 -138.363967) (xy 123.838196 -138.400252) (xy 123.792342 -138.430283) (xy 123.742662 -138.453443)
			(xy 123.690178 -138.469255) (xy 123.635972 -138.477393) (xy 123.58116 -138.47769) (xy 123.526869 -138.47014)
			(xy 123.474217 -138.454898) (xy 123.44908 -138.44397) (xy 123.429138 -138.435378) (xy 123.387138 -138.424372)
			(xy 123.343877 -138.420669) (xy 123.300618 -138.424379) (xy 123.258619 -138.435393) (xy 123.219106 -138.453391)
			(xy 123.18323 -138.477847) (xy 123.152037 -138.508049) (xy 123.126435 -138.543116) (xy 123.107172 -138.582028)
			(xy 123.100592 -138.60272) (xy 123.092289 -138.628827) (xy 123.069244 -138.678528) (xy 123.039326 -138.724422)
			(xy 123.003152 -138.765563) (xy 122.961464 -138.801108) (xy 122.915121 -138.830323) (xy 122.865075 -138.852609)
			(xy 122.812356 -138.867507) (xy 122.758048 -138.874711) (xy 122.703268 -138.874072) (xy 122.649142 -138.865604)
			(xy 122.596785 -138.849481) (xy 122.547272 -138.826034) (xy 122.501623 -138.795746) (xy 122.460775 -138.759239)
			(xy 122.42557 -138.717265) (xy 122.39673 -138.670687) (xy 122.37485 -138.620462) (xy 122.360379 -138.567624)
			(xy 122.353616 -138.513259) (xy 122.354698 -138.458486) (xy 122.363604 -138.404431) (xy 122.380151 -138.352206)
			(xy 122.403998 -138.302885) (xy 122.434655 -138.257482) (xy 122.471491 -138.216932) (xy 122.513749 -138.182067)
			(xy 122.560559 -138.153606) (xy 122.610959 -138.132133) (xy 122.663913 -138.118091) (xy 122.71833 -138.111767)
			(xy 122.773093 -138.113293) (xy 122.827074 -138.122637) (xy 122.879163 -138.139606) (xy 122.92829 -138.163851)
			(xy 122.973443 -138.194875) (xy 122.993912 -138.213084) (xy 123.010168 -138.228324) (xy 123.049538 -138.244834)
			(xy 123.065068 -138.250891) (xy 123.09807 -138.255519) (xy 123.131142 -138.251425) (xy 123.162019 -138.23889)
			(xy 123.188586 -138.218773) (xy 123.209023 -138.19245) (xy 123.215908 -138.17727) (xy 123.227592 -138.149838)
			(xy 123.225814 -138.12012) (xy 123.224754 -138.097245) (xy 123.227434 -138.05153) (xy 123.231148 -138.028934)
			(xy 123.234627 -138.00698) (xy 123.23476 -137.962535) (xy 123.227161 -137.918744) (xy 123.212061 -137.876942)
			(xy 123.18992 -137.838403) (xy 123.161414 -137.804303) (xy 123.127412 -137.77568) (xy 123.088949 -137.753408)
			(xy 123.047199 -137.738164) (xy 123.003435 -137.730415) (xy 122.981212 -137.729976) (xy 121.670572 -137.729976)
			(xy 121.653951 -137.730507) (xy 121.621834 -137.739084) (xy 121.593027 -137.755673) (xy 121.58091 -137.76706)
			(xy 120.372378 -138.975592) (xy 124.245876 -138.975592) (xy 124.249947 -138.91997) (xy 124.262073 -138.865533)
			(xy 124.281996 -138.813442) (xy 124.309292 -138.764807) (xy 124.343378 -138.720664) (xy 124.383527 -138.681955)
			(xy 124.428885 -138.649504) (xy 124.478485 -138.624003) (xy 124.531269 -138.605996) (xy 124.586112 -138.595866)
			(xy 124.641846 -138.593829) (xy 124.697283 -138.599929) (xy 124.75124 -138.614035) (xy 124.802569 -138.635847)
			(xy 124.850175 -138.664901) (xy 124.893043 -138.700576) (xy 124.93026 -138.742113) (xy 124.961033 -138.788626)
			(xy 124.984705 -138.839123) (xy 125.000773 -138.89253) (xy 125.008893 -138.947706) (xy 125.009402 -138.975592)
			(xy 125.008893 -139.003478) (xy 125.000773 -139.058654) (xy 124.984705 -139.112061) (xy 124.961033 -139.162558)
			(xy 124.93026 -139.209071) (xy 124.893043 -139.250608) (xy 124.850175 -139.286283) (xy 124.802569 -139.315337)
			(xy 124.75124 -139.337149) (xy 124.697283 -139.351255) (xy 124.641846 -139.357355) (xy 124.586112 -139.355318)
			(xy 124.531269 -139.345188) (xy 124.478485 -139.327181) (xy 124.428885 -139.30168) (xy 124.383527 -139.269229)
			(xy 124.343378 -139.23052) (xy 124.309292 -139.186377) (xy 124.281996 -139.137742) (xy 124.262073 -139.085651)
			(xy 124.249947 -139.031214) (xy 124.245876 -138.975592) (xy 120.372378 -138.975592) (xy 118.0973 -141.25067)
			(xy 119.456289 -141.25067) (xy 119.459525 -141.195735) (xy 119.470621 -141.141835) (xy 119.489347 -141.09009)
			(xy 119.515316 -141.041572) (xy 119.547987 -140.99729) (xy 119.586682 -140.958163) (xy 119.630598 -140.925002)
			(xy 119.678825 -140.898496) (xy 119.730359 -140.879196) (xy 119.784132 -140.867502) (xy 119.811546 -140.865098)
			(xy 119.834862 -140.862962) (xy 119.880172 -140.851183) (xy 119.922561 -140.831309) (xy 119.960597 -140.804013)
			(xy 119.992994 -140.770216) (xy 120.018659 -140.731061) (xy 120.036723 -140.68787) (xy 120.046577 -140.642102)
			(xy 120.047766 -140.618718) (xy 120.048989 -140.591229) (xy 120.058418 -140.537018) (xy 120.07554 -140.484725)
			(xy 120.099998 -140.435434) (xy 120.131285 -140.39017) (xy 120.168752 -140.349872) (xy 120.211621 -140.315375)
			(xy 120.259002 -140.287397) (xy 120.309912 -140.266518) (xy 120.363294 -140.253172) (xy 120.418039 -140.247634)
			(xy 120.473012 -140.250021) (xy 120.527072 -140.260283) (xy 120.579096 -140.278207) (xy 120.628004 -140.303421)
			(xy 120.672782 -140.3354) (xy 120.712499 -140.373483) (xy 120.746332 -140.416877) (xy 120.773577 -140.464683)
			(xy 120.793671 -140.515908) (xy 120.798066 -140.534709) (xy 121.889011 -140.534709) (xy 121.890195 -140.479545)
			(xy 121.899314 -140.425128) (xy 121.916177 -140.372591) (xy 121.940434 -140.323033) (xy 121.971577 -140.277486)
			(xy 122.008958 -140.236901) (xy 122.051795 -140.202125) (xy 122.099196 -140.173883) (xy 122.150171 -140.152765)
			(xy 122.176794 -140.145516) (xy 122.197732 -140.139739) (xy 122.23741 -140.122074) (xy 122.273503 -140.097915)
			(xy 122.30496 -140.067969) (xy 122.330863 -140.033107) (xy 122.350457 -139.994346) (xy 122.36317 -139.952816)
			(xy 122.368633 -139.909729) (xy 122.366685 -139.866341) (xy 122.362468 -139.845034) (xy 122.356914 -139.817679)
			(xy 122.353056 -139.761992) (xy 122.357353 -139.706338) (xy 122.369715 -139.651903) (xy 122.389876 -139.599851)
			(xy 122.417408 -139.551293) (xy 122.451721 -139.507265) (xy 122.492084 -139.468706) (xy 122.537634 -139.436441)
			(xy 122.5874 -139.411158) (xy 122.640319 -139.393396) (xy 122.695262 -139.383535) (xy 122.751054 -139.381786)
			(xy 122.806507 -139.388185) (xy 122.860434 -139.402596) (xy 122.911687 -139.424712) (xy 122.959169 -139.45406)
			(xy 123.001868 -139.490014) (xy 123.038873 -139.531806) (xy 123.069392 -139.578544) (xy 123.092776 -139.62923)
			(xy 123.108523 -139.682783) (xy 123.116299 -139.738059) (xy 123.115938 -139.793878) (xy 123.107446 -139.849049)
			(xy 123.091006 -139.902393) (xy 123.090852 -139.902716) (xy 126.628076 -139.902716) (xy 126.629413 -139.847305)
			(xy 126.638753 -139.79267) (xy 126.6559 -139.739961) (xy 126.680493 -139.690287) (xy 126.712014 -139.644695)
			(xy 126.7498 -139.604144) (xy 126.793056 -139.569486) (xy 126.840871 -139.541452) (xy 126.89224 -139.520631)
			(xy 126.946081 -139.507461) (xy 127.00126 -139.50222) (xy 127.056617 -139.505019) (xy 127.110987 -139.515797)
			(xy 127.163225 -139.534329) (xy 127.18796 -139.546838) (xy 127.209347 -139.557569) (xy 127.255077 -139.571639)
			(xy 127.302633 -139.576898) (xy 127.350332 -139.573162) (xy 127.396489 -139.560561) (xy 127.43947 -139.539542)
			(xy 127.477756 -139.510847) (xy 127.509994 -139.475493) (xy 127.522986 -139.455398) (xy 127.537896 -139.432033)
			(xy 127.57349 -139.389545) (xy 127.614857 -139.352654) (xy 127.661127 -139.322136) (xy 127.711325 -139.298635)
			(xy 127.764396 -139.282644) (xy 127.819221 -139.274499) (xy 127.874649 -139.274374) (xy 127.929511 -139.282269)
			(xy 127.982653 -139.298019) (xy 128.032958 -139.321292) (xy 128.079365 -139.351599) (xy 128.1209 -139.388302)
			(xy 128.156686 -139.430628) (xy 128.185972 -139.477687) (xy 128.208141 -139.528487) (xy 128.222727 -139.581961)
			(xy 128.229422 -139.636983) (xy 128.228085 -139.692394) (xy 128.218746 -139.747029) (xy 128.201599 -139.799737)
			(xy 128.177007 -139.84941) (xy 128.145486 -139.895002) (xy 128.1077 -139.935554) (xy 128.064445 -139.970211)
			(xy 128.01663 -139.998246) (xy 127.965262 -140.019067) (xy 127.911422 -140.032237) (xy 127.856243 -140.037478)
			(xy 127.800886 -140.03468) (xy 127.746517 -140.023902) (xy 127.694279 -140.005371) (xy 127.669544 -139.992862)
			(xy 127.648155 -139.982135) (xy 127.602425 -139.968065) (xy 127.55487 -139.962805) (xy 127.507171 -139.966541)
			(xy 127.461015 -139.979141) (xy 127.418034 -140.00016) (xy 127.379748 -140.028853) (xy 127.34751 -140.064208)
			(xy 127.334518 -140.084302) (xy 127.319607 -140.107667) (xy 127.284012 -140.150155) (xy 127.242645 -140.187047)
			(xy 127.196375 -140.217565) (xy 127.146177 -140.241066) (xy 127.093106 -140.257058) (xy 127.03828 -140.265202)
			(xy 126.982852 -140.265328) (xy 126.92799 -140.257433) (xy 126.874847 -140.241683) (xy 126.824542 -140.21841)
			(xy 126.778134 -140.188102) (xy 126.736599 -140.151399) (xy 126.700812 -140.109073) (xy 126.671526 -140.062014)
			(xy 126.649357 -140.011213) (xy 126.634771 -139.957738) (xy 126.628076 -139.902716) (xy 123.090852 -139.902716)
			(xy 123.066968 -139.952772) (xy 123.035845 -139.999111) (xy 122.998303 -140.04042) (xy 122.955141 -140.075817)
			(xy 122.907282 -140.104548) (xy 122.855748 -140.125997) (xy 122.828812 -140.133324) (xy 122.807861 -140.139061)
			(xy 122.76818 -140.156729) (xy 122.732084 -140.180891) (xy 122.700626 -140.210843) (xy 122.674723 -140.245711)
			(xy 122.655131 -140.284478) (xy 122.642421 -140.326013) (xy 122.636963 -140.369105) (xy 122.638917 -140.412497)
			(xy 122.643138 -140.433806) (xy 122.648054 -140.45817) (xy 122.652311 -140.50769) (xy 122.650107 -140.557344)
			(xy 122.646186 -140.581888) (xy 122.642801 -140.60378) (xy 122.642788 -140.648076) (xy 122.650454 -140.691703)
			(xy 122.665566 -140.733341) (xy 122.687667 -140.771729) (xy 122.716088 -140.805705) (xy 122.749967 -140.83424)
			(xy 122.78828 -140.85647) (xy 122.829867 -140.871723) (xy 122.873468 -140.879536) (xy 122.895614 -140.880084)
			(xy 122.923033 -140.88067) (xy 122.977292 -140.888639) (xy 123.02985 -140.904296) (xy 123.079624 -140.927317)
			(xy 123.125589 -140.95723) (xy 123.166797 -140.993416) (xy 123.202398 -141.03513) (xy 123.231658 -141.081512)
			(xy 123.253975 -141.131607) (xy 123.268888 -141.184381) (xy 123.270764 -141.19854) (xy 126.627822 -141.19854)
			(xy 126.632731 -141.143628) (xy 126.645494 -141.089995) (xy 126.665845 -141.038758) (xy 126.693361 -140.990985)
			(xy 126.727469 -140.947672) (xy 126.767457 -140.909719) (xy 126.812492 -140.87792) (xy 126.861636 -140.852935)
			(xy 126.913866 -140.835286) (xy 126.968092 -140.825341) (xy 127.023185 -140.823306) (xy 127.077997 -140.829224)
			(xy 127.131387 -140.842971) (xy 127.18224 -140.864262) (xy 127.229499 -140.892653) (xy 127.272178 -140.927551)
			(xy 127.309388 -140.968231) (xy 127.340353 -141.013843) (xy 127.364429 -141.063439) (xy 127.381114 -141.115984)
			(xy 127.390061 -141.170385) (xy 127.391082 -141.225506) (xy 127.384156 -141.2802) (xy 127.369429 -141.333327)
			(xy 127.347206 -141.38378) (xy 127.31795 -141.430509) (xy 127.300482 -141.451838) (xy 127.294811 -141.45895)
			(xy 130.132834 -141.45895) (xy 130.136905 -141.403328) (xy 130.149031 -141.348891) (xy 130.168954 -141.2968)
			(xy 130.19625 -141.248165) (xy 130.230336 -141.204022) (xy 130.270485 -141.165313) (xy 130.315843 -141.132862)
			(xy 130.365443 -141.107361) (xy 130.418227 -141.089354) (xy 130.47307 -141.079224) (xy 130.528804 -141.077187)
			(xy 130.584241 -141.083287) (xy 130.638198 -141.097393) (xy 130.689527 -141.119205) (xy 130.737133 -141.148259)
			(xy 130.780001 -141.183934) (xy 130.817218 -141.225471) (xy 130.847991 -141.271984) (xy 130.871663 -141.322481)
			(xy 130.887731 -141.375888) (xy 130.895851 -141.431064) (xy 130.89636 -141.45895) (xy 130.895851 -141.486836)
			(xy 130.887731 -141.542012) (xy 130.871663 -141.595419) (xy 130.847991 -141.645916) (xy 130.817218 -141.692429)
			(xy 130.780001 -141.733966) (xy 130.737133 -141.769641) (xy 130.689527 -141.798695) (xy 130.638198 -141.820507)
			(xy 130.584241 -141.834613) (xy 130.528804 -141.840713) (xy 130.47307 -141.838676) (xy 130.418227 -141.828546)
			(xy 130.365443 -141.810539) (xy 130.315843 -141.785038) (xy 130.270485 -141.752587) (xy 130.230336 -141.713878)
			(xy 130.19625 -141.669735) (xy 130.168954 -141.6211) (xy 130.149031 -141.569009) (xy 130.136905 -141.514572)
			(xy 130.132834 -141.45895) (xy 127.294811 -141.45895) (xy 127.290691 -141.464117) (xy 127.276816 -141.492276)
			(xy 127.270258 -141.522975) (xy 127.271416 -141.554346) (xy 127.280222 -141.584478) (xy 127.296137 -141.611536)
			(xy 127.306832 -141.623034) (xy 127.325886 -141.642966) (xy 127.358523 -141.687411) (xy 127.384421 -141.736093)
			(xy 127.40304 -141.787995) (xy 127.413994 -141.842038) (xy 127.417052 -141.897095) (xy 127.412152 -141.952018)
			(xy 127.399396 -142.005664) (xy 127.37905 -142.056914) (xy 127.351536 -142.104701) (xy 127.31743 -142.148029)
			(xy 127.277441 -142.185996) (xy 127.232402 -142.217809) (xy 127.183252 -142.242807) (xy 127.131016 -142.260468)
			(xy 127.07678 -142.270425) (xy 127.021677 -142.27247) (xy 126.966853 -142.26656) (xy 126.913451 -142.252819)
			(xy 126.862584 -142.231532) (xy 126.815311 -142.203144) (xy 126.772618 -142.168246) (xy 126.735394 -142.127565)
			(xy 126.704415 -142.081948) (xy 126.680326 -142.032347) (xy 126.663629 -141.979794) (xy 126.654672 -141.925385)
			(xy 126.653642 -141.870253) (xy 126.66056 -141.815547) (xy 126.675281 -141.762407) (xy 126.6975 -141.711941)
			(xy 126.726754 -141.665198) (xy 126.744222 -141.643862) (xy 126.754012 -141.631583) (xy 126.767887 -141.603424)
			(xy 126.774445 -141.572725) (xy 126.773286 -141.541354) (xy 126.764482 -141.511223) (xy 126.748567 -141.484164)
			(xy 126.737872 -141.472666) (xy 126.718927 -141.452635) (xy 126.686304 -141.408193) (xy 126.660419 -141.359516)
			(xy 126.641812 -141.307621) (xy 126.63087 -141.253586) (xy 126.627822 -141.19854) (xy 123.270764 -141.19854)
			(xy 123.276091 -141.238746) (xy 123.275434 -141.293583) (xy 123.266931 -141.347761) (xy 123.250757 -141.400162)
			(xy 123.227246 -141.449707) (xy 123.196883 -141.495375) (xy 123.160293 -141.536224) (xy 123.11823 -141.571413)
			(xy 123.071562 -141.600215) (xy 123.02125 -141.622038) (xy 122.968332 -141.636431) (xy 122.913898 -141.643097)
			(xy 122.85907 -141.6419) (xy 122.804979 -141.632864) (xy 122.752739 -141.616175) (xy 122.703428 -141.592178)
			(xy 122.658061 -141.561366) (xy 122.617574 -141.524375) (xy 122.582802 -141.481968) (xy 122.554461 -141.435018)
			(xy 122.533134 -141.384494) (xy 122.519263 -141.331437) (xy 122.513133 -141.27694) (xy 122.51487 -141.222127)
			(xy 122.519186 -141.195044) (xy 122.522564 -141.17315) (xy 122.522582 -141.128854) (xy 122.51492 -141.085225)
			(xy 122.49981 -141.043586) (xy 122.47771 -141.005196) (xy 122.44929 -140.971219) (xy 122.415409 -140.942684)
			(xy 122.377095 -140.920454) (xy 122.335507 -140.905204) (xy 122.291905 -140.897394) (xy 122.269758 -140.896848)
			(xy 122.242171 -140.89623) (xy 122.187586 -140.888175) (xy 122.134731 -140.872339) (xy 122.084708 -140.849054)
			(xy 122.038563 -140.818805) (xy 121.997256 -140.782224) (xy 121.961651 -140.740073) (xy 121.93249 -140.693232)
			(xy 121.910382 -140.642679) (xy 121.895787 -140.589467) (xy 121.889011 -140.534709) (xy 120.798066 -140.534709)
			(xy 120.806195 -140.569489) (xy 120.810889 -140.624313) (xy 120.807657 -140.679243) (xy 120.796564 -140.733139)
			(xy 120.777842 -140.784881) (xy 120.751879 -140.833395) (xy 120.719215 -140.877675) (xy 120.680526 -140.916802)
			(xy 120.636616 -140.949963) (xy 120.588396 -140.976471) (xy 120.536868 -140.995774) (xy 120.483101 -141.007472)
			(xy 120.45569 -141.009878) (xy 120.43238 -141.012067) (xy 120.387073 -141.023839) (xy 120.344686 -141.043704)
			(xy 120.30665 -141.070993) (xy 120.274252 -141.104782) (xy 120.248586 -141.14393) (xy 120.230519 -141.187115)
			(xy 120.220661 -141.232876) (xy 120.21947 -141.256258) (xy 120.218234 -141.283749) (xy 120.208808 -141.337966)
			(xy 120.191688 -141.390265) (xy 120.16723 -141.439561) (xy 120.135942 -141.484831) (xy 120.098473 -141.525134)
			(xy 120.055601 -141.559635) (xy 120.008217 -141.587617) (xy 119.957303 -141.6085) (xy 119.903916 -141.621848)
			(xy 119.849166 -141.627387) (xy 119.794188 -141.625) (xy 119.740123 -141.614737) (xy 119.688095 -141.596812)
			(xy 119.639182 -141.571596) (xy 119.594401 -141.539613) (xy 119.55468 -141.501526) (xy 119.520845 -141.458127)
			(xy 119.493598 -141.410316) (xy 119.473505 -141.359085) (xy 119.460982 -141.305499) (xy 119.456289 -141.25067)
			(xy 118.0973 -141.25067) (xy 117.893084 -141.454886) (xy 117.893084 -142.118842) (xy 117.487629 -142.524367)
			(xy 119.456227 -142.524367) (xy 119.459053 -142.468406) (xy 119.470032 -142.41346) (xy 119.48893 -142.360711)
			(xy 119.515339 -142.311293) (xy 119.548693 -142.26627) (xy 119.588272 -142.226608) (xy 119.633227 -142.193162)
			(xy 119.68259 -142.166651) (xy 119.7353 -142.147644) (xy 119.790223 -142.136551) (xy 119.846178 -142.13361)
			(xy 119.901961 -142.138884) (xy 119.956373 -142.152261) (xy 120.008243 -142.173452) (xy 120.056456 -142.202001)
			(xy 120.099976 -142.237295) (xy 120.137865 -142.278575) (xy 120.169309 -142.324952) (xy 120.193632 -142.375429)
			(xy 120.210311 -142.428921) (xy 120.218987 -142.484277) (xy 120.219724 -142.512288) (xy 120.220367 -142.534253)
			(xy 120.228315 -142.577469) (xy 120.243578 -142.618674) (xy 120.265702 -142.656638) (xy 120.294027 -142.690232)
			(xy 120.327708 -142.718452) (xy 120.365741 -142.740458) (xy 120.406993 -142.755593) (xy 120.450233 -142.763407)
			(xy 120.4722 -142.764002) (xy 120.500215 -142.764623) (xy 120.555593 -142.773182) (xy 120.609125 -142.789749)
			(xy 120.659658 -142.813966) (xy 120.706105 -142.845315) (xy 120.747467 -142.883119) (xy 120.782856 -142.926567)
			(xy 120.81151 -142.974723) (xy 120.832812 -143.026553) (xy 120.846304 -143.080941) (xy 120.851696 -143.136717)
			(xy 120.848873 -143.192682) (xy 120.837895 -143.247632) (xy 120.818998 -143.300386) (xy 120.792588 -143.349808)
			(xy 120.759233 -143.394837) (xy 120.719652 -143.434502) (xy 120.674695 -143.467952) (xy 120.625329 -143.494467)
			(xy 120.572615 -143.513477) (xy 120.517688 -143.524572) (xy 120.461729 -143.527514) (xy 120.405942 -143.52224)
			(xy 120.351526 -143.508864) (xy 120.299651 -143.487672) (xy 120.251434 -143.459121) (xy 120.207911 -143.423825)
			(xy 120.170018 -143.382543) (xy 120.138571 -143.336162) (xy 120.114246 -143.285681) (xy 120.097566 -143.232185)
			(xy 120.088889 -143.176825) (xy 120.088152 -143.148812) (xy 120.087434 -143.126851) (xy 120.079489 -143.083643)
			(xy 120.064231 -143.042446) (xy 120.042115 -143.004486) (xy 120.013801 -142.970895) (xy 119.980131 -142.942675)
			(xy 119.942109 -142.920665) (xy 119.900869 -142.905523) (xy 119.857639 -142.897699) (xy 119.835676 -142.897098)
			(xy 119.807664 -142.896451) (xy 119.75229 -142.88789) (xy 119.698763 -142.871321) (xy 119.648236 -142.847102)
			(xy 119.601794 -142.815754) (xy 119.560436 -142.77795) (xy 119.525053 -142.734504) (xy 119.496404 -142.686349)
			(xy 119.475106 -142.634523) (xy 119.461617 -142.580139) (xy 119.456227 -142.524367) (xy 117.487629 -142.524367)
			(xy 116.42598 -143.5862) (xy 115.814602 -143.5862) (xy 115.797985 -143.58674) (xy 115.76588 -143.595332)
			(xy 115.737088 -143.611933) (xy 115.72494 -143.623284) (xy 115.510604 -143.83762) (xy 122.513528 -143.83762)
			(xy 122.513939 -143.783042) (xy 122.522123 -143.729079) (xy 122.537913 -143.676833) (xy 122.560986 -143.62737)
			(xy 122.590872 -143.581699) (xy 122.626962 -143.540753) (xy 122.668517 -143.505368) (xy 122.71469 -143.476265)
			(xy 122.76454 -143.454039) (xy 122.817048 -143.439142) (xy 122.871142 -143.43188) (xy 122.92572 -143.4324)
			(xy 122.952764 -143.436086) (xy 122.974426 -143.438985) (xy 123.01812 -143.438162) (xy 123.061029 -143.429871)
			(xy 123.101885 -143.414358) (xy 123.139482 -143.392081) (xy 123.172711 -143.363696) (xy 123.200591 -143.330043)
			(xy 123.222299 -143.292113) (xy 123.237193 -143.251028) (xy 123.244835 -143.207999) (xy 123.245372 -143.18615)
			(xy 123.245626 -143.170656) (xy 123.246069 -143.148201) (xy 123.240108 -143.103693) (xy 123.226419 -143.060925)
			(xy 123.205426 -143.021228) (xy 123.177783 -142.985839) (xy 123.144352 -142.955858) (xy 123.106171 -142.93222)
			(xy 123.064431 -142.915659) (xy 123.02043 -142.906691) (xy 122.975538 -142.905596) (xy 122.953272 -142.908528)
			(xy 122.925949 -142.91223) (xy 122.870816 -142.912734) (xy 122.816184 -142.905297) (xy 122.763192 -142.890076)
			(xy 122.712942 -142.867386) (xy 122.66648 -142.8377) (xy 122.624775 -142.801637) (xy 122.588694 -142.759946)
			(xy 122.558989 -142.713497) (xy 122.536279 -142.663256) (xy 122.521035 -142.61027) (xy 122.513576 -142.555642)
			(xy 122.514057 -142.500508) (xy 122.522468 -142.446018) (xy 122.538634 -142.393306) (xy 122.562218 -142.343469)
			(xy 122.592729 -142.297546) (xy 122.629531 -142.256491) (xy 122.67186 -142.221161) (xy 122.718832 -142.19229)
			(xy 122.76947 -142.170481) (xy 122.82272 -142.156186) (xy 122.877473 -142.149704) (xy 122.932589 -142.15117)
			(xy 122.98692 -142.160553) (xy 123.039335 -142.177657) (xy 123.088743 -142.202128) (xy 123.134114 -142.233454)
			(xy 123.174505 -142.270984) (xy 123.209074 -142.313937) (xy 123.237101 -142.361417) (xy 123.258002 -142.412437)
			(xy 123.271343 -142.465934) (xy 123.276846 -142.520794) (xy 123.276106 -142.548356) (xy 123.275615 -142.570811)
			(xy 123.281578 -142.615324) (xy 123.295272 -142.658096) (xy 123.31627 -142.697795) (xy 123.343918 -142.733187)
			(xy 123.377355 -142.763168) (xy 123.415542 -142.786806) (xy 123.457288 -142.803365) (xy 123.501295 -142.812329)
			(xy 123.546192 -142.813419) (xy 123.56846 -142.810484) (xy 123.597271 -142.806559) (xy 123.655415 -142.806474)
			(xy 123.7129 -142.815203) (xy 123.768398 -142.832545) (xy 123.820626 -142.858098) (xy 123.844812 -142.874238)
			(xy 123.863391 -142.886598) (xy 123.903914 -142.905273) (xy 123.947076 -142.916587) (xy 123.991551 -142.920191)
			(xy 124.035971 -142.915975) (xy 124.078973 -142.90407) (xy 124.119237 -142.884839) (xy 124.155524 -142.858875)
			(xy 124.171456 -142.84325) (xy 124.191406 -142.823608) (xy 124.235972 -142.789727) (xy 124.285011 -142.762721)
			(xy 124.33747 -142.743172) (xy 124.392223 -142.731498) (xy 124.448094 -142.727951) (xy 124.503883 -142.732607)
			(xy 124.558393 -142.745366) (xy 124.610453 -142.765953) (xy 124.658946 -142.793926) (xy 124.702831 -142.828686)
			(xy 124.728372 -142.85587) (xy 130.107652 -142.85587) (xy 130.111543 -142.801528) (xy 130.123128 -142.748292)
			(xy 130.142172 -142.697247) (xy 130.168286 -142.649432) (xy 130.200939 -142.60582) (xy 130.239466 -142.567299)
			(xy 130.283083 -142.534653) (xy 130.330902 -142.508546) (xy 130.38195 -142.489511) (xy 130.435188 -142.477935)
			(xy 130.489531 -142.474052) (xy 130.543873 -142.477943) (xy 130.597109 -142.489528) (xy 130.648153 -142.508572)
			(xy 130.695969 -142.534686) (xy 130.718052 -142.550642) (xy 130.737064 -142.564238) (xy 130.778947 -142.58497)
			(xy 130.823915 -142.597696) (xy 130.870452 -142.601986) (xy 130.916989 -142.597696) (xy 130.961957 -142.58497)
			(xy 131.00384 -142.564238) (xy 131.022852 -142.550642) (xy 131.044894 -142.534611) (xy 131.092726 -142.508476)
			(xy 131.143791 -142.489415) (xy 131.197048 -142.477816) (xy 131.251415 -142.473915) (xy 131.305783 -142.477791)
			(xy 131.359045 -142.489367) (xy 131.410119 -142.508405) (xy 131.457962 -142.534518) (xy 131.501602 -142.567175)
			(xy 131.540149 -142.605711) (xy 131.572819 -142.649341) (xy 131.598947 -142.697177) (xy 131.618001 -142.748244)
			(xy 131.629592 -142.801503) (xy 131.633485 -142.85587) (xy 131.629601 -142.910237) (xy 131.618018 -142.963499)
			(xy 131.598972 -143.014569) (xy 131.572852 -143.062409) (xy 131.540188 -143.106044) (xy 131.501647 -143.144585)
			(xy 131.458012 -143.177249) (xy 131.410173 -143.20337) (xy 131.359103 -143.222417) (xy 131.305842 -143.234)
			(xy 131.251475 -143.237885) (xy 131.197108 -143.233993) (xy 131.143848 -143.222402) (xy 131.092781 -143.203349)
			(xy 131.044945 -143.177222) (xy 131.022852 -143.161258) (xy 131.00384 -143.147662) (xy 130.961957 -143.12693)
			(xy 130.916989 -143.114204) (xy 130.870452 -143.109914) (xy 130.823915 -143.114204) (xy 130.778947 -143.12693)
			(xy 130.737064 -143.147662) (xy 130.718052 -143.161258) (xy 130.695918 -143.177146) (xy 130.648099 -143.203253)
			(xy 130.597051 -143.222288) (xy 130.543814 -143.233865) (xy 130.489471 -143.237748) (xy 130.435128 -143.233857)
			(xy 130.381893 -143.222272) (xy 130.330848 -143.203229) (xy 130.283033 -143.177115) (xy 130.239421 -143.144462)
			(xy 130.200899 -143.105935) (xy 130.168253 -143.062317) (xy 130.142147 -143.014498) (xy 130.123111 -142.96345)
			(xy 130.111535 -142.910213) (xy 130.107652 -142.85587) (xy 124.728372 -142.85587) (xy 124.741165 -142.869486)
			(xy 124.773125 -142.91545) (xy 124.798025 -142.965591) (xy 124.815331 -143.018832) (xy 124.82467 -143.07403)
			(xy 124.825843 -143.130001) (xy 124.818825 -143.185543) (xy 124.803765 -143.239462) (xy 124.780987 -143.290602)
			(xy 124.750981 -143.337864) (xy 124.71439 -143.380235) (xy 124.672001 -143.416803) (xy 124.624722 -143.446784)
			(xy 124.57357 -143.469534) (xy 124.519643 -143.484565) (xy 124.464097 -143.491554) (xy 124.408127 -143.490351)
			(xy 124.352934 -143.480982) (xy 124.299702 -143.463648) (xy 124.249574 -143.438721) (xy 124.22632 -143.423132)
			(xy 124.207726 -143.410794) (xy 124.167207 -143.392111) (xy 124.124048 -143.38079) (xy 124.079575 -143.377181)
			(xy 124.035155 -143.381393) (xy 123.992153 -143.393297) (xy 123.951891 -143.412528) (xy 123.915606 -143.438494)
			(xy 123.899676 -143.45412) (xy 123.881279 -143.472325) (xy 123.840452 -143.504131) (xy 123.795695 -143.53012)
			(xy 123.747834 -143.549813) (xy 123.697747 -143.562849) (xy 123.646358 -143.568988) (xy 123.594611 -143.568115)
			(xy 123.568968 -143.56461) (xy 123.547301 -143.561749) (xy 123.50361 -143.562567) (xy 123.460703 -143.570853)
			(xy 123.419849 -143.586361) (xy 123.382252 -143.608634) (xy 123.349023 -143.637015) (xy 123.321143 -143.670665)
			(xy 123.299435 -143.70859) (xy 123.28454 -143.749673) (xy 123.276897 -143.792698) (xy 123.27636 -143.814546)
			(xy 123.275779 -143.841834) (xy 123.267811 -143.895829) (xy 123.25223 -143.948138) (xy 123.229355 -143.997693)
			(xy 123.199651 -144.043483) (xy 123.163726 -144.084573) (xy 123.122313 -144.120124) (xy 123.076256 -144.149412)
			(xy 123.026496 -144.171837) (xy 122.974048 -144.186944) (xy 122.919983 -144.194422) (xy 122.865404 -144.194121)
			(xy 122.811425 -144.186045) (xy 122.759147 -144.170359) (xy 122.709638 -144.147385) (xy 122.663908 -144.11759)
			(xy 122.62289 -144.081583) (xy 122.587421 -144.040098) (xy 122.558226 -143.993983) (xy 122.5359 -143.944178)
			(xy 122.520899 -143.8917) (xy 122.513528 -143.83762) (xy 115.510604 -143.83762) (xy 115.111944 -144.23628)
			(xy 124.214727 -144.23628) (xy 124.217562 -144.180353) (xy 124.228543 -144.125441) (xy 124.247435 -144.072725)
			(xy 124.273832 -144.023338) (xy 124.307166 -143.978341) (xy 124.346721 -143.938701) (xy 124.391647 -143.905271)
			(xy 124.440977 -143.878768) (xy 124.493653 -143.859763) (xy 124.548541 -143.848664) (xy 124.604462 -143.84571)
			(xy 124.660214 -143.850963) (xy 124.714599 -143.864312) (xy 124.766448 -143.885469) (xy 124.814646 -143.913979)
			(xy 124.858157 -143.94923) (xy 124.896047 -143.990464) (xy 124.927501 -144.036795) (xy 124.951843 -144.087227)
			(xy 124.968549 -144.140676) (xy 124.977261 -144.195993) (xy 124.977792 -144.25199) (xy 124.970129 -144.307462)
			(xy 124.954438 -144.361218) (xy 124.931057 -144.412102) (xy 124.916184 -144.43583) (xy 124.904084 -144.455262)
			(xy 124.886367 -144.497466) (xy 124.876495 -144.542161) (xy 124.874785 -144.587902) (xy 124.881295 -144.633209)
			(xy 124.881594 -144.634104) (xy 126.703935 -144.634104) (xy 126.707812 -144.579708) (xy 126.719393 -144.526419)
			(xy 126.738444 -144.475321) (xy 126.764575 -144.427456) (xy 126.780544 -144.40535) (xy 126.794091 -144.386306)
			(xy 126.814824 -144.34443) (xy 126.827553 -144.29947) (xy 126.831849 -144.25294) (xy 126.827568 -144.206409)
			(xy 126.814853 -144.161445) (xy 126.794133 -144.119563) (xy 126.780544 -144.10055) (xy 126.764584 -144.078462)
			(xy 126.738463 -144.030636) (xy 126.719415 -143.97958) (xy 126.707827 -143.926333) (xy 126.703935 -143.871978)
			(xy 126.707819 -143.817623) (xy 126.719399 -143.764374) (xy 126.73844 -143.713315) (xy 126.764554 -143.665485)
			(xy 126.797209 -143.621859) (xy 126.83574 -143.583325) (xy 126.879364 -143.550667) (xy 126.927191 -143.52455)
			(xy 126.978249 -143.505505) (xy 127.031497 -143.493921) (xy 127.085852 -143.490033) (xy 127.140207 -143.493921)
			(xy 127.193455 -143.505505) (xy 127.244513 -143.52455) (xy 127.29234 -143.550667) (xy 127.335964 -143.583325)
			(xy 127.374495 -143.621859) (xy 127.40715 -143.665485) (xy 127.433264 -143.713315) (xy 127.452305 -143.764374)
			(xy 127.463885 -143.817623) (xy 127.467769 -143.871978) (xy 127.463877 -143.926333) (xy 127.452289 -143.97958)
			(xy 127.433241 -144.030636) (xy 127.40712 -144.078462) (xy 127.39116 -144.10055) (xy 127.37752 -144.119531)
			(xy 127.356795 -144.161423) (xy 127.344077 -144.206398) (xy 127.339794 -144.25294) (xy 127.344091 -144.299481)
			(xy 127.356824 -144.344451) (xy 127.377562 -144.386337) (xy 127.39116 -144.40535) (xy 127.406961 -144.427295)
			(xy 127.43294 -144.474719) (xy 127.45196 -144.525337) (xy 127.463639 -144.578135) (xy 127.467742 -144.632052)
			(xy 127.464189 -144.686009) (xy 127.453049 -144.738923) (xy 127.434547 -144.789733) (xy 127.409053 -144.83742)
			(xy 127.393446 -144.859502) (xy 127.38489 -144.871859) (xy 127.37331 -144.899588) (xy 127.368544 -144.929258)
			(xy 127.370856 -144.959219) (xy 127.380117 -144.987806) (xy 127.395814 -145.013431) (xy 127.406146 -145.024348)
			(xy 127.42568 -145.044513) (xy 127.459173 -145.08957) (xy 127.473637 -145.11655) (xy 129.243834 -145.11655)
			(xy 129.247905 -145.060928) (xy 129.260031 -145.006491) (xy 129.279954 -144.9544) (xy 129.30725 -144.905765)
			(xy 129.341336 -144.861622) (xy 129.381485 -144.822913) (xy 129.426843 -144.790462) (xy 129.476443 -144.764961)
			(xy 129.529227 -144.746954) (xy 129.58407 -144.736824) (xy 129.639804 -144.734787) (xy 129.695241 -144.740887)
			(xy 129.749198 -144.754993) (xy 129.800527 -144.776805) (xy 129.848133 -144.805859) (xy 129.891001 -144.841534)
			(xy 129.928218 -144.883071) (xy 129.958991 -144.929584) (xy 129.982663 -144.980081) (xy 129.998731 -145.033488)
			(xy 130.006851 -145.088664) (xy 130.00736 -145.11655) (xy 130.006851 -145.144436) (xy 129.998731 -145.199612)
			(xy 129.982663 -145.253019) (xy 129.958991 -145.303516) (xy 129.928218 -145.350029) (xy 129.891001 -145.391566)
			(xy 129.848133 -145.427241) (xy 129.800527 -145.456295) (xy 129.749198 -145.478107) (xy 129.695241 -145.492213)
			(xy 129.639804 -145.498313) (xy 129.58407 -145.496276) (xy 129.529227 -145.486146) (xy 129.476443 -145.468139)
			(xy 129.426843 -145.442638) (xy 129.381485 -145.410187) (xy 129.341336 -145.371478) (xy 129.30725 -145.327335)
			(xy 129.279954 -145.2787) (xy 129.260031 -145.226609) (xy 129.247905 -145.172172) (xy 129.243834 -145.11655)
			(xy 127.473637 -145.11655) (xy 127.485699 -145.13905) (xy 127.504687 -145.191884) (xy 127.515724 -145.24693)
			(xy 127.518574 -145.303) (xy 127.513174 -145.358881) (xy 127.499641 -145.413368) (xy 127.478267 -145.465282)
			(xy 127.449515 -145.513503) (xy 127.414005 -145.556988) (xy 127.372504 -145.594799) (xy 127.32591 -145.626117)
			(xy 127.275228 -145.650268) (xy 127.221553 -145.666729) (xy 127.166045 -145.675144) (xy 127.109904 -145.675332)
			(xy 127.054341 -145.667288) (xy 127.000557 -145.651187) (xy 126.949715 -145.627376) (xy 126.902912 -145.59637)
			(xy 126.861159 -145.558838) (xy 126.825359 -145.515591) (xy 126.796285 -145.467564) (xy 126.774564 -145.415794)
			(xy 126.760667 -145.361399) (xy 126.754893 -145.305555) (xy 126.757367 -145.249468) (xy 126.768036 -145.194349)
			(xy 126.786669 -145.141389) (xy 126.812864 -145.091733) (xy 126.829058 -145.068798) (xy 126.837614 -145.056441)
			(xy 126.849193 -145.028711) (xy 126.853959 -144.999042) (xy 126.851647 -144.969081) (xy 126.842386 -144.940494)
			(xy 126.826689 -144.91487) (xy 126.816358 -144.903952) (xy 126.797391 -144.884358) (xy 126.764688 -144.840718)
			(xy 126.73853 -144.792868) (xy 126.719452 -144.74178) (xy 126.707841 -144.688497) (xy 126.703935 -144.634104)
			(xy 124.881594 -144.634104) (xy 124.895812 -144.676618) (xy 124.917869 -144.716726) (xy 124.931932 -144.734788)
			(xy 124.949263 -144.756792) (xy 124.977891 -144.804935) (xy 124.999173 -144.856746) (xy 125.012649 -144.911112)
			(xy 125.018031 -144.966865) (xy 125.015204 -145.022805) (xy 125.004227 -145.077731) (xy 124.985336 -145.130461)
			(xy 124.958939 -145.179862) (xy 124.925602 -145.224872) (xy 124.886041 -145.264524) (xy 124.841108 -145.297966)
			(xy 124.791768 -145.324477) (xy 124.739082 -145.34349) (xy 124.684182 -145.354594) (xy 124.628248 -145.357551)
			(xy 124.572483 -145.352297) (xy 124.518086 -145.338946) (xy 124.466225 -145.317785) (xy 124.418017 -145.289268)
			(xy 124.374496 -145.254008) (xy 124.336598 -145.212764) (xy 124.305139 -145.166421) (xy 124.280794 -145.115977)
			(xy 124.264087 -145.062515) (xy 124.255377 -145.007185) (xy 124.25485 -144.951176) (xy 124.262519 -144.895691)
			(xy 124.278219 -144.841925) (xy 124.301612 -144.791032) (xy 124.31649 -144.7673) (xy 124.328554 -144.747848)
			(xy 124.346268 -144.705648) (xy 124.356142 -144.660959) (xy 124.357855 -144.615223) (xy 124.351352 -144.569921)
			(xy 124.336844 -144.526514) (xy 124.314799 -144.486406) (xy 124.300742 -144.468342) (xy 124.283447 -144.446317)
			(xy 124.254833 -144.39818) (xy 124.233565 -144.346377) (xy 124.2201 -144.292021) (xy 124.214727 -144.23628)
			(xy 115.111944 -144.23628) (xy 113.813844 -145.53438) (xy 98.15703 -145.53438) (xy 98.093022 -145.470118)
			(xy 98.080889 -145.458656) (xy 98.052011 -145.441938) (xy 98.019789 -145.43327) (xy 98.003106 -145.43278)
			(xy 97.53727 -145.43278) (xy 94.685866 -142.581376) (xy 94.374208 -142.581376) (xy 89.830656 -138.037824)
			(xy 89.830656 -137.26033) (xy 89.830126 -137.243691) (xy 89.821443 -137.211565) (xy 89.804738 -137.182782)
			(xy 89.793318 -137.170668) (xy 89.15908 -136.53643) (xy 89.15908 -135.571992) (xy 89.158597 -135.555804)
			(xy 89.150448 -135.52447) (xy 89.134677 -135.496195) (xy 89.112299 -135.472798) (xy 89.084754 -135.455784)
			(xy 89.069418 -135.45058) (xy 89.043798 -135.442186) (xy 88.995035 -135.419193) (xy 88.949996 -135.389563)
			(xy 88.909577 -135.353887) (xy 88.874584 -135.312875) (xy 88.845715 -135.267344) (xy 88.823544 -135.218202)
			(xy 88.808514 -135.166428) (xy 88.800923 -135.113053) (xy 88.800924 -135.059141) (xy 88.808515 -135.005766)
			(xy 88.823546 -134.953992) (xy 88.845718 -134.904851) (xy 88.874588 -134.85932) (xy 88.909581 -134.818309)
			(xy 88.95 -134.782633) (xy 88.99504 -134.753004) (xy 89.043804 -134.730012) (xy 89.069418 -134.7216)
			(xy 89.109296 -134.709154) (xy 89.15908 -134.642098) (xy 89.15908 -133.287516) (xy 88.220296 -132.348478)
			(xy 88.220296 -132.1562) (xy 87.79002 -131.725924) (xy 87.776558 -131.717796) (xy 87.750156 -131.701232)
			(xy 87.702637 -131.660905) (xy 87.662304 -131.613393) (xy 87.645748 -131.586986) (xy 87.63762 -131.573524)
			(xy 87.54364 -131.479544) (xy 87.54364 -130.298952) (xy 87.450676 -130.205734) (xy 87.450676 -127.11811)
			(xy 87.450221 -127.096639) (xy 87.442987 -127.054312) (xy 87.428741 -127.013802) (xy 87.407888 -126.976264)
			(xy 87.381021 -126.942766) (xy 87.348905 -126.91426) (xy 87.312455 -126.891559) (xy 87.272707 -126.875309)
			(xy 87.230793 -126.865972) (xy 87.209376 -126.864364) (xy 87.181811 -126.862475) (xy 87.127613 -126.851745)
			(xy 87.07553 -126.833308) (xy 87.026652 -126.80755) (xy 86.982002 -126.77501) (xy 86.942512 -126.736368)
			(xy 86.909011 -126.692434) (xy 86.882198 -126.644126) (xy 86.862636 -126.592456) (xy 86.850732 -126.538503)
			(xy 86.846736 -126.483398) (xy 86.850732 -126.428293) (xy 86.862637 -126.374341) (xy 86.8822 -126.32267)
			(xy 86.909013 -126.274363) (xy 86.942515 -126.230429) (xy 86.982004 -126.191788) (xy 87.026655 -126.159248)
			(xy 87.075534 -126.133491) (xy 87.127617 -126.115054) (xy 87.181815 -126.104325) (xy 87.209376 -126.102364)
			(xy 87.230804 -126.100844) (xy 87.272733 -126.091514) (xy 87.312495 -126.075263) (xy 87.348957 -126.052556)
			(xy 87.381079 -126.024039) (xy 87.407947 -125.990525) (xy 87.428794 -125.952968) (xy 87.443026 -125.91244)
			(xy 87.450238 -125.870095) (xy 87.450676 -125.848618) (xy 87.450676 -123.620022) (xy 86.798658 -122.968004)
			(xy 86.782177 -122.952247) (xy 86.744701 -122.926283) (xy 86.703193 -122.907422) (xy 86.658985 -122.896271)
			(xy 86.613498 -122.893188) (xy 86.56819 -122.898271) (xy 86.524517 -122.911357) (xy 86.483879 -122.932026)
			(xy 86.46541 -122.945398) (xy 86.443443 -122.961487) (xy 86.39585 -122.98794) (xy 86.344981 -123.007358)
			(xy 86.291868 -123.019348) (xy 86.237589 -123.023667) (xy 86.183248 -123.020227) (xy 86.129948 -123.009097)
			(xy 86.078771 -122.990503) (xy 86.030757 -122.964824) (xy 85.986881 -122.932581) (xy 85.948033 -122.894428)
			(xy 85.915004 -122.85114) (xy 85.888463 -122.803597) (xy 85.868949 -122.752764) (xy 85.856859 -122.699673)
			(xy 85.852439 -122.645403) (xy 85.855778 -122.591056) (xy 85.866808 -122.537735) (xy 85.885306 -122.486524)
			(xy 85.89772 -122.46229) (xy 85.907976 -122.441931) (xy 85.921869 -122.398518) (xy 85.927801 -122.353323)
			(xy 85.925584 -122.307796) (xy 85.915288 -122.263392) (xy 85.897242 -122.221534) (xy 85.872025 -122.183563)
			(xy 85.840443 -122.150695) (xy 85.822282 -122.136916) (xy 85.801312 -122.121246) (xy 85.763451 -122.085093)
			(xy 85.730883 -122.044108) (xy 85.704219 -121.999058) (xy 85.683959 -121.950788) (xy 85.670482 -121.900203)
			(xy 85.666834 -121.87428) (xy 85.6615 -121.830846) (xy 84.97824 -121.14784) (xy 84.83854 -121.14784)
			(xy 82.907886 -119.217186) (xy 78.195932 -119.217186) (xy 78.166468 -119.217186) (xy 76.951586 -119.217186)
			(xy 76.934938 -119.217731) (xy 76.902778 -119.226351) (xy 76.873943 -119.243) (xy 76.8504 -119.266543)
			(xy 76.833751 -119.295378) (xy 76.825131 -119.327538) (xy 76.824586 -119.344186) (xy 76.824586 -119.379238)
			(xy 76.84262 -119.40921) (xy 76.853168 -119.427495) (xy 76.870606 -119.465938) (xy 76.877418 -119.485918)
			(xy 76.885017 -119.507491) (xy 76.906836 -119.547684) (xy 76.935493 -119.583326) (xy 76.970064 -119.613267)
			(xy 77.009434 -119.63654) (xy 77.052331 -119.652395) (xy 77.097373 -119.660321) (xy 77.120242 -119.66067)
			(xy 77.148473 -119.661027) (xy 77.204357 -119.669048) (xy 77.258449 -119.685218) (xy 77.309567 -119.709185)
			(xy 77.356593 -119.740424) (xy 77.398501 -119.778255) (xy 77.434375 -119.821849) (xy 77.463432 -119.870255)
			(xy 77.485036 -119.922415) (xy 77.498715 -119.97719) (xy 77.504171 -120.033383) (xy 77.501285 -120.089766)
			(xy 77.490119 -120.145108) (xy 77.470918 -120.1982) (xy 77.4441 -120.247881) (xy 77.427582 -120.270778)
			(xy 77.413985 -120.28979) (xy 77.39325 -120.331675) (xy 77.380522 -120.376644) (xy 77.376228 -120.423182)
			(xy 77.380515 -120.469721) (xy 77.393238 -120.514692) (xy 77.413967 -120.556579) (xy 77.427582 -120.575578)
			(xy 77.441352 -120.594525) (xy 77.46466 -120.635152) (xy 77.474064 -120.656604) (xy 77.4836 -120.677936)
			(xy 77.509258 -120.71698) (xy 77.541612 -120.750685) (xy 77.579576 -120.777916) (xy 77.621873 -120.797759)
			(xy 77.667082 -120.809546) (xy 77.713683 -120.812882) (xy 77.736954 -120.810782) (xy 77.752456 -120.809168)
			(xy 77.78361 -120.808155) (xy 77.799184 -120.80875) (xy 77.830172 -120.81002) (xy 77.858366 -120.797066)
			(xy 77.873267 -120.789642) (xy 77.898842 -120.768345) (xy 77.91803 -120.741152) (xy 77.929524 -120.709918)
			(xy 77.932539 -120.676774) (xy 77.92687 -120.643979) (xy 77.920342 -120.628664) (xy 77.901546 -120.587516)
			(xy 77.884274 -120.571006) (xy 77.864239 -120.551131) (xy 77.829659 -120.506534) (xy 77.802027 -120.457329)
			(xy 77.781945 -120.40459) (xy 77.769853 -120.349468) (xy 77.766014 -120.293166) (xy 77.770511 -120.236913)
			(xy 77.783247 -120.181936) (xy 77.803944 -120.129436) (xy 77.83215 -120.080558) (xy 77.867249 -120.036368)
			(xy 77.908476 -119.997832) (xy 77.95493 -119.965791) (xy 78.005597 -119.940943) (xy 78.059373 -119.923831)
			(xy 78.115083 -119.914828) (xy 78.171512 -119.914131) (xy 78.218305 -119.920512) (xy 79.876902 -119.920512)
			(xy 79.880973 -119.86489) (xy 79.893099 -119.810453) (xy 79.913022 -119.758362) (xy 79.940318 -119.709727)
			(xy 79.974404 -119.665584) (xy 80.014553 -119.626875) (xy 80.059911 -119.594424) (xy 80.109511 -119.568923)
			(xy 80.162295 -119.550916) (xy 80.217138 -119.540786) (xy 80.272872 -119.538749) (xy 80.328309 -119.544849)
			(xy 80.382266 -119.558955) (xy 80.433595 -119.580767) (xy 80.481201 -119.609821) (xy 80.524069 -119.645496)
			(xy 80.561286 -119.687033) (xy 80.592059 -119.733546) (xy 80.615731 -119.784043) (xy 80.631799 -119.83745)
			(xy 80.639919 -119.892626) (xy 80.640428 -119.920512) (xy 80.639919 -119.948398) (xy 80.631799 -120.003574)
			(xy 80.615731 -120.056981) (xy 80.615288 -120.057926) (xy 81.214466 -120.057926) (xy 81.218537 -120.002304)
			(xy 81.230663 -119.947867) (xy 81.250586 -119.895776) (xy 81.277882 -119.847141) (xy 81.311968 -119.802998)
			(xy 81.352117 -119.764289) (xy 81.397475 -119.731838) (xy 81.447075 -119.706337) (xy 81.499859 -119.68833)
			(xy 81.554702 -119.6782) (xy 81.610436 -119.676163) (xy 81.665873 -119.682263) (xy 81.71983 -119.696369)
			(xy 81.771159 -119.718181) (xy 81.818765 -119.747235) (xy 81.861633 -119.78291) (xy 81.89885 -119.824447)
			(xy 81.929623 -119.87096) (xy 81.953295 -119.921457) (xy 81.969363 -119.974864) (xy 81.977483 -120.03004)
			(xy 81.977992 -120.057926) (xy 81.977483 -120.085812) (xy 81.969363 -120.140988) (xy 81.953295 -120.194395)
			(xy 81.929623 -120.244892) (xy 81.89885 -120.291405) (xy 81.861633 -120.332942) (xy 81.818765 -120.368617)
			(xy 81.771159 -120.397671) (xy 81.71983 -120.419483) (xy 81.665873 -120.433589) (xy 81.610436 -120.439689)
			(xy 81.554702 -120.437652) (xy 81.499859 -120.427522) (xy 81.447075 -120.409515) (xy 81.397475 -120.384014)
			(xy 81.352117 -120.351563) (xy 81.311968 -120.312854) (xy 81.277882 -120.268711) (xy 81.250586 -120.220076)
			(xy 81.230663 -120.167985) (xy 81.218537 -120.113548) (xy 81.214466 -120.057926) (xy 80.615288 -120.057926)
			(xy 80.592059 -120.107478) (xy 80.561286 -120.153991) (xy 80.524069 -120.195528) (xy 80.481201 -120.231203)
			(xy 80.433595 -120.260257) (xy 80.382266 -120.282069) (xy 80.328309 -120.296175) (xy 80.272872 -120.302275)
			(xy 80.217138 -120.300238) (xy 80.162295 -120.290108) (xy 80.109511 -120.272101) (xy 80.059911 -120.2466)
			(xy 80.014553 -120.214149) (xy 79.974404 -120.17544) (xy 79.940318 -120.131297) (xy 79.913022 -120.082662)
			(xy 79.893099 -120.030571) (xy 79.880973 -119.976134) (xy 79.876902 -119.920512) (xy 78.218305 -119.920512)
			(xy 78.227427 -119.921756) (xy 78.281609 -119.937535) (xy 78.332875 -119.961125) (xy 78.380105 -119.99201)
			(xy 78.422271 -120.029516) (xy 78.440788 -120.050814) (xy 78.473046 -120.089168) (xy 78.522576 -120.095518)
			(xy 78.538419 -120.097) (xy 78.569977 -120.093002) (xy 78.599563 -120.081317) (xy 78.612746 -120.072404)
			(xy 78.635461 -120.056566) (xy 78.684535 -120.030914) (xy 78.736802 -120.012626) (xy 78.791164 -120.002087)
			(xy 78.846478 -119.999518) (xy 78.901583 -120.004972) (xy 78.95532 -120.018336) (xy 79.006561 -120.039328)
			(xy 79.054228 -120.067508) (xy 79.097321 -120.102283) (xy 79.134933 -120.142923) (xy 79.166275 -120.188573)
			(xy 79.190688 -120.238275) (xy 79.207659 -120.290985) (xy 79.216831 -120.345594) (xy 79.218012 -120.400955)
			(xy 79.211177 -120.455906) (xy 79.196469 -120.509291) (xy 79.174198 -120.559989) (xy 79.144831 -120.606934)
			(xy 79.108986 -120.649141) (xy 79.067415 -120.685722) (xy 79.020993 -120.715909) (xy 78.970694 -120.739067)
			(xy 78.917576 -120.75471) (xy 78.862754 -120.76251) (xy 78.80738 -120.762301) (xy 78.752618 -120.75409)
			(xy 78.699619 -120.738047) (xy 78.649496 -120.714511) (xy 78.603302 -120.683976) (xy 78.562008 -120.647084)
			(xy 78.543912 -120.626124) (xy 78.53332 -120.614204) (xy 78.507469 -120.595551) (xy 78.477806 -120.583876)
			(xy 78.446176 -120.579906) (xy 78.414548 -120.583888) (xy 78.38489 -120.595573) (xy 78.3717 -120.604534)
			(xy 78.347373 -120.62153) (xy 78.294553 -120.648577) (xy 78.266544 -120.658382) (xy 78.245821 -120.66567)
			(xy 78.207061 -120.686333) (xy 78.172427 -120.713349) (xy 78.142951 -120.745913) (xy 78.119509 -120.783059)
			(xy 78.102798 -120.82368) (xy 78.093315 -120.866568) (xy 78.091343 -120.910448) (xy 78.09694 -120.954014)
			(xy 78.10994 -120.99597) (xy 78.119478 -121.01576) (xy 78.131753 -121.040825) (xy 78.149658 -121.093685)
			(xy 78.159671 -121.14859) (xy 78.161578 -121.204368) (xy 78.155339 -121.259828) (xy 78.141086 -121.313788)
			(xy 78.119125 -121.365095) (xy 78.089923 -121.412656) (xy 78.054104 -121.455456) (xy 78.012432 -121.49258)
			(xy 77.965796 -121.523237) (xy 77.915192 -121.546774) (xy 77.861698 -121.562686) (xy 77.806457 -121.570636)
			(xy 77.750647 -121.570453) (xy 77.695459 -121.562142) (xy 77.642071 -121.545879) (xy 77.591621 -121.522012)
			(xy 77.545187 -121.49105) (xy 77.503759 -121.453653) (xy 77.468221 -121.41062) (xy 77.439332 -121.362869)
			(xy 77.42809 -121.337324) (xy 77.418555 -121.315993) (xy 77.392898 -121.27695) (xy 77.360544 -121.243248)
			(xy 77.32258 -121.21602) (xy 77.280282 -121.196182) (xy 77.235073 -121.184401) (xy 77.188474 -121.181073)
			(xy 77.1652 -121.183146) (xy 77.137584 -121.185771) (xy 77.082142 -121.183959) (xy 77.027547 -121.174134)
			(xy 76.974951 -121.156504) (xy 76.925465 -121.131439) (xy 76.880132 -121.09947) (xy 76.839908 -121.06127)
			(xy 76.805644 -121.017645) (xy 76.778062 -120.969517) (xy 76.757743 -120.9179) (xy 76.745116 -120.863884)
			(xy 76.740449 -120.808609) (xy 76.743839 -120.753241) (xy 76.755215 -120.698948) (xy 76.774336 -120.646876)
			(xy 76.8008 -120.598123) (xy 76.816966 -120.575578) (xy 76.830561 -120.556567) (xy 76.851292 -120.514684)
			(xy 76.864016 -120.469718) (xy 76.868304 -120.423182) (xy 76.86401 -120.376648) (xy 76.85128 -120.331683)
			(xy 76.830543 -120.289803) (xy 76.816966 -120.270778) (xy 76.798805 -120.24554) (xy 76.770076 -120.190401)
			(xy 76.759816 -120.16105) (xy 76.75222 -120.139476) (xy 76.730405 -120.099279) (xy 76.701749 -120.063636)
			(xy 76.667178 -120.033695) (xy 76.627806 -120.010424) (xy 76.584906 -119.994575) (xy 76.539862 -119.986658)
			(xy 76.516992 -119.986298) (xy 76.488552 -119.985928) (xy 76.432261 -119.977791) (xy 76.377803 -119.961384)
			(xy 76.326385 -119.937073) (xy 76.279147 -119.905395) (xy 76.237137 -119.867054) (xy 76.201287 -119.8229)
			(xy 76.172391 -119.773911) (xy 76.151091 -119.721174) (xy 76.137858 -119.665859) (xy 76.132986 -119.609192)
			(xy 76.136583 -119.55243) (xy 76.142088 -119.524526) (xy 76.146359 -119.502273) (xy 76.147866 -119.456992)
			(xy 76.141319 -119.41216) (xy 76.126926 -119.369201) (xy 76.105142 -119.329475) (xy 76.076658 -119.294241)
			(xy 76.042377 -119.264618) (xy 76.003387 -119.241543) (xy 75.960922 -119.225749) (xy 75.91633 -119.217736)
			(xy 75.893676 -119.217186) (xy 73.673208 -119.217186) (xy 73.651771 -119.217631) (xy 73.609507 -119.22483)
			(xy 73.569051 -119.239025) (xy 73.531554 -119.259813) (xy 73.498082 -119.286603) (xy 73.469583 -119.318634)
			(xy 73.446869 -119.354996) (xy 73.430585 -119.394657) (xy 73.421193 -119.436489) (xy 73.418959 -119.479304)
			(xy 73.420986 -119.50065) (xy 73.423649 -119.52762) (xy 73.422241 -119.581795) (xy 73.413183 -119.635226)
			(xy 73.396658 -119.686838) (xy 73.372997 -119.735594) (xy 73.342678 -119.780512) (xy 73.306309 -119.82069)
			(xy 73.264623 -119.855319) (xy 73.218457 -119.883703) (xy 73.16874 -119.905271) (xy 73.116473 -119.919589)
			(xy 73.062705 -119.926369) (xy 73.008519 -119.925475) (xy 72.955004 -119.916925) (xy 72.928988 -119.909336)
			(xy 72.907117 -119.903052) (xy 72.861959 -119.897475) (xy 72.81653 -119.900037) (xy 72.772286 -119.910654)
			(xy 72.730642 -119.928987) (xy 72.692932 -119.954448) (xy 72.660364 -119.986224) (xy 72.633981 -120.023295)
			(xy 72.614628 -120.064474) (xy 72.602924 -120.108444) (xy 72.600566 -120.131078) (xy 72.597805 -120.158626)
			(xy 72.58534 -120.212567) (xy 72.56521 -120.264141) (xy 72.537837 -120.312263) (xy 72.503797 -120.355925)
			(xy 72.463804 -120.394208) (xy 72.418698 -120.42631) (xy 72.369427 -120.451555) (xy 72.317024 -120.469415)
			(xy 72.26259 -120.479513) (xy 72.207267 -120.481638) (xy 72.152219 -120.475746) (xy 72.0986 -120.46196)
			(xy 72.047537 -120.440569) (xy 72.000101 -120.412022) (xy 71.957289 -120.37692) (xy 71.92 -120.335999)
			(xy 71.889016 -120.290118) (xy 71.864988 -120.240241) (xy 71.848421 -120.187415) (xy 71.839663 -120.13275)
			(xy 71.838897 -120.077392) (xy 71.84614 -120.022505) (xy 71.861239 -119.969241) (xy 71.883878 -119.918719)
			(xy 71.913581 -119.871998) (xy 71.949724 -119.830061) (xy 71.991549 -119.793788) (xy 72.038177 -119.763941)
			(xy 72.088629 -119.741145) (xy 72.141846 -119.725881) (xy 72.19671 -119.718468) (xy 72.25207 -119.719062)
			(xy 72.306762 -119.727651) (xy 72.333358 -119.735346) (xy 72.355227 -119.741626) (xy 72.400378 -119.747195)
			(xy 72.445799 -119.744628) (xy 72.490036 -119.734007) (xy 72.531671 -119.715671) (xy 72.569371 -119.690209)
			(xy 72.601931 -119.658435) (xy 72.628305 -119.621367) (xy 72.647652 -119.580192) (xy 72.65935 -119.536228)
			(xy 72.66178 -119.513604) (xy 72.66305 -119.50065) (xy 72.665093 -119.479306) (xy 72.662844 -119.436492)
			(xy 72.653442 -119.394662) (xy 72.637151 -119.355004) (xy 72.614435 -119.318643) (xy 72.585938 -119.286611)
			(xy 72.552469 -119.259816) (xy 72.514977 -119.239019) (xy 72.474526 -119.224811) (xy 72.432265 -119.217593)
			(xy 72.410828 -119.217186) (xy 72.168766 -119.217186) (xy 71.888858 -119.49684) (xy 70.882256 -119.49684)
			(xy 70.605142 -119.21998) (xy 70.420738 -119.21998) (xy 70.404581 -119.220456) (xy 70.373302 -119.228573)
			(xy 70.345069 -119.244294) (xy 70.321698 -119.26661) (xy 70.304689 -119.294086) (xy 70.295135 -119.324956)
			(xy 70.293652 -119.357237) (xy 70.300334 -119.388853) (xy 70.314752 -119.417773) (xy 70.32498 -119.430292)
			(xy 70.359778 -119.47017) (xy 70.399148 -119.479822) (xy 70.426399 -119.486928) (xy 70.478599 -119.508061)
			(xy 70.527126 -119.536638) (xy 70.570925 -119.572038) (xy 70.609045 -119.613491) (xy 70.640659 -119.660096)
			(xy 70.665078 -119.710843) (xy 70.681773 -119.764627) (xy 70.690381 -119.820281) (xy 70.690715 -119.876596)
			(xy 70.682768 -119.932348) (xy 70.666713 -119.986327) (xy 70.642898 -120.03736) (xy 70.61184 -120.084337)
			(xy 70.574214 -120.12624) (xy 70.530838 -120.162156) (xy 70.482654 -120.191307) (xy 70.430709 -120.213059)
			(xy 70.37613 -120.22694) (xy 70.320104 -120.232647) (xy 70.263848 -120.230057) (xy 70.208583 -120.219226)
			(xy 70.155511 -120.20039) (xy 70.105783 -120.173957) (xy 70.060482 -120.140503) (xy 70.040246 -120.120918)
			(xy 70.023651 -120.105077) (xy 69.985869 -120.079061) (xy 69.944029 -120.060255) (xy 69.899491 -120.04927)
			(xy 69.853704 -120.046463) (xy 69.808158 -120.051927) (xy 69.764334 -120.065482) (xy 69.723657 -120.08669)
			(xy 69.70522 -120.100344) (xy 69.682948 -120.116991) (xy 69.634539 -120.144342) (xy 69.582672 -120.164377)
			(xy 69.528446 -120.176671) (xy 69.47301 -120.180965) (xy 69.417538 -120.177168) (xy 69.363205 -120.165359)
			(xy 69.311161 -120.145789) (xy 69.262508 -120.118873) (xy 69.218277 -120.08518) (xy 69.179405 -120.045424)
			(xy 69.146715 -120.000447) (xy 69.120899 -119.951202) (xy 69.102504 -119.898731) (xy 69.091919 -119.844146)
			(xy 69.08937 -119.788603) (xy 69.094909 -119.733277) (xy 69.108419 -119.679342) (xy 69.129615 -119.627938)
			(xy 69.143372 -119.603774) (xy 69.154369 -119.584357) (xy 69.170116 -119.542609) (xy 69.17833 -119.498752)
			(xy 69.17876 -119.454135) (xy 69.171392 -119.410128) (xy 69.156453 -119.368083) (xy 69.134401 -119.329294)
			(xy 69.105915 -119.294951) (xy 69.071869 -119.26611) (xy 69.033311 -119.243658) (xy 68.991424 -119.228283)
			(xy 68.947495 -119.22046) (xy 68.925186 -119.21998) (xy 57.226962 -119.21998) (xy 56.411876 -120.035066)
			(xy 57.086752 -120.035066) (xy 57.090823 -119.979444) (xy 57.102949 -119.925007) (xy 57.122872 -119.872916)
			(xy 57.150168 -119.824281) (xy 57.184254 -119.780138) (xy 57.224403 -119.741429) (xy 57.269761 -119.708978)
			(xy 57.319361 -119.683477) (xy 57.372145 -119.66547) (xy 57.426988 -119.65534) (xy 57.482722 -119.653303)
			(xy 57.538159 -119.659403) (xy 57.592116 -119.673509) (xy 57.643445 -119.695321) (xy 57.691051 -119.724375)
			(xy 57.733919 -119.76005) (xy 57.771136 -119.801587) (xy 57.801909 -119.8481) (xy 57.825581 -119.898597)
			(xy 57.841649 -119.952004) (xy 57.849769 -120.00718) (xy 57.850157 -120.028462) (xy 58.878468 -120.028462)
			(xy 58.882539 -119.97284) (xy 58.894665 -119.918403) (xy 58.914588 -119.866312) (xy 58.941884 -119.817677)
			(xy 58.97597 -119.773534) (xy 59.016119 -119.734825) (xy 59.061477 -119.702374) (xy 59.111077 -119.676873)
			(xy 59.163861 -119.658866) (xy 59.218704 -119.648736) (xy 59.274438 -119.646699) (xy 59.329875 -119.652799)
			(xy 59.383832 -119.666905) (xy 59.435161 -119.688717) (xy 59.482767 -119.717771) (xy 59.525635 -119.753446)
			(xy 59.562852 -119.794983) (xy 59.593625 -119.841496) (xy 59.617297 -119.891993) (xy 59.633365 -119.9454)
			(xy 59.641485 -120.000576) (xy 59.64153 -120.003062) (xy 59.970668 -120.003062) (xy 59.974739 -119.94744)
			(xy 59.986865 -119.893003) (xy 60.006788 -119.840912) (xy 60.034084 -119.792277) (xy 60.06817 -119.748134)
			(xy 60.108319 -119.709425) (xy 60.153677 -119.676974) (xy 60.203277 -119.651473) (xy 60.256061 -119.633466)
			(xy 60.310904 -119.623336) (xy 60.366638 -119.621299) (xy 60.422075 -119.627399) (xy 60.476032 -119.641505)
			(xy 60.527361 -119.663317) (xy 60.574967 -119.692371) (xy 60.617835 -119.728046) (xy 60.655052 -119.769583)
			(xy 60.685825 -119.816096) (xy 60.709497 -119.866593) (xy 60.725565 -119.92) (xy 60.733685 -119.975176)
			(xy 60.734194 -120.003062) (xy 60.73373 -120.028462) (xy 61.062868 -120.028462) (xy 61.066939 -119.97284)
			(xy 61.079065 -119.918403) (xy 61.098988 -119.866312) (xy 61.126284 -119.817677) (xy 61.16037 -119.773534)
			(xy 61.200519 -119.734825) (xy 61.245877 -119.702374) (xy 61.295477 -119.676873) (xy 61.348261 -119.658866)
			(xy 61.403104 -119.648736) (xy 61.458838 -119.646699) (xy 61.514275 -119.652799) (xy 61.568232 -119.666905)
			(xy 61.619561 -119.688717) (xy 61.667167 -119.717771) (xy 61.710035 -119.753446) (xy 61.747252 -119.794983)
			(xy 61.778025 -119.841496) (xy 61.801697 -119.891993) (xy 61.817765 -119.9454) (xy 61.825885 -120.000576)
			(xy 61.825986 -120.00611) (xy 62.129668 -120.00611) (xy 62.133739 -119.950488) (xy 62.145865 -119.896051)
			(xy 62.165788 -119.84396) (xy 62.193084 -119.795325) (xy 62.22717 -119.751182) (xy 62.267319 -119.712473)
			(xy 62.312677 -119.680022) (xy 62.362277 -119.654521) (xy 62.415061 -119.636514) (xy 62.469904 -119.626384)
			(xy 62.525638 -119.624347) (xy 62.581075 -119.630447) (xy 62.635032 -119.644553) (xy 62.686361 -119.666365)
			(xy 62.733967 -119.695419) (xy 62.776835 -119.731094) (xy 62.814052 -119.772631) (xy 62.844825 -119.819144)
			(xy 62.868497 -119.869641) (xy 62.884565 -119.923048) (xy 62.892685 -119.978224) (xy 62.893194 -120.00611)
			(xy 62.892786 -120.028462) (xy 63.450468 -120.028462) (xy 63.454539 -119.97284) (xy 63.466665 -119.918403)
			(xy 63.486588 -119.866312) (xy 63.513884 -119.817677) (xy 63.54797 -119.773534) (xy 63.588119 -119.734825)
			(xy 63.633477 -119.702374) (xy 63.683077 -119.676873) (xy 63.735861 -119.658866) (xy 63.790704 -119.648736)
			(xy 63.846438 -119.646699) (xy 63.901875 -119.652799) (xy 63.955832 -119.666905) (xy 64.007161 -119.688717)
			(xy 64.054767 -119.717771) (xy 64.097635 -119.753446) (xy 64.134852 -119.794983) (xy 64.165625 -119.841496)
			(xy 64.189297 -119.891993) (xy 64.205365 -119.9454) (xy 64.206375 -119.952262) (xy 64.517268 -119.952262)
			(xy 64.521339 -119.89664) (xy 64.533465 -119.842203) (xy 64.553388 -119.790112) (xy 64.580684 -119.741477)
			(xy 64.61477 -119.697334) (xy 64.654919 -119.658625) (xy 64.700277 -119.626174) (xy 64.749877 -119.600673)
			(xy 64.802661 -119.582666) (xy 64.857504 -119.572536) (xy 64.913238 -119.570499) (xy 64.968675 -119.576599)
			(xy 65.022632 -119.590705) (xy 65.073961 -119.612517) (xy 65.121567 -119.641571) (xy 65.164435 -119.677246)
			(xy 65.201652 -119.718783) (xy 65.232425 -119.765296) (xy 65.256097 -119.815793) (xy 65.272165 -119.8692)
			(xy 65.280285 -119.924376) (xy 65.280794 -119.952262) (xy 65.280285 -119.980148) (xy 65.276913 -120.003062)
			(xy 65.812668 -120.003062) (xy 65.816739 -119.94744) (xy 65.828865 -119.893003) (xy 65.848788 -119.840912)
			(xy 65.876084 -119.792277) (xy 65.91017 -119.748134) (xy 65.950319 -119.709425) (xy 65.995677 -119.676974)
			(xy 66.045277 -119.651473) (xy 66.098061 -119.633466) (xy 66.152904 -119.623336) (xy 66.208638 -119.621299)
			(xy 66.264075 -119.627399) (xy 66.318032 -119.641505) (xy 66.369361 -119.663317) (xy 66.416967 -119.692371)
			(xy 66.459835 -119.728046) (xy 66.497052 -119.769583) (xy 66.527825 -119.816096) (xy 66.551497 -119.866593)
			(xy 66.567565 -119.92) (xy 66.575685 -119.975176) (xy 66.576194 -120.003062) (xy 66.57573 -120.028462)
			(xy 66.904868 -120.028462) (xy 66.908939 -119.97284) (xy 66.921065 -119.918403) (xy 66.940988 -119.866312)
			(xy 66.968284 -119.817677) (xy 67.00237 -119.773534) (xy 67.042519 -119.734825) (xy 67.087877 -119.702374)
			(xy 67.137477 -119.676873) (xy 67.190261 -119.658866) (xy 67.245104 -119.648736) (xy 67.300838 -119.646699)
			(xy 67.356275 -119.652799) (xy 67.410232 -119.666905) (xy 67.461561 -119.688717) (xy 67.509167 -119.717771)
			(xy 67.552035 -119.753446) (xy 67.589252 -119.794983) (xy 67.620025 -119.841496) (xy 67.643697 -119.891993)
			(xy 67.659765 -119.9454) (xy 67.664513 -119.977662) (xy 67.971668 -119.977662) (xy 67.975739 -119.92204)
			(xy 67.987865 -119.867603) (xy 68.007788 -119.815512) (xy 68.035084 -119.766877) (xy 68.06917 -119.722734)
			(xy 68.109319 -119.684025) (xy 68.154677 -119.651574) (xy 68.204277 -119.626073) (xy 68.257061 -119.608066)
			(xy 68.311904 -119.597936) (xy 68.367638 -119.595899) (xy 68.423075 -119.601999) (xy 68.477032 -119.616105)
			(xy 68.528361 -119.637917) (xy 68.575967 -119.666971) (xy 68.618835 -119.702646) (xy 68.656052 -119.744183)
			(xy 68.686825 -119.790696) (xy 68.710497 -119.841193) (xy 68.726565 -119.8946) (xy 68.734685 -119.949776)
			(xy 68.735194 -119.977662) (xy 68.734685 -120.005548) (xy 68.726565 -120.060724) (xy 68.710497 -120.114131)
			(xy 68.686825 -120.164628) (xy 68.656052 -120.211141) (xy 68.618835 -120.252678) (xy 68.575967 -120.288353)
			(xy 68.528361 -120.317407) (xy 68.477032 -120.339219) (xy 68.423075 -120.353325) (xy 68.367638 -120.359425)
			(xy 68.311904 -120.357388) (xy 68.257061 -120.347258) (xy 68.204277 -120.329251) (xy 68.154677 -120.30375)
			(xy 68.109319 -120.271299) (xy 68.06917 -120.23259) (xy 68.035084 -120.188447) (xy 68.007788 -120.139812)
			(xy 67.987865 -120.087721) (xy 67.975739 -120.033284) (xy 67.971668 -119.977662) (xy 67.664513 -119.977662)
			(xy 67.667885 -120.000576) (xy 67.668394 -120.028462) (xy 67.667885 -120.056348) (xy 67.659765 -120.111524)
			(xy 67.643697 -120.164931) (xy 67.620025 -120.215428) (xy 67.589252 -120.261941) (xy 67.552035 -120.303478)
			(xy 67.509167 -120.339153) (xy 67.461561 -120.368207) (xy 67.410232 -120.390019) (xy 67.356275 -120.404125)
			(xy 67.300838 -120.410225) (xy 67.245104 -120.408188) (xy 67.190261 -120.398058) (xy 67.137477 -120.380051)
			(xy 67.087877 -120.35455) (xy 67.042519 -120.322099) (xy 67.00237 -120.28339) (xy 66.968284 -120.239247)
			(xy 66.940988 -120.190612) (xy 66.921065 -120.138521) (xy 66.908939 -120.084084) (xy 66.904868 -120.028462)
			(xy 66.57573 -120.028462) (xy 66.575685 -120.030948) (xy 66.567565 -120.086124) (xy 66.551497 -120.139531)
			(xy 66.527825 -120.190028) (xy 66.497052 -120.236541) (xy 66.459835 -120.278078) (xy 66.416967 -120.313753)
			(xy 66.369361 -120.342807) (xy 66.318032 -120.364619) (xy 66.264075 -120.378725) (xy 66.208638 -120.384825)
			(xy 66.152904 -120.382788) (xy 66.098061 -120.372658) (xy 66.045277 -120.354651) (xy 65.995677 -120.32915)
			(xy 65.950319 -120.296699) (xy 65.91017 -120.25799) (xy 65.876084 -120.213847) (xy 65.848788 -120.165212)
			(xy 65.828865 -120.113121) (xy 65.816739 -120.058684) (xy 65.812668 -120.003062) (xy 65.276913 -120.003062)
			(xy 65.272165 -120.035324) (xy 65.256097 -120.088731) (xy 65.232425 -120.139228) (xy 65.201652 -120.185741)
			(xy 65.164435 -120.227278) (xy 65.121567 -120.262953) (xy 65.073961 -120.292007) (xy 65.022632 -120.313819)
			(xy 64.968675 -120.327925) (xy 64.913238 -120.334025) (xy 64.857504 -120.331988) (xy 64.802661 -120.321858)
			(xy 64.749877 -120.303851) (xy 64.700277 -120.27835) (xy 64.654919 -120.245899) (xy 64.61477 -120.20719)
			(xy 64.580684 -120.163047) (xy 64.553388 -120.114412) (xy 64.533465 -120.062321) (xy 64.521339 -120.007884)
			(xy 64.517268 -119.952262) (xy 64.206375 -119.952262) (xy 64.213485 -120.000576) (xy 64.213994 -120.028462)
			(xy 64.213485 -120.056348) (xy 64.205365 -120.111524) (xy 64.189297 -120.164931) (xy 64.165625 -120.215428)
			(xy 64.134852 -120.261941) (xy 64.097635 -120.303478) (xy 64.054767 -120.339153) (xy 64.007161 -120.368207)
			(xy 63.955832 -120.390019) (xy 63.901875 -120.404125) (xy 63.846438 -120.410225) (xy 63.790704 -120.408188)
			(xy 63.735861 -120.398058) (xy 63.683077 -120.380051) (xy 63.633477 -120.35455) (xy 63.588119 -120.322099)
			(xy 63.54797 -120.28339) (xy 63.513884 -120.239247) (xy 63.486588 -120.190612) (xy 63.466665 -120.138521)
			(xy 63.454539 -120.084084) (xy 63.450468 -120.028462) (xy 62.892786 -120.028462) (xy 62.892685 -120.033996)
			(xy 62.884565 -120.089172) (xy 62.868497 -120.142579) (xy 62.844825 -120.193076) (xy 62.814052 -120.239589)
			(xy 62.776835 -120.281126) (xy 62.733967 -120.316801) (xy 62.686361 -120.345855) (xy 62.635032 -120.367667)
			(xy 62.581075 -120.381773) (xy 62.525638 -120.387873) (xy 62.469904 -120.385836) (xy 62.415061 -120.375706)
			(xy 62.362277 -120.357699) (xy 62.312677 -120.332198) (xy 62.267319 -120.299747) (xy 62.22717 -120.261038)
			(xy 62.193084 -120.216895) (xy 62.165788 -120.16826) (xy 62.145865 -120.116169) (xy 62.133739 -120.061732)
			(xy 62.129668 -120.00611) (xy 61.825986 -120.00611) (xy 61.826394 -120.028462) (xy 61.825885 -120.056348)
			(xy 61.817765 -120.111524) (xy 61.801697 -120.164931) (xy 61.778025 -120.215428) (xy 61.747252 -120.261941)
			(xy 61.710035 -120.303478) (xy 61.667167 -120.339153) (xy 61.619561 -120.368207) (xy 61.568232 -120.390019)
			(xy 61.514275 -120.404125) (xy 61.458838 -120.410225) (xy 61.403104 -120.408188) (xy 61.348261 -120.398058)
			(xy 61.295477 -120.380051) (xy 61.245877 -120.35455) (xy 61.200519 -120.322099) (xy 61.16037 -120.28339)
			(xy 61.126284 -120.239247) (xy 61.098988 -120.190612) (xy 61.079065 -120.138521) (xy 61.066939 -120.084084)
			(xy 61.062868 -120.028462) (xy 60.73373 -120.028462) (xy 60.733685 -120.030948) (xy 60.725565 -120.086124)
			(xy 60.709497 -120.139531) (xy 60.685825 -120.190028) (xy 60.655052 -120.236541) (xy 60.617835 -120.278078)
			(xy 60.574967 -120.313753) (xy 60.527361 -120.342807) (xy 60.476032 -120.364619) (xy 60.422075 -120.378725)
			(xy 60.366638 -120.384825) (xy 60.310904 -120.382788) (xy 60.256061 -120.372658) (xy 60.203277 -120.354651)
			(xy 60.153677 -120.32915) (xy 60.108319 -120.296699) (xy 60.06817 -120.25799) (xy 60.034084 -120.213847)
			(xy 60.006788 -120.165212) (xy 59.986865 -120.113121) (xy 59.974739 -120.058684) (xy 59.970668 -120.003062)
			(xy 59.64153 -120.003062) (xy 59.641994 -120.028462) (xy 59.641485 -120.056348) (xy 59.633365 -120.111524)
			(xy 59.617297 -120.164931) (xy 59.593625 -120.215428) (xy 59.562852 -120.261941) (xy 59.525635 -120.303478)
			(xy 59.482767 -120.339153) (xy 59.435161 -120.368207) (xy 59.383832 -120.390019) (xy 59.329875 -120.404125)
			(xy 59.274438 -120.410225) (xy 59.218704 -120.408188) (xy 59.163861 -120.398058) (xy 59.111077 -120.380051)
			(xy 59.061477 -120.35455) (xy 59.016119 -120.322099) (xy 58.97597 -120.28339) (xy 58.941884 -120.239247)
			(xy 58.914588 -120.190612) (xy 58.894665 -120.138521) (xy 58.882539 -120.084084) (xy 58.878468 -120.028462)
			(xy 57.850157 -120.028462) (xy 57.850278 -120.035066) (xy 57.849769 -120.062952) (xy 57.841649 -120.118128)
			(xy 57.825581 -120.171535) (xy 57.801909 -120.222032) (xy 57.771136 -120.268545) (xy 57.733919 -120.310082)
			(xy 57.691051 -120.345757) (xy 57.643445 -120.374811) (xy 57.592116 -120.396623) (xy 57.538159 -120.410729)
			(xy 57.482722 -120.416829) (xy 57.426988 -120.414792) (xy 57.372145 -120.404662) (xy 57.319361 -120.386655)
			(xy 57.269761 -120.361154) (xy 57.224403 -120.328703) (xy 57.184254 -120.289994) (xy 57.150168 -120.245851)
			(xy 57.122872 -120.197216) (xy 57.102949 -120.145125) (xy 57.090823 -120.090688) (xy 57.086752 -120.035066)
			(xy 56.411876 -120.035066) (xy 56.20004 -120.246902) (xy 55.890414 -120.246902) (xy 55.874085 -120.247413)
			(xy 55.8425 -120.255722) (xy 55.814057 -120.271774) (xy 55.790618 -120.294518) (xy 55.773719 -120.322466)
			(xy 55.764464 -120.353787) (xy 55.763414 -120.370092) (xy 55.762085 -120.397999) (xy 55.752275 -120.453001)
			(xy 55.734547 -120.505984) (xy 55.709281 -120.555814) (xy 55.677018 -120.601426) (xy 55.638446 -120.641845)
			(xy 55.594392 -120.676205) (xy 55.545797 -120.703773) (xy 55.493701 -120.723957) (xy 55.439219 -120.736328)
			(xy 55.383514 -120.74062) (xy 55.327779 -120.73674) (xy 55.273206 -120.724774) (xy 55.220962 -120.704975)
			(xy 55.172165 -120.677768) (xy 55.127858 -120.643734) (xy 55.088988 -120.603603) (xy 55.056388 -120.55823)
			(xy 55.04307 -120.533668) (xy 55.031452 -120.510225) (xy 55.014034 -120.460888) (xy 55.003533 -120.409632)
			(xy 55.001414 -120.383554) (xy 54.998112 -120.333008) (xy 54.925214 -120.264682) (xy 46.360588 -120.264682)
			(xy 45.923708 -120.701562) (xy 45.907711 -120.718243) (xy 45.881442 -120.756263) (xy 45.862477 -120.798404)
			(xy 45.85144 -120.84328) (xy 45.848697 -120.88941) (xy 45.854336 -120.935277) (xy 45.868172 -120.97937)
			(xy 45.88975 -121.020235) (xy 45.918359 -121.056528) (xy 45.935392 -121.072148) (xy 45.955461 -121.090412)
			(xy 45.990744 -121.131639) (xy 46.019827 -121.177451) (xy 46.042123 -121.226922) (xy 46.057182 -121.279054)
			(xy 46.064701 -121.332794) (xy 46.064526 -121.387057) (xy 46.056662 -121.440748) (xy 46.041268 -121.492781)
			(xy 46.038128 -121.49963) (xy 50.528218 -121.49963) (xy 50.532289 -121.444008) (xy 50.544415 -121.389571)
			(xy 50.564338 -121.33748) (xy 50.591634 -121.288845) (xy 50.62572 -121.244702) (xy 50.665869 -121.205993)
			(xy 50.711227 -121.173542) (xy 50.760827 -121.148041) (xy 50.813611 -121.130034) (xy 50.868454 -121.119904)
			(xy 50.924188 -121.117867) (xy 50.979625 -121.123967) (xy 51.033582 -121.138073) (xy 51.084911 -121.159885)
			(xy 51.132517 -121.188939) (xy 51.175385 -121.224614) (xy 51.212602 -121.266151) (xy 51.243375 -121.312664)
			(xy 51.267047 -121.363161) (xy 51.283115 -121.416568) (xy 51.291235 -121.471744) (xy 51.291744 -121.49963)
			(xy 51.291235 -121.527516) (xy 51.283115 -121.582692) (xy 51.267047 -121.636099) (xy 51.243375 -121.686596)
			(xy 51.230412 -121.70619) (xy 53.672478 -121.70619) (xy 53.672667 -121.650048) (xy 53.681083 -121.59454)
			(xy 53.697545 -121.540866) (xy 53.721698 -121.490184) (xy 53.753018 -121.44359) (xy 53.790831 -121.402091)
			(xy 53.834318 -121.366583) (xy 53.88254 -121.337833) (xy 53.934456 -121.316462) (xy 53.988943 -121.302932)
			(xy 54.044826 -121.297536) (xy 54.100896 -121.300389) (xy 54.155941 -121.311431) (xy 54.208774 -121.330422)
			(xy 54.258252 -121.356953) (xy 54.303307 -121.39045) (xy 54.323488 -121.409968) (xy 54.334382 -121.420314)
			(xy 54.360025 -121.435959) (xy 54.388612 -121.445186) (xy 54.418562 -121.447485) (xy 54.448223 -121.442729)
			(xy 54.475953 -121.431181) (xy 54.488334 -121.422668) (xy 54.511271 -121.406471) (xy 54.56093 -121.380266)
			(xy 54.613893 -121.361624) (xy 54.669018 -121.350946) (xy 54.725112 -121.348465) (xy 54.780964 -121.354233)
			(xy 54.835367 -121.368127) (xy 54.887146 -121.389845) (xy 54.935181 -121.418919) (xy 54.978436 -121.45472)
			(xy 55.015976 -121.496475) (xy 55.046989 -121.543282) (xy 55.070805 -121.59413) (xy 55.086911 -121.64792)
			(xy 55.094957 -121.703489) (xy 55.094771 -121.759638) (xy 55.086356 -121.815153) (xy 55.069894 -121.868834)
			(xy 55.047976 -121.914832) (xy 56.112376 -121.914832) (xy 56.1146 -121.860171) (xy 56.124608 -121.806387)
			(xy 56.142194 -121.754583) (xy 56.166997 -121.705822) (xy 56.19851 -121.661103) (xy 56.236085 -121.621342)
			(xy 56.278953 -121.587355) (xy 56.326236 -121.559837) (xy 56.351424 -121.54916) (xy 56.372047 -121.540341)
			(xy 56.410068 -121.516553) (xy 56.443318 -121.486457) (xy 56.470764 -121.450987) (xy 56.491552 -121.411247)
			(xy 56.505036 -121.368473) (xy 56.510797 -121.323996) (xy 56.508654 -121.279199) (xy 56.498675 -121.235474)
			(xy 56.490362 -121.214642) (xy 56.480163 -121.189263) (xy 56.466281 -121.13636) (xy 56.460097 -121.082016)
			(xy 56.461736 -121.027346) (xy 56.471165 -120.97347) (xy 56.48819 -120.921493) (xy 56.512464 -120.87248)
			(xy 56.543488 -120.827436) (xy 56.580626 -120.787283) (xy 56.623117 -120.752845) (xy 56.670091 -120.724828)
			(xy 56.720584 -120.703805) (xy 56.773561 -120.690209) (xy 56.827937 -120.684316) (xy 56.882598 -120.68625)
			(xy 56.936422 -120.695968) (xy 56.988306 -120.713273) (xy 57.037188 -120.73781) (xy 57.082065 -120.769076)
			(xy 57.122018 -120.806429) (xy 57.156227 -120.849105) (xy 57.183991 -120.896229) (xy 57.204741 -120.946834)
			(xy 57.218053 -120.999884) (xy 57.223653 -121.054291) (xy 57.221426 -121.10894) (xy 57.211418 -121.162711)
			(xy 57.193834 -121.214502) (xy 57.169034 -121.263251) (xy 57.137528 -121.307959) (xy 57.09996 -121.34771)
			(xy 57.057101 -121.381689) (xy 57.009828 -121.4092) (xy 56.984646 -121.419874) (xy 56.963999 -121.42864)
			(xy 56.925978 -121.452436) (xy 56.892728 -121.482541) (xy 56.865284 -121.518019) (xy 56.844498 -121.557765)
			(xy 56.831018 -121.600545) (xy 56.825262 -121.645028) (xy 56.827409 -121.68983) (xy 56.837393 -121.733558)
			(xy 56.845708 -121.754392) (xy 56.855983 -121.779746) (xy 56.869877 -121.832659) (xy 56.870626 -121.839228)
			(xy 57.683398 -121.839228) (xy 57.687469 -121.783606) (xy 57.699595 -121.729169) (xy 57.719518 -121.677078)
			(xy 57.746814 -121.628443) (xy 57.7809 -121.5843) (xy 57.821049 -121.545591) (xy 57.866407 -121.51314)
			(xy 57.916007 -121.487639) (xy 57.968791 -121.469632) (xy 58.023634 -121.459502) (xy 58.079368 -121.457465)
			(xy 58.134805 -121.463565) (xy 58.188762 -121.477671) (xy 58.240091 -121.499483) (xy 58.287697 -121.528537)
			(xy 58.330565 -121.564212) (xy 58.367782 -121.605749) (xy 58.37958 -121.623582) (xy 80.124806 -121.623582)
			(xy 80.128877 -121.56796) (xy 80.141003 -121.513523) (xy 80.160926 -121.461432) (xy 80.188222 -121.412797)
			(xy 80.222308 -121.368654) (xy 80.262457 -121.329945) (xy 80.307815 -121.297494) (xy 80.357415 -121.271993)
			(xy 80.410199 -121.253986) (xy 80.465042 -121.243856) (xy 80.520776 -121.241819) (xy 80.576213 -121.247919)
			(xy 80.63017 -121.262025) (xy 80.681499 -121.283837) (xy 80.729105 -121.312891) (xy 80.771973 -121.348566)
			(xy 80.80919 -121.390103) (xy 80.839963 -121.436616) (xy 80.863635 -121.487113) (xy 80.879703 -121.54052)
			(xy 80.887823 -121.595696) (xy 80.888332 -121.623582) (xy 80.887823 -121.651468) (xy 80.879703 -121.706644)
			(xy 80.863635 -121.760051) (xy 80.839963 -121.810548) (xy 80.80919 -121.857061) (xy 80.771973 -121.898598)
			(xy 80.729105 -121.934273) (xy 80.698804 -121.952766) (xy 82.178142 -121.952766) (xy 82.182213 -121.897144)
			(xy 82.194339 -121.842707) (xy 82.214262 -121.790616) (xy 82.241558 -121.741981) (xy 82.275644 -121.697838)
			(xy 82.315793 -121.659129) (xy 82.361151 -121.626678) (xy 82.410751 -121.601177) (xy 82.463535 -121.58317)
			(xy 82.518378 -121.57304) (xy 82.574112 -121.571003) (xy 82.629549 -121.577103) (xy 82.683506 -121.591209)
			(xy 82.734835 -121.613021) (xy 82.782441 -121.642075) (xy 82.825309 -121.67775) (xy 82.862526 -121.719287)
			(xy 82.893299 -121.7658) (xy 82.916971 -121.816297) (xy 82.933039 -121.869704) (xy 82.941159 -121.92488)
			(xy 82.941668 -121.952766) (xy 82.941159 -121.980652) (xy 82.933039 -122.035828) (xy 82.916971 -122.089235)
			(xy 82.893299 -122.139732) (xy 82.862526 -122.186245) (xy 82.825309 -122.227782) (xy 82.782441 -122.263457)
			(xy 82.734835 -122.292511) (xy 82.683506 -122.314323) (xy 82.629549 -122.328429) (xy 82.574112 -122.334529)
			(xy 82.518378 -122.332492) (xy 82.463535 -122.322362) (xy 82.410751 -122.304355) (xy 82.361151 -122.278854)
			(xy 82.315793 -122.246403) (xy 82.275644 -122.207694) (xy 82.241558 -122.163551) (xy 82.214262 -122.114916)
			(xy 82.194339 -122.062825) (xy 82.182213 -122.008388) (xy 82.178142 -121.952766) (xy 80.698804 -121.952766)
			(xy 80.681499 -121.963327) (xy 80.63017 -121.985139) (xy 80.576213 -121.999245) (xy 80.520776 -122.005345)
			(xy 80.465042 -122.003308) (xy 80.410199 -121.993178) (xy 80.357415 -121.975171) (xy 80.307815 -121.94967)
			(xy 80.262457 -121.917219) (xy 80.222308 -121.87851) (xy 80.188222 -121.834367) (xy 80.160926 -121.785732)
			(xy 80.141003 -121.733641) (xy 80.128877 -121.679204) (xy 80.124806 -121.623582) (xy 58.37958 -121.623582)
			(xy 58.398555 -121.652262) (xy 58.422227 -121.702759) (xy 58.438295 -121.756166) (xy 58.446415 -121.811342)
			(xy 58.446924 -121.839228) (xy 58.446415 -121.867114) (xy 58.438295 -121.92229) (xy 58.422227 -121.975697)
			(xy 58.398555 -122.026194) (xy 58.367782 -122.072707) (xy 58.330565 -122.114244) (xy 58.287697 -122.149919)
			(xy 58.2678 -122.162062) (xy 59.107068 -122.162062) (xy 59.111139 -122.10644) (xy 59.123265 -122.052003)
			(xy 59.143188 -121.999912) (xy 59.170484 -121.951277) (xy 59.20457 -121.907134) (xy 59.244719 -121.868425)
			(xy 59.290077 -121.835974) (xy 59.339677 -121.810473) (xy 59.392461 -121.792466) (xy 59.447304 -121.782336)
			(xy 59.503038 -121.780299) (xy 59.558475 -121.786399) (xy 59.612432 -121.800505) (xy 59.663761 -121.822317)
			(xy 59.711367 -121.851371) (xy 59.754235 -121.887046) (xy 59.791452 -121.928583) (xy 59.822225 -121.975096)
			(xy 59.845897 -122.025593) (xy 59.861965 -122.079) (xy 59.870085 -122.134176) (xy 59.870594 -122.162062)
			(xy 59.870085 -122.189948) (xy 59.861965 -122.245124) (xy 59.845897 -122.298531) (xy 59.822225 -122.349028)
			(xy 59.791452 -122.395541) (xy 59.754235 -122.437078) (xy 59.711367 -122.472753) (xy 59.663761 -122.501807)
			(xy 59.612432 -122.523619) (xy 59.558475 -122.537725) (xy 59.503038 -122.543825) (xy 59.447304 -122.541788)
			(xy 59.392461 -122.531658) (xy 59.339677 -122.513651) (xy 59.290077 -122.48815) (xy 59.244719 -122.455699)
			(xy 59.20457 -122.41699) (xy 59.170484 -122.372847) (xy 59.143188 -122.324212) (xy 59.123265 -122.272121)
			(xy 59.111139 -122.217684) (xy 59.107068 -122.162062) (xy 58.2678 -122.162062) (xy 58.240091 -122.178973)
			(xy 58.188762 -122.200785) (xy 58.134805 -122.214891) (xy 58.079368 -122.220991) (xy 58.023634 -122.218954)
			(xy 57.968791 -122.208824) (xy 57.916007 -122.190817) (xy 57.866407 -122.165316) (xy 57.821049 -122.132865)
			(xy 57.7809 -122.094156) (xy 57.746814 -122.050013) (xy 57.719518 -122.001378) (xy 57.699595 -121.949287)
			(xy 57.687469 -121.89485) (xy 57.683398 -121.839228) (xy 56.870626 -121.839228) (xy 56.876073 -121.887014)
			(xy 56.874443 -121.941696) (xy 56.865021 -121.995586) (xy 56.848 -122.047577) (xy 56.823728 -122.096606)
			(xy 56.792704 -122.141665) (xy 56.755564 -122.181832) (xy 56.713067 -122.216284) (xy 56.666087 -122.244314)
			(xy 56.615585 -122.265348) (xy 56.562597 -122.278954) (xy 56.508209 -122.284854) (xy 56.453536 -122.282927)
			(xy 56.399699 -122.273212) (xy 56.347801 -122.255908) (xy 56.298906 -122.23137) (xy 56.254015 -122.200102)
			(xy 56.214051 -122.162743) (xy 56.179831 -122.12006) (xy 56.152056 -122.072928) (xy 56.131298 -122.022313)
			(xy 56.11798 -121.969251) (xy 56.112376 -121.914832) (xy 55.047976 -121.914832) (xy 55.045741 -121.919523)
			(xy 55.014418 -121.966123) (xy 54.976602 -122.007628) (xy 54.933111 -122.043142) (xy 54.884884 -122.071897)
			(xy 54.832962 -122.093271) (xy 54.778468 -122.106803) (xy 54.722579 -122.112201) (xy 54.666503 -122.109348)
			(xy 54.61145 -122.098305) (xy 54.558611 -122.079312) (xy 54.509127 -122.052778) (xy 54.464068 -122.019276)
			(xy 54.443884 -121.999756) (xy 54.432932 -121.989475) (xy 54.407306 -121.973823) (xy 54.378734 -121.964586)
			(xy 54.348794 -121.962274) (xy 54.319143 -121.967016) (xy 54.291417 -121.97855) (xy 54.279038 -121.987056)
			(xy 54.256079 -122.003217) (xy 54.206424 -122.029414) (xy 54.153464 -122.04805) (xy 54.098346 -122.058721)
			(xy 54.042258 -122.061197) (xy 53.986413 -122.055425) (xy 53.932018 -122.041529) (xy 53.880247 -122.01981)
			(xy 53.832219 -121.990736) (xy 53.788972 -121.954936) (xy 53.751439 -121.913184) (xy 53.720433 -121.86638)
			(xy 53.696622 -121.815537) (xy 53.680521 -121.761753) (xy 53.672478 -121.70619) (xy 51.230412 -121.70619)
			(xy 51.212602 -121.733109) (xy 51.175385 -121.774646) (xy 51.132517 -121.810321) (xy 51.084911 -121.839375)
			(xy 51.033582 -121.861187) (xy 50.979625 -121.875293) (xy 50.924188 -121.881393) (xy 50.868454 -121.879356)
			(xy 50.813611 -121.869226) (xy 50.760827 -121.851219) (xy 50.711227 -121.825718) (xy 50.665869 -121.793267)
			(xy 50.62572 -121.754558) (xy 50.591634 -121.710415) (xy 50.564338 -121.66178) (xy 50.544415 -121.609689)
			(xy 50.532289 -121.555252) (xy 50.528218 -121.49963) (xy 46.038128 -121.49963) (xy 46.018654 -121.542108)
			(xy 45.989277 -121.587732) (xy 45.95373 -121.628731) (xy 45.91273 -121.664278) (xy 45.867107 -121.693655)
			(xy 45.81778 -121.716268) (xy 45.765746 -121.731663) (xy 45.712055 -121.739526) (xy 45.657792 -121.739701)
			(xy 45.604052 -121.732182) (xy 45.55192 -121.717123) (xy 45.502449 -121.694826) (xy 45.456638 -121.665743)
			(xy 45.415411 -121.63046) (xy 45.397166 -121.610374) (xy 45.381522 -121.593367) (xy 45.345229 -121.564772)
			(xy 45.304367 -121.543204) (xy 45.260281 -121.529373) (xy 45.214422 -121.523735) (xy 45.168299 -121.526474)
			(xy 45.12343 -121.537502) (xy 45.081291 -121.556454) (xy 45.04327 -121.582708) (xy 45.02658 -121.59869)
			(xy 43.892335 -122.732935) (xy 69.582939 -122.732935) (xy 69.587635 -122.67771) (xy 69.600273 -122.623745)
			(xy 69.620587 -122.572177) (xy 69.64815 -122.524092) (xy 69.682382 -122.480502) (xy 69.722561 -122.442325)
			(xy 69.767842 -122.410363) (xy 69.817271 -122.385291) (xy 69.869809 -122.367636) (xy 69.89699 -122.362214)
			(xy 69.918613 -122.357873) (xy 69.959991 -122.342611) (xy 69.998115 -122.320439) (xy 70.031842 -122.292023)
			(xy 70.060161 -122.258214) (xy 70.082223 -122.220026) (xy 70.097366 -122.178605) (xy 70.101714 -122.156982)
			(xy 70.107148 -122.12992) (xy 70.124582 -122.077553) (xy 70.14938 -122.028245) (xy 70.181024 -121.983024)
			(xy 70.218853 -121.942835) (xy 70.262078 -121.908516) (xy 70.309798 -121.880784) (xy 70.361015 -121.860217)
			(xy 70.414662 -121.847244) (xy 70.469617 -121.842137) (xy 70.524736 -121.845001) (xy 70.578866 -121.855778)
			(xy 70.630879 -121.874242) (xy 70.679688 -121.900007) (xy 70.724275 -121.932537) (xy 70.744334 -121.951496)
			(xy 70.760283 -121.966451) (xy 70.796314 -121.991211) (xy 70.836052 -122.009438) (xy 70.878323 -122.020593)
			(xy 70.92188 -122.024349) (xy 70.965437 -122.020593) (xy 71.007708 -122.009438) (xy 71.047446 -121.991211)
			(xy 71.083477 -121.966451) (xy 71.099426 -121.951496) (xy 71.11983 -121.932247) (xy 71.165227 -121.8993)
			(xy 71.214958 -121.873356) (xy 71.267953 -121.854975) (xy 71.323069 -121.844552) (xy 71.379116 -121.842313)
			(xy 71.434887 -121.848306) (xy 71.48918 -121.862401) (xy 71.540823 -121.884295) (xy 71.588703 -121.913516)
			(xy 71.631787 -121.949433) (xy 71.669148 -121.991272) (xy 71.699979 -122.038132) (xy 71.723615 -122.089001)
			(xy 71.739547 -122.142783) (xy 71.747431 -122.198318) (xy 71.747098 -122.25441) (xy 71.743316 -122.282204)
			(xy 71.740378 -122.304678) (xy 71.741546 -122.349981) (xy 71.750732 -122.394358) (xy 71.767646 -122.436402)
			(xy 71.791749 -122.474778) (xy 71.822279 -122.50827) (xy 71.858266 -122.535814) (xy 71.87819 -122.546618)
			(xy 71.902817 -122.559803) (xy 71.948243 -122.592311) (xy 71.988444 -122.631097) (xy 72.022558 -122.67533)
			(xy 72.049858 -122.724065) (xy 72.069759 -122.77626) (xy 72.081835 -122.830799) (xy 72.085829 -122.886516)
			(xy 72.081655 -122.94222) (xy 72.069403 -122.99672) (xy 72.049334 -123.048851) (xy 72.021877 -123.097498)
			(xy 71.98762 -123.14162) (xy 71.947295 -123.180276) (xy 71.901763 -123.212637) (xy 71.852 -123.238013)
			(xy 71.799067 -123.255861) (xy 71.744098 -123.265798) (xy 71.688267 -123.267614) (xy 71.632769 -123.261268)
			(xy 71.578789 -123.246897) (xy 71.527481 -123.224808) (xy 71.479944 -123.195473) (xy 71.437192 -123.159519)
			(xy 71.400141 -123.117715) (xy 71.369582 -123.070954) (xy 71.346169 -123.020238) (xy 71.330402 -122.966649)
			(xy 71.322618 -122.911334) (xy 71.322984 -122.855475) (xy 71.326756 -122.827796) (xy 71.329709 -122.805324)
			(xy 71.328541 -122.760019) (xy 71.319354 -122.715639) (xy 71.302438 -122.673594) (xy 71.278332 -122.635218)
			(xy 71.247798 -122.601727) (xy 71.211807 -122.574185) (xy 71.191882 -122.563382) (xy 71.166659 -122.549809)
			(xy 71.120228 -122.516271) (xy 71.099426 -122.49658) (xy 71.083477 -122.481625) (xy 71.047446 -122.456865)
			(xy 71.007708 -122.438638) (xy 70.965437 -122.427483) (xy 70.92188 -122.423727) (xy 70.878323 -122.427483)
			(xy 70.836052 -122.438638) (xy 70.796314 -122.456865) (xy 70.760283 -122.481625) (xy 70.744334 -122.49658)
			(xy 70.723628 -122.516097) (xy 70.677516 -122.54943) (xy 70.626967 -122.575548) (xy 70.5731 -122.593872)
			(xy 70.545198 -122.59945) (xy 70.523595 -122.60388) (xy 70.48222 -122.619126) (xy 70.444095 -122.641281)
			(xy 70.410366 -122.669683) (xy 70.382043 -122.703478) (xy 70.359975 -122.741653) (xy 70.344826 -122.783063)
			(xy 70.340474 -122.804682) (xy 70.335075 -122.831868) (xy 70.317536 -122.884445) (xy 70.292574 -122.93393)
			(xy 70.260713 -122.979282) (xy 70.222625 -123.019546) (xy 70.179111 -123.053874) (xy 70.131088 -123.081544)
			(xy 70.079565 -123.101973) (xy 70.025629 -123.114731) (xy 69.970414 -123.119549) (xy 69.915083 -123.116327)
			(xy 69.860801 -123.105131) (xy 69.808711 -123.086198) (xy 69.759908 -123.059926) (xy 69.715422 -123.026869)
			(xy 69.676187 -122.987721) (xy 69.64303 -122.943308) (xy 69.61665 -122.894564) (xy 69.597601 -122.842516)
			(xy 69.586285 -122.788258) (xy 69.582939 -122.732935) (xy 43.892335 -122.732935) (xy 43.82516 -122.80011)
			(xy 36.214558 -122.80011) (xy 35.148012 -123.866656) (xy 42.728894 -123.866656) (xy 42.732965 -123.811034)
			(xy 42.745091 -123.756597) (xy 42.765014 -123.704506) (xy 42.79231 -123.655871) (xy 42.826396 -123.611728)
			(xy 42.866545 -123.573019) (xy 42.911903 -123.540568) (xy 42.961503 -123.515067) (xy 43.014287 -123.49706)
			(xy 43.06913 -123.48693) (xy 43.124864 -123.484893) (xy 43.180301 -123.490993) (xy 43.234258 -123.505099)
			(xy 43.285587 -123.526911) (xy 43.333193 -123.555965) (xy 43.376061 -123.59164) (xy 43.413278 -123.633177)
			(xy 43.444051 -123.67969) (xy 43.467723 -123.730187) (xy 43.483791 -123.783594) (xy 43.491911 -123.83877)
			(xy 43.49242 -123.866656) (xy 46.79772 -123.866656) (xy 46.801791 -123.811034) (xy 46.813917 -123.756597)
			(xy 46.83384 -123.704506) (xy 46.861136 -123.655871) (xy 46.895222 -123.611728) (xy 46.935371 -123.573019)
			(xy 46.980729 -123.540568) (xy 47.030329 -123.515067) (xy 47.083113 -123.49706) (xy 47.137956 -123.48693)
			(xy 47.19369 -123.484893) (xy 47.249127 -123.490993) (xy 47.303084 -123.505099) (xy 47.354413 -123.526911)
			(xy 47.402019 -123.555965) (xy 47.444887 -123.59164) (xy 47.482104 -123.633177) (xy 47.512877 -123.67969)
			(xy 47.536549 -123.730187) (xy 47.552617 -123.783594) (xy 47.560737 -123.83877) (xy 47.561246 -123.866656)
			(xy 47.560737 -123.894542) (xy 47.552617 -123.949718) (xy 47.536549 -124.003125) (xy 47.512877 -124.053622)
			(xy 47.482104 -124.100135) (xy 47.444887 -124.141672) (xy 47.402019 -124.177347) (xy 47.354413 -124.206401)
			(xy 47.303084 -124.228213) (xy 47.249127 -124.242319) (xy 47.19369 -124.248419) (xy 47.137956 -124.246382)
			(xy 47.083113 -124.236252) (xy 47.030329 -124.218245) (xy 46.980729 -124.192744) (xy 46.935371 -124.160293)
			(xy 46.895222 -124.121584) (xy 46.861136 -124.077441) (xy 46.83384 -124.028806) (xy 46.813917 -123.976715)
			(xy 46.801791 -123.922278) (xy 46.79772 -123.866656) (xy 43.49242 -123.866656) (xy 43.491911 -123.894542)
			(xy 43.483791 -123.949718) (xy 43.467723 -124.003125) (xy 43.444051 -124.053622) (xy 43.413278 -124.100135)
			(xy 43.376061 -124.141672) (xy 43.333193 -124.177347) (xy 43.285587 -124.206401) (xy 43.234258 -124.228213)
			(xy 43.180301 -124.242319) (xy 43.124864 -124.248419) (xy 43.06913 -124.246382) (xy 43.014287 -124.236252)
			(xy 42.961503 -124.218245) (xy 42.911903 -124.192744) (xy 42.866545 -124.160293) (xy 42.826396 -124.121584)
			(xy 42.79231 -124.077441) (xy 42.765014 -124.028806) (xy 42.745091 -123.976715) (xy 42.732965 -123.922278)
			(xy 42.728894 -123.866656) (xy 35.148012 -123.866656) (xy 34.213292 -124.801376) (xy 34.197439 -124.817929)
			(xy 34.171379 -124.855629) (xy 34.152503 -124.897391) (xy 34.141423 -124.941862) (xy 34.138499 -124.987598)
			(xy 34.143826 -125.033118) (xy 34.157231 -125.076944) (xy 34.178278 -125.117655) (xy 34.206286 -125.153931)
			(xy 34.222944 -125.169676) (xy 34.243112 -125.188502) (xy 34.278353 -125.230948) (xy 34.307113 -125.278029)
			(xy 34.328791 -125.328761) (xy 34.342935 -125.382086) (xy 34.34925 -125.436893) (xy 34.347604 -125.492038)
			(xy 34.338032 -125.546371) (xy 34.320733 -125.598758) (xy 34.296068 -125.648107) (xy 34.264552 -125.693389)
			(xy 34.226842 -125.733658) (xy 34.183724 -125.768075) (xy 34.136099 -125.795923) (xy 34.084958 -125.816619)
			(xy 34.03137 -125.829733) (xy 33.976452 -125.834991) (xy 33.921349 -125.832283) (xy 33.86721 -125.821666)
			(xy 33.815166 -125.803361) (xy 33.766301 -125.777751) (xy 33.743646 -125.762004) (xy 33.72491 -125.749085)
			(xy 33.683876 -125.729415) (xy 33.639998 -125.717357) (xy 33.594675 -125.713294) (xy 33.549352 -125.717357)
			(xy 33.505474 -125.729415) (xy 33.46444 -125.749085) (xy 33.445704 -125.762004) (xy 33.421996 -125.778533)
			(xy 33.370629 -125.805016) (xy 33.315858 -125.82346) (xy 33.258934 -125.833442) (xy 33.230058 -125.834648)
			(xy 33.179004 -125.835664) (xy 30.10789 -128.906778) (xy 38.820862 -128.906778) (xy 38.824838 -128.852452)
			(xy 38.836681 -128.799283) (xy 38.85614 -128.748406) (xy 38.8828 -128.700904) (xy 38.916091 -128.65779)
			(xy 38.955305 -128.619983) (xy 38.999607 -128.588288) (xy 39.04805 -128.563382) (xy 39.099604 -128.545794)
			(xy 39.15317 -128.5359) (xy 39.207605 -128.53391) (xy 39.26175 -128.539868) (xy 39.31445 -128.553646)
			(xy 39.364583 -128.57495) (xy 39.389691 -128.590273) (xy 41.733968 -128.590273) (xy 41.733968 -128.536975)
			(xy 41.741911 -128.484271) (xy 41.757621 -128.433341) (xy 41.780747 -128.38532) (xy 41.810771 -128.341283)
			(xy 41.847023 -128.302212) (xy 41.888694 -128.268981) (xy 41.934852 -128.242332) (xy 41.984466 -128.22286)
			(xy 42.036428 -128.211) (xy 42.089578 -128.207017) (xy 42.142728 -128.211) (xy 42.19469 -128.22286)
			(xy 42.244304 -128.242332) (xy 42.290462 -128.268981) (xy 42.332133 -128.302212) (xy 42.368385 -128.341283)
			(xy 42.398409 -128.38532) (xy 42.421535 -128.433341) (xy 42.437245 -128.484271) (xy 42.445188 -128.536975)
			(xy 42.445686 -128.563624) (xy 42.445188 -128.590273) (xy 42.437245 -128.642977) (xy 42.421535 -128.693907)
			(xy 42.398409 -128.741928) (xy 42.368385 -128.785965) (xy 42.332133 -128.825036) (xy 42.290462 -128.858267)
			(xy 42.244304 -128.884916) (xy 42.19469 -128.904388) (xy 42.142728 -128.916248) (xy 42.089578 -128.920232)
			(xy 42.036428 -128.916248) (xy 41.984466 -128.904388) (xy 41.934852 -128.884916) (xy 41.888694 -128.858267)
			(xy 41.847023 -128.825036) (xy 41.810771 -128.785965) (xy 41.780747 -128.741928) (xy 41.757621 -128.693907)
			(xy 41.741911 -128.642977) (xy 41.733968 -128.590273) (xy 39.389691 -128.590273) (xy 39.411079 -128.603326)
			(xy 39.452949 -128.63817) (xy 39.489298 -128.678739) (xy 39.519354 -128.724168) (xy 39.542475 -128.773489)
			(xy 39.558168 -128.825651) (xy 39.566099 -128.879542) (xy 39.566596 -128.906778) (xy 39.566099 -128.934014)
			(xy 39.558168 -128.987905) (xy 39.542475 -129.040067) (xy 39.519354 -129.089388) (xy 39.489298 -129.134817)
			(xy 39.452949 -129.175386) (xy 39.434182 -129.191004) (xy 46.596564 -129.191004) (xy 46.60054 -129.136678)
			(xy 46.612383 -129.083509) (xy 46.631842 -129.032632) (xy 46.658502 -128.98513) (xy 46.691793 -128.942016)
			(xy 46.731007 -128.904209) (xy 46.775309 -128.872514) (xy 46.823752 -128.847608) (xy 46.875306 -128.83002)
			(xy 46.928872 -128.820126) (xy 46.983307 -128.818136) (xy 47.037452 -128.824094) (xy 47.090152 -128.837872)
			(xy 47.140285 -128.859176) (xy 47.186781 -128.887552) (xy 47.228651 -128.922396) (xy 47.265 -128.962965)
			(xy 47.295056 -129.008394) (xy 47.318177 -129.057715) (xy 47.33387 -129.109877) (xy 47.341801 -129.163768)
			(xy 47.342298 -129.191004) (xy 47.341801 -129.21824) (xy 47.33387 -129.272131) (xy 47.318177 -129.324293)
			(xy 47.295056 -129.373614) (xy 47.265 -129.419043) (xy 47.228651 -129.459612) (xy 47.186781 -129.494456)
			(xy 47.140285 -129.522832) (xy 47.090152 -129.544136) (xy 47.037452 -129.557914) (xy 46.983307 -129.563872)
			(xy 46.928872 -129.561882) (xy 46.875306 -129.551988) (xy 46.823752 -129.5344) (xy 46.775309 -129.509494)
			(xy 46.731007 -129.477799) (xy 46.691793 -129.439992) (xy 46.658502 -129.396878) (xy 46.631842 -129.349376)
			(xy 46.612383 -129.298499) (xy 46.60054 -129.24533) (xy 46.596564 -129.191004) (xy 39.434182 -129.191004)
			(xy 39.411079 -129.21023) (xy 39.364583 -129.238606) (xy 39.31445 -129.25991) (xy 39.26175 -129.273688)
			(xy 39.207605 -129.279646) (xy 39.15317 -129.277656) (xy 39.099604 -129.267762) (xy 39.04805 -129.250174)
			(xy 38.999607 -129.225268) (xy 38.955305 -129.193573) (xy 38.916091 -129.155766) (xy 38.8828 -129.112652)
			(xy 38.85614 -129.06515) (xy 38.836681 -129.014273) (xy 38.824838 -128.961104) (xy 38.820862 -128.906778)
			(xy 30.10789 -128.906778) (xy 29.85008 -129.164588) (xy 29.85008 -129.238248) (xy 29.85064 -129.255161)
			(xy 29.859585 -129.287786) (xy 29.876781 -129.316917) (xy 29.901023 -129.340513) (xy 29.930608 -129.356916)
			(xy 29.963462 -129.364977) (xy 29.980382 -129.364994) (xy 29.984954 -129.364994) (xy 30.012479 -129.36416)
			(xy 30.067292 -129.369461) (xy 30.120772 -129.382587) (xy 30.17181 -129.403266) (xy 30.219345 -129.431067)
			(xy 30.262389 -129.465413) (xy 30.300049 -129.50559) (xy 30.331542 -129.550764) (xy 30.356213 -129.599996)
			(xy 30.37355 -129.652263) (xy 30.382537 -129.702793) (xy 43.354488 -129.702793) (xy 43.354488 -129.649495)
			(xy 43.362431 -129.596791) (xy 43.378141 -129.545861) (xy 43.401267 -129.49784) (xy 43.431291 -129.453803)
			(xy 43.467543 -129.414732) (xy 43.509214 -129.381501) (xy 43.555372 -129.354852) (xy 43.604986 -129.33538)
			(xy 43.656948 -129.32352) (xy 43.710098 -129.319537) (xy 43.763248 -129.32352) (xy 43.81521 -129.33538)
			(xy 43.864824 -129.354852) (xy 43.910982 -129.381501) (xy 43.952653 -129.414732) (xy 43.988905 -129.453803)
			(xy 44.018929 -129.49784) (xy 44.042055 -129.545861) (xy 44.057765 -129.596791) (xy 44.065708 -129.649495)
			(xy 44.066206 -129.676144) (xy 44.065708 -129.702793) (xy 44.057765 -129.755497) (xy 44.042055 -129.806427)
			(xy 44.018929 -129.854448) (xy 43.988905 -129.898485) (xy 43.952653 -129.937556) (xy 43.910982 -129.970787)
			(xy 43.864824 -129.997436) (xy 43.81521 -130.016908) (xy 43.763248 -130.028768) (xy 43.710098 -130.032752)
			(xy 43.656948 -130.028768) (xy 43.604986 -130.016908) (xy 43.555372 -129.997436) (xy 43.509214 -129.970787)
			(xy 43.467543 -129.937556) (xy 43.431291 -129.898485) (xy 43.401267 -129.854448) (xy 43.378141 -129.806427)
			(xy 43.362431 -129.755497) (xy 43.354488 -129.702793) (xy 30.382537 -129.702793) (xy 30.383193 -129.70648)
			(xy 30.384942 -129.76152) (xy 30.378759 -129.81624) (xy 30.364775 -129.869502) (xy 30.343278 -129.920201)
			(xy 30.314717 -129.967283) (xy 30.279683 -130.009769) (xy 30.238906 -130.046778) (xy 30.193231 -130.07754)
			(xy 30.143609 -130.101417) (xy 30.091069 -130.117911) (xy 30.063948 -130.122676) (xy 30.041881 -130.126698)
			(xy 29.999531 -130.141461) (xy 29.960427 -130.163425) (xy 29.925783 -130.191909) (xy 29.896674 -130.226029)
			(xy 29.874002 -130.264727) (xy 29.858472 -130.306802) (xy 29.850564 -130.350949) (xy 29.85008 -130.373374)
			(xy 29.85008 -131.153662) (xy 30.610554 -131.153662) (xy 30.614625 -131.09804) (xy 30.626751 -131.043603)
			(xy 30.646674 -130.991512) (xy 30.67397 -130.942877) (xy 30.708056 -130.898734) (xy 30.748205 -130.860025)
			(xy 30.793563 -130.827574) (xy 30.843163 -130.802073) (xy 30.895947 -130.784066) (xy 30.95079 -130.773936)
			(xy 31.006524 -130.771899) (xy 31.061961 -130.777999) (xy 31.115918 -130.792105) (xy 31.167247 -130.813917)
			(xy 31.214853 -130.842971) (xy 31.257721 -130.878646) (xy 31.294938 -130.920183) (xy 31.325711 -130.966696)
			(xy 31.349383 -131.017193) (xy 31.365451 -131.0706) (xy 31.373571 -131.125776) (xy 31.37408 -131.153662)
			(xy 31.373571 -131.181548) (xy 31.365923 -131.233517) (xy 35.016556 -131.233517) (xy 35.01949 -131.177679)
			(xy 35.030539 -131.122865) (xy 35.049467 -131.070251) (xy 35.075869 -131.020961) (xy 35.092132 -130.998214)
			(xy 35.10527 -130.979699) (xy 35.125419 -130.939021) (xy 35.13801 -130.895407) (xy 35.142642 -130.850249)
			(xy 35.139166 -130.804988) (xy 35.127694 -130.761066) (xy 35.108592 -130.719886) (xy 35.095942 -130.701034)
			(xy 35.080269 -130.677882) (xy 35.055134 -130.627944) (xy 35.037553 -130.574873) (xy 35.027903 -130.519805)
			(xy 35.026391 -130.463919) (xy 35.033048 -130.40841) (xy 35.047732 -130.354466) (xy 35.07013 -130.303241)
			(xy 35.099761 -130.255832) (xy 35.135992 -130.213254) (xy 35.178047 -130.176417) (xy 35.225026 -130.146109)
			(xy 35.275924 -130.12298) (xy 35.329652 -130.107525) (xy 35.38506 -130.100073) (xy 35.440963 -130.100784)
			(xy 35.496163 -130.109644) (xy 35.549481 -130.126463) (xy 35.599774 -130.15088) (xy 35.645966 -130.182373)
			(xy 35.68707 -130.220269) (xy 35.722205 -130.263756) (xy 35.75062 -130.311904) (xy 35.771706 -130.363682)
			(xy 35.785012 -130.417982) (xy 35.790254 -130.473643) (xy 35.787319 -130.529473) (xy 35.785504 -130.538474)
			(xy 38.874202 -130.538474) (xy 38.878178 -130.484148) (xy 38.890021 -130.430979) (xy 38.90948 -130.380102)
			(xy 38.93614 -130.3326) (xy 38.969431 -130.289486) (xy 39.008645 -130.251679) (xy 39.052947 -130.219984)
			(xy 39.10139 -130.195078) (xy 39.152944 -130.17749) (xy 39.20651 -130.167596) (xy 39.260945 -130.165606)
			(xy 39.31509 -130.171564) (xy 39.36779 -130.185342) (xy 39.379864 -130.190473) (xy 40.87748 -130.190473)
			(xy 40.87748 -130.137175) (xy 40.885423 -130.084471) (xy 40.901133 -130.033541) (xy 40.924259 -129.98552)
			(xy 40.954283 -129.941483) (xy 40.990535 -129.902412) (xy 41.032206 -129.869181) (xy 41.078364 -129.842532)
			(xy 41.127978 -129.82306) (xy 41.17994 -129.8112) (xy 41.23309 -129.807217) (xy 41.28624 -129.8112)
			(xy 41.338202 -129.82306) (xy 41.387816 -129.842532) (xy 41.433974 -129.869181) (xy 41.475645 -129.902412)
			(xy 41.511897 -129.941483) (xy 41.541921 -129.98552) (xy 41.565047 -130.033541) (xy 41.580757 -130.084471)
			(xy 41.588608 -130.136563) (xy 44.877871 -130.136563) (xy 44.886107 -130.082914) (xy 44.902389 -130.031135)
			(xy 44.926339 -129.982427) (xy 44.957402 -129.937917) (xy 44.99486 -129.898636) (xy 45.037845 -129.865493)
			(xy 45.085361 -129.839258) (xy 45.136308 -129.820536) (xy 45.189506 -129.809761) (xy 45.243722 -129.807184)
			(xy 45.297702 -129.812864) (xy 45.350195 -129.826668) (xy 45.399986 -129.848279) (xy 45.44592 -129.877194)
			(xy 45.466762 -129.894584) (xy 45.484238 -129.909064) (xy 45.523266 -129.932218) (xy 45.565784 -129.948075)
			(xy 45.610442 -129.956131) (xy 45.655822 -129.956131) (xy 45.70048 -129.948075) (xy 45.742998 -129.932218)
			(xy 45.782026 -129.909064) (xy 45.799502 -129.894584) (xy 45.820052 -129.877309) (xy 45.865459 -129.848667)
			(xy 45.914652 -129.827165) (xy 45.966514 -129.81329) (xy 46.019871 -129.807357) (xy 46.073515 -129.809499)
			(xy 46.126229 -129.819669) (xy 46.17682 -129.837636) (xy 46.224141 -129.862993) (xy 46.26712 -129.895165)
			(xy 46.304783 -129.933423) (xy 46.336277 -129.976901) (xy 46.360888 -130.024614) (xy 46.378059 -130.07548)
			(xy 46.387401 -130.128348) (xy 46.388701 -130.182018) (xy 46.381932 -130.235276) (xy 46.367245 -130.286914)
			(xy 46.344974 -130.335763) (xy 46.315623 -130.380716) (xy 46.298104 -130.40106) (xy 46.283117 -130.418447)
			(xy 46.259123 -130.457579) (xy 46.24255 -130.500384) (xy 46.233934 -130.54547) (xy 46.233773 -130.565144)
			(xy 46.989502 -130.565144) (xy 46.993478 -130.510818) (xy 47.005321 -130.457649) (xy 47.02478 -130.406772)
			(xy 47.05144 -130.35927) (xy 47.084731 -130.316156) (xy 47.123945 -130.278349) (xy 47.168247 -130.246654)
			(xy 47.21669 -130.221748) (xy 47.268244 -130.20416) (xy 47.32181 -130.194266) (xy 47.376245 -130.192276)
			(xy 47.43039 -130.198234) (xy 47.48309 -130.212012) (xy 47.533223 -130.233316) (xy 47.579719 -130.261692)
			(xy 47.621589 -130.296536) (xy 47.657938 -130.337105) (xy 47.687994 -130.382534) (xy 47.711115 -130.431855)
			(xy 47.726808 -130.484017) (xy 47.734739 -130.537908) (xy 47.735236 -130.565144) (xy 47.734739 -130.59238)
			(xy 47.726808 -130.646271) (xy 47.711115 -130.698433) (xy 47.687994 -130.747754) (xy 47.657938 -130.793183)
			(xy 47.621589 -130.833752) (xy 47.579719 -130.868596) (xy 47.533223 -130.896972) (xy 47.48309 -130.918276)
			(xy 47.43039 -130.932054) (xy 47.376245 -130.938012) (xy 47.32181 -130.936022) (xy 47.268244 -130.926128)
			(xy 47.21669 -130.90854) (xy 47.168247 -130.883634) (xy 47.123945 -130.851939) (xy 47.084731 -130.814132)
			(xy 47.05144 -130.771018) (xy 47.02478 -130.723516) (xy 47.005321 -130.672639) (xy 46.993478 -130.61947)
			(xy 46.989502 -130.565144) (xy 46.233773 -130.565144) (xy 46.233558 -130.59137) (xy 46.241432 -130.636592)
			(xy 46.257301 -130.679663) (xy 46.280649 -130.719183) (xy 46.29531 -130.736848) (xy 46.312118 -130.757037)
			(xy 46.340141 -130.801468) (xy 46.361151 -130.849613) (xy 46.374668 -130.900374) (xy 46.380383 -130.952593)
			(xy 46.378165 -131.005076) (xy 46.368066 -131.056626) (xy 46.350316 -131.106066) (xy 46.32532 -131.152267)
			(xy 46.293649 -131.194176) (xy 46.256025 -131.230835) (xy 46.213308 -131.261407) (xy 46.166473 -131.285194)
			(xy 46.116589 -131.301654) (xy 46.064794 -131.31041) (xy 46.012271 -131.311264) (xy 45.960219 -131.304195)
			(xy 45.909826 -131.289364) (xy 45.862242 -131.267111) (xy 45.818555 -131.237943) (xy 45.77976 -131.202525)
			(xy 45.746744 -131.161668) (xy 45.72026 -131.116303) (xy 45.700913 -131.067465) (xy 45.689145 -131.016271)
			(xy 45.685224 -130.963887) (xy 45.689239 -130.911511) (xy 45.7011 -130.860338) (xy 45.720534 -130.811535)
			(xy 45.747099 -130.766218) (xy 45.780189 -130.72542) (xy 45.819047 -130.690073) (xy 45.84065 -130.675126)
			(xy 45.853491 -130.665969) (xy 45.874699 -130.642647) (xy 45.889535 -130.614833) (xy 45.897093 -130.584229)
			(xy 45.896911 -130.552706) (xy 45.888999 -130.522192) (xy 45.873841 -130.494551) (xy 45.852364 -130.471476)
			(xy 45.83938 -130.462528) (xy 45.828963 -130.455718) (xy 45.809008 -130.440842) (xy 45.799502 -130.43281)
			(xy 45.782026 -130.41833) (xy 45.742998 -130.395176) (xy 45.70048 -130.379319) (xy 45.655822 -130.371263)
			(xy 45.610442 -130.371263) (xy 45.565784 -130.379319) (xy 45.523266 -130.395176) (xy 45.484238 -130.41833)
			(xy 45.466762 -130.43281) (xy 45.445924 -130.450204) (xy 45.399989 -130.479119) (xy 45.350199 -130.50073)
			(xy 45.297706 -130.514536) (xy 45.243726 -130.520216) (xy 45.189509 -130.517639) (xy 45.136312 -130.506865)
			(xy 45.085364 -130.488144) (xy 45.037848 -130.461909) (xy 44.994863 -130.428767) (xy 44.957405 -130.389486)
			(xy 44.926341 -130.344977) (xy 44.90239 -130.296269) (xy 44.886108 -130.24449) (xy 44.877872 -130.190841)
			(xy 44.877871 -130.136563) (xy 41.588608 -130.136563) (xy 41.5887 -130.137175) (xy 41.589198 -130.163824)
			(xy 41.5887 -130.190473) (xy 41.580757 -130.243177) (xy 41.565047 -130.294107) (xy 41.541921 -130.342128)
			(xy 41.511897 -130.386165) (xy 41.475645 -130.425236) (xy 41.433974 -130.458467) (xy 41.387816 -130.485116)
			(xy 41.338202 -130.504588) (xy 41.28624 -130.516448) (xy 41.23309 -130.520432) (xy 41.17994 -130.516448)
			(xy 41.127978 -130.504588) (xy 41.078364 -130.485116) (xy 41.032206 -130.458467) (xy 40.990535 -130.425236)
			(xy 40.954283 -130.386165) (xy 40.924259 -130.342128) (xy 40.901133 -130.294107) (xy 40.885423 -130.243177)
			(xy 40.87748 -130.190473) (xy 39.379864 -130.190473) (xy 39.417923 -130.206646) (xy 39.464419 -130.235022)
			(xy 39.506289 -130.269866) (xy 39.542638 -130.310435) (xy 39.572694 -130.355864) (xy 39.595815 -130.405185)
			(xy 39.611508 -130.457347) (xy 39.619439 -130.511238) (xy 39.619936 -130.538474) (xy 39.619439 -130.56571)
			(xy 39.611508 -130.619601) (xy 39.595815 -130.671763) (xy 39.572694 -130.721084) (xy 39.542638 -130.766513)
			(xy 39.506289 -130.807082) (xy 39.464419 -130.841926) (xy 39.417923 -130.870302) (xy 39.36779 -130.891606)
			(xy 39.31509 -130.905384) (xy 39.260945 -130.911342) (xy 39.20651 -130.909352) (xy 39.152944 -130.899458)
			(xy 39.10139 -130.88187) (xy 39.052947 -130.856964) (xy 39.008645 -130.825269) (xy 38.969431 -130.787462)
			(xy 38.93614 -130.744348) (xy 38.90948 -130.696846) (xy 38.890021 -130.645969) (xy 38.878178 -130.5928)
			(xy 38.874202 -130.538474) (xy 35.785504 -130.538474) (xy 35.776271 -130.584277) (xy 35.757345 -130.636883)
			(xy 35.730946 -130.686165) (xy 35.714686 -130.708908) (xy 35.701527 -130.727409) (xy 35.681379 -130.768091)
			(xy 35.668789 -130.811708) (xy 35.66416 -130.856868) (xy 35.667639 -130.902133) (xy 35.679116 -130.946056)
			(xy 35.688114 -130.965448) (xy 40.088055 -130.965448) (xy 40.09213 -130.912367) (xy 40.10426 -130.860531)
			(xy 40.124161 -130.811154) (xy 40.151366 -130.765393) (xy 40.185238 -130.724321) (xy 40.224982 -130.688902)
			(xy 40.269667 -130.659964) (xy 40.318246 -130.638186) (xy 40.369579 -130.62408) (xy 40.422465 -130.617974)
			(xy 40.475663 -130.620013) (xy 40.527926 -130.630149) (xy 40.578029 -130.648144) (xy 40.612195 -130.666723)
			(xy 42.364396 -130.666723) (xy 42.364396 -130.613425) (xy 42.372339 -130.560721) (xy 42.388049 -130.509791)
			(xy 42.411175 -130.46177) (xy 42.441199 -130.417733) (xy 42.477451 -130.378662) (xy 42.519122 -130.345431)
			(xy 42.56528 -130.318782) (xy 42.614894 -130.29931) (xy 42.666856 -130.28745) (xy 42.720006 -130.283467)
			(xy 42.773156 -130.28745) (xy 42.825118 -130.29931) (xy 42.874732 -130.318782) (xy 42.92089 -130.345431)
			(xy 42.962561 -130.378662) (xy 42.998813 -130.417733) (xy 43.028837 -130.46177) (xy 43.051963 -130.509791)
			(xy 43.067673 -130.560721) (xy 43.075616 -130.613425) (xy 43.076114 -130.640074) (xy 43.075616 -130.666723)
			(xy 43.067673 -130.719427) (xy 43.051963 -130.770357) (xy 43.028837 -130.818378) (xy 42.998813 -130.862415)
			(xy 42.962561 -130.901486) (xy 42.92089 -130.934717) (xy 42.874732 -130.961366) (xy 42.825118 -130.980838)
			(xy 42.773156 -130.992698) (xy 42.720006 -130.996682) (xy 42.666856 -130.992698) (xy 42.614894 -130.980838)
			(xy 42.56528 -130.961366) (xy 42.519122 -130.934717) (xy 42.477451 -130.901486) (xy 42.441199 -130.862415)
			(xy 42.411175 -130.818378) (xy 42.388049 -130.770357) (xy 42.372339 -130.719427) (xy 42.364396 -130.666723)
			(xy 40.612195 -130.666723) (xy 40.624798 -130.673576) (xy 40.667137 -130.70585) (xy 40.704053 -130.744208)
			(xy 40.734681 -130.787752) (xy 40.758303 -130.835461) (xy 40.774366 -130.886217) (xy 40.782493 -130.93883)
			(xy 40.783002 -130.965448) (xy 40.782493 -130.992066) (xy 40.77931 -131.012671) (xy 43.650398 -131.012671)
			(xy 43.650398 -130.959373) (xy 43.658341 -130.906669) (xy 43.674051 -130.855739) (xy 43.697177 -130.807718)
			(xy 43.727201 -130.763681) (xy 43.763453 -130.72461) (xy 43.805124 -130.691379) (xy 43.851282 -130.66473)
			(xy 43.900896 -130.645258) (xy 43.952858 -130.633398) (xy 44.006008 -130.629415) (xy 44.059158 -130.633398)
			(xy 44.11112 -130.645258) (xy 44.160734 -130.66473) (xy 44.206892 -130.691379) (xy 44.248563 -130.72461)
			(xy 44.284815 -130.763681) (xy 44.314839 -130.807718) (xy 44.337965 -130.855739) (xy 44.353675 -130.906669)
			(xy 44.361618 -130.959373) (xy 44.362116 -130.986022) (xy 44.361618 -131.012671) (xy 44.353675 -131.065375)
			(xy 44.337965 -131.116305) (xy 44.314839 -131.164326) (xy 44.284815 -131.208363) (xy 44.248563 -131.247434)
			(xy 44.206892 -131.280665) (xy 44.160734 -131.307314) (xy 44.11112 -131.326786) (xy 44.059158 -131.338646)
			(xy 44.006008 -131.34263) (xy 43.952858 -131.338646) (xy 43.900896 -131.326786) (xy 43.851282 -131.307314)
			(xy 43.805124 -131.280665) (xy 43.763453 -131.247434) (xy 43.727201 -131.208363) (xy 43.697177 -131.164326)
			(xy 43.674051 -131.116305) (xy 43.658341 -131.065375) (xy 43.650398 -131.012671) (xy 40.77931 -131.012671)
			(xy 40.774366 -131.044679) (xy 40.758303 -131.095435) (xy 40.734681 -131.143144) (xy 40.704053 -131.186688)
			(xy 40.667137 -131.225046) (xy 40.624798 -131.25732) (xy 40.578029 -131.282752) (xy 40.527926 -131.300747)
			(xy 40.475663 -131.310883) (xy 40.422465 -131.312922) (xy 40.369579 -131.306816) (xy 40.318246 -131.29271)
			(xy 40.269667 -131.270932) (xy 40.224982 -131.241994) (xy 40.185238 -131.206575) (xy 40.151366 -131.165503)
			(xy 40.124161 -131.119742) (xy 40.10426 -131.070365) (xy 40.09213 -131.018529) (xy 40.088055 -130.965448)
			(xy 35.688114 -130.965448) (xy 35.698223 -130.987236) (xy 35.710876 -131.006088) (xy 35.72661 -131.029202)
			(xy 35.751755 -131.079145) (xy 35.769345 -131.132222) (xy 35.779002 -131.187298) (xy 35.780521 -131.243193)
			(xy 35.773869 -131.298712) (xy 35.759188 -131.352666) (xy 35.736792 -131.403901) (xy 35.70716 -131.45132)
			(xy 35.670927 -131.493908) (xy 35.628869 -131.530755) (xy 35.581885 -131.56107) (xy 35.53098 -131.584207)
			(xy 35.477245 -131.599669) (xy 35.421828 -131.607126) (xy 35.365917 -131.606418) (xy 35.310707 -131.59756)
			(xy 35.25738 -131.580742) (xy 35.207078 -131.556323) (xy 35.160877 -131.524827) (xy 35.119765 -131.486928)
			(xy 35.084622 -131.443435) (xy 35.056201 -131.395281) (xy 35.03511 -131.343495) (xy 35.0218 -131.289187)
			(xy 35.016556 -131.233517) (xy 31.365923 -131.233517) (xy 31.365451 -131.236724) (xy 31.349383 -131.290131)
			(xy 31.325711 -131.340628) (xy 31.294938 -131.387141) (xy 31.257721 -131.428678) (xy 31.214853 -131.464353)
			(xy 31.167247 -131.493407) (xy 31.115918 -131.515219) (xy 31.061961 -131.529325) (xy 31.006524 -131.535425)
			(xy 30.95079 -131.533388) (xy 30.895947 -131.523258) (xy 30.843163 -131.505251) (xy 30.793563 -131.47975)
			(xy 30.748205 -131.447299) (xy 30.708056 -131.40859) (xy 30.67397 -131.364447) (xy 30.646674 -131.315812)
			(xy 30.626751 -131.263721) (xy 30.614625 -131.209284) (xy 30.610554 -131.153662) (xy 29.85008 -131.153662)
			(xy 29.85008 -131.887448) (xy 42.725501 -131.887448) (xy 42.72841 -131.83497) (xy 42.738998 -131.783489)
			(xy 42.757034 -131.734122) (xy 42.782127 -131.687941) (xy 42.813733 -131.645948) (xy 42.851166 -131.609054)
			(xy 42.893613 -131.57806) (xy 42.940153 -131.553639) (xy 42.989776 -131.536321) (xy 43.041405 -131.526481)
			(xy 43.09392 -131.524334) (xy 43.14618 -131.529925) (xy 43.197051 -131.543134) (xy 43.24543 -131.563673)
			(xy 43.290266 -131.591098) (xy 43.330586 -131.624812) (xy 43.348402 -131.644136) (xy 43.364018 -131.660902)
			(xy 43.400106 -131.689123) (xy 43.440663 -131.710427) (xy 43.48438 -131.724124) (xy 43.529842 -131.729772)
			(xy 43.575582 -131.727189) (xy 43.620119 -131.716457) (xy 43.641264 -131.707636) (xy 43.665422 -131.697328)
			(xy 43.716083 -131.683463) (xy 43.768255 -131.677385) (xy 43.820747 -131.679233) (xy 43.872362 -131.688964)
			(xy 43.921923 -131.706357) (xy 43.9683 -131.731016) (xy 44.010434 -131.762376) (xy 44.011812 -131.76377)
			(xy 44.885861 -131.76377) (xy 44.889936 -131.710689) (xy 44.902066 -131.658853) (xy 44.921967 -131.609476)
			(xy 44.949172 -131.563715) (xy 44.983044 -131.522643) (xy 45.022788 -131.487224) (xy 45.067473 -131.458286)
			(xy 45.116052 -131.436508) (xy 45.167385 -131.422402) (xy 45.220271 -131.416296) (xy 45.273469 -131.418335)
			(xy 45.325732 -131.428471) (xy 45.375835 -131.446466) (xy 45.422604 -131.471898) (xy 45.464943 -131.504172)
			(xy 45.501859 -131.54253) (xy 45.532487 -131.586074) (xy 45.556109 -131.633783) (xy 45.572172 -131.684539)
			(xy 45.575426 -131.705604) (xy 46.976802 -131.705604) (xy 46.980778 -131.651278) (xy 46.992621 -131.598109)
			(xy 47.01208 -131.547232) (xy 47.03874 -131.49973) (xy 47.072031 -131.456616) (xy 47.111245 -131.418809)
			(xy 47.155547 -131.387114) (xy 47.20399 -131.362208) (xy 47.255544 -131.34462) (xy 47.30911 -131.334726)
			(xy 47.363545 -131.332736) (xy 47.41769 -131.338694) (xy 47.47039 -131.352472) (xy 47.520523 -131.373776)
			(xy 47.567019 -131.402152) (xy 47.608889 -131.436996) (xy 47.645238 -131.477565) (xy 47.675294 -131.522994)
			(xy 47.698415 -131.572315) (xy 47.714108 -131.624477) (xy 47.722039 -131.678368) (xy 47.722536 -131.705604)
			(xy 47.722039 -131.73284) (xy 47.714108 -131.786731) (xy 47.698415 -131.838893) (xy 47.675294 -131.888214)
			(xy 47.645238 -131.933643) (xy 47.608889 -131.974212) (xy 47.567019 -132.009056) (xy 47.520523 -132.037432)
			(xy 47.47039 -132.058736) (xy 47.41769 -132.072514) (xy 47.363545 -132.078472) (xy 47.30911 -132.076482)
			(xy 47.255544 -132.066588) (xy 47.20399 -132.049) (xy 47.155547 -132.024094) (xy 47.111245 -131.992399)
			(xy 47.072031 -131.954592) (xy 47.03874 -131.911478) (xy 47.01208 -131.863976) (xy 46.992621 -131.813099)
			(xy 46.980778 -131.75993) (xy 46.976802 -131.705604) (xy 45.575426 -131.705604) (xy 45.580299 -131.737152)
			(xy 45.580808 -131.76377) (xy 45.580299 -131.790388) (xy 45.572172 -131.843001) (xy 45.556109 -131.893757)
			(xy 45.532487 -131.941466) (xy 45.501859 -131.98501) (xy 45.464943 -132.023368) (xy 45.422604 -132.055642)
			(xy 45.375835 -132.081074) (xy 45.325732 -132.099069) (xy 45.273469 -132.109205) (xy 45.220271 -132.111244)
			(xy 45.167385 -132.105138) (xy 45.116052 -132.091032) (xy 45.067473 -132.069254) (xy 45.022788 -132.040316)
			(xy 44.983044 -132.004897) (xy 44.949172 -131.963825) (xy 44.921967 -131.918064) (xy 44.902066 -131.868687)
			(xy 44.889936 -131.816851) (xy 44.885861 -131.76377) (xy 44.011812 -131.76377) (xy 44.047366 -131.799724)
			(xy 44.078252 -131.842208) (xy 44.102388 -131.888858) (xy 44.119225 -131.938611) (xy 44.128377 -131.990332)
			(xy 44.129636 -132.042842) (xy 44.122973 -132.094942) (xy 44.108541 -132.145445) (xy 44.086668 -132.193198)
			(xy 44.057853 -132.237113) (xy 44.022754 -132.276188) (xy 43.982171 -132.309532) (xy 43.937029 -132.336385)
			(xy 43.888359 -132.356133) (xy 43.837269 -132.368327) (xy 43.784926 -132.372689) (xy 43.732523 -132.369118)
			(xy 43.681255 -132.357697) (xy 43.632292 -132.338686) (xy 43.58675 -132.312518) (xy 43.545668 -132.279791)
			(xy 43.527472 -132.260848) (xy 43.51156 -132.244357) (xy 43.474885 -132.216885) (xy 43.433882 -132.196427)
			(xy 43.389878 -132.183644) (xy 43.344295 -132.178951) (xy 43.298609 -132.182499) (xy 43.254298 -132.194174)
			(xy 43.23334 -132.203444) (xy 43.20937 -132.214224) (xy 43.159018 -132.22929) (xy 43.106998 -132.236796)
			(xy 43.05444 -132.236577) (xy 43.002485 -132.228639) (xy 42.95226 -132.213153) (xy 42.904854 -132.190457)
			(xy 42.861298 -132.161042) (xy 42.822537 -132.125546) (xy 42.789411 -132.084742) (xy 42.762639 -132.039512)
			(xy 42.742804 -131.990841) (xy 42.730334 -131.939783) (xy 42.725501 -131.887448) (xy 29.85008 -131.887448)
			(xy 29.85008 -132.263866) (xy 38.674588 -132.263866) (xy 38.678909 -132.209724) (xy 38.691045 -132.156782)
			(xy 38.710738 -132.106163) (xy 38.737572 -132.05894) (xy 38.770978 -132.016113) (xy 38.810247 -131.978589)
			(xy 38.854548 -131.947164) (xy 38.902942 -131.922504) (xy 38.954404 -131.905132) (xy 39.007843 -131.895414)
			(xy 39.062126 -131.893558) (xy 39.116103 -131.899603) (xy 39.168631 -131.91342) (xy 39.218597 -131.934717)
			(xy 39.264941 -131.963043) (xy 39.306681 -131.997797) (xy 39.342934 -132.038242) (xy 39.37293 -132.083523)
			(xy 39.396035 -132.132678) (xy 39.411759 -132.184667) (xy 39.419768 -132.238389) (xy 39.419892 -132.292703)
			(xy 39.41213 -132.346461) (xy 39.396645 -132.398521) (xy 39.373767 -132.447783) (xy 39.343978 -132.4932)
			(xy 39.326312 -132.513832) (xy 39.310958 -132.531905) (xy 39.286598 -132.572586) (xy 39.281692 -132.5859)
			(xy 40.084636 -132.5859) (xy 40.084873 -132.532616) (xy 40.093247 -132.479995) (xy 40.109562 -132.42927)
			(xy 40.133434 -132.381632) (xy 40.164303 -132.338201) (xy 40.201445 -132.299995) (xy 40.243987 -132.267912)
			(xy 40.290931 -132.242704) (xy 40.341175 -132.224964) (xy 40.39354 -132.215107) (xy 40.446796 -132.213366)
			(xy 40.499692 -132.21978) (xy 40.550988 -132.2342) (xy 40.599479 -132.256288) (xy 40.644026 -132.285523)
			(xy 40.66413 -132.303012) (xy 40.681666 -132.318185) (xy 40.721168 -132.342469) (xy 40.76442 -132.35918)
			(xy 40.809988 -132.367763) (xy 40.856357 -132.367933) (xy 40.901986 -132.359684) (xy 40.94536 -132.34329)
			(xy 40.985038 -132.319296) (xy 41.002712 -132.304282) (xy 41.022942 -132.286931) (xy 41.067753 -132.258079)
			(xy 41.116445 -132.23641) (xy 41.167876 -132.222435) (xy 41.220839 -132.216482) (xy 41.274089 -132.218689)
			(xy 41.326377 -132.229006) (xy 41.376475 -132.247189) (xy 41.423207 -132.272813) (xy 41.465476 -132.305275)
			(xy 41.502289 -132.343814) (xy 41.532783 -132.387524) (xy 41.556241 -132.43538) (xy 41.572113 -132.486258)
			(xy 41.580025 -132.538964) (xy 41.579793 -132.592259) (xy 41.571421 -132.644893) (xy 41.555107 -132.695631)
			(xy 41.531233 -132.743281) (xy 41.500359 -132.786724) (xy 41.463211 -132.82494) (xy 41.420661 -132.857033)
			(xy 41.373708 -132.882248) (xy 41.323453 -132.899995) (xy 41.271077 -132.909855) (xy 41.21781 -132.911598)
			(xy 41.164901 -132.905183) (xy 41.113594 -132.890761) (xy 41.065092 -132.868669) (xy 41.020535 -132.839427)
			(xy 41.000426 -132.821934) (xy 40.982844 -132.806818) (xy 40.943351 -132.782536) (xy 40.900107 -132.765824)
			(xy 40.854549 -132.757237) (xy 40.808189 -132.75706) (xy 40.762566 -132.765298) (xy 40.719196 -132.781679)
			(xy 40.679519 -132.805658) (xy 40.661844 -132.820664) (xy 40.64157 -132.837956) (xy 40.596764 -132.866794)
			(xy 40.548079 -132.888449) (xy 40.496657 -132.902413) (xy 40.443705 -132.908357) (xy 40.390467 -132.906142)
			(xy 40.338193 -132.89582) (xy 40.288108 -132.877633) (xy 40.24139 -132.852009) (xy 40.199135 -132.819549)
			(xy 40.162334 -132.781014) (xy 40.131852 -132.73731) (xy 40.108405 -132.689462) (xy 40.092542 -132.638594)
			(xy 40.084636 -132.5859) (xy 39.281692 -132.5859) (xy 39.270202 -132.617078) (xy 39.262339 -132.663838)
			(xy 39.263282 -132.711246) (xy 39.272998 -132.757656) (xy 39.29115 -132.801461) (xy 39.317109 -132.841141)
			(xy 39.349974 -132.875321) (xy 39.368984 -132.889498) (xy 39.391109 -132.905872) (xy 39.430949 -132.943846)
			(xy 39.464895 -132.987129) (xy 42.020645 -132.987129) (xy 42.021368 -132.934165) (xy 42.029928 -132.881893)
			(xy 42.046136 -132.831465) (xy 42.069635 -132.783994) (xy 42.099907 -132.740527) (xy 42.136283 -132.702024)
			(xy 42.177961 -132.669334) (xy 42.224021 -132.643178) (xy 42.273448 -132.624133) (xy 42.32515 -132.612619)
			(xy 42.377988 -132.608891) (xy 42.430794 -132.61303) (xy 42.482406 -132.624946) (xy 42.531683 -132.644375)
			(xy 42.577538 -132.670889) (xy 42.61896 -132.703902) (xy 42.655036 -132.742687) (xy 42.684968 -132.786388)
			(xy 42.708097 -132.834041) (xy 42.723912 -132.884593) (xy 42.732065 -132.936931) (xy 42.732392 -132.950437)
			(xy 56.381894 -132.950437) (xy 56.381894 -132.897139) (xy 56.389837 -132.844435) (xy 56.405547 -132.793505)
			(xy 56.428673 -132.745484) (xy 56.458697 -132.701447) (xy 56.494949 -132.662376) (xy 56.53662 -132.629145)
			(xy 56.582778 -132.602496) (xy 56.632392 -132.583024) (xy 56.684354 -132.571164) (xy 56.737504 -132.567181)
			(xy 56.790654 -132.571164) (xy 56.842616 -132.583024) (xy 56.89223 -132.602496) (xy 56.938388 -132.629145)
			(xy 56.980059 -132.662376) (xy 57.016311 -132.701447) (xy 57.046335 -132.745484) (xy 57.069461 -132.793505)
			(xy 57.085171 -132.844435) (xy 57.093114 -132.897139) (xy 57.093612 -132.923788) (xy 57.093114 -132.950437)
			(xy 57.085171 -133.003141) (xy 57.069461 -133.054071) (xy 57.046335 -133.102092) (xy 57.016311 -133.146129)
			(xy 56.980059 -133.1852) (xy 56.938388 -133.218431) (xy 56.89223 -133.24508) (xy 56.842616 -133.264552)
			(xy 56.790654 -133.276412) (xy 56.737504 -133.280396) (xy 56.684354 -133.276412) (xy 56.632392 -133.264552)
			(xy 56.582778 -133.24508) (xy 56.53662 -133.218431) (xy 56.494949 -133.1852) (xy 56.458697 -133.146129)
			(xy 56.428673 -133.102092) (xy 56.405547 -133.054071) (xy 56.389837 -133.003141) (xy 56.381894 -132.950437)
			(xy 42.732392 -132.950437) (xy 42.732706 -132.963412) (xy 42.733339 -132.986996) (xy 42.742304 -133.033311)
			(xy 42.759663 -133.077176) (xy 42.78482 -133.117083) (xy 42.816911 -133.151661) (xy 42.854832 -133.179723)
			(xy 42.897281 -133.200303) (xy 42.919904 -133.206998) (xy 42.945808 -133.214548) (xy 42.995068 -133.236564)
			(xy 43.040325 -133.26594) (xy 43.080488 -133.301969) (xy 43.114588 -133.343782) (xy 43.141804 -133.39037)
			(xy 43.161478 -133.44061) (xy 43.167808 -133.46684) (xy 43.173327 -133.489365) (xy 43.191441 -133.532052)
			(xy 43.217 -133.570744) (xy 43.249155 -133.604157) (xy 43.286839 -133.63118) (xy 43.328801 -133.650918)
			(xy 43.373647 -133.662714) (xy 43.419889 -133.666178) (xy 43.465992 -133.661194) (xy 43.488356 -133.655054)
			(xy 43.514191 -133.647846) (xy 43.567325 -133.640539) (xy 43.620951 -133.641488) (xy 43.673793 -133.650672)
			(xy 43.724595 -133.667872) (xy 43.772148 -133.692678) (xy 43.815321 -133.724501) (xy 43.834558 -133.743192)
			(xy 43.851154 -133.759169) (xy 43.888962 -133.785481) (xy 43.930892 -133.804551) (xy 43.975571 -133.815753)
			(xy 44.021538 -133.818723) (xy 44.067287 -133.813361) (xy 44.111322 -133.799845) (xy 44.131992 -133.789674)
			(xy 44.156386 -133.777465) (xy 44.20805 -133.759955) (xy 44.26178 -133.750526) (xy 44.316319 -133.749399)
			(xy 44.370392 -133.756599) (xy 44.422735 -133.77196) (xy 44.472125 -133.795121) (xy 44.517406 -133.825542)
			(xy 44.557519 -133.86251) (xy 44.591528 -133.905162) (xy 44.618637 -133.9525) (xy 44.638211 -134.003417)
			(xy 44.649794 -134.056724) (xy 44.653114 -134.111174) (xy 44.648226 -134.16407) (xy 45.659812 -134.16407)
			(xy 45.663788 -134.109744) (xy 45.675631 -134.056575) (xy 45.69509 -134.005698) (xy 45.72175 -133.958196)
			(xy 45.755041 -133.915082) (xy 45.794255 -133.877275) (xy 45.838557 -133.84558) (xy 45.887 -133.820674)
			(xy 45.938554 -133.803086) (xy 45.99212 -133.793192) (xy 46.046555 -133.791202) (xy 46.1007 -133.79716)
			(xy 46.1534 -133.810938) (xy 46.203533 -133.832242) (xy 46.250029 -133.860618) (xy 46.291899 -133.895462)
			(xy 46.328248 -133.936031) (xy 46.358304 -133.98146) (xy 46.381425 -134.030781) (xy 46.397118 -134.082943)
			(xy 46.405049 -134.136834) (xy 46.405546 -134.16407) (xy 46.405049 -134.191306) (xy 46.397118 -134.245197)
			(xy 46.381425 -134.297359) (xy 46.374273 -134.312616) (xy 51.753389 -134.312616) (xy 51.75847 -134.258258)
			(xy 51.771249 -134.20518) (xy 51.791463 -134.154465) (xy 51.8187 -134.10715) (xy 51.852404 -134.064201)
			(xy 51.891886 -134.026495) (xy 51.93634 -133.994803) (xy 51.984858 -133.969771) (xy 52.036449 -133.951911)
			(xy 52.090058 -133.941588) (xy 52.144592 -133.939012) (xy 52.198937 -133.944237) (xy 52.251981 -133.957155)
			(xy 52.302642 -133.977503) (xy 52.349885 -134.004865) (xy 52.392745 -134.038683) (xy 52.411884 -134.058152)
			(xy 52.423654 -134.069822) (xy 52.451864 -134.087197) (xy 52.483597 -134.096723) (xy 52.516713 -134.097756)
			(xy 52.548979 -134.090227) (xy 52.578217 -134.074644) (xy 52.5907 -134.06374) (xy 52.611489 -134.044959)
			(xy 52.657722 -134.013315) (xy 52.708174 -133.988953) (xy 52.761704 -133.972421) (xy 52.817108 -133.964093)
			(xy 52.873133 -133.964156) (xy 52.928517 -133.972609) (xy 52.982011 -133.989262) (xy 53.032407 -134.013738)
			(xy 53.055774 -134.029196) (xy 53.074748 -134.041654) (xy 53.116097 -134.060363) (xy 53.160112 -134.071429)
			(xy 53.205393 -134.074499) (xy 53.250499 -134.069477) (xy 53.293996 -134.056522) (xy 53.334499 -134.036045)
			(xy 53.37072 -134.008699) (xy 53.386482 -133.992366) (xy 53.405671 -133.972289) (xy 53.44884 -133.937349)
			(xy 53.496619 -133.909039) (xy 53.547999 -133.887957) (xy 53.601893 -133.874551) (xy 53.657162 -133.869102)
			(xy 53.712637 -133.871726) (xy 53.767144 -133.882368) (xy 53.819532 -133.900802) (xy 53.868692 -133.92664)
			(xy 53.891434 -133.942582) (xy 53.909475 -133.955197) (xy 53.949001 -133.974573) (xy 53.991276 -133.986845)
			(xy 54.035034 -133.991647) (xy 54.078964 -133.988833) (xy 54.121752 -133.978489) (xy 54.162116 -133.960925)
			(xy 54.18074 -133.949186) (xy 54.205046 -133.933708) (xy 54.257443 -133.90973) (xy 54.312908 -133.894108)
			(xy 54.370118 -133.887216) (xy 54.427706 -133.889216) (xy 54.484299 -133.900062) (xy 54.538546 -133.919495)
			(xy 54.589154 -133.947051) (xy 54.634913 -133.982072) (xy 54.655212 -134.002526) (xy 54.667579 -134.014567)
			(xy 54.69722 -134.032217) (xy 54.73051 -134.04127) (xy 54.765007 -134.041063) (xy 54.798186 -134.031611)
			(xy 54.8132 -134.0231) (xy 54.836148 -134.009594) (xy 54.88508 -133.988594) (xy 54.936505 -133.974778)
			(xy 54.989373 -133.968428) (xy 55.042607 -133.969672) (xy 55.09512 -133.978485) (xy 55.145843 -133.994688)
			(xy 55.193741 -134.01795) (xy 55.216044 -134.032498) (xy 55.234494 -134.044319) (xy 55.274485 -134.062214)
			(xy 55.316951 -134.072996) (xy 55.360635 -134.076344) (xy 55.404247 -134.072161) (xy 55.446499 -134.060571)
			(xy 55.486141 -134.041915) (xy 55.504334 -134.029704) (xy 55.526273 -134.01486) (xy 55.573629 -133.99113)
			(xy 55.623977 -133.974675) (xy 55.676207 -133.965858) (xy 55.729167 -133.964874) (xy 55.781688 -133.971743)
			(xy 55.832613 -133.986314) (xy 55.880819 -134.008267) (xy 55.925242 -134.037117) (xy 55.964902 -134.072227)
			(xy 55.998926 -134.112824) (xy 56.026562 -134.158011) (xy 56.047202 -134.206794) (xy 56.060389 -134.258094)
			(xy 56.065834 -134.310783) (xy 56.063415 -134.363696) (xy 56.053187 -134.415668) (xy 56.035376 -134.465552)
			(xy 56.010372 -134.512249) (xy 55.978729 -134.554727) (xy 55.941145 -134.592051) (xy 55.898447 -134.623397)
			(xy 55.851577 -134.648075) (xy 55.80157 -134.665539) (xy 55.749528 -134.675404) (xy 55.696599 -134.677454)
			(xy 55.64395 -134.671642) (xy 55.592742 -134.658098) (xy 55.544105 -134.637119) (xy 55.521352 -134.623556)
			(xy 55.502503 -134.612361) (xy 55.461849 -134.595958) (xy 55.418984 -134.586774) (xy 55.375179 -134.585083)
			(xy 55.331733 -134.590935) (xy 55.289936 -134.604155) (xy 55.251028 -134.624351) (xy 55.233316 -134.637272)
			(xy 55.211358 -134.653334) (xy 55.163778 -134.679706) (xy 55.112869 -134.698878) (xy 55.059712 -134.710442)
			(xy 55.005439 -134.714152) (xy 54.951203 -134.70993) (xy 54.898158 -134.697864) (xy 54.847432 -134.678213)
			(xy 54.800103 -134.651393) (xy 54.757178 -134.617975) (xy 54.738016 -134.598664) (xy 54.725705 -134.586561)
			(xy 54.696045 -134.568918) (xy 54.66274 -134.559877) (xy 54.62823 -134.560099) (xy 54.595044 -134.56957)
			(xy 54.580028 -134.57809) (xy 54.556787 -134.591742) (xy 54.50721 -134.612893) (xy 54.455102 -134.626678)
			(xy 54.401551 -134.63281) (xy 54.347675 -134.63116) (xy 54.2946 -134.621764) (xy 54.243433 -134.604816)
			(xy 54.195243 -134.580672) (xy 54.172866 -134.565644) (xy 54.15451 -134.55351) (xy 54.114606 -134.534984)
			(xy 54.072108 -134.523608) (xy 54.028285 -134.519721) (xy 53.984448 -134.523441) (xy 53.941906 -134.534655)
			(xy 53.901932 -134.553029) (xy 53.88356 -134.565136) (xy 53.859248 -134.581251) (xy 53.806739 -134.606645)
			(xy 53.750978 -134.623757) (xy 53.693264 -134.632189) (xy 53.634938 -134.631745) (xy 53.577359 -134.622436)
			(xy 53.521865 -134.604479) (xy 53.469748 -134.57829) (xy 53.445664 -134.561834) (xy 53.426911 -134.549044)
			(xy 53.385874 -134.529651) (xy 53.342043 -134.517865) (xy 53.296814 -134.51406) (xy 53.25163 -134.518358)
			(xy 53.20793 -134.530621) (xy 53.167106 -134.55046) (xy 53.130461 -134.577241) (xy 53.114448 -134.59333)
			(xy 53.095314 -134.612623) (xy 53.052531 -134.646112) (xy 53.005336 -134.673031) (xy 52.954732 -134.692809)
			(xy 52.901792 -134.705027) (xy 52.847638 -134.709425) (xy 52.79342 -134.705909) (xy 52.740287 -134.694556)
			(xy 52.689368 -134.675604) (xy 52.641741 -134.649457) (xy 52.598418 -134.616669) (xy 52.579016 -134.597648)
			(xy 52.567065 -134.586177) (xy 52.538538 -134.569353) (xy 52.506643 -134.560434) (xy 52.473527 -134.560019)
			(xy 52.441419 -134.568137) (xy 52.41248 -134.58424) (xy 52.4002 -134.595362) (xy 52.380266 -134.614015)
			(xy 52.335979 -134.645942) (xy 52.287594 -134.67123) (xy 52.236099 -134.689362) (xy 52.182544 -134.699968)
			(xy 52.128025 -134.702831) (xy 52.073654 -134.697894) (xy 52.020542 -134.685256) (xy 51.969774 -134.665176)
			(xy 51.922387 -134.638064) (xy 51.879349 -134.604473) (xy 51.841539 -134.565091) (xy 51.809729 -134.52072)
			(xy 51.784569 -134.472269) (xy 51.766573 -134.420725) (xy 51.756109 -134.367143) (xy 51.753389 -134.312616)
			(xy 46.374273 -134.312616) (xy 46.358304 -134.34668) (xy 46.328248 -134.392109) (xy 46.291899 -134.432678)
			(xy 46.250029 -134.467522) (xy 46.203533 -134.495898) (xy 46.1534 -134.517202) (xy 46.1007 -134.53098)
			(xy 46.046555 -134.536938) (xy 45.99212 -134.534948) (xy 45.938554 -134.525054) (xy 45.887 -134.507466)
			(xy 45.838557 -134.48256) (xy 45.794255 -134.450865) (xy 45.755041 -134.413058) (xy 45.72175 -134.369944)
			(xy 45.69509 -134.322442) (xy 45.675631 -134.271565) (xy 45.663788 -134.218396) (xy 45.659812 -134.16407)
			(xy 44.648226 -134.16407) (xy 44.648094 -134.165493) (xy 44.634852 -134.218412) (xy 44.613696 -134.268693)
			(xy 44.585122 -134.315161) (xy 44.567856 -134.336282) (xy 44.553761 -134.353659) (xy 44.531236 -134.392315)
			(xy 44.51583 -134.434318) (xy 44.508018 -134.47837) (xy 44.508043 -134.52311) (xy 44.515903 -134.567153)
			(xy 44.531356 -134.609139) (xy 44.553923 -134.64777) (xy 44.582908 -134.681851) (xy 44.59986 -134.696454)
			(xy 44.627038 -134.7216) (xy 44.64303 -134.737295) (xy 44.679494 -134.763331) (xy 44.719961 -134.782565)
			(xy 44.763175 -134.7944) (xy 44.807795 -134.79847) (xy 44.852437 -134.794648) (xy 44.895715 -134.783052)
			(xy 44.936288 -134.764043) (xy 44.972896 -134.738209) (xy 44.988988 -134.722616) (xy 45.007951 -134.704103)
			(xy 45.050502 -134.672514) (xy 45.09736 -134.647757) (xy 45.147435 -134.630409) (xy 45.199564 -134.620871)
			(xy 45.252538 -134.619366) (xy 45.305125 -134.625928) (xy 45.356105 -134.640405) (xy 45.404292 -134.66246)
			(xy 45.448568 -134.691582) (xy 45.487905 -134.727094) (xy 45.521389 -134.768171) (xy 45.533169 -134.788214)
			(xy 47.55784 -134.788214) (xy 47.562064 -134.734562) (xy 47.574313 -134.682156) (xy 47.594307 -134.632189)
			(xy 47.621592 -134.5858) (xy 47.655546 -134.544044) (xy 47.695396 -134.507873) (xy 47.740236 -134.47811)
			(xy 47.789043 -134.455432) (xy 47.840706 -134.440356) (xy 47.89405 -134.433225) (xy 47.94786 -134.434202)
			(xy 48.00091 -134.443264) (xy 48.051992 -134.460205) (xy 48.099944 -134.48464) (xy 48.143673 -134.516011)
			(xy 48.182185 -134.553604) (xy 48.198786 -134.574788) (xy 48.213398 -134.593116) (xy 48.248053 -134.624664)
			(xy 48.2879 -134.649331) (xy 48.331591 -134.666281) (xy 48.377649 -134.674942) (xy 48.424513 -134.675019)
			(xy 48.470598 -134.666511) (xy 48.492664 -134.658608) (xy 48.518622 -134.649146) (xy 48.572491 -134.636886)
			(xy 48.627565 -134.632525) (xy 48.682693 -134.636155) (xy 48.73672 -134.647699) (xy 48.788517 -134.666915)
			(xy 48.837 -134.693403) (xy 48.881155 -134.726607) (xy 48.920059 -134.765834) (xy 48.952897 -134.810262)
			(xy 48.978982 -134.858962) (xy 48.99777 -134.910916) (xy 49.008867 -134.965037) (xy 49.012041 -135.020193)
			(xy 49.007225 -135.075229) (xy 48.99452 -135.128995) (xy 48.974192 -135.180366) (xy 48.946667 -135.228268)
			(xy 48.912519 -135.271697) (xy 48.872464 -135.309747) (xy 48.827339 -135.341621) (xy 48.778088 -135.366651)
			(xy 48.725741 -135.384316) (xy 48.671394 -135.394244) (xy 48.616183 -135.396229) (xy 48.561263 -135.390229)
			(xy 48.507783 -135.376369) (xy 48.456861 -135.35494) (xy 48.409564 -135.326389) (xy 48.36688 -135.291314)
			(xy 48.329701 -135.250448) (xy 48.313848 -135.227822) (xy 48.300276 -135.20866) (xy 48.26736 -135.175181)
			(xy 48.228857 -135.148314) (xy 48.186077 -135.128972) (xy 48.140473 -135.117812) (xy 48.093595 -135.115214)
			(xy 48.047037 -135.121266) (xy 48.024542 -135.128) (xy 47.998801 -135.135856) (xy 47.945696 -135.144595)
			(xy 47.891882 -135.145244) (xy 47.838582 -135.137788) (xy 47.787012 -135.122398) (xy 47.738344 -135.099423)
			(xy 47.693686 -135.069387) (xy 47.654057 -135.032974) (xy 47.620358 -134.991012) (xy 47.593356 -134.944458)
			(xy 47.573666 -134.894371) (xy 47.561737 -134.841891) (xy 47.55784 -134.788214) (xy 45.533169 -134.788214)
			(xy 45.548242 -134.813859) (xy 45.56784 -134.863097) (xy 45.579729 -134.914741) (xy 45.583631 -134.967592)
			(xy 45.579457 -135.020423) (xy 45.567304 -135.072005) (xy 45.547453 -135.121142) (xy 45.520366 -135.166692)
			(xy 45.486672 -135.207596) (xy 45.447154 -135.242906) (xy 45.402729 -135.2718) (xy 45.354429 -135.293608)
			(xy 45.303376 -135.307823) (xy 45.250755 -135.314115) (xy 45.19779 -135.312338) (xy 45.14571 -135.302533)
			(xy 45.095725 -135.284927) (xy 45.048995 -135.259931) (xy 45.006607 -135.228124) (xy 44.987718 -135.209534)
			(xy 44.971675 -135.193893) (xy 44.935221 -135.167852) (xy 44.894764 -135.148612) (xy 44.851558 -135.13677)
			(xy 44.806944 -135.132694) (xy 44.762308 -135.136509) (xy 44.719033 -135.148098) (xy 44.678464 -135.167101)
			(xy 44.641859 -135.192928) (xy 44.625768 -135.208518) (xy 44.606756 -135.227022) (xy 44.564198 -135.25869)
			(xy 44.517317 -135.283516) (xy 44.467206 -135.300922) (xy 44.41503 -135.310502) (xy 44.362003 -135.312035)
			(xy 44.309361 -135.305484) (xy 44.258328 -135.291001) (xy 44.210092 -135.268924) (xy 44.165775 -135.239767)
			(xy 44.126409 -135.204208) (xy 44.092911 -135.163074) (xy 44.066059 -135.117324) (xy 44.046478 -135.068022)
			(xy 44.034625 -135.016314) (xy 44.030776 -134.963406) (xy 44.035019 -134.910528) (xy 44.047257 -134.85891)
			(xy 44.067203 -134.809755) (xy 44.094395 -134.764205) (xy 44.11091 -134.743444) (xy 44.124805 -134.725887)
			(xy 44.146791 -134.686887) (xy 44.161608 -134.644639) (xy 44.168799 -134.60045) (xy 44.16814 -134.555684)
			(xy 44.159652 -134.511725) (xy 44.143598 -134.469931) (xy 44.120473 -134.431595) (xy 44.090993 -134.3979)
			(xy 44.073826 -134.383526) (xy 44.06453 -134.375991) (xy 44.046863 -134.359847) (xy 44.03852 -134.351268)
			(xy 44.022261 -134.334955) (xy 43.984972 -134.307928) (xy 43.943427 -134.288055) (xy 43.898984 -134.275985)
			(xy 43.853094 -134.272112) (xy 43.807256 -134.276563) (xy 43.762968 -134.289193) (xy 43.742102 -134.298944)
			(xy 43.715328 -134.311526) (xy 43.658624 -134.328376) (xy 43.629326 -134.332472) (xy 43.60753 -134.335584)
			(xy 43.565374 -134.348268) (xy 43.526035 -134.368028) (xy 43.490691 -134.394271) (xy 43.460398 -134.426214)
			(xy 43.436063 -134.462899) (xy 43.418415 -134.503229) (xy 43.407981 -134.545998) (xy 43.40606 -134.56793)
			(xy 43.403779 -134.594828) (xy 43.39211 -134.647531) (xy 43.372622 -134.69787) (xy 43.34576 -134.744692)
			(xy 43.31214 -134.786924) (xy 43.272533 -134.823599) (xy 43.227844 -134.853876) (xy 43.179098 -134.877063)
			(xy 43.127411 -134.892629) (xy 43.073967 -134.900216) (xy 43.01999 -134.899651) (xy 42.966717 -134.890947)
			(xy 42.915367 -134.874304) (xy 42.867117 -134.850102) (xy 42.823071 -134.818896) (xy 42.78424 -134.7814)
			(xy 42.751511 -134.738474) (xy 42.725635 -134.6911) (xy 42.707205 -134.640365) (xy 42.696641 -134.587428)
			(xy 42.694188 -134.533504) (xy 42.6999 -134.479828) (xy 42.713647 -134.427628) (xy 42.735113 -134.3781)
			(xy 42.763808 -134.332379) (xy 42.799074 -134.291512) (xy 42.840103 -134.256434) (xy 42.885956 -134.227951)
			(xy 42.935582 -134.206712) (xy 42.987845 -134.193206) (xy 43.014646 -134.189978) (xy 43.036482 -134.187248)
			(xy 43.078827 -134.17529) (xy 43.118481 -134.156221) (xy 43.154261 -134.130612) (xy 43.185099 -134.099225)
			(xy 43.210074 -134.062999) (xy 43.228441 -134.023015) (xy 43.239652 -133.980466) (xy 43.241976 -133.958584)
			(xy 43.244516 -133.935978) (xy 43.246442 -133.919269) (xy 43.242628 -133.885868) (xy 43.230216 -133.854626)
			(xy 43.210066 -133.827715) (xy 43.183582 -133.807009) (xy 43.152606 -133.793946) (xy 43.119292 -133.789437)
			(xy 43.085958 -133.793794) (xy 43.054922 -133.806714) (xy 43.041316 -133.816598) (xy 43.020905 -133.831957)
			(xy 42.976372 -133.856985) (xy 42.928654 -133.87522) (xy 42.878779 -133.886268) (xy 42.827824 -133.889891)
			(xy 42.776888 -133.886012) (xy 42.72707 -133.874712) (xy 42.679444 -133.856237) (xy 42.635038 -133.830985)
			(xy 42.59481 -133.799501) (xy 42.559628 -133.762463) (xy 42.530251 -133.720672) (xy 42.507313 -133.675028)
			(xy 42.491308 -133.626516) (xy 42.482582 -133.576183) (xy 42.4815 -133.55066) (xy 42.480328 -133.527113)
			(xy 42.470477 -133.481017) (xy 42.452291 -133.437529) (xy 42.426393 -133.398144) (xy 42.393674 -133.364212)
			(xy 42.355255 -133.3369) (xy 42.312458 -133.317145) (xy 42.28973 -133.310884) (xy 42.264171 -133.303925)
			(xy 42.215282 -133.283539) (xy 42.169953 -133.256135) (xy 42.129183 -133.22232) (xy 42.093871 -133.182839)
			(xy 42.064797 -133.138562) (xy 42.042602 -133.090468) (xy 42.027775 -133.039616) (xy 42.020645 -132.987129)
			(xy 39.464895 -132.987129) (xy 39.464915 -132.987154) (xy 39.492301 -133.034896) (xy 39.512538 -133.086079)
			(xy 39.525206 -133.139641) (xy 39.53004 -133.194467) (xy 39.526941 -133.249419) (xy 39.515972 -133.303353)
			(xy 39.497363 -133.355151) (xy 39.471499 -133.403734) (xy 39.455598 -133.4262) (xy 39.441804 -133.445935)
			(xy 39.421129 -133.489411) (xy 39.409018 -133.536005) (xy 39.405904 -133.584046) (xy 39.4119 -133.631814)
			(xy 39.42679 -133.677595) (xy 39.450041 -133.71975) (xy 39.464996 -133.73862) (xy 39.481703 -133.759414)
			(xy 39.509621 -133.804864) (xy 39.530773 -133.853831) (xy 39.544724 -133.905313) (xy 39.551191 -133.95826)
			(xy 39.550041 -134.011587) (xy 39.541298 -134.064206) (xy 39.525139 -134.115039) (xy 39.501896 -134.163049)
			(xy 39.487348 -134.185406) (xy 39.474452 -134.205373) (xy 39.45562 -134.24901) (xy 39.44523 -134.295387)
			(xy 39.443642 -134.342888) (xy 39.450914 -134.389856) (xy 39.466791 -134.434652) (xy 39.49072 -134.475716)
			(xy 39.50589 -134.494016) (xy 39.522265 -134.513611) (xy 39.549837 -134.556591) (xy 39.570989 -134.603068)
			(xy 39.585287 -134.65209) (xy 39.59244 -134.70265) (xy 39.592299 -134.753714) (xy 39.584867 -134.804235)
			(xy 39.570298 -134.853176) (xy 39.559992 -134.87654) (xy 39.550847 -134.897582) (xy 39.539421 -134.942013)
			(xy 39.539405 -134.942239) (xy 40.060308 -134.942239) (xy 40.067673 -134.887436) (xy 40.083055 -134.834322)
			(xy 40.106118 -134.784065) (xy 40.136355 -134.737768) (xy 40.154352 -134.716774) (xy 40.168877 -134.699784)
			(xy 40.192276 -134.661703) (xy 40.208648 -134.620113) (xy 40.217487 -134.5763) (xy 40.21852 -134.531616)
			(xy 40.211716 -134.48744) (xy 40.197284 -134.445139) (xy 40.17567 -134.406016) (xy 40.161972 -134.388352)
			(xy 40.145938 -134.367808) (xy 40.11954 -134.322877) (xy 40.100154 -134.274506) (xy 40.088214 -134.223781)
			(xy 40.08399 -134.171841) (xy 40.087575 -134.119853) (xy 40.098889 -134.068984) (xy 40.117678 -134.020378)
			(xy 40.14352 -133.975125) (xy 40.175835 -133.934243) (xy 40.213897 -133.898649) (xy 40.25685 -133.869143)
			(xy 40.303731 -133.846387) (xy 40.353486 -133.830894) (xy 40.404998 -133.82301) (xy 40.457109 -133.822913)
			(xy 40.50865 -133.830605) (xy 40.558463 -133.845913) (xy 40.605428 -133.868493) (xy 40.648491 -133.897839)
			(xy 40.686685 -133.933291) (xy 40.719152 -133.974052) (xy 40.745163 -134.019208) (xy 40.764133 -134.067744)
			(xy 40.775637 -134.11857) (xy 40.779416 -134.170544) (xy 40.775385 -134.2225) (xy 40.763634 -134.273269)
			(xy 40.744429 -134.321713) (xy 40.718199 -134.366742) (xy 40.70223 -134.387336) (xy 40.688555 -134.405034)
			(xy 40.667052 -134.444248) (xy 40.652735 -134.486618) (xy 40.646046 -134.530838) (xy 40.647189 -134.575547)
			(xy 40.656131 -134.619367) (xy 40.672596 -134.660949) (xy 40.696076 -134.699013) (xy 40.710612 -134.716012)
			(xy 40.728641 -134.73698) (xy 40.759001 -134.783196) (xy 40.782197 -134.833392) (xy 40.797721 -134.886464)
			(xy 40.805232 -134.941248) (xy 40.804564 -134.99654) (xy 40.795733 -135.051126) (xy 40.778932 -135.103808)
			(xy 40.75453 -135.153428) (xy 40.723063 -135.198898) (xy 40.685222 -135.239218) (xy 40.658529 -135.260313)
			(xy 41.883828 -135.260313) (xy 41.883828 -135.207015) (xy 41.891771 -135.154311) (xy 41.907481 -135.103381)
			(xy 41.930607 -135.05536) (xy 41.960631 -135.011323) (xy 41.996883 -134.972252) (xy 42.038554 -134.939021)
			(xy 42.084712 -134.912372) (xy 42.134326 -134.8929) (xy 42.186288 -134.88104) (xy 42.239438 -134.877057)
			(xy 42.292588 -134.88104) (xy 42.34455 -134.8929) (xy 42.394164 -134.912372) (xy 42.440322 -134.939021)
			(xy 42.481993 -134.972252) (xy 42.518245 -135.011323) (xy 42.548269 -135.05536) (xy 42.571395 -135.103381)
			(xy 42.587105 -135.154311) (xy 42.595048 -135.207015) (xy 42.595546 -135.233664) (xy 42.595048 -135.260313)
			(xy 42.587105 -135.313017) (xy 42.571395 -135.363947) (xy 42.548269 -135.411968) (xy 42.518245 -135.456005)
			(xy 42.481993 -135.495076) (xy 42.440322 -135.528307) (xy 42.394164 -135.554956) (xy 42.34455 -135.574428)
			(xy 42.292588 -135.586288) (xy 42.239438 -135.590272) (xy 42.186288 -135.586288) (xy 42.134326 -135.574428)
			(xy 42.084712 -135.554956) (xy 42.038554 -135.528307) (xy 41.996883 -135.495076) (xy 41.960631 -135.456005)
			(xy 41.930607 -135.411968) (xy 41.907481 -135.363947) (xy 41.891771 -135.313017) (xy 41.883828 -135.260313)
			(xy 40.658529 -135.260313) (xy 40.641838 -135.273503) (xy 40.593863 -135.301001) (xy 40.542352 -135.321107)
			(xy 40.488435 -135.33338) (xy 40.433297 -135.337551) (xy 40.378147 -135.333527) (xy 40.324198 -135.321397)
			(xy 40.272633 -135.301429) (xy 40.224586 -135.274059) (xy 40.181111 -135.239889) (xy 40.143163 -135.19967)
			(xy 40.111575 -135.154284) (xy 40.087041 -135.104729) (xy 40.070099 -135.052092) (xy 40.061123 -134.997529)
			(xy 40.060308 -134.942239) (xy 39.539405 -134.942239) (xy 39.536147 -134.987773) (xy 39.541132 -135.033378)
			(xy 39.554215 -135.07735) (xy 39.57497 -135.118263) (xy 39.602726 -135.154791) (xy 39.636581 -135.18575)
			(xy 39.65575 -135.198358) (xy 39.677409 -135.21239) (xy 39.716628 -135.245937) (xy 39.75045 -135.284918)
			(xy 39.778131 -135.328475) (xy 39.79906 -135.37565) (xy 39.812777 -135.425402) (xy 39.81898 -135.476637)
			(xy 39.817532 -135.528225) (xy 39.808465 -135.579031) (xy 39.791978 -135.627936) (xy 39.768435 -135.673862)
			(xy 39.738355 -135.715798) (xy 39.702399 -135.75282) (xy 39.682166 -135.768842) (xy 39.669428 -135.779264)
			(xy 39.649201 -135.805205) (xy 39.636303 -135.835466) (xy 39.631595 -135.868022) (xy 39.635392 -135.900697)
			(xy 39.647439 -135.931307) (xy 39.656766 -135.944864) (xy 39.672731 -135.967443) (xy 39.698465 -136.016388)
			(xy 39.716683 -136.068599) (xy 39.726985 -136.122929) (xy 39.729146 -136.178185) (xy 39.723118 -136.233154)
			(xy 39.709033 -136.286628) (xy 39.687201 -136.337434) (xy 39.6581 -136.384455) (xy 39.62237 -136.42666)
			(xy 39.580796 -136.463122) (xy 39.53429 -136.493039) (xy 39.483873 -136.515756) (xy 39.430653 -136.530773)
			(xy 39.375798 -136.537761) (xy 39.320513 -136.536566) (xy 39.266012 -136.527214) (xy 39.21349 -136.50991)
			(xy 39.164103 -136.485036) (xy 39.118933 -136.453136) (xy 39.078974 -136.414912) (xy 39.045101 -136.371202)
			(xy 39.01806 -136.322966) (xy 38.998444 -136.271264) (xy 38.986683 -136.217231) (xy 38.983037 -136.162054)
			(xy 38.987584 -136.106943) (xy 39.000225 -136.053109) (xy 39.020683 -136.001734) (xy 39.048508 -135.953947)
			(xy 39.083089 -135.910796) (xy 39.123667 -135.873229) (xy 39.146226 -135.857234) (xy 39.159551 -135.847562)
			(xy 39.181126 -135.822704) (xy 39.195615 -135.793149) (xy 39.202051 -135.760868) (xy 39.200004 -135.728017)
			(xy 39.189612 -135.696785) (xy 39.181024 -135.682736) (xy 39.167899 -135.661808) (xy 39.146995 -135.617052)
			(xy 39.132646 -135.569785) (xy 39.125142 -135.520961) (xy 39.124635 -135.471566) (xy 39.131134 -135.422598)
			(xy 39.144508 -135.375046) (xy 39.1541 -135.352282) (xy 39.162867 -135.331076) (xy 39.173566 -135.286461)
			(xy 39.176075 -135.240649) (xy 39.170314 -135.195133) (xy 39.156468 -135.151391) (xy 39.13499 -135.110849)
			(xy 39.106578 -135.074825) (xy 39.072156 -135.044492) (xy 39.052754 -135.032242) (xy 39.031006 -135.018523)
			(xy 38.991264 -134.985898) (xy 38.956626 -134.947898) (xy 38.92781 -134.905314) (xy 38.905415 -134.85903)
			(xy 38.889906 -134.810006) (xy 38.881607 -134.759263) (xy 38.880688 -134.707853) (xy 38.887169 -134.656846)
			(xy 38.900916 -134.6073) (xy 38.921642 -134.560245) (xy 38.934898 -134.538212) (xy 38.946978 -134.517764)
			(xy 38.964219 -134.47352) (xy 38.972945 -134.426844) (xy 38.972851 -134.379359) (xy 38.963942 -134.332717)
			(xy 38.946527 -134.288541) (xy 38.921212 -134.248367) (xy 38.905434 -134.230618) (xy 38.886563 -134.209593)
			(xy 38.8548 -134.162872) (xy 38.830456 -134.11189) (xy 38.814091 -134.057816) (xy 38.806079 -134.001892)
			(xy 38.806603 -133.945399) (xy 38.815653 -133.889633) (xy 38.83302 -133.835873) (xy 38.858306 -133.785352)
			(xy 38.874192 -133.761988) (xy 38.887565 -133.741951) (xy 38.907411 -133.698068) (xy 38.918644 -133.651233)
			(xy 38.920861 -133.603121) (xy 38.913984 -133.555451) (xy 38.898259 -133.509928) (xy 38.874246 -133.468178)
			(xy 38.858952 -133.449568) (xy 38.841226 -133.428313) (xy 38.811547 -133.381599) (xy 38.788925 -133.331088)
			(xy 38.773834 -133.27784) (xy 38.766589 -133.222971) (xy 38.767344 -133.167631) (xy 38.776082 -133.11298)
			(xy 38.79262 -133.060164) (xy 38.816611 -133.010289) (xy 38.847552 -132.964401) (xy 38.86581 -132.9436)
			(xy 38.881363 -132.925703) (xy 38.906232 -132.885341) (xy 38.923189 -132.841069) (xy 38.931648 -132.794421)
			(xy 38.931315 -132.747014) (xy 38.922201 -132.70049) (xy 38.904623 -132.656461) (xy 38.87919 -132.616452)
			(xy 38.846782 -132.58185) (xy 38.827964 -132.567426) (xy 38.806361 -132.55096) (xy 38.767604 -132.512906)
			(xy 38.734783 -132.46963) (xy 38.708593 -132.422046) (xy 38.689589 -132.371164) (xy 38.678173 -132.318063)
			(xy 38.674588 -132.263866) (xy 29.85008 -132.263866) (xy 29.85008 -132.867146) (xy 30.000448 -133.017514)
			(xy 31.184848 -133.017514) (xy 31.188919 -132.961892) (xy 31.201045 -132.907455) (xy 31.220968 -132.855364)
			(xy 31.248264 -132.806729) (xy 31.28235 -132.762586) (xy 31.322499 -132.723877) (xy 31.367857 -132.691426)
			(xy 31.417457 -132.665925) (xy 31.470241 -132.647918) (xy 31.525084 -132.637788) (xy 31.580818 -132.635751)
			(xy 31.636255 -132.641851) (xy 31.690212 -132.655957) (xy 31.741541 -132.677769) (xy 31.789147 -132.706823)
			(xy 31.832015 -132.742498) (xy 31.869232 -132.784035) (xy 31.900005 -132.830548) (xy 31.923677 -132.881045)
			(xy 31.939745 -132.934452) (xy 31.947865 -132.989628) (xy 31.948374 -133.017514) (xy 31.947865 -133.0454)
			(xy 31.939745 -133.100576) (xy 31.923677 -133.153983) (xy 31.900005 -133.20448) (xy 31.869232 -133.250993)
			(xy 31.832015 -133.29253) (xy 31.789147 -133.328205) (xy 31.741541 -133.357259) (xy 31.690212 -133.379071)
			(xy 31.636255 -133.393177) (xy 31.580818 -133.399277) (xy 31.525084 -133.39724) (xy 31.470241 -133.38711)
			(xy 31.417457 -133.369103) (xy 31.367857 -133.343602) (xy 31.322499 -133.311151) (xy 31.28235 -133.272442)
			(xy 31.248264 -133.228299) (xy 31.220968 -133.179664) (xy 31.201045 -133.127573) (xy 31.188919 -133.073136)
			(xy 31.184848 -133.017514) (xy 30.000448 -133.017514) (xy 32.297116 -135.314182) (xy 37.58514 -135.314182)
			(xy 37.589211 -135.25856) (xy 37.601337 -135.204123) (xy 37.62126 -135.152032) (xy 37.648556 -135.103397)
			(xy 37.682642 -135.059254) (xy 37.722791 -135.020545) (xy 37.768149 -134.988094) (xy 37.817749 -134.962593)
			(xy 37.870533 -134.944586) (xy 37.925376 -134.934456) (xy 37.98111 -134.932419) (xy 38.036547 -134.938519)
			(xy 38.090504 -134.952625) (xy 38.141833 -134.974437) (xy 38.189439 -135.003491) (xy 38.232307 -135.039166)
			(xy 38.269524 -135.080703) (xy 38.300297 -135.127216) (xy 38.323969 -135.177713) (xy 38.340037 -135.23112)
			(xy 38.348157 -135.286296) (xy 38.348666 -135.314182) (xy 38.348157 -135.342068) (xy 38.340037 -135.397244)
			(xy 38.323969 -135.450651) (xy 38.300297 -135.501148) (xy 38.269524 -135.547661) (xy 38.232307 -135.589198)
			(xy 38.189439 -135.624873) (xy 38.141833 -135.653927) (xy 38.090504 -135.675739) (xy 38.036547 -135.689845)
			(xy 37.98111 -135.695945) (xy 37.925376 -135.693908) (xy 37.870533 -135.683778) (xy 37.817749 -135.665771)
			(xy 37.768149 -135.64027) (xy 37.722791 -135.607819) (xy 37.682642 -135.56911) (xy 37.648556 -135.524967)
			(xy 37.62126 -135.476332) (xy 37.601337 -135.424241) (xy 37.589211 -135.369804) (xy 37.58514 -135.314182)
			(xy 32.297116 -135.314182) (xy 33.573699 -136.590765) (xy 40.07738 -136.590765) (xy 40.07738 -136.537467)
			(xy 40.085323 -136.484763) (xy 40.101033 -136.433833) (xy 40.124159 -136.385812) (xy 40.154183 -136.341775)
			(xy 40.190435 -136.302704) (xy 40.232106 -136.269473) (xy 40.278264 -136.242824) (xy 40.327878 -136.223352)
			(xy 40.37984 -136.211492) (xy 40.43299 -136.207509) (xy 40.48614 -136.211492) (xy 40.538102 -136.223352)
			(xy 40.587716 -136.242824) (xy 40.633874 -136.269473) (xy 40.675545 -136.302704) (xy 40.711797 -136.341775)
			(xy 40.741821 -136.385812) (xy 40.764947 -136.433833) (xy 40.780657 -136.484763) (xy 40.7886 -136.537467)
			(xy 40.789098 -136.564116) (xy 40.7886 -136.590765) (xy 40.780657 -136.643469) (xy 40.764947 -136.694399)
			(xy 40.741821 -136.74242) (xy 40.711797 -136.786457) (xy 40.675545 -136.825528) (xy 40.633874 -136.858759)
			(xy 40.587716 -136.885408) (xy 40.538102 -136.90488) (xy 40.48614 -136.91674) (xy 40.43299 -136.920724)
			(xy 40.37984 -136.91674) (xy 40.327878 -136.90488) (xy 40.278264 -136.885408) (xy 40.232106 -136.858759)
			(xy 40.190435 -136.825528) (xy 40.154183 -136.786457) (xy 40.124159 -136.74242) (xy 40.101033 -136.694399)
			(xy 40.085323 -136.643469) (xy 40.07738 -136.590765) (xy 33.573699 -136.590765) (xy 34.014519 -137.031585)
			(xy 42.077201 -137.031585) (xy 42.082716 -136.97741) (xy 42.096622 -136.92476) (xy 42.118578 -136.874927)
			(xy 42.148046 -136.829133) (xy 42.165778 -136.808464) (xy 42.180812 -136.790897) (xy 42.204794 -136.751369)
			(xy 42.221232 -136.708156) (xy 42.229586 -136.662683) (xy 42.22958 -136.616449) (xy 42.221214 -136.570978)
			(xy 42.204763 -136.527769) (xy 42.180771 -136.488247) (xy 42.165778 -136.470644) (xy 42.148414 -136.450454)
			(xy 42.119446 -136.405772) (xy 42.097641 -136.357191) (xy 42.083508 -136.30585) (xy 42.077381 -136.252953)
			(xy 42.079401 -136.199741) (xy 42.089523 -136.147462) (xy 42.107508 -136.09734) (xy 42.132935 -136.050553)
			(xy 42.165208 -136.008196) (xy 42.20357 -135.971264) (xy 42.24712 -135.940622) (xy 42.294839 -135.916988)
			(xy 42.345607 -135.900918) (xy 42.398233 -135.892787) (xy 42.451483 -135.892787) (xy 42.504109 -135.900918)
			(xy 42.554877 -135.916988) (xy 42.602596 -135.940622) (xy 42.646146 -135.971264) (xy 42.684508 -136.008196)
			(xy 42.716781 -136.050553) (xy 42.742208 -136.09734) (xy 42.760193 -136.147462) (xy 42.770315 -136.199741)
			(xy 42.772335 -136.252953) (xy 42.766208 -136.30585) (xy 42.752075 -136.357191) (xy 42.73027 -136.405772)
			(xy 42.701302 -136.450454) (xy 42.683938 -136.470644) (xy 42.668994 -136.488283) (xy 42.645006 -136.527795)
			(xy 42.631187 -136.564089) (xy 44.859624 -136.564089) (xy 44.863741 -136.508818) (xy 44.875999 -136.454767)
			(xy 44.896128 -136.403127) (xy 44.923682 -136.355038) (xy 44.958056 -136.311561) (xy 44.998489 -136.273654)
			(xy 45.044091 -136.242153) (xy 45.093856 -136.217755) (xy 45.146685 -136.200996) (xy 45.201414 -136.192246)
			(xy 45.256836 -136.191698) (xy 45.311727 -136.199366) (xy 45.364877 -136.215078) (xy 45.415114 -136.238489)
			(xy 45.461329 -136.269083) (xy 45.482256 -136.287256) (xy 45.499348 -136.30198) (xy 45.537627 -136.325839)
			(xy 45.579519 -136.342561) (xy 45.623705 -136.351621) (xy 45.668798 -136.352733) (xy 45.713377 -136.345863)
			(xy 45.756043 -136.331227) (xy 45.795452 -136.309285) (xy 45.813218 -136.295384) (xy 45.834007 -136.278964)
			(xy 45.87962 -136.252024) (xy 45.928798 -136.232331) (xy 45.980399 -136.220343) (xy 46.033222 -136.216338)
			(xy 46.086039 -136.22041) (xy 46.137624 -136.232464) (xy 46.186778 -136.25222) (xy 46.232356 -136.279218)
			(xy 46.253146 -136.295638) (xy 46.270934 -136.309514) (xy 46.310317 -136.331506) (xy 46.352966 -136.346193)
			(xy 46.39754 -136.353113) (xy 46.442634 -136.352046) (xy 46.486831 -136.343028) (xy 46.528738 -136.326341)
			(xy 46.567037 -136.302512) (xy 46.584108 -136.287764) (xy 46.59522 -136.278006) (xy 46.618744 -136.260079)
			(xy 46.631098 -136.25195) (xy 46.649198 -136.239674) (xy 46.681294 -136.209972) (xy 46.707829 -136.175211)
			(xy 46.728019 -136.13642) (xy 46.741267 -136.094744) (xy 46.747182 -136.051415) (xy 46.745588 -136.007714)
			(xy 46.736534 -135.96493) (xy 46.720286 -135.92433) (xy 46.697324 -135.887112) (xy 46.683168 -135.870442)
			(xy 46.66568 -135.849947) (xy 46.636505 -135.804653) (xy 46.614485 -135.755482) (xy 46.600122 -135.703555)
			(xy 46.593744 -135.650057) (xy 46.595496 -135.596209) (xy 46.605338 -135.543239) (xy 46.623047 -135.492356)
			(xy 46.648217 -135.44472) (xy 46.680274 -135.401419) (xy 46.718488 -135.36344) (xy 46.761986 -135.331651)
			(xy 46.809776 -135.306775) (xy 46.860768 -135.289381) (xy 46.913798 -135.279865) (xy 46.967656 -135.278445)
			(xy 47.021113 -135.285153) (xy 47.07295 -135.299837) (xy 47.121984 -135.32216) (xy 47.167097 -135.351614)
			(xy 47.207259 -135.387526) (xy 47.241554 -135.429078) (xy 47.269199 -135.475321) (xy 47.289564 -135.525201)
			(xy 47.302184 -135.577578) (xy 47.306771 -135.631259) (xy 47.303932 -135.674238) (xy 58.193559 -135.674238)
			(xy 58.195096 -135.621689) (xy 58.204538 -135.569972) (xy 58.221668 -135.52027) (xy 58.246096 -135.473719)
			(xy 58.277262 -135.431382) (xy 58.314455 -135.394228) (xy 58.356824 -135.363105) (xy 58.4034 -135.338726)
			(xy 58.45312 -135.321647) (xy 58.504847 -135.312259) (xy 58.557397 -135.310776) (xy 58.60957 -135.317233)
			(xy 58.660174 -135.331481) (xy 58.708051 -135.353196) (xy 58.752108 -135.38188) (xy 58.772044 -135.399018)
			(xy 58.789646 -135.414009) (xy 58.829166 -135.437996) (xy 58.872372 -135.454442) (xy 58.917839 -135.462802)
			(xy 58.964069 -135.462802) (xy 59.009536 -135.454442) (xy 59.052742 -135.437996) (xy 59.092262 -135.414009)
			(xy 59.109864 -135.399018) (xy 59.12905 -135.382514) (xy 59.171305 -135.354663) (xy 59.217155 -135.333241)
			(xy 59.265629 -135.318703) (xy 59.3157 -135.311356) (xy 59.366308 -135.311356) (xy 59.416379 -135.318703)
			(xy 59.464853 -135.333241) (xy 59.510703 -135.354663) (xy 59.552958 -135.382514) (xy 59.572144 -135.399018)
			(xy 59.589746 -135.414009) (xy 59.629266 -135.437996) (xy 59.672472 -135.454442) (xy 59.717939 -135.462802)
			(xy 59.764169 -135.462802) (xy 59.809636 -135.454442) (xy 59.852842 -135.437996) (xy 59.892362 -135.414009)
			(xy 59.909964 -135.399018) (xy 59.929886 -135.381862) (xy 59.973945 -135.353177) (xy 60.021824 -135.331463)
			(xy 60.07243 -135.317214) (xy 60.124606 -135.310758) (xy 60.177158 -135.312241) (xy 60.228887 -135.32163)
			(xy 60.278608 -135.33871) (xy 60.325187 -135.36309) (xy 60.367558 -135.394214) (xy 60.404752 -135.43137)
			(xy 60.43592 -135.473709) (xy 60.460348 -135.520262) (xy 60.477479 -135.569966) (xy 60.486922 -135.621685)
			(xy 60.488459 -135.674236) (xy 60.482057 -135.726418) (xy 60.46786 -135.777039) (xy 60.446195 -135.824941)
			(xy 60.417556 -135.869029) (xy 60.400438 -135.888984) (xy 60.385415 -135.906582) (xy 60.361408 -135.946135)
			(xy 60.344951 -135.989377) (xy 60.336586 -136.034882) (xy 60.336589 -136.081149) (xy 60.344959 -136.126654)
			(xy 60.361422 -136.169894) (xy 60.385433 -136.209443) (xy 60.400438 -136.227058) (xy 60.418223 -136.247825)
			(xy 60.447717 -136.293862) (xy 60.469633 -136.343952) (xy 60.483429 -136.396857) (xy 60.488764 -136.45127)
			(xy 60.485507 -136.505847) (xy 60.473737 -136.55924) (xy 60.453747 -136.610128) (xy 60.426028 -136.657255)
			(xy 60.391268 -136.699457) (xy 60.350324 -136.73569) (xy 60.32754 -136.750806) (xy 60.314355 -136.759816)
			(xy 60.292541 -136.783122) (xy 60.277193 -136.811112) (xy 60.269271 -136.842036) (xy 60.26927 -136.873958)
			(xy 60.277191 -136.904882) (xy 60.292538 -136.932873) (xy 60.31435 -136.95618) (xy 60.32754 -136.965182)
			(xy 60.339226 -136.972777) (xy 60.361479 -136.989559) (xy 60.37199 -136.99871) (xy 60.389604 -137.013715)
			(xy 60.429152 -137.037727) (xy 60.47239 -137.054189) (xy 60.517894 -137.062558) (xy 60.56416 -137.062558)
			(xy 60.609664 -137.054189) (xy 60.652902 -137.037727) (xy 60.69245 -137.013715) (xy 60.710064 -136.99871)
			(xy 60.729947 -136.981507) (xy 60.774042 -136.952864) (xy 60.82195 -136.931197) (xy 60.872577 -136.916999)
			(xy 60.924766 -136.910596) (xy 60.977324 -136.912135) (xy 61.029049 -136.921579) (xy 61.078759 -136.938713)
			(xy 61.125318 -136.963145) (xy 61.167662 -136.994317) (xy 61.204822 -137.031517) (xy 61.235949 -137.073893)
			(xy 61.260333 -137.120478) (xy 61.277414 -137.170206) (xy 61.286804 -137.221941) (xy 61.288286 -137.2745)
			(xy 61.281829 -137.326683) (xy 61.267578 -137.377295) (xy 61.24586 -137.42518) (xy 61.217171 -137.469244)
			(xy 61.20003 -137.489184) (xy 61.185047 -137.506792) (xy 61.161062 -137.546311) (xy 61.144618 -137.589516)
			(xy 61.136258 -137.634981) (xy 61.136257 -137.68121) (xy 61.144616 -137.726676) (xy 61.161058 -137.769881)
			(xy 61.185042 -137.809401) (xy 61.20003 -137.827004) (xy 61.217184 -137.846932) (xy 61.245881 -137.89099)
			(xy 61.267607 -137.938871) (xy 61.281866 -137.989481) (xy 61.28833 -138.041662) (xy 61.286853 -138.094221)
			(xy 61.277467 -138.145957) (xy 61.260389 -138.195686) (xy 61.236008 -138.242271) (xy 61.204881 -138.284648)
			(xy 61.16772 -138.321846) (xy 61.125376 -138.353017) (xy 61.078816 -138.377447) (xy 61.029105 -138.394577)
			(xy 60.977379 -138.404015) (xy 60.924821 -138.405547) (xy 60.872634 -138.399136) (xy 60.822009 -138.384931)
			(xy 60.774106 -138.363254) (xy 60.730018 -138.334602) (xy 60.710064 -138.317478) (xy 60.692466 -138.302438)
			(xy 60.652933 -138.278365) (xy 60.60969 -138.261858) (xy 60.56417 -138.253465) (xy 60.517884 -138.253465)
			(xy 60.472364 -138.261858) (xy 60.429121 -138.278365) (xy 60.389588 -138.302438) (xy 60.37199 -138.317478)
			(xy 60.352783 -138.33393) (xy 60.310532 -138.361719) (xy 60.264698 -138.383085) (xy 60.216248 -138.397577)
			(xy 60.166209 -138.404887) (xy 60.115639 -138.404862) (xy 60.065607 -138.397501) (xy 60.017172 -138.38296)
			(xy 59.971359 -138.361547) (xy 59.929137 -138.333715) (xy 59.909964 -138.317224) (xy 59.892362 -138.302233)
			(xy 59.852842 -138.278246) (xy 59.809636 -138.2618) (xy 59.764169 -138.25344) (xy 59.717939 -138.25344)
			(xy 59.672472 -138.2618) (xy 59.629266 -138.278246) (xy 59.589746 -138.302233) (xy 59.572144 -138.317224)
			(xy 59.552958 -138.333728) (xy 59.510703 -138.361579) (xy 59.464853 -138.383001) (xy 59.416379 -138.397539)
			(xy 59.366308 -138.404886) (xy 59.3157 -138.404886) (xy 59.265629 -138.397539) (xy 59.217155 -138.383001)
			(xy 59.171305 -138.361579) (xy 59.12905 -138.333728) (xy 59.109864 -138.317224) (xy 59.092262 -138.302233)
			(xy 59.052742 -138.278246) (xy 59.009536 -138.2618) (xy 58.964069 -138.25344) (xy 58.917839 -138.25344)
			(xy 58.872372 -138.2618) (xy 58.829166 -138.278246) (xy 58.789646 -138.302233) (xy 58.772044 -138.317224)
			(xy 58.752057 -138.334313) (xy 58.707989 -138.362997) (xy 58.6601 -138.384707) (xy 58.609484 -138.398947)
			(xy 58.5573 -138.405392) (xy 58.504741 -138.403894) (xy 58.453008 -138.394486) (xy 58.403286 -138.377385)
			(xy 58.356711 -138.352982) (xy 58.314349 -138.321834) (xy 58.277169 -138.284654) (xy 58.24602 -138.242292)
			(xy 58.221616 -138.195718) (xy 58.204515 -138.145996) (xy 58.195107 -138.094263) (xy 58.193608 -138.041704)
			(xy 58.200052 -137.989519) (xy 58.214292 -137.938904) (xy 58.236002 -137.891014) (xy 58.264685 -137.846946)
			(xy 58.281824 -137.827004) (xy 58.296821 -137.809407) (xy 58.32081 -137.769887) (xy 58.337256 -137.72668)
			(xy 58.345616 -137.681211) (xy 58.345615 -137.63498) (xy 58.337253 -137.589512) (xy 58.320806 -137.546305)
			(xy 58.296816 -137.506786) (xy 58.281824 -137.489184) (xy 58.265363 -137.469962) (xy 58.23751 -137.427714)
			(xy 58.216085 -137.38187) (xy 58.201543 -137.333401) (xy 58.194192 -137.283334) (xy 58.194187 -137.232731)
			(xy 58.201529 -137.182663) (xy 58.216062 -137.134192) (xy 58.237478 -137.088343) (xy 58.265323 -137.04609)
			(xy 58.281824 -137.026904) (xy 58.296821 -137.009307) (xy 58.32081 -136.969787) (xy 58.337256 -136.92658)
			(xy 58.345616 -136.881111) (xy 58.345615 -136.83488) (xy 58.337253 -136.789412) (xy 58.320806 -136.746205)
			(xy 58.296816 -136.706686) (xy 58.281824 -136.689084) (xy 58.265358 -136.669889) (xy 58.237518 -136.627671)
			(xy 58.216098 -136.581861) (xy 58.20155 -136.533428) (xy 58.194183 -136.483397) (xy 58.194152 -136.432827)
			(xy 58.201458 -136.382787) (xy 58.215947 -136.334336) (xy 58.237311 -136.2885) (xy 58.265099 -136.246248)
			(xy 58.28157 -136.227058) (xy 58.296588 -136.209443) (xy 58.320661 -136.169913) (xy 58.337169 -136.126673)
			(xy 58.345563 -136.081157) (xy 58.345566 -136.034874) (xy 58.337177 -135.989357) (xy 58.320675 -135.946115)
			(xy 58.296607 -135.906582) (xy 58.28157 -135.888984) (xy 58.264462 -135.869022) (xy 58.235823 -135.824936)
			(xy 58.214158 -135.777036) (xy 58.199962 -135.726418) (xy 58.193559 -135.674238) (xy 47.303932 -135.674238)
			(xy 47.30322 -135.685019) (xy 47.291613 -135.73763) (xy 47.272214 -135.787893) (xy 47.245466 -135.834661)
			(xy 47.211979 -135.876867) (xy 47.172518 -135.913548) (xy 47.150528 -135.929116) (xy 47.132727 -135.941802)
			(xy 47.101357 -135.972238) (xy 47.075654 -136.00759) (xy 47.056376 -136.046817) (xy 47.04409 -136.088764)
			(xy 47.039159 -136.132193) (xy 47.041728 -136.175826) (xy 47.05172 -136.218376) (xy 47.068843 -136.258591)
			(xy 47.092591 -136.295286) (xy 47.107094 -136.31164) (xy 47.125128 -136.331851) (xy 47.155753 -136.376526)
			(xy 47.179588 -136.425165) (xy 47.179626 -136.425282) (xy 50.300878 -136.425282) (xy 50.305068 -136.369963)
			(xy 50.317226 -136.315834) (xy 50.337096 -136.264037) (xy 50.364258 -136.215664) (xy 50.39814 -136.171735)
			(xy 50.438028 -136.133177) (xy 50.483079 -136.100802) (xy 50.532345 -136.075294) (xy 50.584785 -136.05719)
			(xy 50.639295 -136.046873) (xy 50.694724 -136.044559) (xy 50.749904 -136.050298) (xy 50.803671 -136.063968)
			(xy 50.854891 -136.085282) (xy 50.902484 -136.11379) (xy 50.945446 -136.14889) (xy 50.982871 -136.189842)
			(xy 51.013971 -136.235784) (xy 51.038088 -136.285745) (xy 51.051729 -136.329166) (xy 53.55285 -136.329166)
			(xy 53.556921 -136.273544) (xy 53.569047 -136.219107) (xy 53.58897 -136.167016) (xy 53.616266 -136.118381)
			(xy 53.650352 -136.074238) (xy 53.690501 -136.035529) (xy 53.735859 -136.003078) (xy 53.785459 -135.977577)
			(xy 53.838243 -135.95957) (xy 53.893086 -135.94944) (xy 53.94882 -135.947403) (xy 54.004257 -135.953503)
			(xy 54.058214 -135.967609) (xy 54.109543 -135.989421) (xy 54.157149 -136.018475) (xy 54.200017 -136.05415)
			(xy 54.237234 -136.095687) (xy 54.268007 -136.1422) (xy 54.291679 -136.192697) (xy 54.307747 -136.246104)
			(xy 54.315867 -136.30128) (xy 54.316376 -136.329166) (xy 54.315867 -136.357052) (xy 54.307747 -136.412228)
			(xy 54.291679 -136.465635) (xy 54.268007 -136.516132) (xy 54.237234 -136.562645) (xy 54.200017 -136.604182)
			(xy 54.157149 -136.639857) (xy 54.109543 -136.668911) (xy 54.058214 -136.690723) (xy 54.004257 -136.704829)
			(xy 53.94882 -136.710929) (xy 53.893086 -136.708892) (xy 53.838243 -136.698762) (xy 53.785459 -136.680755)
			(xy 53.735859 -136.655254) (xy 53.690501 -136.622803) (xy 53.650352 -136.584094) (xy 53.616266 -136.539951)
			(xy 53.58897 -136.491316) (xy 53.569047 -136.439225) (xy 53.556921 -136.384788) (xy 53.55285 -136.329166)
			(xy 51.051729 -136.329166) (xy 51.054715 -136.338672) (xy 51.0635 -136.39345) (xy 51.06426 -136.448922)
			(xy 51.061112 -136.476486) (xy 51.058545 -136.500085) (xy 51.061199 -136.547474) (xy 51.072603 -136.593547)
			(xy 51.092359 -136.636704) (xy 51.119781 -136.675445) (xy 51.153917 -136.708423) (xy 51.19358 -136.734493)
			(xy 51.237392 -136.752749) (xy 51.260502 -136.758172) (xy 51.287827 -136.764482) (xy 51.340336 -136.784172)
			(xy 51.389296 -136.811517) (xy 51.433598 -136.845899) (xy 51.453288 -136.865868) (xy 51.465159 -136.877508)
			(xy 51.493505 -136.894852) (xy 51.525367 -136.904293) (xy 51.558586 -136.905192) (xy 51.590912 -136.897488)
			(xy 51.620154 -136.881702) (xy 51.632612 -136.870694) (xy 51.652514 -136.852457) (xy 51.696588 -136.821288)
			(xy 51.744617 -136.796646) (xy 51.795641 -136.779022) (xy 51.84864 -136.768768) (xy 51.902556 -136.766089)
			(xy 51.95631 -136.77104) (xy 52.008829 -136.78352) (xy 52.059065 -136.80328) (xy 52.106011 -136.829927)
			(xy 52.127658 -136.846056) (xy 52.14661 -136.860006) (xy 52.188529 -136.88138) (xy 52.233663 -136.89468)
			(xy 52.280474 -136.899453) (xy 52.327364 -136.895535) (xy 52.372734 -136.883061) (xy 52.415036 -136.862456)
			(xy 52.434236 -136.84885) (xy 52.457107 -136.832512) (xy 52.506761 -136.806178) (xy 52.559804 -136.787594)
			(xy 52.615037 -136.777182) (xy 52.671206 -136.775177) (xy 52.72704 -136.781626) (xy 52.781273 -136.796382)
			(xy 52.832678 -136.81911) (xy 52.880089 -136.849297) (xy 52.901596 -136.867392) (xy 52.913316 -136.876971)
			(xy 52.940179 -136.890899) (xy 52.969565 -136.898115) (xy 52.999823 -136.898212) (xy 53.029255 -136.891185)
			(xy 53.056206 -136.877428) (xy 53.067966 -136.8679) (xy 53.089076 -136.850301) (xy 53.135548 -136.820958)
			(xy 53.185825 -136.798759) (xy 53.238818 -136.784186) (xy 53.293377 -136.777555) (xy 53.348318 -136.779009)
			(xy 53.40245 -136.788517) (xy 53.454597 -136.805874) (xy 53.50363 -136.830701) (xy 53.548485 -136.862462)
			(xy 53.588187 -136.900466) (xy 53.621877 -136.94389) (xy 53.648823 -136.991791) (xy 53.668442 -137.043131)
			(xy 53.680306 -137.096795) (xy 53.684159 -137.151621) (xy 53.679918 -137.206417) (xy 53.667674 -137.259996)
			(xy 53.647693 -137.311196) (xy 53.620408 -137.358905) (xy 53.586412 -137.402089) (xy 53.546441 -137.439812)
			(xy 53.501363 -137.471254) (xy 53.452156 -137.495734) (xy 53.399887 -137.512721) (xy 53.345689 -137.521846)
			(xy 53.290739 -137.522911) (xy 53.236229 -137.515894) (xy 53.18334 -137.500946) (xy 53.133221 -137.478392)
			(xy 53.086958 -137.448721) (xy 53.065934 -137.431018) (xy 53.054266 -137.421371) (xy 53.027388 -137.407447)
			(xy 52.997988 -137.400241) (xy 52.967718 -137.400157) (xy 52.938279 -137.407199) (xy 52.911324 -137.420973)
			(xy 52.899564 -137.43051) (xy 52.878033 -137.448349) (xy 52.830693 -137.478098) (xy 52.779439 -137.500439)
			(xy 52.725422 -137.51487) (xy 52.669854 -137.521067) (xy 52.613985 -137.518891) (xy 52.559069 -137.508391)
			(xy 52.506337 -137.489802) (xy 52.456976 -137.463542) (xy 52.434236 -137.447274) (xy 52.415047 -137.433644)
			(xy 52.372748 -137.413012) (xy 52.327373 -137.400521) (xy 52.280474 -137.396598) (xy 52.233655 -137.401378)
			(xy 52.188515 -137.414696) (xy 52.1466 -137.436097) (xy 52.127658 -137.450068) (xy 52.104909 -137.467018)
			(xy 52.055382 -137.494682) (xy 52.002303 -137.514705) (xy 51.946844 -137.526645) (xy 51.890228 -137.53024)
			(xy 51.833705 -137.525409) (xy 51.77852 -137.51226) (xy 51.725891 -137.491083) (xy 51.67698 -137.462344)
			(xy 51.632864 -137.426678) (xy 51.613308 -137.406126) (xy 51.601696 -137.394249) (xy 51.57368 -137.376425)
			(xy 51.542016 -137.366423) (xy 51.508844 -137.364921) (xy 51.476406 -137.372019) (xy 51.446894 -137.387238)
			(xy 51.434238 -137.397998) (xy 51.414225 -137.415521) (xy 51.370223 -137.445406) (xy 51.322417 -137.468728)
			(xy 51.27178 -137.485012) (xy 51.219342 -137.493928) (xy 51.166169 -137.495295) (xy 51.113342 -137.489083)
			(xy 51.061935 -137.47542) (xy 51.012995 -137.454584) (xy 50.967517 -137.426998) (xy 50.926425 -137.393224)
			(xy 50.890555 -137.353948) (xy 50.860637 -137.309969) (xy 50.837278 -137.262181) (xy 50.820955 -137.211557)
			(xy 50.811999 -137.159125) (xy 50.810593 -137.105953) (xy 50.813208 -137.079482) (xy 50.815411 -137.055855)
			(xy 50.812058 -137.008526) (xy 50.799982 -136.962642) (xy 50.7796 -136.919795) (xy 50.751621 -136.881475)
			(xy 50.717018 -136.849013) (xy 50.676992 -136.823535) (xy 50.632933 -136.805927) (xy 50.609754 -136.800844)
			(xy 50.582627 -136.795029) (xy 50.530293 -136.776619) (xy 50.481178 -136.750823) (xy 50.436316 -136.718186)
			(xy 50.396655 -136.679394) (xy 50.36303 -136.635268) (xy 50.336152 -136.586737) (xy 50.316585 -136.534824)
			(xy 50.304744 -136.480625) (xy 50.300878 -136.425282) (xy 47.179626 -136.425282) (xy 47.196129 -136.476743)
			(xy 47.205029 -136.530171) (xy 47.206099 -136.584326) (xy 47.199317 -136.638064) (xy 47.184826 -136.690255)
			(xy 47.162931 -136.739798) (xy 47.134094 -136.785648) (xy 47.098923 -136.82684) (xy 47.058158 -136.862506)
			(xy 47.012658 -136.891894) (xy 46.963383 -136.914385) (xy 46.911371 -136.929504) (xy 46.857718 -136.936934)
			(xy 46.803555 -136.936517) (xy 46.750023 -136.928263) (xy 46.69825 -136.912345) (xy 46.649327 -136.889098)
			(xy 46.604285 -136.859014) (xy 46.583854 -136.84123) (xy 46.566812 -136.826412) (xy 46.528518 -136.802482)
			(xy 46.486595 -136.7857) (xy 46.442366 -136.776596) (xy 46.397224 -136.775456) (xy 46.352591 -136.782317)
			(xy 46.309875 -136.796961) (xy 46.270422 -136.818929) (xy 46.252638 -136.832848) (xy 46.231849 -136.849203)
			(xy 46.186294 -136.876083) (xy 46.137188 -136.89574) (xy 46.085669 -136.907719) (xy 46.032928 -136.911743)
			(xy 45.980187 -136.907719) (xy 45.928668 -136.89574) (xy 45.879562 -136.876083) (xy 45.834007 -136.849203)
			(xy 45.813218 -136.832848) (xy 45.795473 -136.818919) (xy 45.756054 -136.796987) (xy 45.713382 -136.782359)
			(xy 45.668798 -136.775492) (xy 45.623702 -136.776604) (xy 45.579511 -136.78566) (xy 45.537613 -136.802374)
			(xy 45.499322 -136.826222) (xy 45.482256 -136.840976) (xy 45.461312 -136.85913) (xy 45.415095 -136.889721)
			(xy 45.364857 -136.91313) (xy 45.311706 -136.928839) (xy 45.256814 -136.936503) (xy 45.201393 -136.935952)
			(xy 45.146664 -136.9272) (xy 45.093836 -136.910437) (xy 45.044073 -136.886036) (xy 44.998472 -136.854533)
			(xy 44.958041 -136.816623) (xy 44.92367 -136.773144) (xy 44.896118 -136.725053) (xy 44.875993 -136.673412)
			(xy 44.863738 -136.61936) (xy 44.859624 -136.564089) (xy 42.631187 -136.564089) (xy 42.628558 -136.570994)
			(xy 42.620193 -136.616454) (xy 42.620187 -136.662677) (xy 42.62854 -136.70814) (xy 42.644976 -136.751343)
			(xy 42.668953 -136.790861) (xy 42.683938 -136.808464) (xy 42.700236 -136.827425) (xy 42.727857 -136.869099)
			(xy 42.74921 -136.914306) (xy 42.763853 -136.96211) (xy 42.771483 -137.011521) (xy 42.771942 -137.061516)
			(xy 42.76522 -137.111058) (xy 42.751458 -137.159123) (xy 42.741596 -137.182098) (xy 42.732822 -137.202772)
			(xy 42.721861 -137.246321) (xy 42.718728 -137.291118) (xy 42.723521 -137.335769) (xy 42.736089 -137.378881)
			(xy 42.756041 -137.419112) (xy 42.782756 -137.455208) (xy 42.815401 -137.486045) (xy 42.85296 -137.510662)
			(xy 42.873422 -137.519918) (xy 42.897536 -137.530698) (xy 42.94252 -137.558383) (xy 42.982919 -137.59241)
			(xy 43.017847 -137.632034) (xy 43.046536 -137.676383) (xy 43.068357 -137.724485) (xy 43.073251 -137.74166)
			(xy 43.874941 -137.74166) (xy 43.879016 -137.688579) (xy 43.891146 -137.636743) (xy 43.911047 -137.587366)
			(xy 43.938252 -137.541605) (xy 43.972124 -137.500533) (xy 44.011868 -137.465114) (xy 44.056553 -137.436176)
			(xy 44.105132 -137.414398) (xy 44.156465 -137.400292) (xy 44.209351 -137.394186) (xy 44.262549 -137.396225)
			(xy 44.314812 -137.406361) (xy 44.364915 -137.424356) (xy 44.411684 -137.449788) (xy 44.454023 -137.482062)
			(xy 44.490939 -137.52042) (xy 44.521567 -137.563964) (xy 44.545189 -137.611673) (xy 44.561252 -137.662429)
			(xy 44.569379 -137.715042) (xy 44.569888 -137.74166) (xy 44.569379 -137.768278) (xy 44.561252 -137.820891)
			(xy 44.545189 -137.871647) (xy 44.521567 -137.919356) (xy 44.490939 -137.9629) (xy 44.454023 -138.001258)
			(xy 44.411684 -138.033532) (xy 44.364915 -138.058964) (xy 44.314812 -138.076959) (xy 44.262549 -138.087095)
			(xy 44.209351 -138.089134) (xy 44.156465 -138.083028) (xy 44.105132 -138.068922) (xy 44.056553 -138.047144)
			(xy 44.011868 -138.018206) (xy 43.972124 -137.982787) (xy 43.938252 -137.941715) (xy 43.911047 -137.895954)
			(xy 43.891146 -137.846577) (xy 43.879016 -137.794741) (xy 43.874941 -137.74166) (xy 43.073251 -137.74166)
			(xy 43.082831 -137.775283) (xy 43.08964 -137.827663) (xy 43.088634 -137.880473) (xy 43.079836 -137.932556)
			(xy 43.063439 -137.982766) (xy 43.039802 -138.030003) (xy 43.009445 -138.073228) (xy 42.973035 -138.111493)
			(xy 42.931369 -138.143958) (xy 42.895731 -138.164062) (xy 45.659812 -138.164062) (xy 45.663788 -138.109736)
			(xy 45.675631 -138.056567) (xy 45.69509 -138.00569) (xy 45.72175 -137.958188) (xy 45.755041 -137.915074)
			(xy 45.794255 -137.877267) (xy 45.838557 -137.845572) (xy 45.887 -137.820666) (xy 45.938554 -137.803078)
			(xy 45.99212 -137.793184) (xy 46.046555 -137.791194) (xy 46.1007 -137.797152) (xy 46.1534 -137.81093)
			(xy 46.203533 -137.832234) (xy 46.250029 -137.86061) (xy 46.291899 -137.895454) (xy 46.328248 -137.936023)
			(xy 46.358304 -137.981452) (xy 46.381425 -138.030773) (xy 46.397118 -138.082935) (xy 46.405049 -138.136826)
			(xy 46.405546 -138.164062) (xy 46.405049 -138.191298) (xy 46.397118 -138.245189) (xy 46.381425 -138.297351)
			(xy 46.358304 -138.346672) (xy 46.328248 -138.392101) (xy 46.291899 -138.43267) (xy 46.250029 -138.467514)
			(xy 46.203533 -138.49589) (xy 46.1534 -138.517194) (xy 46.1007 -138.530972) (xy 46.046555 -138.53693)
			(xy 45.99212 -138.53494) (xy 45.938554 -138.525046) (xy 45.887 -138.507458) (xy 45.838557 -138.482552)
			(xy 45.794255 -138.450857) (xy 45.755041 -138.41305) (xy 45.72175 -138.369936) (xy 45.69509 -138.322434)
			(xy 45.675631 -138.271557) (xy 45.663788 -138.218388) (xy 45.659812 -138.164062) (xy 42.895731 -138.164062)
			(xy 42.885364 -138.16991) (xy 42.836029 -138.188779) (xy 42.784448 -138.200151) (xy 42.731752 -138.203776)
			(xy 42.6791 -138.199575) (xy 42.627645 -138.18764) (xy 42.57852 -138.168233) (xy 42.532801 -138.14178)
			(xy 42.491493 -138.108862) (xy 42.455502 -138.070201) (xy 42.425619 -138.026647) (xy 42.4025 -137.979155)
			(xy 42.386653 -137.928768) (xy 42.378424 -137.876593) (xy 42.377996 -137.823775) (xy 42.385377 -137.771473)
			(xy 42.400405 -137.720836) (xy 42.411142 -137.696702) (xy 42.420209 -137.676139) (xy 42.431761 -137.632714)
			(xy 42.435503 -137.587934) (xy 42.431316 -137.543193) (xy 42.419332 -137.499885) (xy 42.399924 -137.459356)
			(xy 42.373696 -137.422869) (xy 42.341464 -137.391559) (xy 42.304231 -137.3664) (xy 42.283888 -137.35685)
			(xy 42.259213 -137.345328) (xy 42.213507 -137.315724) (xy 42.172985 -137.279346) (xy 42.13864 -137.237088)
			(xy 42.111314 -137.189984) (xy 42.091678 -137.139192) (xy 42.080213 -137.085957) (xy 42.077201 -137.031585)
			(xy 34.014519 -137.031585) (xy 34.774753 -137.791819) (xy 38.983972 -137.791819) (xy 38.984071 -137.737424)
			(xy 38.992079 -137.683621) (xy 39.007825 -137.631555) (xy 39.030976 -137.582332) (xy 39.061038 -137.536999)
			(xy 39.097373 -137.496519) (xy 39.139208 -137.461753) (xy 39.185653 -137.43344) (xy 39.235723 -137.412182)
			(xy 39.288351 -137.398431) (xy 39.342419 -137.392479) (xy 39.396779 -137.394452) (xy 39.450273 -137.404309)
			(xy 39.501766 -137.421841) (xy 39.550162 -137.446673) (xy 39.594432 -137.47828) (xy 39.633636 -137.515988)
			(xy 39.66694 -137.558996) (xy 39.693636 -137.60639) (xy 39.713156 -137.657162) (xy 39.725086 -137.710232)
			(xy 39.729171 -137.764474) (xy 39.725326 -137.818733) (xy 39.713631 -137.871856) (xy 39.694336 -137.922714)
			(xy 39.66785 -137.970226) (xy 39.651686 -137.992104) (xy 39.638628 -138.009767) (xy 39.618254 -138.04868)
			(xy 39.604876 -138.090518) (xy 39.598893 -138.134033) (xy 39.599977 -138.163946) (xy 40.059871 -138.163946)
			(xy 40.063959 -138.109019) (xy 40.076088 -138.055292) (xy 40.095995 -138.003936) (xy 40.123244 -137.956071)
			(xy 40.157243 -137.912738) (xy 40.19725 -137.874882) (xy 40.242395 -137.843328) (xy 40.291692 -137.818764)
			(xy 40.344069 -137.801724) (xy 40.398384 -137.792581) (xy 40.453452 -137.791532) (xy 40.508075 -137.798602)
			(xy 40.561063 -137.813636) (xy 40.611259 -137.836307) (xy 40.657572 -137.866119) (xy 40.678608 -137.8839)
			(xy 40.69572 -137.898271) (xy 40.733977 -137.921357) (xy 40.775683 -137.937394) (xy 40.819552 -137.945888)
			(xy 40.86423 -137.946577) (xy 40.908339 -137.93944) (xy 40.95052 -137.924697) (xy 40.989471 -137.902802)
			(xy 41.00703 -137.88898) (xy 41.028076 -137.872351) (xy 41.074167 -137.844917) (xy 41.12385 -137.824706)
			(xy 41.176003 -137.812176) (xy 41.229445 -137.807609) (xy 41.282968 -137.811109) (xy 41.33536 -137.822598)
			(xy 41.385437 -137.841814) (xy 41.432065 -137.868324) (xy 41.47419 -137.901527) (xy 41.510858 -137.940672)
			(xy 41.54124 -137.984874) (xy 41.56465 -138.033134) (xy 41.580556 -138.084358) (xy 41.588599 -138.137388)
			(xy 41.588598 -138.191026) (xy 41.580553 -138.244056) (xy 41.564644 -138.295279) (xy 41.541233 -138.343538)
			(xy 41.510849 -138.387739) (xy 41.47418 -138.426883) (xy 41.432054 -138.460084) (xy 41.385424 -138.486592)
			(xy 41.335347 -138.505806) (xy 41.282954 -138.517293) (xy 41.229431 -138.520791) (xy 41.175989 -138.516222)
			(xy 41.123837 -138.50369) (xy 41.074154 -138.483477) (xy 41.028065 -138.456041) (xy 41.00703 -138.439398)
			(xy 40.989481 -138.425526) (xy 40.950505 -138.40358) (xy 40.908287 -138.388802) (xy 40.864132 -138.381649)
			(xy 40.819408 -138.382343) (xy 40.775497 -138.390862) (xy 40.733757 -138.406942) (xy 40.69548 -138.430087)
			(xy 40.678354 -138.444478) (xy 40.657325 -138.462266) (xy 40.610988 -138.492041) (xy 40.560773 -138.51467)
			(xy 40.507773 -138.52966) (xy 40.453144 -138.536684) (xy 40.398076 -138.535591) (xy 40.343769 -138.526402)
			(xy 40.291407 -138.509319) (xy 40.242129 -138.484714) (xy 40.197011 -138.453123) (xy 40.157035 -138.415234)
			(xy 40.123072 -138.371873) (xy 40.095862 -138.323985) (xy 40.075999 -138.272612) (xy 40.063914 -138.218876)
			(xy 40.059871 -138.163946) (xy 39.599977 -138.163946) (xy 39.600484 -138.177928) (xy 39.609601 -138.220896)
			(xy 39.625972 -138.261655) (xy 39.64911 -138.298991) (xy 39.66337 -138.3157) (xy 39.6811 -138.336333)
			(xy 39.711003 -138.381778) (xy 39.73398 -138.431088) (xy 39.749542 -138.483216) (xy 39.757359 -138.537052)
			(xy 39.757334 -138.551137) (xy 47.102004 -138.551137) (xy 47.102004 -138.497839) (xy 47.109947 -138.445135)
			(xy 47.125657 -138.394205) (xy 47.148783 -138.346184) (xy 47.178807 -138.302147) (xy 47.215059 -138.263076)
			(xy 47.25673 -138.229845) (xy 47.302888 -138.203196) (xy 47.352502 -138.183724) (xy 47.404464 -138.171864)
			(xy 47.457614 -138.167881) (xy 47.510764 -138.171864) (xy 47.562726 -138.183724) (xy 47.61234 -138.203196)
			(xy 47.658498 -138.229845) (xy 47.680614 -138.247482) (xy 54.494287 -138.247482) (xy 54.495208 -138.19487)
			(xy 54.503861 -138.142967) (xy 54.520059 -138.092902) (xy 54.543449 -138.045766) (xy 54.573521 -138.002585)
			(xy 54.60962 -137.9643) (xy 54.65096 -137.931744) (xy 54.696641 -137.905627) (xy 54.745669 -137.886517)
			(xy 54.796974 -137.874831) (xy 54.849442 -137.870822) (xy 54.901928 -137.874578) (xy 54.953289 -137.886018)
			(xy 55.002408 -137.904891) (xy 55.025544 -137.917428) (xy 55.045886 -137.928301) (xy 55.089462 -137.943398)
			(xy 55.135046 -137.950388) (xy 55.181143 -137.949044) (xy 55.226243 -137.939408) (xy 55.268865 -137.921797)
			(xy 55.307612 -137.896788) (xy 55.324756 -137.88136) (xy 55.344229 -137.863669) (xy 55.38753 -137.833789)
			(xy 55.434843 -137.810784) (xy 55.485085 -137.79518) (xy 55.537107 -137.787334) (xy 55.589717 -137.787427)
			(xy 55.64171 -137.795456) (xy 55.691897 -137.811237) (xy 55.739129 -137.834409) (xy 55.782324 -137.864442)
			(xy 55.820494 -137.900647) (xy 55.852765 -137.942197) (xy 55.878398 -137.98814) (xy 55.896806 -138.037424)
			(xy 55.907569 -138.088921) (xy 55.910438 -138.141452) (xy 55.90535 -138.193815) (xy 55.89242 -138.244812)
			(xy 55.871945 -138.293273) (xy 55.844392 -138.338091) (xy 55.810393 -138.378239) (xy 55.770727 -138.412799)
			(xy 55.7263 -138.440978) (xy 55.678131 -138.462132) (xy 55.627322 -138.475777) (xy 55.575035 -138.481601)
			(xy 55.522469 -138.479469) (xy 55.470825 -138.469431) (xy 55.421288 -138.451717) (xy 55.397908 -138.439652)
			(xy 55.377376 -138.429129) (xy 55.333488 -138.414911) (xy 55.287755 -138.408847) (xy 55.241679 -138.411137)
			(xy 55.196772 -138.421705) (xy 55.15451 -138.440204) (xy 55.116281 -138.466026) (xy 55.099458 -138.481816)
			(xy 55.080316 -138.499873) (xy 55.037712 -138.530757) (xy 54.991028 -138.555035) (xy 54.941278 -138.572178)
			(xy 54.889548 -138.581813) (xy 54.836963 -138.58373) (xy 54.784668 -138.577887) (xy 54.733802 -138.564412)
			(xy 54.685474 -138.543598) (xy 54.640735 -138.515898) (xy 54.600559 -138.481916) (xy 54.565822 -138.442391)
			(xy 54.53728 -138.398184) (xy 54.515555 -138.350258) (xy 54.501119 -138.299657) (xy 54.494287 -138.247482)
			(xy 47.680614 -138.247482) (xy 47.700169 -138.263076) (xy 47.736421 -138.302147) (xy 47.766445 -138.346184)
			(xy 47.789571 -138.394205) (xy 47.805281 -138.445135) (xy 47.813224 -138.497839) (xy 47.813722 -138.524488)
			(xy 47.813224 -138.551137) (xy 47.805281 -138.603841) (xy 47.789571 -138.654771) (xy 47.766445 -138.702792)
			(xy 47.736421 -138.746829) (xy 47.700169 -138.7859) (xy 47.658498 -138.819131) (xy 47.61234 -138.84578)
			(xy 47.562726 -138.865252) (xy 47.510764 -138.877112) (xy 47.457614 -138.881096) (xy 47.404464 -138.877112)
			(xy 47.352502 -138.865252) (xy 47.302888 -138.84578) (xy 47.25673 -138.819131) (xy 47.215059 -138.7859)
			(xy 47.178807 -138.746829) (xy 47.148783 -138.702792) (xy 47.125657 -138.654771) (xy 47.109947 -138.603841)
			(xy 47.102004 -138.551137) (xy 39.757334 -138.551137) (xy 39.757263 -138.591452) (xy 39.749258 -138.645261)
			(xy 39.733514 -138.697333) (xy 39.710364 -138.746562) (xy 39.680302 -138.791902) (xy 39.643966 -138.832388)
			(xy 39.602129 -138.86716) (xy 39.55568 -138.895479) (xy 39.505607 -138.916742) (xy 39.452974 -138.930497)
			(xy 39.398901 -138.936453) (xy 39.344536 -138.934482) (xy 39.291035 -138.924626) (xy 39.239537 -138.907096)
			(xy 39.191135 -138.882262) (xy 39.146859 -138.850655) (xy 39.107649 -138.812944) (xy 39.074341 -138.769933)
			(xy 39.047641 -138.722536) (xy 39.028117 -138.671759) (xy 39.016184 -138.618683) (xy 39.012096 -138.564437)
			(xy 39.015941 -138.510172) (xy 39.027635 -138.457043) (xy 39.046931 -138.40618) (xy 39.073418 -138.358663)
			(xy 39.089584 -138.336782) (xy 39.10256 -138.319061) (xy 39.122942 -138.280162) (xy 39.13633 -138.238336)
			(xy 39.142324 -138.194832) (xy 39.140745 -138.150944) (xy 39.13164 -138.107983) (xy 39.115281 -138.067228)
			(xy 39.092155 -138.029894) (xy 39.0779 -138.013186) (xy 39.060207 -137.992523) (xy 39.030311 -137.94708)
			(xy 39.00734 -137.897773) (xy 38.991783 -137.84565) (xy 38.983972 -137.791819) (xy 34.774753 -137.791819)
			(xy 35.896804 -138.91387) (xy 35.913074 -138.92944) (xy 35.95004 -138.955152) (xy 35.990959 -138.973946)
			(xy 36.03455 -138.985234) (xy 36.079448 -138.988663) (xy 36.124248 -138.984124) (xy 36.167546 -138.971761)
			(xy 36.207988 -138.95196) (xy 36.244306 -138.925342) (xy 36.275365 -138.892738) (xy 36.288218 -138.874246)
			(xy 36.303922 -138.851399) (xy 36.34087 -138.810068) (xy 36.383408 -138.774517) (xy 36.430642 -138.745494)
			(xy 36.481578 -138.723608) (xy 36.535143 -138.709322) (xy 36.590212 -138.702934) (xy 36.645626 -138.70458)
			(xy 36.700219 -138.714225) (xy 36.752842 -138.731666) (xy 36.802389 -138.756537) (xy 36.847816 -138.788313)
			(xy 36.868354 -138.806936) (xy 36.88461 -138.82243) (xy 36.975034 -138.861038) (xy 37.059108 -138.828526)
			(xy 37.07511 -138.815572) (xy 37.096529 -138.79854) (xy 37.143306 -138.770139) (xy 37.19366 -138.748713)
			(xy 37.246559 -138.7347) (xy 37.300917 -138.728387) (xy 37.355619 -138.729905) (xy 37.409544 -138.739221)
			(xy 37.461584 -138.756146) (xy 37.510673 -138.780331) (xy 37.555804 -138.811281) (xy 37.59605 -138.84836)
			(xy 37.630586 -138.890809) (xy 37.658704 -138.937756) (xy 37.679827 -138.988238) (xy 37.680689 -138.991573)
			(xy 44.07661 -138.991573) (xy 44.07661 -138.938275) (xy 44.084553 -138.885571) (xy 44.100263 -138.834641)
			(xy 44.123389 -138.78662) (xy 44.153413 -138.742583) (xy 44.189665 -138.703512) (xy 44.231336 -138.670281)
			(xy 44.277494 -138.643632) (xy 44.327108 -138.62416) (xy 44.37907 -138.6123) (xy 44.43222 -138.608317)
			(xy 44.48537 -138.6123) (xy 44.537332 -138.62416) (xy 44.586946 -138.643632) (xy 44.633104 -138.670281)
			(xy 44.674775 -138.703512) (xy 44.711027 -138.742583) (xy 44.741051 -138.78662) (xy 44.764177 -138.834641)
			(xy 44.779887 -138.885571) (xy 44.783425 -138.909044) (xy 48.758346 -138.909044) (xy 48.762417 -138.853422)
			(xy 48.774543 -138.798985) (xy 48.794466 -138.746894) (xy 48.821762 -138.698259) (xy 48.855848 -138.654116)
			(xy 48.895997 -138.615407) (xy 48.941355 -138.582956) (xy 48.990955 -138.557455) (xy 49.043739 -138.539448)
			(xy 49.098582 -138.529318) (xy 49.154316 -138.527281) (xy 49.209753 -138.533381) (xy 49.26371 -138.547487)
			(xy 49.315039 -138.569299) (xy 49.362645 -138.598353) (xy 49.405513 -138.634028) (xy 49.44273 -138.675565)
			(xy 49.473503 -138.722078) (xy 49.497175 -138.772575) (xy 49.513243 -138.825982) (xy 49.521363 -138.881158)
			(xy 49.521872 -138.909044) (xy 49.521363 -138.93693) (xy 49.513243 -138.992106) (xy 49.497175 -139.045513)
			(xy 49.473503 -139.09601) (xy 49.44273 -139.142523) (xy 49.405513 -139.18406) (xy 49.362645 -139.219735)
			(xy 49.315039 -139.248789) (xy 49.26371 -139.270601) (xy 49.209753 -139.284707) (xy 49.154316 -139.290807)
			(xy 49.098582 -139.28877) (xy 49.043739 -139.27864) (xy 48.990955 -139.260633) (xy 48.941355 -139.235132)
			(xy 48.895997 -139.202681) (xy 48.855848 -139.163972) (xy 48.821762 -139.119829) (xy 48.794466 -139.071194)
			(xy 48.774543 -139.019103) (xy 48.762417 -138.964666) (xy 48.758346 -138.909044) (xy 44.783425 -138.909044)
			(xy 44.78783 -138.938275) (xy 44.788328 -138.964924) (xy 44.78783 -138.991573) (xy 44.779887 -139.044277)
			(xy 44.764177 -139.095207) (xy 44.741051 -139.143228) (xy 44.711027 -139.187265) (xy 44.674775 -139.226336)
			(xy 44.633104 -139.259567) (xy 44.586946 -139.286216) (xy 44.537332 -139.305688) (xy 44.48537 -139.317548)
			(xy 44.43222 -139.321532) (xy 44.37907 -139.317548) (xy 44.327108 -139.305688) (xy 44.277494 -139.286216)
			(xy 44.231336 -139.259567) (xy 44.189665 -139.226336) (xy 44.153413 -139.187265) (xy 44.123389 -139.143228)
			(xy 44.100263 -139.095207) (xy 44.084553 -139.044277) (xy 44.07661 -138.991573) (xy 37.680689 -138.991573)
			(xy 37.693522 -139.04122) (xy 37.699507 -139.095615) (xy 37.69766 -139.150308) (xy 37.688019 -139.204175)
			(xy 37.670782 -139.256113) (xy 37.646302 -139.305055) (xy 37.615081 -139.349998) (xy 37.577759 -139.390021)
			(xy 37.577346 -139.390353) (xy 42.610268 -139.390353) (xy 42.610268 -139.337055) (xy 42.618211 -139.284351)
			(xy 42.633921 -139.233421) (xy 42.657047 -139.1854) (xy 42.687071 -139.141363) (xy 42.723323 -139.102292)
			(xy 42.764994 -139.069061) (xy 42.811152 -139.042412) (xy 42.860766 -139.02294) (xy 42.912728 -139.01108)
			(xy 42.965878 -139.007097) (xy 43.019028 -139.01108) (xy 43.07099 -139.02294) (xy 43.120604 -139.042412)
			(xy 43.166762 -139.069061) (xy 43.208433 -139.102292) (xy 43.244685 -139.141363) (xy 43.274709 -139.1854)
			(xy 43.297835 -139.233421) (xy 43.313545 -139.284351) (xy 43.321488 -139.337055) (xy 43.321986 -139.363704)
			(xy 43.321488 -139.390353) (xy 43.313545 -139.443057) (xy 43.297835 -139.493987) (xy 43.274709 -139.542008)
			(xy 43.244685 -139.586045) (xy 43.208433 -139.625116) (xy 43.166762 -139.658347) (xy 43.120604 -139.684996)
			(xy 43.07099 -139.704468) (xy 43.019028 -139.716328) (xy 42.965878 -139.720312) (xy 42.912728 -139.716328)
			(xy 42.860766 -139.704468) (xy 42.811152 -139.684996) (xy 42.764994 -139.658347) (xy 42.723323 -139.625116)
			(xy 42.687071 -139.586045) (xy 42.657047 -139.542008) (xy 42.633921 -139.493987) (xy 42.618211 -139.443057)
			(xy 42.610268 -139.390353) (xy 37.577346 -139.390353) (xy 37.535104 -139.424301) (xy 37.487988 -139.452136)
			(xy 37.43738 -139.472954) (xy 37.384316 -139.48633) (xy 37.329886 -139.491987) (xy 37.275206 -139.489811)
			(xy 37.221397 -139.479846) (xy 37.169564 -139.462296) (xy 37.12077 -139.437522) (xy 37.076016 -139.406031)
			(xy 37.055806 -139.38758) (xy 37.03955 -139.372086) (xy 36.949126 -139.333478) (xy 36.865052 -139.36599)
			(xy 36.84905 -139.378944) (xy 36.841269 -139.385287) (xy 36.825132 -139.397232) (xy 36.816792 -139.40282)
			(xy 36.798292 -139.41565) (xy 36.765722 -139.446726) (xy 36.739133 -139.483052) (xy 36.719357 -139.523492)
			(xy 36.707011 -139.566782) (xy 36.702481 -139.611571) (xy 36.705909 -139.656457) (xy 36.717187 -139.700038)
			(xy 36.735964 -139.740952) (xy 36.761652 -139.77792) (xy 36.777168 -139.794234) (xy 37.148262 -140.165328)
			(xy 38.971484 -140.165328) (xy 38.97546 -140.111002) (xy 38.987303 -140.057833) (xy 39.006762 -140.006956)
			(xy 39.033422 -139.959454) (xy 39.066713 -139.91634) (xy 39.105927 -139.878533) (xy 39.150229 -139.846838)
			(xy 39.198672 -139.821932) (xy 39.250226 -139.804344) (xy 39.303792 -139.79445) (xy 39.358227 -139.79246)
			(xy 39.412372 -139.798418) (xy 39.465072 -139.812196) (xy 39.515205 -139.8335) (xy 39.561701 -139.861876)
			(xy 39.603571 -139.89672) (xy 39.63992 -139.937289) (xy 39.669976 -139.982718) (xy 39.693097 -140.032039)
			(xy 39.70879 -140.084201) (xy 39.716721 -140.138092) (xy 39.717218 -140.165328) (xy 39.716721 -140.192564)
			(xy 39.70879 -140.246455) (xy 39.693097 -140.298617) (xy 39.669976 -140.347938) (xy 39.63992 -140.393367)
			(xy 39.603571 -140.433936) (xy 39.561701 -140.46878) (xy 39.515205 -140.497156) (xy 39.465072 -140.51846)
			(xy 39.412372 -140.532238) (xy 39.382419 -140.535534) (xy 40.855773 -140.535534) (xy 40.863685 -140.480765)
			(xy 40.879611 -140.427768) (xy 40.903202 -140.37771) (xy 40.933937 -140.331692) (xy 40.952166 -140.31087)
			(xy 40.96689 -140.293942) (xy 40.99072 -140.255933) (xy 41.00751 -140.214332) (xy 41.016739 -140.17043)
			(xy 41.01812 -140.12559) (xy 41.011611 -140.081203) (xy 40.997413 -140.038648) (xy 40.975968 -139.999244)
			(xy 40.962326 -139.981432) (xy 40.946423 -139.960746) (xy 40.920257 -139.915608) (xy 40.901141 -139.867062)
			(xy 40.889504 -139.816202) (xy 40.885608 -139.764174) (xy 40.889541 -139.712148) (xy 40.901216 -139.661297)
			(xy 40.920367 -139.612765) (xy 40.946566 -139.567645) (xy 40.97922 -139.526954) (xy 41.017596 -139.491606)
			(xy 41.06083 -139.4624) (xy 41.107946 -139.439991) (xy 41.157886 -139.424885) (xy 41.209523 -139.417422)
			(xy 41.261696 -139.417769) (xy 41.31323 -139.42592) (xy 41.362964 -139.44169) (xy 41.409778 -139.464725)
			(xy 41.452618 -139.494505) (xy 41.490519 -139.53036) (xy 41.522629 -139.571483) (xy 41.548224 -139.616948)
			(xy 41.566727 -139.665731) (xy 41.577723 -139.716733) (xy 41.580963 -139.768806) (xy 41.576374 -139.820778)
			(xy 41.564061 -139.871478) (xy 41.544299 -139.919765) (xy 41.517534 -139.964551) (xy 41.501314 -139.984988)
			(xy 41.487427 -140.002622) (xy 41.465456 -140.041759) (xy 41.450696 -140.084144) (xy 41.443604 -140.128462)
			(xy 41.444399 -140.173337) (xy 41.453059 -140.217376) (xy 41.469313 -140.259211) (xy 41.492658 -140.297544)
			(xy 41.507156 -140.31468) (xy 41.525092 -140.335755) (xy 41.555192 -140.382191) (xy 41.578092 -140.432568)
			(xy 41.585548 -140.458677) (xy 42.08906 -140.458677) (xy 42.08906 -140.405379) (xy 42.097003 -140.352675)
			(xy 42.112713 -140.301745) (xy 42.135839 -140.253724) (xy 42.165863 -140.209687) (xy 42.202115 -140.170616)
			(xy 42.243786 -140.137385) (xy 42.289944 -140.110736) (xy 42.339558 -140.091264) (xy 42.39152 -140.079404)
			(xy 42.44467 -140.075421) (xy 42.49782 -140.079404) (xy 42.549782 -140.091264) (xy 42.599396 -140.110736)
			(xy 42.645554 -140.137385) (xy 42.687225 -140.170616) (xy 42.723477 -140.209687) (xy 42.723698 -140.210011)
			(xy 43.627792 -140.210011) (xy 43.627792 -140.156713) (xy 43.635735 -140.104009) (xy 43.651445 -140.053079)
			(xy 43.674571 -140.005058) (xy 43.704595 -139.961021) (xy 43.740847 -139.92195) (xy 43.782518 -139.888719)
			(xy 43.828676 -139.86207) (xy 43.87829 -139.842598) (xy 43.930252 -139.830738) (xy 43.983402 -139.826755)
			(xy 44.036552 -139.830738) (xy 44.088514 -139.842598) (xy 44.138128 -139.86207) (xy 44.184286 -139.888719)
			(xy 44.225957 -139.92195) (xy 44.262209 -139.961021) (xy 44.292233 -140.005058) (xy 44.315359 -140.053079)
			(xy 44.331069 -140.104009) (xy 44.339012 -140.156713) (xy 44.33951 -140.183362) (xy 44.339012 -140.210011)
			(xy 44.331069 -140.262715) (xy 44.315359 -140.313645) (xy 44.292233 -140.361666) (xy 44.262209 -140.405703)
			(xy 44.225957 -140.444774) (xy 44.184286 -140.478005) (xy 44.138128 -140.504654) (xy 44.088514 -140.524126)
			(xy 44.036552 -140.535986) (xy 43.983402 -140.53997) (xy 43.930252 -140.535986) (xy 43.87829 -140.524126)
			(xy 43.828676 -140.504654) (xy 43.782518 -140.478005) (xy 43.740847 -140.444774) (xy 43.704595 -140.405703)
			(xy 43.674571 -140.361666) (xy 43.651445 -140.313645) (xy 43.635735 -140.262715) (xy 43.627792 -140.210011)
			(xy 42.723698 -140.210011) (xy 42.753501 -140.253724) (xy 42.776627 -140.301745) (xy 42.792337 -140.352675)
			(xy 42.80028 -140.405379) (xy 42.800778 -140.432028) (xy 42.80028 -140.458677) (xy 42.792337 -140.511381)
			(xy 42.776627 -140.562311) (xy 42.767423 -140.581424) (xy 44.85141 -140.581424) (xy 44.852812 -140.527117)
			(xy 44.861903 -140.473558) (xy 44.8785 -140.42183) (xy 44.902267 -140.37298) (xy 44.932724 -140.327995)
			(xy 44.950634 -140.307568) (xy 44.96528 -140.290858) (xy 44.988982 -140.253275) (xy 45.005782 -140.212141)
			(xy 45.015167 -140.168712) (xy 45.016853 -140.124311) (xy 45.010786 -140.080295) (xy 44.997153 -140.038005)
			(xy 44.976368 -139.998734) (xy 44.96308 -139.980924) (xy 44.947193 -139.959726) (xy 44.921408 -139.913454)
			(xy 44.90295 -139.863802) (xy 44.892247 -139.811923) (xy 44.889547 -139.75902) (xy 44.894914 -139.706321)
			(xy 44.908222 -139.655048) (xy 44.929163 -139.606391) (xy 44.957251 -139.561479) (xy 44.991835 -139.521354)
			(xy 45.032111 -139.486948) (xy 45.077146 -139.459057) (xy 45.125894 -139.43833) (xy 45.177225 -139.425247)
			(xy 45.229948 -139.420112) (xy 45.282838 -139.423044) (xy 45.33467 -139.433975) (xy 45.38424 -139.452651)
			(xy 45.430399 -139.47864) (xy 45.472075 -139.511337) (xy 45.508301 -139.549985) (xy 45.538238 -139.593686)
			(xy 45.56119 -139.641427) (xy 45.576625 -139.692101) (xy 45.584184 -139.74453) (xy 45.583693 -139.7975)
			(xy 45.575163 -139.84978) (xy 45.558791 -139.900159) (xy 45.534958 -139.947466) (xy 45.504216 -139.990605)
			(xy 45.467279 -140.028574) (xy 45.446442 -140.044932) (xy 45.434666 -140.054262) (xy 45.41557 -140.07745)
			(xy 45.402432 -140.104464) (xy 45.40165 -140.108021) (xy 50.353223 -140.108021) (xy 50.358877 -140.05413)
			(xy 50.372278 -140.001627) (xy 50.393144 -139.951618) (xy 50.421034 -139.90516) (xy 50.45536 -139.863232)
			(xy 50.495398 -139.826719) (xy 50.540303 -139.796391) (xy 50.589127 -139.772888) (xy 50.640841 -139.756706)
			(xy 50.694354 -139.748187) (xy 50.748537 -139.747509) (xy 50.802246 -139.754687) (xy 50.854349 -139.769571)
			(xy 50.879248 -139.780264) (xy 50.899619 -139.788978) (xy 50.94255 -139.799921) (xy 50.986728 -139.803252)
			(xy 51.030815 -139.798871) (xy 51.073474 -139.786909) (xy 51.113411 -139.76773) (xy 51.149417 -139.741914)
			(xy 51.165252 -139.726416) (xy 51.18423 -139.707766) (xy 51.226486 -139.675436) (xy 51.272909 -139.649442)
			(xy 51.322556 -139.630312) (xy 51.374419 -139.618435) (xy 51.427443 -139.614052) (xy 51.480552 -139.617253)
			(xy 51.532667 -139.627972) (xy 51.582728 -139.645992) (xy 51.629718 -139.670946) (xy 51.672684 -139.702327)
			(xy 51.692048 -139.720574) (xy 51.70425 -139.731839) (xy 51.733148 -139.748182) (xy 51.765289 -139.756493)
			(xy 51.798487 -139.756206) (xy 51.83048 -139.747342) (xy 51.859091 -139.730504) (xy 51.871118 -139.71905)
			(xy 51.89057 -139.700101) (xy 51.933804 -139.667245) (xy 51.981261 -139.640852) (xy 52.031981 -139.621457)
			(xy 52.084939 -139.609449) (xy 52.139064 -139.605074) (xy 52.193263 -139.608418) (xy 52.246439 -139.619415)
			(xy 52.297519 -139.637841) (xy 52.34547 -139.663326) (xy 52.389322 -139.695352) (xy 52.40909 -139.71397)
			(xy 52.421492 -139.725275) (xy 52.450775 -139.741638) (xy 52.483311 -139.749799) (xy 52.516849 -139.749194)
			(xy 52.54907 -139.739865) (xy 52.577743 -139.722457) (xy 52.589684 -139.710668) (xy 52.608941 -139.691136)
			(xy 52.65216 -139.657364) (xy 52.699862 -139.630292) (xy 52.751018 -139.610505) (xy 52.804521 -139.59843)
			(xy 52.859217 -139.594328) (xy 52.913923 -139.598288) (xy 52.967457 -139.610225) (xy 53.018664 -139.629879)
			(xy 53.066436 -139.656827) (xy 53.109742 -139.690487) (xy 53.147647 -139.730131) (xy 53.179331 -139.774903)
			(xy 53.20411 -139.823836) (xy 53.221448 -139.875873) (xy 53.230972 -139.929889) (xy 53.232474 -139.984717)
			(xy 53.225924 -140.039173) (xy 53.211462 -140.092081) (xy 53.189401 -140.142298) (xy 53.160217 -140.188739)
			(xy 53.124541 -140.2304) (xy 53.083144 -140.266381) (xy 53.03692 -140.295906) (xy 52.986867 -140.318336)
			(xy 52.934066 -140.333187) (xy 52.87966 -140.340138) (xy 52.824822 -140.339038) (xy 52.770737 -140.329913)
			(xy 52.718575 -140.312957) (xy 52.669461 -140.288539) (xy 52.624457 -140.257186) (xy 52.604162 -140.238734)
			(xy 52.591602 -140.227588) (xy 52.562024 -140.211714) (xy 52.52933 -140.204103) (xy 52.495782 -140.205282)
			(xy 52.463703 -140.21517) (xy 52.435313 -140.233082) (xy 52.423568 -140.245084) (xy 52.404164 -140.265416)
			(xy 52.36049 -140.300787) (xy 52.312098 -140.329366) (xy 52.260036 -140.350534) (xy 52.205432 -140.363833)
			(xy 52.149467 -140.368975) (xy 52.093353 -140.365848) (xy 52.038306 -140.354521) (xy 51.985517 -140.335239)
			(xy 51.936129 -140.308418) (xy 51.891212 -140.27464) (xy 51.871118 -140.25499) (xy 51.859057 -140.243597)
			(xy 51.830439 -140.226836) (xy 51.79847 -140.218015) (xy 51.765306 -140.217729) (xy 51.733189 -140.225999)
			(xy 51.704288 -140.242266) (xy 51.692048 -140.253466) (xy 51.671775 -140.272669) (xy 51.626478 -140.305324)
			(xy 51.576812 -140.330849) (xy 51.523891 -140.348669) (xy 51.468902 -140.358386) (xy 51.413078 -140.359781)
			(xy 51.357672 -140.352823) (xy 51.303927 -140.337669) (xy 51.278282 -140.326618) (xy 51.257898 -140.317937)
			(xy 51.214971 -140.306991) (xy 51.170797 -140.303656) (xy 51.126713 -140.308033) (xy 51.084056 -140.319989)
			(xy 51.04412 -140.339162) (xy 51.008114 -140.364971) (xy 50.992278 -140.380466) (xy 50.973037 -140.399544)
			(xy 50.929921 -140.432367) (xy 50.882506 -140.458597) (xy 50.831791 -140.477682) (xy 50.778847 -140.489219)
			(xy 50.72479 -140.492964) (xy 50.67076 -140.488839) (xy 50.617898 -140.476931) (xy 50.567318 -140.45749)
			(xy 50.520088 -140.430927) (xy 50.477205 -140.397803) (xy 50.439572 -140.358815) (xy 50.407985 -140.314788)
			(xy 50.383108 -140.266648) (xy 50.365467 -140.215413) (xy 50.355435 -140.162163) (xy 50.353223 -140.108021)
			(xy 45.40165 -140.108021) (xy 45.395984 -140.133802) (xy 45.396581 -140.163835) (xy 45.404193 -140.192894)
			(xy 45.418395 -140.219364) (xy 45.438399 -140.241773) (xy 45.450506 -140.250672) (xy 45.473112 -140.26769)
			(xy 45.490203 -140.280953) (xy 45.527957 -140.302072) (xy 45.56874 -140.316499) (xy 45.611375 -140.323818)
			(xy 45.654635 -140.323818) (xy 45.69727 -140.316499) (xy 45.738053 -140.302072) (xy 45.775807 -140.280953)
			(xy 45.792898 -140.26769) (xy 45.813607 -140.251466) (xy 45.858641 -140.224272) (xy 45.906986 -140.203527)
			(xy 45.957723 -140.189625) (xy 46.00989 -140.18283) (xy 46.062496 -140.183271) (xy 46.114542 -140.19094)
			(xy 46.165039 -140.205691) (xy 46.213029 -140.227243) (xy 46.257601 -140.255189) (xy 46.278038 -140.271754)
			(xy 46.295111 -140.285376) (xy 46.332904 -140.307257) (xy 46.373881 -140.322357) (xy 46.416836 -140.330232)
			(xy 46.460504 -140.330651) (xy 46.503602 -140.3236) (xy 46.54486 -140.309288) (xy 46.583066 -140.288135)
			(xy 46.600364 -140.274802) (xy 46.62179 -140.258278) (xy 46.668401 -140.23081) (xy 46.718495 -140.210372)
			(xy 46.771019 -140.197396) (xy 46.824867 -140.192153) (xy 46.878907 -140.194754) (xy 46.932003 -140.205144)
			(xy 46.983038 -140.223105) (xy 47.030938 -140.248259) (xy 47.074696 -140.280076) (xy 47.113391 -140.317889)
			(xy 47.146211 -140.360901) (xy 47.172464 -140.408207) (xy 47.191598 -140.458814) (xy 47.203211 -140.511655)
			(xy 47.207059 -140.565621) (xy 47.20306 -140.619576) (xy 47.191299 -140.672385) (xy 47.172024 -140.722938)
			(xy 47.145639 -140.770171) (xy 47.112699 -140.813091) (xy 47.073898 -140.850795) (xy 47.030052 -140.882491)
			(xy 46.982082 -140.90751) (xy 46.930997 -140.925329) (xy 46.877872 -140.93557) (xy 46.823825 -140.93802)
			(xy 46.769991 -140.932627) (xy 46.717504 -140.919503) (xy 46.667467 -140.898926) (xy 46.620933 -140.871328)
			(xy 46.599602 -140.854684) (xy 46.582345 -140.841285) (xy 46.544177 -140.82003) (xy 46.502934 -140.805622)
			(xy 46.459834 -140.798486) (xy 46.416148 -140.798832) (xy 46.373167 -140.806651) (xy 46.332157 -140.821711)
			(xy 46.294331 -140.843569) (xy 46.277276 -140.857224) (xy 46.256847 -140.873722) (xy 46.212285 -140.901499)
			(xy 46.164333 -140.922898) (xy 46.113898 -140.937514) (xy 46.061935 -140.945072) (xy 46.009426 -140.945428)
			(xy 45.957365 -140.938575) (xy 45.906737 -140.924643) (xy 45.858499 -140.903896) (xy 45.813565 -140.876725)
			(xy 45.792898 -140.860526) (xy 45.775821 -140.84723) (xy 45.73808 -140.826052) (xy 45.697293 -140.811583)
			(xy 45.654643 -140.804242) (xy 45.611367 -140.804242) (xy 45.568717 -140.811583) (xy 45.52793 -140.826052)
			(xy 45.490189 -140.84723) (xy 45.473112 -140.860526) (xy 45.451717 -140.877267) (xy 45.40508 -140.905127)
			(xy 45.354962 -140.926089) (xy 45.302377 -140.93973) (xy 45.248389 -140.945773) (xy 45.19409 -140.944096)
			(xy 45.140578 -140.934733) (xy 45.088935 -140.917874) (xy 45.040206 -140.89386) (xy 44.995376 -140.863175)
			(xy 44.955353 -140.826442) (xy 44.920945 -140.784402) (xy 44.892849 -140.737906) (xy 44.871633 -140.687895)
			(xy 44.857727 -140.63538) (xy 44.85141 -140.581424) (xy 42.767423 -140.581424) (xy 42.753501 -140.610332)
			(xy 42.723477 -140.654369) (xy 42.687225 -140.69344) (xy 42.645554 -140.726671) (xy 42.599396 -140.75332)
			(xy 42.549782 -140.772792) (xy 42.49782 -140.784652) (xy 42.44467 -140.788636) (xy 42.39152 -140.784652)
			(xy 42.339558 -140.772792) (xy 42.289944 -140.75332) (xy 42.243786 -140.726671) (xy 42.202115 -140.69344)
			(xy 42.165863 -140.654369) (xy 42.135839 -140.610332) (xy 42.112713 -140.562311) (xy 42.097003 -140.511381)
			(xy 42.08906 -140.458677) (xy 41.585548 -140.458677) (xy 41.593288 -140.485779) (xy 41.600447 -140.540653)
			(xy 41.599409 -140.595981) (xy 41.590198 -140.650547) (xy 41.573017 -140.703151) (xy 41.548244 -140.752634)
			(xy 41.516423 -140.797909) (xy 41.478256 -140.837978) (xy 41.434581 -140.871961) (xy 41.38636 -140.899109)
			(xy 41.334653 -140.918826) (xy 41.280599 -140.930677) (xy 41.225386 -140.934402) (xy 41.17023 -140.929918)
			(xy 41.116343 -140.917325) (xy 41.064913 -140.8969) (xy 41.017069 -140.869091) (xy 40.973865 -140.834511)
			(xy 40.936252 -140.793921) (xy 40.905057 -140.748214) (xy 40.880966 -140.698394) (xy 40.86451 -140.64556)
			(xy 40.85605 -140.590872) (xy 40.855773 -140.535534) (xy 39.382419 -140.535534) (xy 39.358227 -140.538196)
			(xy 39.303792 -140.536206) (xy 39.250226 -140.526312) (xy 39.198672 -140.508724) (xy 39.150229 -140.483818)
			(xy 39.105927 -140.452123) (xy 39.066713 -140.414316) (xy 39.033422 -140.371202) (xy 39.006762 -140.3237)
			(xy 38.987303 -140.272823) (xy 38.97546 -140.219654) (xy 38.971484 -140.165328) (xy 37.148262 -140.165328)
			(xy 38.530276 -141.547342) (xy 41.339768 -141.547342) (xy 41.343839 -141.49172) (xy 41.355965 -141.437283)
			(xy 41.375888 -141.385192) (xy 41.403184 -141.336557) (xy 41.43727 -141.292414) (xy 41.477419 -141.253705)
			(xy 41.522777 -141.221254) (xy 41.572377 -141.195753) (xy 41.625161 -141.177746) (xy 41.680004 -141.167616)
			(xy 41.735738 -141.165579) (xy 41.791175 -141.171679) (xy 41.845132 -141.185785) (xy 41.896461 -141.207597)
			(xy 41.944067 -141.236651) (xy 41.986935 -141.272326) (xy 42.024152 -141.313863) (xy 42.054925 -141.360376)
			(xy 42.078597 -141.410873) (xy 42.090769 -141.45133) (xy 47.476166 -141.45133) (xy 47.480142 -141.397004)
			(xy 47.491985 -141.343835) (xy 47.511444 -141.292958) (xy 47.538104 -141.245456) (xy 47.571395 -141.202342)
			(xy 47.610609 -141.164535) (xy 47.654911 -141.13284) (xy 47.703354 -141.107934) (xy 47.754908 -141.090346)
			(xy 47.808474 -141.080452) (xy 47.862909 -141.078462) (xy 47.917054 -141.08442) (xy 47.969754 -141.098198)
			(xy 48.019887 -141.119502) (xy 48.066383 -141.147878) (xy 48.108253 -141.182722) (xy 48.144602 -141.223291)
			(xy 48.174658 -141.26872) (xy 48.197779 -141.318041) (xy 48.213472 -141.370203) (xy 48.221403 -141.424094)
			(xy 48.2219 -141.45133) (xy 48.221403 -141.478566) (xy 48.213472 -141.532457) (xy 48.197779 -141.584619)
			(xy 48.174658 -141.63394) (xy 48.144602 -141.679369) (xy 48.108253 -141.719938) (xy 48.066383 -141.754782)
			(xy 48.019887 -141.783158) (xy 47.969754 -141.804462) (xy 47.917054 -141.81824) (xy 47.862909 -141.824198)
			(xy 47.808474 -141.822208) (xy 47.754908 -141.812314) (xy 47.703354 -141.794726) (xy 47.654911 -141.76982)
			(xy 47.610609 -141.738125) (xy 47.571395 -141.700318) (xy 47.538104 -141.657204) (xy 47.511444 -141.609702)
			(xy 47.491985 -141.558825) (xy 47.480142 -141.505656) (xy 47.476166 -141.45133) (xy 42.090769 -141.45133)
			(xy 42.094665 -141.46428) (xy 42.102785 -141.519456) (xy 42.103294 -141.547342) (xy 42.102785 -141.575228)
			(xy 42.094665 -141.630404) (xy 42.078597 -141.683811) (xy 42.054925 -141.734308) (xy 42.024152 -141.780821)
			(xy 41.986935 -141.822358) (xy 41.944067 -141.858033) (xy 41.896461 -141.887087) (xy 41.845132 -141.908899)
			(xy 41.791175 -141.923005) (xy 41.735738 -141.929105) (xy 41.680004 -141.927068) (xy 41.625161 -141.916938)
			(xy 41.572377 -141.898931) (xy 41.522777 -141.87343) (xy 41.477419 -141.840979) (xy 41.43727 -141.80227)
			(xy 41.403184 -141.758127) (xy 41.375888 -141.709492) (xy 41.355965 -141.657401) (xy 41.343839 -141.602964)
			(xy 41.339768 -141.547342) (xy 38.530276 -141.547342) (xy 39.155878 -142.172944) (xy 39.228522 -142.188692)
			(xy 39.263828 -142.175738) (xy 39.264082 -142.175738) (xy 39.28979 -142.166619) (xy 39.343082 -142.154984)
			(xy 39.397487 -142.151059) (xy 39.451897 -142.154923) (xy 39.505201 -142.166499) (xy 39.556313 -142.185551)
			(xy 39.60419 -142.211688) (xy 39.647855 -142.24438) (xy 39.686418 -142.282958) (xy 39.719092 -142.326636)
			(xy 39.745211 -142.374522) (xy 39.764243 -142.425642) (xy 39.775798 -142.478951) (xy 39.779641 -142.533362)
			(xy 39.775695 -142.587766) (xy 39.764038 -142.641053) (xy 39.75481 -142.66672) (xy 39.750095 -142.680487)
			(xy 39.746356 -142.709339) (xy 39.749251 -142.738288) (xy 39.758631 -142.765828) (xy 39.774008 -142.790526)
			(xy 39.78402 -142.801086) (xy 39.841678 -142.858744) (xy 42.503344 -142.858744) (xy 42.520633 -142.858159)
			(xy 42.553939 -142.848866) (xy 42.583528 -142.830976) (xy 42.60723 -142.805799) (xy 42.623305 -142.775185)
			(xy 42.62755 -142.758414) (xy 42.633379 -142.73339) (xy 42.650866 -142.685077) (xy 42.674684 -142.639552)
			(xy 42.704404 -142.597639) (xy 42.739484 -142.560098) (xy 42.759122 -142.54353) (xy 42.776872 -142.528392)
			(xy 42.80705 -142.492825) (xy 42.830223 -142.452344) (xy 42.845611 -142.408311) (xy 42.852696 -142.362207)
			(xy 42.85124 -142.315586) (xy 42.841292 -142.270014) (xy 42.823186 -142.227027) (xy 42.797532 -142.18807)
			(xy 42.781728 -142.170912) (xy 42.763743 -142.151475) (xy 42.733134 -142.108264) (xy 42.709259 -142.060997)
			(xy 42.692644 -142.010717) (xy 42.683657 -141.958531) (xy 42.682494 -141.90559) (xy 42.689182 -141.85306)
			(xy 42.703573 -141.802098) (xy 42.72535 -141.753829) (xy 42.754032 -141.709316) (xy 42.788989 -141.66954)
			(xy 42.829449 -141.635377) (xy 42.874521 -141.60758) (xy 42.923212 -141.586762) (xy 42.974447 -141.573382)
			(xy 43.027099 -141.567735) (xy 43.080007 -141.569944) (xy 43.132005 -141.579962) (xy 43.181947 -141.597568)
			(xy 43.228732 -141.622373) (xy 43.271329 -141.653831) (xy 43.3088 -141.691249) (xy 43.340318 -141.733802)
			(xy 43.365189 -141.780552) (xy 43.382866 -141.830469) (xy 43.392957 -141.882452) (xy 43.395241 -141.935357)
			(xy 43.389668 -141.988017) (xy 43.376361 -142.039272) (xy 43.355612 -142.087992) (xy 43.327879 -142.133103)
			(xy 43.293773 -142.173611) (xy 43.274234 -142.191486) (xy 43.257101 -142.207291) (xy 43.228347 -142.243972)
			(xy 43.206764 -142.285282) (xy 43.193075 -142.329834) (xy 43.187739 -142.376135) (xy 43.190936 -142.422633)
			(xy 43.202558 -142.467769) (xy 43.222215 -142.510029) (xy 43.249249 -142.547996) (xy 43.265598 -142.564612)
			(xy 43.27486 -142.573675) (xy 43.292274 -142.592869) (xy 43.300396 -142.602966) (xy 43.314875 -142.620565)
			(xy 43.34897 -142.650795) (xy 43.38791 -142.674461) (xy 43.430446 -142.690805) (xy 43.475214 -142.699302)
			(xy 43.520779 -142.69968) (xy 43.565682 -142.691927) (xy 43.608483 -142.676292) (xy 43.64781 -142.653275)
			(xy 43.665394 -142.63878) (xy 43.686689 -142.621156) (xy 43.733396 -142.591594) (xy 43.783881 -142.569082)
			(xy 43.837085 -142.554092) (xy 43.891897 -142.546938) (xy 43.947166 -142.54777) (xy 44.001738 -142.556569)
			(xy 44.054467 -142.573153) (xy 44.104252 -142.597173) (xy 44.150048 -142.628127) (xy 44.190897 -142.665367)
			(xy 44.225944 -142.708112) (xy 44.254455 -142.755468) (xy 44.265596 -142.780766) (xy 44.271748 -142.794371)
			(xy 44.289376 -142.818461) (xy 44.312121 -142.837795) (xy 44.338736 -142.851313) (xy 44.367765 -142.858276)
			(xy 44.38269 -142.858744) (xy 44.48556 -142.858744) (xy 45.691044 -144.064228) (xy 45.691044 -144.072864)
			(xy 45.738288 -144.139158) (xy 45.77715 -144.152366) (xy 45.801726 -144.161202) (xy 45.848394 -144.184648)
			(xy 45.891426 -144.214242) (xy 45.930018 -144.249429) (xy 45.947076 -144.269206) (xy 45.985176 -144.314926)
			(xy 46.011084 -144.314926) (xy 46.12132 -144.425162) (xy 46.55058 -144.425162) (xy 48.534066 -142.441676)
			(xy 56.373776 -142.441676) (xy 56.474614 -142.390622) (xy 56.491378 -142.370302) (xy 56.50961 -142.349222)
			(xy 56.551144 -142.31206) (xy 56.597642 -142.281334) (xy 56.648115 -142.257699) (xy 56.701488 -142.241658)
			(xy 56.756628 -142.233551) (xy 56.81236 -142.233551) (xy 56.8675 -142.241658) (xy 56.920873 -142.257699)
			(xy 56.971346 -142.281334) (xy 57.017844 -142.31206) (xy 57.059378 -142.349222) (xy 57.07761 -142.370302)
			(xy 57.094374 -142.390622) (xy 57.195212 -142.441676) (xy 59.232546 -142.441676) (xy 61.453268 -140.220954)
			(xy 61.456824 -140.21689) (xy 61.457332 -140.216382) (xy 61.471813 -140.199838) (xy 61.504029 -140.169916)
			(xy 61.521594 -140.156692) (xy 61.528452 -140.151866) (xy 61.544454 -140.141198) (xy 61.572648 -140.123926)
			(xy 61.604652 -140.066522) (xy 61.604652 -140.033248) (xy 62.094364 -139.543282) (xy 62.094364 -131.998466)
			(xy 61.333888 -131.23799) (xy 60.74537 -131.23799) (xy 60.721996 -131.238515) (xy 60.676035 -131.247055)
			(xy 60.632412 -131.263858) (xy 60.592599 -131.288358) (xy 60.557941 -131.319728) (xy 60.529605 -131.356909)
			(xy 60.50855 -131.398646) (xy 60.495486 -131.443531) (xy 60.490853 -131.490048) (xy 60.494808 -131.536628)
			(xy 60.500514 -131.5593) (xy 60.506896 -131.584092) (xy 60.513589 -131.634846) (xy 60.513267 -131.686039)
			(xy 60.505934 -131.736705) (xy 60.49173 -131.785889) (xy 60.470922 -131.832663) (xy 60.443903 -131.876146)
			(xy 60.42787 -131.896104) (xy 60.414198 -131.913327) (xy 60.392381 -131.951504) (xy 60.377462 -131.992867)
			(xy 60.369887 -132.036181) (xy 60.369881 -132.080152) (xy 60.377445 -132.123467) (xy 60.392353 -132.164834)
			(xy 60.414159 -132.203017) (xy 60.42787 -132.220208) (xy 60.445791 -132.242631) (xy 60.475242 -132.291899)
			(xy 60.49679 -132.3451) (xy 60.509925 -132.400975) (xy 60.514338 -132.458205) (xy 60.509924 -132.515434)
			(xy 60.496787 -132.571309) (xy 60.475238 -132.62451) (xy 60.445786 -132.673777) (xy 60.42787 -132.696204)
			(xy 60.414198 -132.713427) (xy 60.392381 -132.751604) (xy 60.377462 -132.792967) (xy 60.369887 -132.836281)
			(xy 60.369881 -132.880252) (xy 60.377445 -132.923567) (xy 60.392353 -132.964934) (xy 60.414159 -133.003117)
			(xy 60.42787 -133.020308) (xy 60.42914 -133.021832) (xy 60.439046 -133.034532) (xy 60.456826 -133.058662)
			(xy 60.51042 -133.08584) (xy 60.570872 -133.086094) (xy 60.624466 -133.059424) (xy 60.642754 -133.03504)
			(xy 60.659449 -133.013495) (xy 60.69809 -132.975057) (xy 60.74192 -132.942659) (xy 60.790001 -132.916992)
			(xy 60.841309 -132.898604) (xy 60.894749 -132.887887) (xy 60.94918 -132.88507) (xy 61.00344 -132.890212)
			(xy 61.056372 -132.903205) (xy 61.106847 -132.92377) (xy 61.153787 -132.95147) (xy 61.196191 -132.985713)
			(xy 61.233154 -133.025768) (xy 61.263887 -133.07078) (xy 61.287734 -133.11979) (xy 61.304187 -133.171751)
			(xy 61.312894 -133.225555) (xy 61.313669 -133.280053) (xy 61.306497 -133.334082) (xy 61.29153 -133.386491)
			(xy 61.269088 -133.436159) (xy 61.239648 -133.482028) (xy 61.222128 -133.502908) (xy 61.207942 -133.522143)
			(xy 61.186289 -133.564745) (xy 61.172986 -133.610645) (xy 61.168502 -133.658223) (xy 61.172995 -133.7058)
			(xy 61.186306 -133.751698) (xy 61.207966 -133.794296) (xy 61.222128 -133.81355) (xy 61.240124 -133.835002)
			(xy 61.270141 -133.882268) (xy 61.292752 -133.933492) (xy 61.307447 -133.987521) (xy 61.313895 -134.043141)
			(xy 61.311952 -134.099099) (xy 61.30166 -134.154138) (xy 61.283253 -134.207018) (xy 61.257143 -134.256549)
			(xy 61.223918 -134.301619) (xy 61.184326 -134.341212) (xy 61.139258 -134.374438) (xy 61.089727 -134.400549)
			(xy 61.036847 -134.418958) (xy 60.981809 -134.42925) (xy 60.925851 -134.431195) (xy 60.870231 -134.424749)
			(xy 60.816201 -134.410055) (xy 60.764976 -134.387446) (xy 60.71771 -134.357429) (xy 60.696348 -134.33933)
			(xy 60.677053 -134.325114) (xy 60.634319 -134.30343) (xy 60.588279 -134.290139) (xy 60.540564 -134.285711)
			(xy 60.492864 -134.290303) (xy 60.446869 -134.303752) (xy 60.40421 -134.325581) (xy 60.384944 -134.339838)
			(xy 60.36203 -134.358897) (xy 60.31134 -134.390239) (xy 60.256314 -134.413128) (xy 60.227464 -134.42061)
			(xy 60.202668 -134.426095) (xy 60.152129 -134.431079) (xy 60.101382 -134.429147) (xy 60.051368 -134.420336)
			(xy 60.027058 -134.41299) (xy 60.004585 -134.405383) (xy 59.961625 -134.385248) (xy 59.92158 -134.359804)
			(xy 59.903106 -134.344918) (xy 59.885882 -134.331252) (xy 59.847705 -134.309447) (xy 59.806345 -134.294539)
			(xy 59.763036 -134.286971) (xy 59.719072 -134.286971) (xy 59.675763 -134.294539) (xy 59.634403 -134.309447)
			(xy 59.596226 -134.331252) (xy 59.579002 -134.344918) (xy 59.556579 -134.36284) (xy 59.507311 -134.392292)
			(xy 59.45411 -134.413841) (xy 59.398234 -134.426977) (xy 59.341004 -134.431391) (xy 59.283774 -134.426977)
			(xy 59.227898 -134.413841) (xy 59.174697 -134.392292) (xy 59.125429 -134.36284) (xy 59.103006 -134.344918)
			(xy 59.085782 -134.331252) (xy 59.047605 -134.309447) (xy 59.006245 -134.294539) (xy 58.962936 -134.286971)
			(xy 58.918972 -134.286971) (xy 58.875663 -134.294539) (xy 58.834303 -134.309447) (xy 58.796126 -134.331252)
			(xy 58.778902 -134.344918) (xy 58.756982 -134.362452) (xy 58.708896 -134.391407) (xy 58.683144 -134.402576)
			(xy 58.657338 -134.412686) (xy 58.603545 -134.426023) (xy 58.54837 -134.431244) (xy 58.49303 -134.428236)
			(xy 58.438747 -134.417063) (xy 58.386717 -134.397972) (xy 58.338088 -134.371386) (xy 58.293935 -134.337889)
			(xy 58.25523 -134.298222) (xy 58.222828 -134.253259) (xy 58.197444 -134.203993) (xy 58.179637 -134.151509)
			(xy 58.1698 -134.096968) (xy 58.168152 -134.041571) (xy 58.174727 -133.98654) (xy 58.189381 -133.933091)
			(xy 58.211791 -133.882402) (xy 58.241461 -133.835592) (xy 58.259218 -133.814312) (xy 58.273516 -133.794997)
			(xy 58.295348 -133.752195) (xy 58.308767 -133.706058) (xy 58.313297 -133.658223) (xy 58.308776 -133.610387)
			(xy 58.295365 -133.564248) (xy 58.27354 -133.521442) (xy 58.259218 -133.502146) (xy 58.240161 -133.479231)
			(xy 58.208822 -133.42854) (xy 58.185935 -133.373513) (xy 58.178446 -133.344666) (xy 58.17296 -133.31987)
			(xy 58.167975 -133.269331) (xy 58.169907 -133.218584) (xy 58.178719 -133.16857) (xy 58.186066 -133.14426)
			(xy 58.193672 -133.121787) (xy 58.213805 -133.078825) (xy 58.239247 -133.038778) (xy 58.254138 -133.020308)
			(xy 58.267802 -133.003085) (xy 58.289603 -132.96491) (xy 58.304507 -132.923553) (xy 58.312069 -132.880247)
			(xy 58.312063 -132.836286) (xy 58.30449 -132.792982) (xy 58.289575 -132.751628) (xy 58.267764 -132.71346)
			(xy 58.254138 -132.696204) (xy 58.236216 -132.673781) (xy 58.206763 -132.624513) (xy 58.185212 -132.571312)
			(xy 58.172075 -132.515435) (xy 58.16766 -132.458205) (xy 58.172073 -132.400974) (xy 58.18521 -132.345097)
			(xy 58.206758 -132.291895) (xy 58.23621 -132.242626) (xy 58.254138 -132.220208) (xy 58.267802 -132.202985)
			(xy 58.289603 -132.16481) (xy 58.304507 -132.123453) (xy 58.312069 -132.080147) (xy 58.312063 -132.036186)
			(xy 58.30449 -131.992882) (xy 58.289575 -131.951528) (xy 58.267764 -131.91336) (xy 58.254138 -131.896104)
			(xy 58.238119 -131.876137) (xy 58.211124 -131.832644) (xy 58.19033 -131.785868) (xy 58.176127 -131.736688)
			(xy 58.168783 -131.686028) (xy 58.168435 -131.634839) (xy 58.17509 -131.584084) (xy 58.181494 -131.5593)
			(xy 58.187174 -131.536627) (xy 58.19111 -131.490057) (xy 58.186464 -131.443553) (xy 58.173393 -131.398682)
			(xy 58.152338 -131.356958) (xy 58.124008 -131.319787) (xy 58.08936 -131.288423) (xy 58.04956 -131.263923)
			(xy 58.005952 -131.247114) (xy 57.960006 -131.238561) (xy 57.936638 -131.23799) (xy 55.73522 -131.23799)
			(xy 55.720699 -131.238395) (xy 55.692411 -131.244978) (xy 55.666344 -131.257786) (xy 55.643847 -131.276154)
			(xy 55.626085 -131.299133) (xy 55.61965 -131.312158) (xy 55.607517 -131.337497) (xy 55.576921 -131.384613)
			(xy 55.539747 -131.426734) (xy 55.4968 -131.46295) (xy 55.449006 -131.492477) (xy 55.3974 -131.514678)
			(xy 55.343097 -131.529073) (xy 55.287269 -131.53535) (xy 55.231125 -131.533374) (xy 55.175877 -131.523188)
			(xy 55.12272 -131.505012) (xy 55.072802 -131.479238) (xy 55.049674 -131.463288) (xy 55.030236 -131.451068)
			(xy 54.987987 -131.433106) (xy 54.943198 -131.42303) (xy 54.897327 -131.42117) (xy 54.851869 -131.427587)
			(xy 54.808304 -131.44207) (xy 54.768053 -131.464148) (xy 54.749954 -131.478274) (xy 54.731038 -131.493155)
			(xy 54.690082 -131.518433) (xy 54.646207 -131.538218) (xy 54.600147 -131.552178) (xy 54.576472 -131.556506)
			(xy 54.552013 -131.560203) (xy 54.502573 -131.561855) (xy 54.47792 -131.559808) (xy 54.452712 -131.556861)
			(xy 54.403366 -131.545002) (xy 54.356092 -131.526541) (xy 54.311769 -131.501819) (xy 54.29123 -131.48691)
			(xy 54.271736 -131.474423) (xy 54.229278 -131.455985) (xy 54.184183 -131.445538) (xy 54.137942 -131.443427)
			(xy 54.092083 -131.449723) (xy 54.048121 -131.464216) (xy 54.00751 -131.486429) (xy 53.989224 -131.500626)
			(xy 53.979134 -131.508675) (xy 53.958034 -131.523548) (xy 53.94706 -131.530344) (xy 53.91277 -131.548886)
			(xy 53.888248 -131.560057) (xy 53.836824 -131.576161) (xy 53.783646 -131.584866) (xy 53.729772 -131.585999)
			(xy 53.676275 -131.579537) (xy 53.62422 -131.56561) (xy 53.574643 -131.544494) (xy 53.528533 -131.51661)
			(xy 53.486807 -131.482512) (xy 53.450295 -131.442881) (xy 53.419726 -131.398506) (xy 53.395707 -131.350269)
			(xy 53.386736 -131.324858) (xy 53.381239 -131.309926) (xy 53.364027 -131.283176) (xy 53.340736 -131.261511)
			(xy 53.312813 -131.246276) (xy 53.281991 -131.238416) (xy 53.266086 -131.23799) (xy 53.143912 -131.23799)
			(xy 48.566832 -126.66091) (xy 48.566832 -124.188982) (xy 49.417732 -123.338082) (xy 49.814226 -123.338082)
			(xy 50.077878 -123.07443) (xy 53.268118 -123.07443) (xy 53.53177 -123.338082) (xy 54.004972 -123.338082)
			(xy 54.553866 -123.886976) (xy 54.601364 -123.890024) (xy 54.616537 -123.890606) (xy 54.646451 -123.885448)
			(xy 54.674308 -123.87339) (xy 54.686708 -123.864624) (xy 54.710033 -123.847612) (xy 54.760771 -123.820072)
			(xy 54.81508 -123.800494) (xy 54.871719 -123.789323) (xy 54.929395 -123.786816) (xy 54.98679 -123.793029)
			(xy 55.042593 -123.807821) (xy 55.09553 -123.830853) (xy 55.144391 -123.8616) (xy 55.18806 -123.899359)
			(xy 55.207154 -123.921012) (xy 55.219512 -123.934544) (xy 55.250236 -123.95449) (xy 55.285359 -123.964895)
			(xy 55.303674 -123.965462) (xy 55.511192 -123.965462) (xy 55.537608 -123.952762) (xy 55.563737 -123.940632)
			(xy 55.618735 -123.923501) (xy 55.675684 -123.914838) (xy 55.733288 -123.914838) (xy 55.790237 -123.923501)
			(xy 55.845235 -123.940632) (xy 55.871364 -123.952762) (xy 55.89778 -123.965462) (xy 56.247792 -123.965462)
			(xy 56.274208 -123.952762) (xy 56.300337 -123.940632) (xy 56.355335 -123.923501) (xy 56.412284 -123.914838)
			(xy 56.469888 -123.914838) (xy 56.526837 -123.923501) (xy 56.581835 -123.940632) (xy 56.607964 -123.952762)
			(xy 56.63438 -123.965462) (xy 66.822828 -123.965462) (xy 67.418458 -124.561092) (xy 67.435475 -124.577393)
			(xy 67.474355 -124.604011) (xy 67.517478 -124.623001) (xy 67.563363 -124.633713) (xy 67.610436 -124.635778)
			(xy 67.657083 -124.629125) (xy 67.701702 -124.613984) (xy 67.742764 -124.590873) (xy 67.761104 -124.576078)
			(xy 67.782048 -124.559123) (xy 67.827801 -124.530658) (xy 67.877104 -124.508914) (xy 67.928977 -124.494324)
			(xy 67.982386 -124.48718) (xy 68.036269 -124.487622) (xy 68.089554 -124.495643) (xy 68.14118 -124.511082)
			(xy 68.19012 -124.533632) (xy 68.235399 -124.562845) (xy 68.276117 -124.598139) (xy 68.311463 -124.638812)
			(xy 68.326508 -124.661168) (xy 68.335517 -124.674226) (xy 68.358759 -124.695802) (xy 68.386604 -124.710982)
			(xy 68.417332 -124.718829) (xy 68.433188 -124.719334) (xy 72.79894 -124.719334) (xy 72.806052 -124.712222)
			(xy 75.941428 -124.712222) (xy 75.963078 -124.711782) (xy 76.00575 -124.704438) (xy 76.046559 -124.689966)
			(xy 76.084325 -124.668785) (xy 76.117954 -124.64151) (xy 76.146473 -124.608928) (xy 76.169055 -124.571984)
			(xy 76.185049 -124.531747) (xy 76.19399 -124.48938) (xy 76.19562 -124.446111) (xy 76.189891 -124.403192)
			(xy 76.176971 -124.361866) (xy 76.167488 -124.342398) (xy 76.155189 -124.317275) (xy 76.137265 -124.264291)
			(xy 76.12727 -124.209257) (xy 76.125419 -124.153353) (xy 76.131752 -124.097778) (xy 76.146134 -124.043724)
			(xy 76.168254 -123.99235) (xy 76.197641 -123.944757) (xy 76.233662 -123.901965) (xy 76.275546 -123.864893)
			(xy 76.322396 -123.834335) (xy 76.373205 -123.810946) (xy 76.426886 -123.795228) (xy 76.482286 -123.787518)
			(xy 76.538219 -123.78798) (xy 76.593484 -123.796606) (xy 76.646897 -123.813211) (xy 76.697312 -123.837437)
			(xy 76.743649 -123.868767) (xy 76.784915 -123.906527) (xy 76.802996 -123.92787) (xy 76.814513 -123.941134)
			(xy 76.84326 -123.961299) (xy 76.876414 -123.972869) (xy 76.911465 -123.974968) (xy 76.945763 -123.967439)
			(xy 76.961492 -123.95962) (xy 76.986128 -123.946943) (xy 77.038212 -123.92805) (xy 77.092481 -123.91689)
			(xy 77.147793 -123.913697) (xy 77.202986 -123.918537) (xy 77.256898 -123.93131) (xy 77.308396 -123.951746)
			(xy 77.356397 -123.979416) (xy 77.39989 -124.013737) (xy 77.437962 -124.053989) (xy 77.469812 -124.099323)
			(xy 77.494769 -124.148788) (xy 77.51231 -124.201343) (xy 77.522065 -124.255882) (xy 77.523829 -124.311258)
			(xy 77.517564 -124.366307) (xy 77.510894 -124.393198) (xy 77.505445 -124.415813) (xy 77.501922 -124.462191)
			(xy 77.506898 -124.508436) (xy 77.515416 -124.536962) (xy 83.467192 -124.536962) (xy 83.471263 -124.48134)
			(xy 83.483389 -124.426903) (xy 83.503312 -124.374812) (xy 83.530608 -124.326177) (xy 83.564694 -124.282034)
			(xy 83.604843 -124.243325) (xy 83.650201 -124.210874) (xy 83.699801 -124.185373) (xy 83.752585 -124.167366)
			(xy 83.807428 -124.157236) (xy 83.863162 -124.155199) (xy 83.918599 -124.161299) (xy 83.972556 -124.175405)
			(xy 84.023885 -124.197217) (xy 84.071491 -124.226271) (xy 84.114359 -124.261946) (xy 84.151576 -124.303483)
			(xy 84.182349 -124.349996) (xy 84.206021 -124.400493) (xy 84.222089 -124.4539) (xy 84.230209 -124.509076)
			(xy 84.230718 -124.536962) (xy 84.230209 -124.564848) (xy 84.222089 -124.620024) (xy 84.206021 -124.673431)
			(xy 84.182349 -124.723928) (xy 84.151576 -124.770441) (xy 84.114359 -124.811978) (xy 84.071491 -124.847653)
			(xy 84.023885 -124.876707) (xy 83.972556 -124.898519) (xy 83.918599 -124.912625) (xy 83.863162 -124.918725)
			(xy 83.807428 -124.916688) (xy 83.752585 -124.906558) (xy 83.699801 -124.888551) (xy 83.650201 -124.86305)
			(xy 83.604843 -124.830599) (xy 83.564694 -124.79189) (xy 83.530608 -124.747747) (xy 83.503312 -124.699112)
			(xy 83.483389 -124.647021) (xy 83.471263 -124.592584) (xy 83.467192 -124.536962) (xy 77.515416 -124.536962)
			(xy 77.520206 -124.553003) (xy 77.541403 -124.594404) (xy 77.569781 -124.631256) (xy 77.604391 -124.662328)
			(xy 77.644078 -124.686583) (xy 77.687517 -124.703211) (xy 77.733256 -124.711655) (xy 77.756512 -124.712222)
			(xy 77.85354 -124.712222) (xy 79.06512 -125.923802) (xy 82.609942 -125.923802) (xy 82.614013 -125.86818)
			(xy 82.626139 -125.813743) (xy 82.646062 -125.761652) (xy 82.673358 -125.713017) (xy 82.707444 -125.668874)
			(xy 82.747593 -125.630165) (xy 82.792951 -125.597714) (xy 82.842551 -125.572213) (xy 82.895335 -125.554206)
			(xy 82.950178 -125.544076) (xy 83.005912 -125.542039) (xy 83.061349 -125.548139) (xy 83.115306 -125.562245)
			(xy 83.166635 -125.584057) (xy 83.214241 -125.613111) (xy 83.257109 -125.648786) (xy 83.294326 -125.690323)
			(xy 83.325099 -125.736836) (xy 83.348771 -125.787333) (xy 83.364839 -125.84074) (xy 83.372959 -125.895916)
			(xy 83.373468 -125.923802) (xy 83.372959 -125.951688) (xy 83.364839 -126.006864) (xy 83.348771 -126.060271)
			(xy 83.325099 -126.110768) (xy 83.294326 -126.157281) (xy 83.257109 -126.198818) (xy 83.214241 -126.234493)
			(xy 83.166635 -126.263547) (xy 83.115306 -126.285359) (xy 83.061349 -126.299465) (xy 83.005912 -126.305565)
			(xy 82.950178 -126.303528) (xy 82.895335 -126.293398) (xy 82.842551 -126.275391) (xy 82.792951 -126.24989)
			(xy 82.747593 -126.217439) (xy 82.707444 -126.17873) (xy 82.673358 -126.134587) (xy 82.646062 -126.085952)
			(xy 82.626139 -126.033861) (xy 82.614013 -125.979424) (xy 82.609942 -125.923802) (xy 79.06512 -125.923802)
			(xy 80.516222 -127.374904) (xy 80.516222 -127.522478) (xy 83.35467 -127.522478) (xy 83.358741 -127.466856)
			(xy 83.370867 -127.412419) (xy 83.39079 -127.360328) (xy 83.418086 -127.311693) (xy 83.452172 -127.26755)
			(xy 83.492321 -127.228841) (xy 83.537679 -127.19639) (xy 83.587279 -127.170889) (xy 83.640063 -127.152882)
			(xy 83.694906 -127.142752) (xy 83.75064 -127.140715) (xy 83.806077 -127.146815) (xy 83.860034 -127.160921)
			(xy 83.911363 -127.182733) (xy 83.958969 -127.211787) (xy 84.001837 -127.247462) (xy 84.039054 -127.288999)
			(xy 84.069827 -127.335512) (xy 84.093499 -127.386009) (xy 84.109567 -127.439416) (xy 84.117687 -127.494592)
			(xy 84.118196 -127.522478) (xy 84.117687 -127.550364) (xy 84.109567 -127.60554) (xy 84.093499 -127.658947)
			(xy 84.070075 -127.708914) (xy 84.74913 -127.708914) (xy 84.753201 -127.653292) (xy 84.765327 -127.598855)
			(xy 84.78525 -127.546764) (xy 84.812546 -127.498129) (xy 84.846632 -127.453986) (xy 84.886781 -127.415277)
			(xy 84.932139 -127.382826) (xy 84.981739 -127.357325) (xy 85.034523 -127.339318) (xy 85.089366 -127.329188)
			(xy 85.1451 -127.327151) (xy 85.200537 -127.333251) (xy 85.254494 -127.347357) (xy 85.305823 -127.369169)
			(xy 85.353429 -127.398223) (xy 85.396297 -127.433898) (xy 85.433514 -127.475435) (xy 85.464287 -127.521948)
			(xy 85.487959 -127.572445) (xy 85.504027 -127.625852) (xy 85.512147 -127.681028) (xy 85.512656 -127.708914)
			(xy 85.512147 -127.7368) (xy 85.504027 -127.791976) (xy 85.487959 -127.845383) (xy 85.464287 -127.89588)
			(xy 85.433514 -127.942393) (xy 85.426279 -127.950468) (xy 86.20709 -127.950468) (xy 86.211161 -127.894846)
			(xy 86.223287 -127.840409) (xy 86.24321 -127.788318) (xy 86.270506 -127.739683) (xy 86.304592 -127.69554)
			(xy 86.344741 -127.656831) (xy 86.390099 -127.62438) (xy 86.439699 -127.598879) (xy 86.492483 -127.580872)
			(xy 86.547326 -127.570742) (xy 86.60306 -127.568705) (xy 86.658497 -127.574805) (xy 86.712454 -127.588911)
			(xy 86.763783 -127.610723) (xy 86.811389 -127.639777) (xy 86.854257 -127.675452) (xy 86.891474 -127.716989)
			(xy 86.922247 -127.763502) (xy 86.945919 -127.813999) (xy 86.961987 -127.867406) (xy 86.970107 -127.922582)
			(xy 86.970616 -127.950468) (xy 86.970107 -127.978354) (xy 86.961987 -128.03353) (xy 86.945919 -128.086937)
			(xy 86.922247 -128.137434) (xy 86.891474 -128.183947) (xy 86.854257 -128.225484) (xy 86.811389 -128.261159)
			(xy 86.763783 -128.290213) (xy 86.712454 -128.312025) (xy 86.658497 -128.326131) (xy 86.60306 -128.332231)
			(xy 86.547326 -128.330194) (xy 86.492483 -128.320064) (xy 86.439699 -128.302057) (xy 86.390099 -128.276556)
			(xy 86.344741 -128.244105) (xy 86.304592 -128.205396) (xy 86.270506 -128.161253) (xy 86.24321 -128.112618)
			(xy 86.223287 -128.060527) (xy 86.211161 -128.00609) (xy 86.20709 -127.950468) (xy 85.426279 -127.950468)
			(xy 85.396297 -127.98393) (xy 85.353429 -128.019605) (xy 85.305823 -128.048659) (xy 85.254494 -128.070471)
			(xy 85.200537 -128.084577) (xy 85.1451 -128.090677) (xy 85.089366 -128.08864) (xy 85.034523 -128.07851)
			(xy 84.981739 -128.060503) (xy 84.932139 -128.035002) (xy 84.886781 -128.002551) (xy 84.846632 -127.963842)
			(xy 84.812546 -127.919699) (xy 84.78525 -127.871064) (xy 84.765327 -127.818973) (xy 84.753201 -127.764536)
			(xy 84.74913 -127.708914) (xy 84.070075 -127.708914) (xy 84.069827 -127.709444) (xy 84.039054 -127.755957)
			(xy 84.001837 -127.797494) (xy 83.958969 -127.833169) (xy 83.911363 -127.862223) (xy 83.860034 -127.884035)
			(xy 83.806077 -127.898141) (xy 83.75064 -127.904241) (xy 83.694906 -127.902204) (xy 83.640063 -127.892074)
			(xy 83.587279 -127.874067) (xy 83.537679 -127.848566) (xy 83.492321 -127.816115) (xy 83.452172 -127.777406)
			(xy 83.418086 -127.733263) (xy 83.39079 -127.684628) (xy 83.370867 -127.632537) (xy 83.358741 -127.5781)
			(xy 83.35467 -127.522478) (xy 80.516222 -127.522478) (xy 80.516222 -129.044954) (xy 81.32318 -129.851912)
			(xy 81.363312 -129.85877) (xy 81.389133 -129.863537) (xy 81.43924 -129.879226) (xy 81.486724 -129.901638)
			(xy 81.530685 -129.930349) (xy 81.570295 -129.964816) (xy 81.604805 -130.00439) (xy 81.633563 -130.048321)
			(xy 81.656025 -130.09578) (xy 81.671768 -130.145871) (xy 81.673798 -130.156966) (xy 86.36203 -130.156966)
			(xy 86.366101 -130.101344) (xy 86.378227 -130.046907) (xy 86.39815 -129.994816) (xy 86.425446 -129.946181)
			(xy 86.459532 -129.902038) (xy 86.499681 -129.863329) (xy 86.545039 -129.830878) (xy 86.594639 -129.805377)
			(xy 86.647423 -129.78737) (xy 86.702266 -129.77724) (xy 86.758 -129.775203) (xy 86.813437 -129.781303)
			(xy 86.867394 -129.795409) (xy 86.918723 -129.817221) (xy 86.966329 -129.846275) (xy 87.009197 -129.88195)
			(xy 87.046414 -129.923487) (xy 87.077187 -129.97) (xy 87.100859 -130.020497) (xy 87.116927 -130.073904)
			(xy 87.125047 -130.12908) (xy 87.125556 -130.156966) (xy 87.125047 -130.184852) (xy 87.116927 -130.240028)
			(xy 87.100859 -130.293435) (xy 87.077187 -130.343932) (xy 87.046414 -130.390445) (xy 87.009197 -130.431982)
			(xy 86.966329 -130.467657) (xy 86.918723 -130.496711) (xy 86.867394 -130.518523) (xy 86.813437 -130.532629)
			(xy 86.758 -130.538729) (xy 86.702266 -130.536692) (xy 86.647423 -130.526562) (xy 86.594639 -130.508555)
			(xy 86.545039 -130.483054) (xy 86.499681 -130.450603) (xy 86.459532 -130.411894) (xy 86.425446 -130.367751)
			(xy 86.39815 -130.319116) (xy 86.378227 -130.267025) (xy 86.366101 -130.212588) (xy 86.36203 -130.156966)
			(xy 81.673798 -130.156966) (xy 81.676494 -130.171698) (xy 81.676494 -130.171952) (xy 81.683352 -130.212084)
			(xy 82.658712 -131.187444) (xy 84.926422 -131.187444) (xy 84.930493 -131.131822) (xy 84.942619 -131.077385)
			(xy 84.962542 -131.025294) (xy 84.989838 -130.976659) (xy 85.023924 -130.932516) (xy 85.064073 -130.893807)
			(xy 85.109431 -130.861356) (xy 85.159031 -130.835855) (xy 85.211815 -130.817848) (xy 85.266658 -130.807718)
			(xy 85.322392 -130.805681) (xy 85.377829 -130.811781) (xy 85.431786 -130.825887) (xy 85.483115 -130.847699)
			(xy 85.530721 -130.876753) (xy 85.573589 -130.912428) (xy 85.610806 -130.953965) (xy 85.641579 -131.000478)
			(xy 85.665251 -131.050975) (xy 85.681319 -131.104382) (xy 85.689439 -131.159558) (xy 85.689948 -131.187444)
			(xy 85.689439 -131.21533) (xy 85.681319 -131.270506) (xy 85.665251 -131.323913) (xy 85.641579 -131.37441)
			(xy 85.610806 -131.420923) (xy 85.573589 -131.46246) (xy 85.530721 -131.498135) (xy 85.483115 -131.527189)
			(xy 85.431786 -131.549001) (xy 85.377829 -131.563107) (xy 85.322392 -131.569207) (xy 85.266658 -131.56717)
			(xy 85.211815 -131.55704) (xy 85.159031 -131.539033) (xy 85.109431 -131.513532) (xy 85.064073 -131.481081)
			(xy 85.023924 -131.442372) (xy 84.989838 -131.398229) (xy 84.962542 -131.349594) (xy 84.942619 -131.297503)
			(xy 84.930493 -131.243066) (xy 84.926422 -131.187444) (xy 82.658712 -131.187444) (xy 82.723736 -131.252468)
			(xy 82.736907 -131.264724) (xy 82.768442 -131.282009) (xy 82.803543 -131.289826) (xy 82.821526 -131.289298)
			(xy 82.822034 -131.289298) (xy 82.849023 -131.287984) (xy 82.902902 -131.292064) (xy 82.955667 -131.303706)
			(xy 83.00626 -131.322678) (xy 83.053669 -131.348601) (xy 83.096946 -131.380954) (xy 83.135224 -131.419091)
			(xy 83.167737 -131.462248) (xy 83.193833 -131.509562) (xy 83.212992 -131.560085) (xy 83.224828 -131.612806)
			(xy 83.229106 -131.66667) (xy 83.227926 -131.693666) (xy 83.227926 -131.69519) (xy 83.227672 -131.699508)
			(xy 83.227615 -131.716931) (xy 83.235895 -131.750762) (xy 83.253045 -131.781076) (xy 83.26501 -131.793742)
			(xy 84.17306 -132.701792) (xy 84.17306 -135.025892) (xy 84.964522 -135.025892) (xy 84.968593 -134.97027)
			(xy 84.980719 -134.915833) (xy 85.000642 -134.863742) (xy 85.027938 -134.815107) (xy 85.062024 -134.770964)
			(xy 85.102173 -134.732255) (xy 85.147531 -134.699804) (xy 85.197131 -134.674303) (xy 85.249915 -134.656296)
			(xy 85.304758 -134.646166) (xy 85.360492 -134.644129) (xy 85.415929 -134.650229) (xy 85.469886 -134.664335)
			(xy 85.521215 -134.686147) (xy 85.568821 -134.715201) (xy 85.611689 -134.750876) (xy 85.648906 -134.792413)
			(xy 85.679679 -134.838926) (xy 85.703351 -134.889423) (xy 85.719419 -134.94283) (xy 85.727539 -134.998006)
			(xy 85.728048 -135.025892) (xy 85.727539 -135.053778) (xy 85.724578 -135.073898) (xy 86.02421 -135.073898)
			(xy 86.028281 -135.018276) (xy 86.040407 -134.963839) (xy 86.06033 -134.911748) (xy 86.087626 -134.863113)
			(xy 86.121712 -134.81897) (xy 86.161861 -134.780261) (xy 86.207219 -134.74781) (xy 86.256819 -134.722309)
			(xy 86.309603 -134.704302) (xy 86.364446 -134.694172) (xy 86.42018 -134.692135) (xy 86.475617 -134.698235)
			(xy 86.529574 -134.712341) (xy 86.580903 -134.734153) (xy 86.628509 -134.763207) (xy 86.671377 -134.798882)
			(xy 86.708594 -134.840419) (xy 86.739367 -134.886932) (xy 86.763039 -134.937429) (xy 86.779107 -134.990836)
			(xy 86.787227 -135.046012) (xy 86.787736 -135.073898) (xy 86.787227 -135.101784) (xy 86.779107 -135.15696)
			(xy 86.763039 -135.210367) (xy 86.739367 -135.260864) (xy 86.708594 -135.307377) (xy 86.671377 -135.348914)
			(xy 86.628509 -135.384589) (xy 86.580903 -135.413643) (xy 86.529574 -135.435455) (xy 86.475617 -135.449561)
			(xy 86.42018 -135.455661) (xy 86.364446 -135.453624) (xy 86.309603 -135.443494) (xy 86.256819 -135.425487)
			(xy 86.207219 -135.399986) (xy 86.161861 -135.367535) (xy 86.121712 -135.328826) (xy 86.087626 -135.284683)
			(xy 86.06033 -135.236048) (xy 86.040407 -135.183957) (xy 86.028281 -135.12952) (xy 86.02421 -135.073898)
			(xy 85.724578 -135.073898) (xy 85.719419 -135.108954) (xy 85.703351 -135.162361) (xy 85.679679 -135.212858)
			(xy 85.648906 -135.259371) (xy 85.611689 -135.300908) (xy 85.568821 -135.336583) (xy 85.521215 -135.365637)
			(xy 85.469886 -135.387449) (xy 85.415929 -135.401555) (xy 85.360492 -135.407655) (xy 85.304758 -135.405618)
			(xy 85.249915 -135.395488) (xy 85.197131 -135.377481) (xy 85.147531 -135.35198) (xy 85.102173 -135.319529)
			(xy 85.062024 -135.28082) (xy 85.027938 -135.236677) (xy 85.000642 -135.188042) (xy 84.980719 -135.135951)
			(xy 84.968593 -135.081514) (xy 84.964522 -135.025892) (xy 84.17306 -135.025892) (xy 84.17306 -136.608312)
			(xy 86.234776 -136.608312) (xy 86.238847 -136.55269) (xy 86.250973 -136.498253) (xy 86.270896 -136.446162)
			(xy 86.298192 -136.397527) (xy 86.332278 -136.353384) (xy 86.372427 -136.314675) (xy 86.417785 -136.282224)
			(xy 86.467385 -136.256723) (xy 86.520169 -136.238716) (xy 86.575012 -136.228586) (xy 86.630746 -136.226549)
			(xy 86.686183 -136.232649) (xy 86.74014 -136.246755) (xy 86.791469 -136.268567) (xy 86.839075 -136.297621)
			(xy 86.881943 -136.333296) (xy 86.91916 -136.374833) (xy 86.949933 -136.421346) (xy 86.973605 -136.471843)
			(xy 86.989673 -136.52525) (xy 86.997793 -136.580426) (xy 86.998302 -136.608312) (xy 86.997793 -136.636198)
			(xy 86.989673 -136.691374) (xy 86.973605 -136.744781) (xy 86.949933 -136.795278) (xy 86.91916 -136.841791)
			(xy 86.881943 -136.883328) (xy 86.839075 -136.919003) (xy 86.791469 -136.948057) (xy 86.74014 -136.969869)
			(xy 86.686183 -136.983975) (xy 86.630746 -136.990075) (xy 86.575012 -136.988038) (xy 86.520169 -136.977908)
			(xy 86.467385 -136.959901) (xy 86.417785 -136.9344) (xy 86.372427 -136.901949) (xy 86.332278 -136.86324)
			(xy 86.298192 -136.819097) (xy 86.270896 -136.770462) (xy 86.250973 -136.718371) (xy 86.238847 -136.663934)
			(xy 86.234776 -136.608312) (xy 84.17306 -136.608312) (xy 84.17306 -137.56513) (xy 84.173526 -137.58741)
			(xy 84.181302 -137.631288) (xy 84.18832 -137.650474) (xy 86.061802 -137.650474) (xy 86.065873 -137.594852)
			(xy 86.077999 -137.540415) (xy 86.097922 -137.488324) (xy 86.125218 -137.439689) (xy 86.159304 -137.395546)
			(xy 86.199453 -137.356837) (xy 86.244811 -137.324386) (xy 86.294411 -137.298885) (xy 86.347195 -137.280878)
			(xy 86.402038 -137.270748) (xy 86.457772 -137.268711) (xy 86.513209 -137.274811) (xy 86.567166 -137.288917)
			(xy 86.618495 -137.310729) (xy 86.666101 -137.339783) (xy 86.708969 -137.375458) (xy 86.746186 -137.416995)
			(xy 86.776959 -137.463508) (xy 86.800631 -137.514005) (xy 86.816699 -137.567412) (xy 86.824819 -137.622588)
			(xy 86.825328 -137.650474) (xy 86.824819 -137.67836) (xy 86.816699 -137.733536) (xy 86.800631 -137.786943)
			(xy 86.776959 -137.83744) (xy 86.746186 -137.883953) (xy 86.708969 -137.92549) (xy 86.666101 -137.961165)
			(xy 86.618495 -137.990219) (xy 86.567166 -138.012031) (xy 86.513209 -138.026137) (xy 86.457772 -138.032237)
			(xy 86.402038 -138.0302) (xy 86.347195 -138.02007) (xy 86.294411 -138.002063) (xy 86.244811 -137.976562)
			(xy 86.199453 -137.944111) (xy 86.159304 -137.905402) (xy 86.125218 -137.861259) (xy 86.097922 -137.812624)
			(xy 86.077999 -137.760533) (xy 86.065873 -137.706096) (xy 86.061802 -137.650474) (xy 84.18832 -137.650474)
			(xy 84.19661 -137.673137) (xy 84.218982 -137.711675) (xy 84.247731 -137.745722) (xy 84.281977 -137.774233)
			(xy 84.32067 -137.796336) (xy 84.362624 -137.811353) (xy 84.406555 -137.818823) (xy 84.428838 -137.81913)
			(xy 84.456217 -137.819404) (xy 84.510462 -137.826839) (xy 84.563087 -137.841953) (xy 84.613011 -137.864436)
			(xy 84.659208 -137.893825) (xy 84.700728 -137.929516) (xy 84.736719 -137.970777) (xy 84.766442 -138.01676)
			(xy 84.789285 -138.066519) (xy 84.80478 -138.119033) (xy 84.812608 -138.173223) (xy 84.812608 -138.227976)
			(xy 84.80478 -138.282166) (xy 84.789285 -138.33468) (xy 84.766442 -138.38444) (xy 84.73672 -138.430423)
			(xy 84.700728 -138.471683) (xy 84.659208 -138.507375) (xy 84.613011 -138.536764) (xy 84.563088 -138.559247)
			(xy 84.510463 -138.574361) (xy 84.456217 -138.581796) (xy 84.428838 -138.582146) (xy 84.406558 -138.582458)
			(xy 84.362633 -138.589928) (xy 84.320685 -138.604946) (xy 84.281999 -138.62705) (xy 84.247761 -138.655562)
			(xy 84.219021 -138.689609) (xy 84.19666 -138.728147) (xy 84.181363 -138.769994) (xy 84.1736 -138.813868)
			(xy 84.17306 -138.836146) (xy 84.17306 -141.253978) (xy 85.355633 -141.253978) (xy 85.35992 -141.196922)
			(xy 85.37268 -141.141146) (xy 85.393626 -141.087901) (xy 85.422289 -141.038381) (xy 85.439758 -141.01572)
			(xy 85.450037 -141.001989) (xy 85.463509 -140.970457) (xy 85.468106 -140.936478) (xy 85.463497 -140.9025)
			(xy 85.450014 -140.870974) (xy 85.439758 -140.857224) (xy 85.422877 -140.835327) (xy 85.394943 -140.787615)
			(xy 85.374189 -140.736371) (xy 85.361049 -140.682667) (xy 85.3558 -140.627629) (xy 85.35855 -140.572409)
			(xy 85.369243 -140.518165) (xy 85.387654 -140.466033) (xy 85.413397 -140.417104) (xy 85.445935 -140.372404)
			(xy 85.484584 -140.332869) (xy 85.528535 -140.299327) (xy 85.576867 -140.272481) (xy 85.628569 -140.252894)
			(xy 85.682557 -140.240975) (xy 85.7377 -140.236974) (xy 85.792843 -140.240975) (xy 85.846831 -140.252894)
			(xy 85.898533 -140.272481) (xy 85.946865 -140.299327) (xy 85.990816 -140.332869) (xy 86.029465 -140.372404)
			(xy 86.062003 -140.417104) (xy 86.087746 -140.466033) (xy 86.106157 -140.518165) (xy 86.11685 -140.572409)
			(xy 86.1196 -140.627629) (xy 86.114351 -140.682667) (xy 86.101211 -140.736371) (xy 86.080457 -140.787615)
			(xy 86.052523 -140.835327) (xy 86.035642 -140.857224) (xy 86.025416 -140.870992) (xy 86.011936 -140.90251)
			(xy 86.007328 -140.936478) (xy 86.011925 -140.970448) (xy 86.025393 -141.001971) (xy 86.035642 -141.01572)
			(xy 86.053082 -141.038401) (xy 86.081742 -141.087916) (xy 86.102687 -141.141157) (xy 86.115445 -141.196927)
			(xy 86.119732 -141.253978) (xy 86.115452 -141.311029) (xy 86.102699 -141.366802) (xy 86.081761 -141.420044)
			(xy 86.053107 -141.469563) (xy 86.035642 -141.492224) (xy 86.025416 -141.505992) (xy 86.011936 -141.53751)
			(xy 86.007328 -141.571478) (xy 86.011925 -141.605448) (xy 86.025393 -141.636971) (xy 86.035642 -141.65072)
			(xy 86.052523 -141.672617) (xy 86.080457 -141.720329) (xy 86.101211 -141.771573) (xy 86.114351 -141.825277)
			(xy 86.1196 -141.880315) (xy 86.11685 -141.935535) (xy 86.106157 -141.989779) (xy 86.087746 -142.041911)
			(xy 86.062003 -142.09084) (xy 86.029465 -142.13554) (xy 85.990816 -142.175075) (xy 85.946865 -142.208617)
			(xy 85.898533 -142.235463) (xy 85.846831 -142.25505) (xy 85.792843 -142.266969) (xy 85.7377 -142.27097)
			(xy 85.682557 -142.266969) (xy 85.628569 -142.25505) (xy 85.576867 -142.235463) (xy 85.528535 -142.208617)
			(xy 85.484584 -142.175075) (xy 85.445935 -142.13554) (xy 85.413397 -142.09084) (xy 85.387654 -142.041911)
			(xy 85.369243 -141.989779) (xy 85.35855 -141.935535) (xy 85.3558 -141.880315) (xy 85.361049 -141.825277)
			(xy 85.374189 -141.771573) (xy 85.394943 -141.720329) (xy 85.422877 -141.672617) (xy 85.439758 -141.65072)
			(xy 85.450037 -141.636989) (xy 85.463509 -141.605457) (xy 85.468106 -141.571478) (xy 85.463497 -141.5375)
			(xy 85.450014 -141.505974) (xy 85.439758 -141.492224) (xy 85.422264 -141.469583) (xy 85.393607 -141.420059)
			(xy 85.372667 -141.366812) (xy 85.359914 -141.311035) (xy 85.355633 -141.253978) (xy 84.17306 -141.253978)
			(xy 84.17306 -141.419834) (xy 86.249764 -143.496538) (xy 86.266696 -143.512714) (xy 86.305307 -143.539198)
			(xy 86.348116 -143.558164) (xy 86.393674 -143.56897) (xy 86.44044 -143.57125) (xy 86.486832 -143.564926)
			(xy 86.531283 -143.550214) (xy 86.572287 -143.527611) (xy 86.608458 -143.49788) (xy 86.623906 -143.480282)
			(xy 86.641959 -143.459497) (xy 86.683023 -143.42283) (xy 86.728931 -143.392444) (xy 86.778729 -143.368972)
			(xy 86.831383 -143.3529) (xy 86.8858 -143.344563) (xy 86.940851 -143.344134) (xy 86.995392 -143.35162)
			(xy 87.048291 -143.366868) (xy 87.098449 -143.38956) (xy 87.144825 -143.419225) (xy 87.186457 -143.455248)
			(xy 87.222478 -143.496879) (xy 87.252143 -143.543256) (xy 87.274834 -143.593415) (xy 87.290081 -143.646314)
			(xy 87.297567 -143.700855) (xy 87.297136 -143.755905) (xy 87.288798 -143.810323) (xy 87.272726 -143.862977)
			(xy 87.249253 -143.912774) (xy 87.218867 -143.958681) (xy 87.182198 -143.999745) (xy 87.16137 -144.017746)
			(xy 87.143776 -144.033206) (xy 87.114023 -144.06937) (xy 87.091399 -144.110373) (xy 87.076671 -144.154827)
			(xy 87.070338 -144.201227) (xy 87.072613 -144.248002) (xy 87.083421 -144.293568) (xy 87.102394 -144.336383)
			(xy 87.128891 -144.374996) (xy 87.145114 -144.391888) (xy 88.429476 -145.67625) (xy 121.896387 -145.67625)
			(xy 121.901642 -145.621271) (xy 121.914771 -145.567626) (xy 121.9355 -145.516434) (xy 121.963397 -145.468768)
			(xy 121.997876 -145.425624) (xy 122.038218 -145.387904) (xy 122.083579 -145.356397) (xy 122.133009 -145.331762)
			(xy 122.185476 -145.314514) (xy 122.239882 -145.305014) (xy 122.267472 -145.303748) (xy 122.291107 -145.302495)
			(xy 122.337339 -145.292395) (xy 122.380905 -145.273916) (xy 122.4203 -145.247696) (xy 122.454165 -145.214641)
			(xy 122.481329 -145.175891) (xy 122.500856 -145.132785) (xy 122.512071 -145.08681) (xy 122.513852 -145.06321)
			(xy 122.51578 -145.035652) (xy 122.526602 -144.981479) (xy 122.545125 -144.929433) (xy 122.570961 -144.880604)
			(xy 122.60357 -144.836012) (xy 122.64227 -144.79659) (xy 122.686252 -144.763162) (xy 122.734595 -144.736427)
			(xy 122.786289 -144.716946) (xy 122.840253 -144.705124) (xy 122.895357 -144.70121) (xy 122.95045 -144.705285)
			(xy 123.004379 -144.717264) (xy 123.056016 -144.736896) (xy 123.104281 -144.763771) (xy 123.148165 -144.797327)
			(xy 123.18675 -144.836862) (xy 123.219229 -144.881549) (xy 123.244922 -144.930454) (xy 123.263293 -144.982553)
			(xy 123.273957 -145.036757) (xy 123.276691 -145.091933) (xy 123.271438 -145.146926) (xy 123.258307 -145.200586)
			(xy 123.237574 -145.251791) (xy 123.209672 -145.29947) (xy 123.175184 -145.342625) (xy 123.134833 -145.380355)
			(xy 123.089461 -145.41187) (xy 123.040017 -145.436511) (xy 122.987537 -145.453763) (xy 122.933117 -145.463264)
			(xy 122.90552 -145.46453) (xy 122.881878 -145.465703) (xy 122.835637 -145.475809) (xy 122.792065 -145.494296)
			(xy 122.752666 -145.520526) (xy 122.718801 -145.553594) (xy 122.691639 -145.592357) (xy 122.672119 -145.635476)
			(xy 122.660914 -145.681463) (xy 122.65914 -145.705068) (xy 122.657133 -145.732615) (xy 122.646303 -145.786772)
			(xy 122.627775 -145.838801) (xy 122.601937 -145.887613) (xy 122.569328 -145.932188) (xy 122.530631 -145.971594)
			(xy 122.486655 -146.005006) (xy 122.43832 -146.031726) (xy 122.386636 -146.051195) (xy 122.332685 -146.063006)
			(xy 122.277594 -146.066912) (xy 122.222515 -146.062832) (xy 122.168602 -146.050849) (xy 122.11698 -146.031216)
			(xy 122.06873 -146.004343) (xy 122.02486 -145.970791) (xy 121.986289 -145.931263) (xy 121.953822 -145.886584)
			(xy 121.928138 -145.83769) (xy 121.909776 -145.785603) (xy 121.899118 -145.731412) (xy 121.896387 -145.67625)
			(xy 88.429476 -145.67625) (xy 89.226136 -146.47291) (xy 123.417074 -146.47291) (xy 123.421145 -146.417288)
			(xy 123.433271 -146.362851) (xy 123.453194 -146.31076) (xy 123.48049 -146.262125) (xy 123.514576 -146.217982)
			(xy 123.554725 -146.179273) (xy 123.600083 -146.146822) (xy 123.649683 -146.121321) (xy 123.702467 -146.103314)
			(xy 123.75731 -146.093184) (xy 123.813044 -146.091147) (xy 123.868481 -146.097247) (xy 123.922438 -146.111353)
			(xy 123.973767 -146.133165) (xy 124.021373 -146.162219) (xy 124.064241 -146.197894) (xy 124.101458 -146.239431)
			(xy 124.132231 -146.285944) (xy 124.155903 -146.336441) (xy 124.171971 -146.389848) (xy 124.180091 -146.445024)
			(xy 124.1806 -146.47291) (xy 124.180091 -146.500796) (xy 124.171971 -146.555972) (xy 124.155903 -146.609379)
			(xy 124.132231 -146.659876) (xy 124.101458 -146.706389) (xy 124.064241 -146.747926) (xy 124.021373 -146.783601)
			(xy 123.973767 -146.812655) (xy 123.922438 -146.834467) (xy 123.868481 -146.848573) (xy 123.813044 -146.854673)
			(xy 123.75731 -146.852636) (xy 123.702467 -146.842506) (xy 123.649683 -146.824499) (xy 123.600083 -146.798998)
			(xy 123.554725 -146.766547) (xy 123.514576 -146.727838) (xy 123.48049 -146.683695) (xy 123.453194 -146.63506)
			(xy 123.433271 -146.582969) (xy 123.421145 -146.528532) (xy 123.417074 -146.47291) (xy 89.226136 -146.47291)
			(xy 90.499692 -147.746466) (xy 116.517926 -147.746466) (xy 116.521997 -147.690844) (xy 116.534123 -147.636407)
			(xy 116.554046 -147.584316) (xy 116.581342 -147.535681) (xy 116.615428 -147.491538) (xy 116.655577 -147.452829)
			(xy 116.700935 -147.420378) (xy 116.750535 -147.394877) (xy 116.803319 -147.37687) (xy 116.858162 -147.36674)
			(xy 116.913896 -147.364703) (xy 116.969333 -147.370803) (xy 117.02329 -147.384909) (xy 117.074619 -147.406721)
			(xy 117.122225 -147.435775) (xy 117.165093 -147.47145) (xy 117.20231 -147.512987) (xy 117.233083 -147.5595)
			(xy 117.256755 -147.609997) (xy 117.272823 -147.663404) (xy 117.280943 -147.71858) (xy 117.281452 -147.746466)
			(xy 117.280943 -147.774352) (xy 117.272823 -147.829528) (xy 117.256755 -147.882935) (xy 117.233083 -147.933432)
			(xy 117.20231 -147.979945) (xy 117.165093 -148.021482) (xy 117.122225 -148.057157) (xy 117.074619 -148.086211)
			(xy 117.02329 -148.108023) (xy 116.969333 -148.122129) (xy 116.913896 -148.128229) (xy 116.858162 -148.126192)
			(xy 116.803319 -148.116062) (xy 116.750535 -148.098055) (xy 116.700935 -148.072554) (xy 116.655577 -148.040103)
			(xy 116.615428 -148.001394) (xy 116.581342 -147.957251) (xy 116.554046 -147.908616) (xy 116.534123 -147.856525)
			(xy 116.521997 -147.802088) (xy 116.517926 -147.746466) (xy 90.499692 -147.746466) (xy 91.865789 -149.112563)
			(xy 100.808339 -149.112563) (xy 100.81483 -149.05777) (xy 100.829147 -149.004483) (xy 100.85099 -148.953815)
			(xy 100.879903 -148.906821) (xy 100.915284 -148.864481) (xy 100.956394 -148.82768) (xy 101.002377 -148.797183)
			(xy 101.052273 -148.773629) (xy 101.105041 -148.757507) (xy 101.159582 -148.749154) (xy 101.214757 -148.748744)
			(xy 101.269415 -148.756285) (xy 101.322417 -148.771622) (xy 101.372658 -148.794433) (xy 101.419088 -148.824242)
			(xy 101.440234 -148.841968) (xy 101.452415 -148.851955) (xy 101.480504 -148.866188) (xy 101.511226 -148.873096)
			(xy 101.542704 -148.872258) (xy 101.573015 -148.863725) (xy 101.600306 -148.848018) (xy 101.611938 -148.837396)
			(xy 101.632102 -148.818566) (xy 101.676878 -148.786334) (xy 101.72583 -148.760888) (xy 101.777936 -148.742758)
			(xy 101.83211 -148.732322) (xy 101.887223 -148.729798) (xy 101.942125 -148.735238) (xy 101.99567 -148.748529)
			(xy 102.046743 -148.769394) (xy 102.094278 -148.797398) (xy 102.137283 -148.831957) (xy 102.174863 -148.872349)
			(xy 102.204954 -148.915882) (xy 107.543598 -148.915882) (xy 107.547669 -148.86026) (xy 107.559795 -148.805823)
			(xy 107.579718 -148.753732) (xy 107.607014 -148.705097) (xy 107.6411 -148.660954) (xy 107.681249 -148.622245)
			(xy 107.726607 -148.589794) (xy 107.776207 -148.564293) (xy 107.828991 -148.546286) (xy 107.883834 -148.536156)
			(xy 107.939568 -148.534119) (xy 107.995005 -148.540219) (xy 108.048962 -148.554325) (xy 108.100291 -148.576137)
			(xy 108.147897 -148.605191) (xy 108.190765 -148.640866) (xy 108.227982 -148.682403) (xy 108.258755 -148.728916)
			(xy 108.282427 -148.779413) (xy 108.293988 -148.817838) (xy 118.677942 -148.817838) (xy 118.682013 -148.762216)
			(xy 118.694139 -148.707779) (xy 118.714062 -148.655688) (xy 118.741358 -148.607053) (xy 118.775444 -148.56291)
			(xy 118.815593 -148.524201) (xy 118.860951 -148.49175) (xy 118.910551 -148.466249) (xy 118.963335 -148.448242)
			(xy 119.018178 -148.438112) (xy 119.073912 -148.436075) (xy 119.129349 -148.442175) (xy 119.183306 -148.456281)
			(xy 119.234635 -148.478093) (xy 119.282241 -148.507147) (xy 119.325109 -148.542822) (xy 119.362326 -148.584359)
			(xy 119.393099 -148.630872) (xy 119.416771 -148.681369) (xy 119.432839 -148.734776) (xy 119.440959 -148.789952)
			(xy 119.441468 -148.817838) (xy 119.440959 -148.845724) (xy 119.432839 -148.9009) (xy 119.416771 -148.954307)
			(xy 119.393099 -149.004804) (xy 119.362326 -149.051317) (xy 119.325109 -149.092854) (xy 119.282241 -149.128529)
			(xy 119.234635 -149.157583) (xy 119.183306 -149.179395) (xy 119.129349 -149.193501) (xy 119.073912 -149.199601)
			(xy 119.018178 -149.197564) (xy 118.963335 -149.187434) (xy 118.910551 -149.169427) (xy 118.860951 -149.143926)
			(xy 118.815593 -149.111475) (xy 118.775444 -149.072766) (xy 118.741358 -149.028623) (xy 118.714062 -148.979988)
			(xy 118.694139 -148.927897) (xy 118.682013 -148.87346) (xy 118.677942 -148.817838) (xy 108.293988 -148.817838)
			(xy 108.298495 -148.83282) (xy 108.306615 -148.887996) (xy 108.307124 -148.915882) (xy 108.306615 -148.943768)
			(xy 108.298495 -148.998944) (xy 108.282427 -149.052351) (xy 108.258755 -149.102848) (xy 108.227982 -149.149361)
			(xy 108.190765 -149.190898) (xy 108.147897 -149.226573) (xy 108.117596 -149.245066) (xy 110.747046 -149.245066)
			(xy 110.751117 -149.189444) (xy 110.763243 -149.135007) (xy 110.783166 -149.082916) (xy 110.810462 -149.034281)
			(xy 110.844548 -148.990138) (xy 110.884697 -148.951429) (xy 110.930055 -148.918978) (xy 110.979655 -148.893477)
			(xy 111.032439 -148.87547) (xy 111.087282 -148.86534) (xy 111.143016 -148.863303) (xy 111.198453 -148.869403)
			(xy 111.25241 -148.883509) (xy 111.303739 -148.905321) (xy 111.351345 -148.934375) (xy 111.394213 -148.97005)
			(xy 111.43143 -149.011587) (xy 111.462203 -149.0581) (xy 111.485875 -149.108597) (xy 111.501943 -149.162004)
			(xy 111.510063 -149.21718) (xy 111.510572 -149.245066) (xy 111.510063 -149.272952) (xy 111.501943 -149.328128)
			(xy 111.485875 -149.381535) (xy 111.462203 -149.432032) (xy 111.43143 -149.478545) (xy 111.394213 -149.520082)
			(xy 111.351345 -149.555757) (xy 111.303739 -149.584811) (xy 111.25241 -149.606623) (xy 111.198453 -149.620729)
			(xy 111.143016 -149.626829) (xy 111.087282 -149.624792) (xy 111.032439 -149.614662) (xy 110.979655 -149.596655)
			(xy 110.930055 -149.571154) (xy 110.884697 -149.538703) (xy 110.844548 -149.499994) (xy 110.810462 -149.455851)
			(xy 110.783166 -149.407216) (xy 110.763243 -149.355125) (xy 110.751117 -149.300688) (xy 110.747046 -149.245066)
			(xy 108.117596 -149.245066) (xy 108.100291 -149.255627) (xy 108.048962 -149.277439) (xy 107.995005 -149.291545)
			(xy 107.939568 -149.297645) (xy 107.883834 -149.295608) (xy 107.828991 -149.285478) (xy 107.776207 -149.267471)
			(xy 107.726607 -149.24197) (xy 107.681249 -149.209519) (xy 107.6411 -149.17081) (xy 107.607014 -149.126667)
			(xy 107.579718 -149.078032) (xy 107.559795 -149.025941) (xy 107.547669 -148.971504) (xy 107.543598 -148.915882)
			(xy 102.204954 -148.915882) (xy 102.206233 -148.917733) (xy 102.230739 -148.967162) (xy 102.24787 -149.019605)
			(xy 102.257269 -149.073969) (xy 102.258739 -149.12912) (xy 102.25225 -149.183907) (xy 102.237938 -149.237189)
			(xy 102.216101 -149.287854) (xy 102.187194 -149.334845) (xy 102.15182 -149.377182) (xy 102.110717 -149.413983)
			(xy 102.064742 -149.44448) (xy 102.014853 -149.468037) (xy 101.962092 -149.484162) (xy 101.907559 -149.49252)
			(xy 101.85239 -149.492936) (xy 101.797736 -149.485402) (xy 101.744738 -149.470074) (xy 101.6945 -149.447273)
			(xy 101.64807 -149.417473) (xy 101.626924 -149.399752) (xy 101.614776 -149.389721) (xy 101.586678 -149.37549)
			(xy 101.555947 -149.368586) (xy 101.524461 -149.369432) (xy 101.494145 -149.377976) (xy 101.466851 -149.393696)
			(xy 101.45522 -149.404324) (xy 101.435033 -149.423135) (xy 101.390254 -149.455373) (xy 101.341299 -149.480825)
			(xy 101.289188 -149.498959) (xy 101.235008 -149.509399) (xy 101.17989 -149.511926) (xy 101.124982 -149.506486)
			(xy 101.07143 -149.493195) (xy 101.020352 -149.472329) (xy 100.972812 -149.444322) (xy 100.929801 -149.40976)
			(xy 100.892217 -149.369363) (xy 100.860845 -149.323974) (xy 100.836337 -149.27454) (xy 100.819205 -149.22209)
			(xy 100.809807 -149.16772) (xy 100.808339 -149.112563) (xy 91.865789 -149.112563) (xy 93.424412 -150.671186)
			(xy 96.987831 -150.671186) (xy 96.994484 -150.615512) (xy 97.009217 -150.561413) (xy 97.031711 -150.510054)
			(xy 97.061482 -150.462541) (xy 97.079308 -150.440898) (xy 97.088692 -150.429194) (xy 97.102327 -150.402485)
			(xy 97.109343 -150.37333) (xy 97.109352 -150.343343) (xy 97.102352 -150.314183) (xy 97.088733 -150.287467)
			(xy 97.079308 -150.275798) (xy 97.061482 -150.254155) (xy 97.031711 -150.206642) (xy 97.009217 -150.155283)
			(xy 96.994484 -150.101184) (xy 96.987831 -150.04551) (xy 96.9894 -149.989463) (xy 96.999158 -149.934249)
			(xy 97.016895 -149.881059) (xy 97.042228 -149.831039) (xy 97.074611 -149.785267) (xy 97.113346 -149.744728)
			(xy 97.157599 -149.710298) (xy 97.206416 -149.682718) (xy 97.258745 -149.662582) (xy 97.313458 -149.650324)
			(xy 97.369376 -149.646208) (xy 97.425294 -149.650324) (xy 97.480007 -149.662582) (xy 97.532336 -149.682718)
			(xy 97.581153 -149.710298) (xy 97.625406 -149.744728) (xy 97.664141 -149.785267) (xy 97.696524 -149.831039)
			(xy 97.721857 -149.881059) (xy 97.739594 -149.934249) (xy 97.749352 -149.989463) (xy 97.750921 -150.04551)
			(xy 97.744268 -150.101184) (xy 97.729535 -150.155283) (xy 97.707041 -150.206642) (xy 97.67727 -150.254155)
			(xy 97.659444 -150.275798) (xy 97.649971 -150.287434) (xy 97.636349 -150.314164) (xy 97.62935 -150.343336)
			(xy 97.629358 -150.373337) (xy 97.636375 -150.402505) (xy 97.650011 -150.429227) (xy 97.659444 -150.440898)
			(xy 97.67727 -150.462541) (xy 97.707041 -150.510054) (xy 97.729535 -150.561413) (xy 97.744268 -150.615512)
			(xy 97.750921 -150.671186) (xy 97.749352 -150.727233) (xy 97.739594 -150.782447) (xy 97.721857 -150.835637)
			(xy 97.696524 -150.885657) (xy 97.664141 -150.931429) (xy 97.625406 -150.971968) (xy 97.581153 -151.006398)
			(xy 97.532336 -151.033978) (xy 97.480007 -151.054114) (xy 97.425294 -151.066372) (xy 97.369376 -151.070488)
			(xy 97.313458 -151.066372) (xy 97.258745 -151.054114) (xy 97.206416 -151.033978) (xy 97.157599 -151.006398)
			(xy 97.113346 -150.971968) (xy 97.074611 -150.931429) (xy 97.042228 -150.885657) (xy 97.016895 -150.835637)
			(xy 96.999158 -150.782447) (xy 96.9894 -150.727233) (xy 96.987831 -150.671186) (xy 93.424412 -150.671186)
			(xy 94.294452 -151.541226) (xy 99.272344 -151.541226)
		)
		(stroke
			(width 0)
			(type solid)
		)
		(fill yes)
		(layer "In6.Cu")
		(net "P1V538_BMC_NODE1")
	)
	(gr_poly
		(pts
			(xy 160.321244 -109.032802) (xy 160.344305 -109.032304) (xy 160.389671 -109.023992) (xy 160.432792 -109.00763)
			(xy 160.472253 -108.983756) (xy 160.506758 -108.953153) (xy 160.535175 -108.916826) (xy 160.55657 -108.875968)
			(xy 160.570242 -108.831919) (xy 160.575741 -108.786127) (xy 160.572886 -108.740094) (xy 160.561772 -108.695332)
			(xy 160.552638 -108.674154) (xy 160.546533 -108.660991) (xy 160.53611 -108.63391) (xy 160.53181 -108.620052)
			(xy 160.52501 -108.595748) (xy 160.517139 -108.545897) (xy 160.515922 -108.495443) (xy 160.521381 -108.44527)
			(xy 160.526984 -108.420662) (xy 160.533958 -108.394091) (xy 160.554495 -108.343142) (xy 160.582126 -108.295664)
			(xy 160.61628 -108.252639) (xy 160.63595 -108.233464) (xy 160.653424 -108.217461) (xy 160.691635 -108.18944)
			(xy 160.71215 -108.177584) (xy 160.74009 -108.16209) (xy 160.813496 -108.04779) (xy 160.805876 -108.000038)
			(xy 160.802068 -107.972555) (xy 160.801498 -107.917077) (xy 160.808969 -107.8621) (xy 160.824324 -107.808786)
			(xy 160.84724 -107.758258) (xy 160.877232 -107.711581) (xy 160.913668 -107.669741) (xy 160.955781 -107.63362)
			(xy 161.002681 -107.603979) (xy 161.053379 -107.581443) (xy 161.106808 -107.566489) (xy 161.161838 -107.55943)
			(xy 161.217311 -107.560416) (xy 161.272056 -107.569427) (xy 161.324919 -107.586272) (xy 161.374784 -107.610596)
			(xy 161.420601 -107.641886) (xy 161.461402 -107.679481) (xy 161.496328 -107.722591) (xy 161.524642 -107.770304)
			(xy 161.545746 -107.821615) (xy 161.559196 -107.875441) (xy 161.564708 -107.930648) (xy 161.562166 -107.986072)
			(xy 161.551623 -108.040542) (xy 161.533301 -108.092912) (xy 161.507588 -108.142075) (xy 161.475025 -108.186996)
			(xy 161.4363 -108.226726) (xy 161.392228 -108.260429) (xy 161.368232 -108.274358) (xy 161.340292 -108.289852)
			(xy 161.26714 -108.404152) (xy 161.274506 -108.45165) (xy 161.2773 -108.475018) (xy 161.278811 -108.4927)
			(xy 161.278937 -108.528191) (xy 161.277554 -108.545884) (xy 161.274938 -108.570289) (xy 161.264239 -108.618191)
			(xy 161.256218 -108.641388) (xy 161.249614 -108.658152) (xy 161.242502 -108.674154) (xy 161.23346 -108.695366)
			(xy 161.222353 -108.740114) (xy 161.219501 -108.786131) (xy 161.224999 -108.831908) (xy 161.238664 -108.875942)
			(xy 161.26005 -108.916788) (xy 161.288455 -108.953106) (xy 161.322945 -108.983703) (xy 161.36239 -109.007575)
			(xy 161.405494 -109.023939) (xy 161.450843 -109.032258) (xy 161.473896 -109.032802) (xy 162.653472 -109.032802)
			(xy 162.689032 -109.002576) (xy 162.69462 -108.998004) (xy 162.695382 -108.997242) (xy 162.703764 -108.990638)
			(xy 162.729914 -108.971369) (xy 162.787382 -108.941102) (xy 162.818064 -108.93044) (xy 162.840132 -108.922736)
			(xy 162.881211 -108.900448) (xy 162.917517 -108.87102) (xy 162.947826 -108.835444) (xy 162.971113 -108.794923)
			(xy 162.986591 -108.750825) (xy 162.993739 -108.70464) (xy 162.993578 -108.681266) (xy 162.993324 -108.657898)
			(xy 162.993649 -108.646874) (xy 162.995427 -108.624889) (xy 162.99688 -108.613956) (xy 163.001262 -108.586006)
			(xy 163.0172 -108.531724) (xy 163.040979 -108.480391) (xy 163.072078 -108.433132) (xy 163.109815 -108.390983)
			(xy 163.153362 -108.35487) (xy 163.201764 -108.325583) (xy 163.253961 -108.303764) (xy 163.308808 -108.289894)
			(xy 163.365102 -108.284274) (xy 163.421608 -108.287029) (xy 163.477088 -108.298099) (xy 163.530325 -108.317239)
			(xy 163.580152 -108.344032) (xy 163.625475 -108.377889) (xy 163.665303 -108.418068) (xy 163.69876 -108.463687)
			(xy 163.725114 -108.513748) (xy 163.743786 -108.567151) (xy 163.754367 -108.622726) (xy 163.756626 -108.679254)
			(xy 163.754054 -108.707428) (xy 163.749228 -108.739686) (xy 163.746307 -108.761422) (xy 163.747093 -108.805268)
			(xy 163.755395 -108.848327) (xy 163.770966 -108.889323) (xy 163.793344 -108.927036) (xy 163.821864 -108.960348)
			(xy 163.855679 -108.988269) (xy 163.893786 -109.00997) (xy 163.935053 -109.024807) (xy 163.978254 -109.032339)
			(xy 164.00018 -109.032802) (xy 164.019484 -109.032802) (xy 164.041413 -109.032342) (xy 164.084619 -109.024815)
			(xy 164.125891 -109.009981) (xy 164.164003 -108.988281) (xy 164.197824 -108.96036) (xy 164.226349 -108.927047)
			(xy 164.24873 -108.889331) (xy 164.264304 -108.848332) (xy 164.272607 -108.805268) (xy 164.273393 -108.761418)
			(xy 164.270436 -108.739686) (xy 164.265699 -108.713248) (xy 164.262819 -108.659615) (xy 164.26749 -108.606108)
			(xy 164.279618 -108.553785) (xy 164.298964 -108.50368) (xy 164.325146 -108.456783) (xy 164.357647 -108.414021)
			(xy 164.395823 -108.37624) (xy 164.43892 -108.344187) (xy 164.486087 -108.318494) (xy 164.53639 -108.29967)
			(xy 164.588837 -108.288087) (xy 164.642389 -108.283973) (xy 164.669216 -108.28528) (xy 164.691773 -108.285155)
			(xy 164.736291 -108.277909) (xy 164.77883 -108.262918) (xy 164.818056 -108.240654) (xy 164.852737 -108.211816)
			(xy 164.881782 -108.17731) (xy 164.904281 -108.138218) (xy 164.919526 -108.095769) (xy 164.92704 -108.051295)
			(xy 164.92728 -108.02874) (xy 164.927465 -108.001579) (xy 164.934585 -107.947734) (xy 164.949272 -107.895442)
			(xy 164.971228 -107.845763) (xy 165.000008 -107.799701) (xy 165.035032 -107.758187) (xy 165.07559 -107.722061)
			(xy 165.120862 -107.692054) (xy 165.169934 -107.668771) (xy 165.221811 -107.652685) (xy 165.275446 -107.644121)
			(xy 165.329754 -107.643251) (xy 165.383635 -107.650094) (xy 165.436001 -107.66451) (xy 165.485793 -107.686209)
			(xy 165.532003 -107.714752) (xy 165.553136 -107.731814) (xy 165.575906 -107.751551) (xy 165.61553 -107.796946)
			(xy 165.64752 -107.848009) (xy 165.671081 -107.903467) (xy 165.685625 -107.961942) (xy 165.688772 -107.99191)
			(xy 165.690664 -108.01893) (xy 165.687709 -108.073012) (xy 165.677129 -108.126132) (xy 165.659138 -108.17722)
			(xy 165.634097 -108.225247) (xy 165.60251 -108.269246) (xy 165.565014 -108.308332) (xy 165.543992 -108.325412)
			(xy 165.523187 -108.341161) (xy 165.478102 -108.367433) (xy 165.429858 -108.387317) (xy 165.379356 -108.400444)
			(xy 165.353492 -108.403898) (xy 165.336282 -108.405708) (xy 165.301685 -108.406598) (xy 165.284404 -108.405676)
			(xy 165.261848 -108.4058) (xy 165.217331 -108.413044) (xy 165.174792 -108.428033) (xy 165.135568 -108.450297)
			(xy 165.10089 -108.479136) (xy 165.071849 -108.513644) (xy 165.049355 -108.552737) (xy 165.034117 -108.595187)
			(xy 165.026612 -108.639661) (xy 165.02634 -108.662216) (xy 165.02634 -108.673392) (xy 165.026364 -108.694609)
			(xy 165.032618 -108.736572) (xy 165.045753 -108.776913) (xy 165.065406 -108.814512) (xy 165.091031 -108.848326)
			(xy 165.121915 -108.877413) (xy 165.157202 -108.900968) (xy 165.19591 -108.918335) (xy 165.216332 -108.92409)
			(xy 165.239725 -108.930596) (xy 165.284767 -108.948735) (xy 165.327145 -108.972438) (xy 165.346888 -108.986574)
			(xy 165.355016 -108.99267) (xy 165.366954 -109.002576) (xy 165.402514 -109.032802) (xy 166.001954 -109.032802)
			(xy 166.023945 -109.032339) (xy 166.067271 -109.024771) (xy 166.108646 -109.009853) (xy 166.146834 -108.988031)
			(xy 166.180691 -108.959958) (xy 166.209207 -108.926473) (xy 166.23153 -108.888577) (xy 166.24699 -108.847401)
			(xy 166.255128 -108.804179) (xy 166.255699 -108.7602) (xy 166.252652 -108.738416) (xy 166.248651 -108.710615)
			(xy 166.247894 -108.654453) (xy 166.255384 -108.598787) (xy 166.270961 -108.544824) (xy 166.294286 -108.493729)
			(xy 166.324855 -108.446609) (xy 166.343076 -108.425234) (xy 166.363396 -108.403898) (xy 166.378381 -108.388388)
			(xy 166.403428 -108.353282) (xy 166.42219 -108.314453) (xy 166.43413 -108.273015) (xy 166.438904 -108.230155)
			(xy 166.436377 -108.187105) (xy 166.426619 -108.145099) (xy 166.409912 -108.105343) (xy 166.386734 -108.068976)
			(xy 166.357751 -108.037043) (xy 166.341044 -108.023406) (xy 166.320036 -108.00636) (xy 166.282574 -107.96733)
			(xy 166.250996 -107.923402) (xy 166.225936 -107.875457) (xy 166.207896 -107.824454) (xy 166.197236 -107.771415)
			(xy 166.19417 -107.717403) (xy 166.19601 -107.690412) (xy 166.198803 -107.663224) (xy 166.211178 -107.60999)
			(xy 166.231021 -107.559066) (xy 166.257927 -107.511494) (xy 166.291345 -107.468248) (xy 166.330592 -107.430212)
			(xy 166.374863 -107.398164) (xy 166.423254 -107.372761) (xy 166.474775 -107.354522) (xy 166.52837 -107.343819)
			(xy 166.582944 -107.340873) (xy 166.63738 -107.345744) (xy 166.690565 -107.358331) (xy 166.741409 -107.378378)
			(xy 166.788873 -107.405473) (xy 166.81069 -107.421934) (xy 166.835375 -107.441974) (xy 166.878359 -107.48882)
			(xy 166.912993 -107.542136) (xy 166.92626 -107.571032) (xy 166.935785 -107.591716) (xy 166.961063 -107.629588)
			(xy 166.992692 -107.662342) (xy 167.029657 -107.688929) (xy 167.070773 -107.708493) (xy 167.114719 -107.720409)
			(xy 167.160086 -107.724293) (xy 167.1828 -107.72267) (xy 167.209317 -107.720666) (xy 167.262436 -107.723152)
			(xy 167.314692 -107.733005) (xy 167.36507 -107.750033) (xy 167.389048 -107.761532) (xy 167.413687 -107.77444)
			(xy 167.45927 -107.806313) (xy 167.499744 -107.844465) (xy 167.53425 -107.888089) (xy 167.562057 -107.936261)
			(xy 167.582577 -107.987959) (xy 167.595373 -108.042088) (xy 167.600175 -108.097502) (xy 167.596882 -108.153025)
			(xy 167.585563 -108.207483) (xy 167.566458 -108.25972) (xy 167.539972 -108.30863) (xy 167.506666 -108.353177)
			(xy 167.467245 -108.392416) (xy 167.422545 -108.425517) (xy 167.373514 -108.451778) (xy 167.321189 -108.470642)
			(xy 167.26668 -108.48171) (xy 167.238934 -108.483654) (xy 167.217642 -108.486055) (xy 167.176237 -108.497069)
			(xy 167.137263 -108.514865) (xy 167.101823 -108.538941) (xy 167.070918 -108.568615) (xy 167.045422 -108.603048)
			(xy 167.026058 -108.641267) (xy 167.013371 -108.682191) (xy 167.01008 -108.703364) (xy 167.006524 -108.735114)
			(xy 167.006016 -108.738416) (xy 167.002981 -108.760199) (xy 167.003568 -108.804171) (xy 167.011716 -108.847387)
			(xy 167.027182 -108.888554) (xy 167.049505 -108.926444) (xy 167.078016 -108.959926) (xy 167.111866 -108.987999)
			(xy 167.150043 -109.009826) (xy 167.191408 -109.024755) (xy 167.234726 -109.032341) (xy 167.256714 -109.032802)
			(xy 168.47693 -109.032802) (xy 168.498718 -109.032351) (xy 168.541654 -109.024915) (xy 168.582694 -109.010265)
			(xy 168.620634 -108.988832) (xy 168.654363 -108.961242) (xy 168.682893 -108.928305) (xy 168.705388 -108.890985)
			(xy 168.72119 -108.850375) (xy 168.729834 -108.807665) (xy 168.731069 -108.764107) (xy 168.72839 -108.74248)
			(xy 168.725596 -108.722668) (xy 168.724072 -108.707682) (xy 168.720863 -108.68527) (xy 168.707553 -108.642)
			(xy 168.686791 -108.601772) (xy 168.659233 -108.565855) (xy 168.62575 -108.535387) (xy 168.587401 -108.51133)
			(xy 168.545398 -108.494444) (xy 168.501068 -108.485263) (xy 168.478454 -108.484162) (xy 168.450879 -108.482977)
			(xy 168.396482 -108.473648) (xy 168.343997 -108.456579) (xy 168.294518 -108.432127) (xy 168.249078 -108.400801)
			(xy 168.208625 -108.363256) (xy 168.174002 -108.320275) (xy 168.145934 -108.272754) (xy 168.125004 -108.221685)
			(xy 168.11165 -108.168134) (xy 168.10615 -108.113217) (xy 168.10862 -108.058081) (xy 168.119007 -108.003876)
			(xy 168.137094 -107.951733) (xy 168.162505 -107.902739) (xy 168.19471 -107.857918) (xy 168.213532 -107.837732)
			(xy 168.233672 -107.817619) (xy 168.278839 -107.782987) (xy 168.328648 -107.755445) (xy 168.381994 -107.735604)
			(xy 168.437695 -107.723905) (xy 168.494516 -107.720606) (xy 168.522904 -107.72267) (xy 168.549529 -107.725562)
			(xy 168.601655 -107.737855) (xy 168.651549 -107.757315) (xy 168.698234 -107.78356) (xy 168.74079 -107.816074)
			(xy 168.778382 -107.854219) (xy 168.810272 -107.897245) (xy 168.835833 -107.944307) (xy 168.854563 -107.99448)
			(xy 168.866094 -108.04678) (xy 168.868598 -108.073444) (xy 168.871809 -108.095855) (xy 168.885121 -108.139124)
			(xy 168.905885 -108.179351) (xy 168.933443 -108.215267) (xy 168.966924 -108.245735) (xy 169.005272 -108.269794)
			(xy 169.047274 -108.286682) (xy 169.091602 -108.295867) (xy 169.114216 -108.296964) (xy 169.140646 -108.298081)
			(xy 169.192837 -108.306704) (xy 169.243337 -108.322452) (xy 169.291179 -108.345024) (xy 169.335445 -108.373986)
			(xy 169.375287 -108.408784) (xy 169.409941 -108.448751) (xy 169.438745 -108.493121) (xy 169.461144 -108.541043)
			(xy 169.469308 -108.566204) (xy 169.477515 -108.594782) (xy 169.485976 -108.653632) (xy 169.485185 -108.713081)
			(xy 169.480738 -108.74248) (xy 169.478067 -108.764109) (xy 169.479286 -108.80767) (xy 169.487919 -108.850384)
			(xy 169.503714 -108.890999) (xy 169.526208 -108.928323) (xy 169.55474 -108.961261) (xy 169.588474 -108.988848)
			(xy 169.626421 -109.010275) (xy 169.667467 -109.024912) (xy 169.710409 -109.032331) (xy 169.732198 -109.032802)
			(xy 170.044872 -109.032802) (xy 170.173396 -108.904278) (xy 170.188511 -108.888558) (xy 170.213666 -108.852938)
			(xy 170.23237 -108.813546) (xy 170.244074 -108.771539) (xy 170.248433 -108.728151) (xy 170.245321 -108.684656)
			(xy 170.234827 -108.64233) (xy 170.217261 -108.602418) (xy 170.193139 -108.566091) (xy 170.178476 -108.549948)
			(xy 170.159552 -108.530336) (xy 170.126892 -108.486708) (xy 170.100773 -108.438875) (xy 170.081728 -108.387813)
			(xy 170.070144 -108.33456) (xy 170.066256 -108.2802) (xy 170.070144 -108.22584) (xy 170.081728 -108.172587)
			(xy 170.100773 -108.121525) (xy 170.126892 -108.073692) (xy 170.159552 -108.030064) (xy 170.198088 -107.991528)
			(xy 170.241716 -107.958868) (xy 170.289549 -107.932749) (xy 170.340611 -107.913704) (xy 170.393864 -107.90212)
			(xy 170.448224 -107.898232) (xy 170.502584 -107.90212) (xy 170.555837 -107.913704) (xy 170.606899 -107.932749)
			(xy 170.654732 -107.958868) (xy 170.69836 -107.991528) (xy 170.717972 -108.010452) (xy 170.734126 -108.025094)
			(xy 170.770458 -108.049186) (xy 170.810367 -108.066728) (xy 170.852684 -108.077206) (xy 170.896168 -108.080311)
			(xy 170.939544 -108.075954) (xy 170.981542 -108.064262) (xy 171.020929 -108.045578) (xy 171.056553 -108.020449)
			(xy 171.072302 -108.005372) (xy 171.196 -107.881674) (xy 172.305726 -107.881674) (xy 174.3837 -105.8037)
			(xy 174.3837 -105.428542) (xy 174.337726 -105.36301) (xy 174.29988 -105.349294) (xy 174.274215 -105.339496)
			(xy 174.225776 -105.313585) (xy 174.181555 -105.280993) (xy 174.142466 -105.242395) (xy 174.109318 -105.198588)
			(xy 174.082796 -105.150481) (xy 174.06345 -105.099066) (xy 174.051679 -105.045407) (xy 174.047726 -104.990616)
			(xy 174.051674 -104.935824) (xy 174.063441 -104.882164) (xy 174.082783 -104.830748) (xy 174.109301 -104.782638)
			(xy 174.142445 -104.738829) (xy 174.181531 -104.700228) (xy 174.22575 -104.667632) (xy 174.274187 -104.641717)
			(xy 174.29988 -104.631998) (xy 174.337726 -104.618282) (xy 174.3837 -104.55275) (xy 174.3837 -103.808784)
			(xy 174.383238 -103.792756) (xy 174.375254 -103.761711) (xy 174.359792 -103.73363) (xy 174.337828 -103.710283)
			(xy 174.324518 -103.701342) (xy 174.300991 -103.685834) (xy 174.258349 -103.649001) (xy 174.221586 -103.606297)
			(xy 174.191503 -103.558652) (xy 174.168753 -103.507101) (xy 174.15383 -103.452766) (xy 174.147059 -103.396826)
			(xy 174.148587 -103.340499) (xy 174.158381 -103.285009) (xy 174.166784 -103.258112) (xy 174.173482 -103.236375)
			(xy 174.17993 -103.191354) (xy 174.178268 -103.145904) (xy 174.168549 -103.101474) (xy 174.151082 -103.059481)
			(xy 174.126424 -103.021265) (xy 174.095363 -102.988043) (xy 174.058888 -102.960876) (xy 174.038768 -102.950264)
			(xy 174.014678 -102.937793) (xy 173.969976 -102.907063) (xy 173.930077 -102.870312) (xy 173.895785 -102.828281)
			(xy 173.867793 -102.781816) (xy 173.846663 -102.731855) (xy 173.832822 -102.679405) (xy 173.826549 -102.625524)
			(xy 173.827971 -102.571297) (xy 173.837059 -102.517819) (xy 173.85363 -102.466166) (xy 173.877349 -102.417381)
			(xy 173.907739 -102.372448) (xy 173.944186 -102.332271) (xy 173.985956 -102.297662) (xy 174.032207 -102.269317)
			(xy 174.082006 -102.247809) (xy 174.13435 -102.233571) (xy 174.161196 -102.229666) (xy 174.183928 -102.226318)
			(xy 174.227746 -102.212503) (xy 174.268368 -102.191038) (xy 174.304469 -102.162621) (xy 174.334876 -102.128179)
			(xy 174.358597 -102.088832) (xy 174.37486 -102.045863) (xy 174.383135 -102.00067) (xy 174.3837 -101.977698)
			(xy 174.3837 -101.411532) (xy 174.335948 -101.345492) (xy 174.297086 -101.332284) (xy 174.270684 -101.322923)
			(xy 174.22074 -101.297558) (xy 174.175043 -101.265162) (xy 174.134575 -101.22643) (xy 174.100207 -101.182196)
			(xy 174.072679 -101.133411) (xy 174.052582 -101.081125) (xy 174.040348 -101.026461) (xy 174.036241 -100.970596)
			(xy 174.04035 -100.914731) (xy 174.052584 -100.860068) (xy 174.072682 -100.807782) (xy 174.100212 -100.758997)
			(xy 174.13458 -100.714764) (xy 174.175049 -100.676033) (xy 174.220746 -100.643638) (xy 174.270691 -100.618274)
			(xy 174.297086 -100.608892) (xy 174.335948 -100.595684) (xy 174.3837 -100.529644) (xy 174.3837 -100.18268)
			(xy 174.383212 -100.166821) (xy 174.375378 -100.136085) (xy 174.3602 -100.108234) (xy 174.338617 -100.084991)
			(xy 174.311965 -100.067795) (xy 174.297086 -100.062284) (xy 174.270684 -100.052923) (xy 174.22074 -100.027558)
			(xy 174.175043 -99.995162) (xy 174.134575 -99.95643) (xy 174.100207 -99.912196) (xy 174.072679 -99.863411)
			(xy 174.052582 -99.811125) (xy 174.040348 -99.756461) (xy 174.036241 -99.700596) (xy 174.04035 -99.644731)
			(xy 174.052584 -99.590068) (xy 174.072682 -99.537782) (xy 174.100212 -99.488997) (xy 174.13458 -99.444764)
			(xy 174.175049 -99.406033) (xy 174.220746 -99.373638) (xy 174.270691 -99.348274) (xy 174.297086 -99.338892)
			(xy 174.311967 -99.333388) (xy 174.338617 -99.316189) (xy 174.360197 -99.292944) (xy 174.375371 -99.265092)
			(xy 174.3832 -99.234355) (xy 174.3837 -99.218496) (xy 174.3837 -98.426778) (xy 174.372016 -98.401378)
			(xy 174.361009 -98.376287) (xy 174.345492 -98.32374) (xy 174.337652 -98.269513) (xy 174.337649 -98.214723)
			(xy 174.345484 -98.160496) (xy 174.360996 -98.107947) (xy 174.372016 -98.082862) (xy 174.3837 -98.057462)
			(xy 174.3837 -97.427034) (xy 172.555154 -95.598488) (xy 172.538399 -95.582457) (xy 172.50021 -95.55616)
			(xy 172.457883 -95.53723) (xy 172.412824 -95.526296) (xy 172.366528 -95.52372) (xy 172.320534 -95.529588)
			(xy 172.276369 -95.543706) (xy 172.235498 -95.565604) (xy 172.21708 -95.579692) (xy 172.195002 -95.596665)
			(xy 172.14689 -95.624704) (xy 172.095212 -95.645451) (xy 172.041067 -95.658465) (xy 171.985606 -95.663469)
			(xy 171.930006 -95.660356) (xy 171.87545 -95.649194) (xy 171.823095 -95.630219) (xy 171.774056 -95.603834)
			(xy 171.729374 -95.5706) (xy 171.689997 -95.531224) (xy 171.656764 -95.486541) (xy 171.63038 -95.437501)
			(xy 171.611405 -95.385147) (xy 171.600243 -95.33059) (xy 171.597131 -95.274991) (xy 171.602136 -95.219529)
			(xy 171.61515 -95.165385) (xy 171.635897 -95.113707) (xy 171.663937 -95.065595) (xy 171.680886 -95.043498)
			(xy 171.694948 -95.025065) (xy 171.716825 -94.984196) (xy 171.730928 -94.940036) (xy 171.736788 -94.894051)
			(xy 171.734211 -94.847766) (xy 171.723282 -94.802716) (xy 171.704365 -94.760395) (xy 171.678086 -94.722206)
			(xy 171.66209 -94.705424) (xy 171.200064 -94.243398) (xy 165.220142 -94.243398) (xy 165.197042 -94.243928)
			(xy 165.15161 -94.252325) (xy 165.108444 -94.268796) (xy 165.068967 -94.292799) (xy 165.034478 -94.323541)
			(xy 165.006115 -94.360012) (xy 164.984811 -94.401008) (xy 164.971268 -94.44518) (xy 164.965933 -94.491073)
			(xy 164.96898 -94.537173) (xy 164.980311 -94.581964) (xy 164.999551 -94.623969) (xy 165.01237 -94.643194)
			(xy 165.027915 -94.666222) (xy 165.052894 -94.715848) (xy 165.070413 -94.768571) (xy 165.080102 -94.823278)
			(xy 165.081757 -94.878811) (xy 165.075342 -94.933998) (xy 165.060993 -94.987671) (xy 165.039013 -95.038696)
			(xy 165.009868 -95.085996) (xy 164.974172 -95.128569) (xy 164.93268 -95.165517) (xy 164.88627 -95.196058)
			(xy 164.835922 -95.219548) (xy 164.7827 -95.235489) (xy 164.727729 -95.243544) (xy 164.672171 -95.243544)
			(xy 164.6172 -95.235489) (xy 164.563978 -95.219548) (xy 164.51363 -95.196058) (xy 164.46722 -95.165517)
			(xy 164.425728 -95.128569) (xy 164.390032 -95.085996) (xy 164.360887 -95.038696) (xy 164.338907 -94.987671)
			(xy 164.324558 -94.933998) (xy 164.318143 -94.878811) (xy 164.319798 -94.823278) (xy 164.329487 -94.768571)
			(xy 164.347006 -94.715848) (xy 164.371985 -94.666222) (xy 164.38753 -94.643194) (xy 164.400375 -94.623984)
			(xy 164.419617 -94.581974) (xy 164.430949 -94.537178) (xy 164.433998 -94.491072) (xy 164.428662 -94.445174)
			(xy 164.415117 -94.400997) (xy 164.393811 -94.359995) (xy 164.365444 -94.323521) (xy 164.330951 -94.292774)
			(xy 164.291469 -94.268769) (xy 164.248298 -94.252296) (xy 164.202861 -94.243898) (xy 164.179758 -94.243398)
			(xy 153.5303 -94.243398) (xy 135.133588 -75.846686) (xy 122.749818 -75.846686) (xy 117.18798 -70.284848)
			(xy 117.18798 -64.856614) (xy 117.187497 -64.834393) (xy 117.179719 -64.790637) (xy 117.164451 -64.7489)
			(xy 117.142158 -64.710453) (xy 117.113518 -64.676469) (xy 117.079406 -64.647984) (xy 117.040859 -64.625864)
			(xy 116.999053 -64.610784) (xy 116.955262 -64.603204) (xy 116.91082 -64.603355) (xy 116.867081 -64.611231)
			(xy 116.825379 -64.626594) (xy 116.805964 -64.637412) (xy 116.782259 -64.650706) (xy 116.731917 -64.671186)
			(xy 116.679178 -64.684315) (xy 116.62511 -64.689827) (xy 116.597938 -64.689228) (xy 116.575672 -64.688801)
			(xy 116.531547 -64.694807) (xy 116.489145 -64.708413) (xy 116.449764 -64.729201) (xy 116.414609 -64.756536)
			(xy 116.384757 -64.78958) (xy 116.361123 -64.827322) (xy 116.344429 -64.868606) (xy 116.335187 -64.912168)
			(xy 116.33368 -64.956673) (xy 116.336318 -64.978788) (xy 116.339203 -65.001407) (xy 116.340216 -65.046994)
			(xy 116.33835 -65.06972) (xy 116.335223 -65.096758) (xy 116.322287 -65.149627) (xy 116.301972 -65.200122)
			(xy 116.274689 -65.247218) (xy 116.240992 -65.289961) (xy 116.201564 -65.327483) (xy 116.157206 -65.359023)
			(xy 116.108817 -65.383942) (xy 116.057378 -65.401733) (xy 116.003934 -65.412036) (xy 115.949568 -65.414643)
			(xy 115.895384 -65.409499) (xy 115.842479 -65.396709) (xy 115.791929 -65.376533) (xy 115.76812 -65.363344)
			(xy 115.743916 -65.348833) (xy 115.699681 -65.313795) (xy 115.661087 -65.272625) (xy 115.628979 -65.226219)
			(xy 115.604055 -65.17559) (xy 115.586859 -65.121843) (xy 115.577767 -65.066149) (xy 115.576977 -65.009724)
			(xy 115.584506 -64.953797) (xy 115.60019 -64.899589) (xy 115.623686 -64.848282) (xy 115.654482 -64.800996)
			(xy 115.691907 -64.75876) (xy 115.735145 -64.722497) (xy 115.783251 -64.692998) (xy 115.835178 -64.670905)
			(xy 115.889792 -64.656702) (xy 115.945903 -64.650696) (xy 115.974114 -64.651382) (xy 115.996378 -64.651804)
			(xy 116.040496 -64.645791) (xy 116.08289 -64.632181) (xy 116.122264 -64.611391) (xy 116.157412 -64.584056)
			(xy 116.187258 -64.551014) (xy 116.210888 -64.513275) (xy 116.227579 -64.471996) (xy 116.23682 -64.42844)
			(xy 116.238329 -64.38394) (xy 116.235734 -64.361822) (xy 116.232237 -64.333515) (xy 116.232686 -64.276481)
			(xy 116.24162 -64.220149) (xy 116.258839 -64.165775) (xy 116.283959 -64.114569) (xy 116.316422 -64.067673)
			(xy 116.355503 -64.026131) (xy 116.400332 -63.990869) (xy 116.44991 -63.962673) (xy 116.503133 -63.94217)
			(xy 116.558815 -63.929817) (xy 116.615715 -63.925891) (xy 116.672566 -63.930477) (xy 116.728101 -63.943474)
			(xy 116.781082 -63.964592) (xy 116.805964 -63.978536) (xy 116.825389 -63.989344) (xy 116.86709 -64.004731)
			(xy 116.910833 -64.012628) (xy 116.955282 -64.012794) (xy 116.999082 -64.005222) (xy 117.040896 -63.990145)
			(xy 117.07945 -63.968023) (xy 117.113566 -63.93953) (xy 117.142203 -63.905535) (xy 117.164489 -63.867076)
			(xy 117.179744 -63.825326) (xy 117.187501 -63.781559) (xy 117.18798 -63.759334) (xy 117.18798 -63.094362)
			(xy 117.187526 -63.07246) (xy 117.180021 -63.029305) (xy 117.165224 -62.988077) (xy 117.143572 -62.949999)
			(xy 117.115709 -62.9162) (xy 117.08246 -62.887683) (xy 117.044812 -62.865293) (xy 117.00388 -62.849694)
			(xy 116.96088 -62.841349) (xy 116.917085 -62.840505) (xy 116.895372 -62.84341) (xy 116.868206 -62.847098)
			(xy 116.813386 -62.847572) (xy 116.759062 -62.840197) (xy 116.706353 -62.825125) (xy 116.656342 -62.802665)
			(xy 116.610061 -62.77328) (xy 116.56846 -62.737574) (xy 116.532397 -62.696284) (xy 116.502613 -62.650258)
			(xy 116.479722 -62.600443) (xy 116.464194 -62.547866) (xy 116.45635 -62.493608) (xy 116.456351 -62.438786)
			(xy 116.464196 -62.384528) (xy 116.479724 -62.331951) (xy 116.502616 -62.282137) (xy 116.532401 -62.236111)
			(xy 116.568464 -62.194821) (xy 116.610066 -62.159117) (xy 116.656348 -62.129733) (xy 116.706358 -62.107273)
			(xy 116.759068 -62.092201) (xy 116.813392 -62.084827) (xy 116.868212 -62.085302) (xy 116.895372 -62.08903)
			(xy 116.917082 -62.091897) (xy 116.960862 -62.091021) (xy 117.003844 -62.082656) (xy 117.044756 -62.067047)
			(xy 117.082387 -62.044658) (xy 117.115625 -62.016151) (xy 117.143485 -61.982369) (xy 117.165144 -61.944312)
			(xy 117.17996 -61.903107) (xy 117.187495 -61.859972) (xy 117.18798 -61.838078) (xy 117.18798 -60.949078)
			(xy 116.860574 -60.621672) (xy 113.120424 -60.621672) (xy 113.098229 -60.622152) (xy 113.054521 -60.629912)
			(xy 113.012827 -60.645147) (xy 112.974413 -60.667394) (xy 112.940448 -60.695976) (xy 112.911965 -60.730025)
			(xy 112.889831 -60.768504) (xy 112.874718 -60.810244) (xy 112.867087 -60.853974) (xy 112.867169 -60.898365)
			(xy 112.874962 -60.942066) (xy 112.890229 -60.98375) (xy 112.900968 -61.00318) (xy 112.915187 -61.027238)
			(xy 112.937202 -61.078603) (xy 112.951491 -61.132628) (xy 112.957749 -61.18816) (xy 112.955842 -61.244011)
			(xy 112.945811 -61.298987) (xy 112.92787 -61.351912) (xy 112.902402 -61.401656) (xy 112.869954 -61.447153)
			(xy 112.831217 -61.487433) (xy 112.78702 -61.521633) (xy 112.738309 -61.549022) (xy 112.686124 -61.569015)
			(xy 112.631582 -61.581185) (xy 112.575848 -61.58527) (xy 112.520114 -61.581185) (xy 112.465572 -61.569015)
			(xy 112.413387 -61.549022) (xy 112.364676 -61.521633) (xy 112.320479 -61.487433) (xy 112.281742 -61.447153)
			(xy 112.249294 -61.401656) (xy 112.223826 -61.351912) (xy 112.205885 -61.298987) (xy 112.195854 -61.244011)
			(xy 112.193947 -61.18816) (xy 112.200205 -61.132628) (xy 112.214494 -61.078603) (xy 112.236509 -61.027238)
			(xy 112.250728 -61.00318) (xy 112.261475 -60.983755) (xy 112.276747 -60.942076) (xy 112.284545 -60.898377)
			(xy 112.284629 -60.853988) (xy 112.276998 -60.810259) (xy 112.261884 -60.768522) (xy 112.239747 -60.730047)
			(xy 112.21126 -60.696004) (xy 112.177291 -60.667429) (xy 112.138873 -60.645193) (xy 112.097175 -60.629971)
			(xy 112.053466 -60.622228) (xy 112.031272 -60.621672) (xy 100.23602 -60.621672) (xy 98.473783 -62.383909)
			(xy 106.020631 -62.383909) (xy 106.027807 -62.329349) (xy 106.042749 -62.276386) (xy 106.065147 -62.22612)
			(xy 106.094537 -62.179595) (xy 106.112056 -62.158372) (xy 106.12733 -62.139657) (xy 106.151252 -62.097696)
			(xy 106.166816 -62.051972) (xy 106.17346 -62.004131) (xy 106.170946 -61.955896) (xy 106.159364 -61.909004)
			(xy 106.139131 -61.865146) (xy 106.125518 -61.84519) (xy 106.109846 -61.822572) (xy 106.084576 -61.773689)
			(xy 106.066593 -61.721682) (xy 106.05627 -61.66763) (xy 106.053823 -61.612656) (xy 106.059301 -61.557901)
			(xy 106.072591 -61.504502) (xy 106.093417 -61.453566) (xy 106.121346 -61.406153) (xy 106.1558 -61.363245)
			(xy 106.196062 -61.325733) (xy 106.241296 -61.294397) (xy 106.290565 -61.269887) (xy 106.342844 -61.252712)
			(xy 106.397049 -61.243228) (xy 106.452054 -61.241632) (xy 106.506718 -61.247957) (xy 106.559905 -61.262072)
			(xy 106.610512 -61.283684) (xy 106.657487 -61.312345) (xy 106.699857 -61.347458) (xy 106.73674 -61.388296)
			(xy 106.767372 -61.434011) (xy 106.791116 -61.483653) (xy 106.80748 -61.536192) (xy 106.816124 -61.590537)
			(xy 106.816868 -61.645561) (xy 106.809697 -61.70012) (xy 106.79476 -61.753082) (xy 106.772367 -61.803348)
			(xy 106.742982 -61.849874) (xy 106.725466 -61.871098) (xy 106.710219 -61.889835) (xy 106.686293 -61.931789)
			(xy 106.670725 -61.977509) (xy 106.664076 -62.025346) (xy 106.66558 -62.054241) (xy 106.983179 -62.054241)
			(xy 106.986858 -61.999477) (xy 106.998347 -61.945805) (xy 107.017409 -61.894333) (xy 107.043651 -61.846124)
			(xy 107.07653 -61.802174) (xy 107.115368 -61.763389) (xy 107.159363 -61.73057) (xy 107.207608 -61.704394)
			(xy 107.259105 -61.685402) (xy 107.312793 -61.673986) (xy 107.340146 -61.671708) (xy 107.362262 -61.669763)
			(xy 107.405363 -61.659136) (xy 107.445964 -61.641184) (xy 107.482829 -61.616453) (xy 107.514838 -61.585694)
			(xy 107.541017 -61.549842) (xy 107.560571 -61.509988) (xy 107.572905 -61.467343) (xy 107.577644 -61.423205)
			(xy 107.574643 -61.378914) (xy 107.569762 -61.357256) (xy 107.563606 -61.330507) (xy 107.558191 -61.275885)
			(xy 107.560659 -61.221051) (xy 107.570959 -61.167136) (xy 107.588879 -61.115254) (xy 107.614048 -61.066475)
			(xy 107.645948 -61.021807) (xy 107.68392 -60.982171) (xy 107.72718 -60.948385) (xy 107.774834 -60.921147)
			(xy 107.8259 -60.90102) (xy 107.879324 -60.888417) (xy 107.934002 -60.883601) (xy 107.988806 -60.88667)
			(xy 108.042604 -60.89756) (xy 108.094287 -60.916048) (xy 108.142786 -60.94175) (xy 108.187103 -60.974138)
			(xy 108.22632 -61.012542) (xy 108.25963 -61.056169) (xy 108.286343 -61.10412) (xy 108.30591 -61.155403)
			(xy 108.317926 -61.208962) (xy 108.322143 -61.263689) (xy 108.318474 -61.318456) (xy 108.306994 -61.372132)
			(xy 108.287941 -61.423609) (xy 108.261709 -61.471824) (xy 108.228837 -61.515782) (xy 108.190006 -61.554577)
			(xy 108.146016 -61.587406) (xy 108.097776 -61.613593) (xy 108.046281 -61.632596) (xy 107.992594 -61.644024)
			(xy 107.96524 -61.646308) (xy 107.943121 -61.648222) (xy 107.900017 -61.658852) (xy 107.859415 -61.676807)
			(xy 107.822549 -61.701543) (xy 107.79054 -61.732305) (xy 107.764361 -61.768161) (xy 107.744808 -61.808018)
			(xy 107.732476 -61.850666) (xy 107.727739 -61.894808) (xy 107.730741 -61.939101) (xy 107.735624 -61.96076)
			(xy 107.741678 -61.987534) (xy 107.747088 -62.042154) (xy 107.744615 -62.096986) (xy 107.734309 -62.150898)
			(xy 107.716384 -62.202777) (xy 107.69121 -62.251551) (xy 107.671405 -62.279276) (xy 108.432852 -62.279276)
			(xy 108.436923 -62.223654) (xy 108.449049 -62.169217) (xy 108.468972 -62.117126) (xy 108.496268 -62.068491)
			(xy 108.530354 -62.024348) (xy 108.570503 -61.985639) (xy 108.615861 -61.953188) (xy 108.665461 -61.927687)
			(xy 108.718245 -61.90968) (xy 108.773088 -61.89955) (xy 108.828822 -61.897513) (xy 108.884259 -61.903613)
			(xy 108.938216 -61.917719) (xy 108.989545 -61.939531) (xy 109.037151 -61.968585) (xy 109.080019 -62.00426)
			(xy 109.117236 -62.045797) (xy 109.148009 -62.09231) (xy 109.171681 -62.142807) (xy 109.187749 -62.196214)
			(xy 109.195869 -62.25139) (xy 109.196378 -62.279276) (xy 109.195869 -62.307162) (xy 109.187749 -62.362338)
			(xy 109.171681 -62.415745) (xy 109.148009 -62.466242) (xy 109.117236 -62.512755) (xy 109.080019 -62.554292)
			(xy 109.037151 -62.589967) (xy 108.989545 -62.619021) (xy 108.938216 -62.640833) (xy 108.884259 -62.654939)
			(xy 108.828822 -62.661039) (xy 108.773088 -62.659002) (xy 108.718245 -62.648872) (xy 108.665461 -62.630865)
			(xy 108.615861 -62.605364) (xy 108.570503 -62.572913) (xy 108.530354 -62.534204) (xy 108.496268 -62.490061)
			(xy 108.468972 -62.441426) (xy 108.449049 -62.389335) (xy 108.436923 -62.334898) (xy 108.432852 -62.279276)
			(xy 107.671405 -62.279276) (xy 107.659306 -62.296214) (xy 107.62133 -62.335844) (xy 107.578068 -62.369624)
			(xy 107.530411 -62.396854) (xy 107.479344 -62.416975) (xy 107.425921 -62.429569) (xy 107.371244 -62.434378)
			(xy 107.316442 -62.431301) (xy 107.262647 -62.420403) (xy 107.210969 -62.401909) (xy 107.162475 -62.376199)
			(xy 107.118165 -62.343806) (xy 107.078955 -62.305397) (xy 107.045654 -62.261765) (xy 107.018949 -62.213812)
			(xy 106.999392 -62.162526) (xy 106.987386 -62.108967) (xy 106.983179 -62.054241) (xy 106.66558 -62.054241)
			(xy 106.666586 -62.073579) (xy 106.678164 -62.120468) (xy 106.698392 -62.164325) (xy 106.712004 -62.18428)
			(xy 106.727651 -62.206918) (xy 106.752923 -62.255802) (xy 106.770908 -62.30781) (xy 106.781232 -62.361864)
			(xy 106.78368 -62.416839) (xy 106.778202 -62.471596) (xy 106.764912 -62.524998) (xy 106.744086 -62.575935)
			(xy 106.716155 -62.62335) (xy 106.6817 -62.66626) (xy 106.641436 -62.703772) (xy 106.5962 -62.735108)
			(xy 106.546929 -62.759618) (xy 106.494647 -62.776793) (xy 106.44044 -62.786276) (xy 106.385433 -62.78787)
			(xy 106.330768 -62.781543) (xy 106.277579 -62.767425) (xy 106.226971 -62.74581) (xy 106.179995 -62.717146)
			(xy 106.137626 -62.682029) (xy 106.100744 -62.641188) (xy 106.070114 -62.59547) (xy 106.046372 -62.545824)
			(xy 106.030011 -62.493282) (xy 106.021371 -62.438935) (xy 106.020631 -62.383909) (xy 98.473783 -62.383909)
			(xy 96.757158 -64.100534) (xy 100.775618 -64.100534) (xy 100.778725 -64.045621) (xy 100.789685 -63.991724)
			(xy 100.80827 -63.939958) (xy 100.834097 -63.891398) (xy 100.866629 -63.84705) (xy 100.905192 -63.807833)
			(xy 100.948986 -63.77456) (xy 100.997105 -63.74792) (xy 101.022658 -63.737744) (xy 101.044982 -63.728761)
			(xy 101.085966 -63.703552) (xy 101.121474 -63.671081) (xy 101.150238 -63.632508) (xy 101.171229 -63.589212)
			(xy 101.183699 -63.542739) (xy 101.187201 -63.494751) (xy 101.184964 -63.47079) (xy 101.182248 -63.44342)
			(xy 101.183788 -63.38844) (xy 101.193208 -63.334251) (xy 101.210311 -63.281977) (xy 101.234744 -63.2327)
			(xy 101.265999 -63.187443) (xy 101.30343 -63.147143) (xy 101.346259 -63.112636) (xy 101.3936 -63.084637)
			(xy 101.444472 -63.063726) (xy 101.497818 -63.050337) (xy 101.552535 -63.044747) (xy 101.607487 -63.047072)
			(xy 101.661535 -63.057265) (xy 101.71356 -63.075113) (xy 101.762482 -63.100247) (xy 101.807289 -63.132146)
			(xy 101.84705 -63.170149) (xy 101.880942 -63.213467) (xy 101.908262 -63.261203) (xy 101.928444 -63.312368)
			(xy 101.941069 -63.365901) (xy 101.945876 -63.420691) (xy 101.942766 -63.475605) (xy 101.931802 -63.529502)
			(xy 101.913213 -63.581266) (xy 101.887382 -63.629825) (xy 101.854846 -63.674171) (xy 101.845375 -63.683801)
			(xy 106.879397 -63.683801) (xy 106.881129 -63.628251) (xy 106.890902 -63.57354) (xy 106.90851 -63.520826)
			(xy 106.933581 -63.471224) (xy 106.965583 -63.425785) (xy 107.003839 -63.38547) (xy 107.047539 -63.351132)
			(xy 107.095759 -63.323498) (xy 107.147479 -63.303153) (xy 107.201603 -63.290527) (xy 107.256986 -63.285888)
			(xy 107.312457 -63.289333) (xy 107.36684 -63.300791) (xy 107.418986 -63.320017) (xy 107.46779 -63.346606)
			(xy 107.51222 -63.379995) (xy 107.551335 -63.419477) (xy 107.584308 -63.464217) (xy 107.594388 -63.483137)
			(xy 108.074439 -63.483137) (xy 108.081433 -63.428424) (xy 108.096234 -63.375289) (xy 108.118531 -63.324839)
			(xy 108.147861 -63.278126) (xy 108.183613 -63.236123) (xy 108.22504 -63.199706) (xy 108.271279 -63.169634)
			(xy 108.321367 -63.146534) (xy 108.37426 -63.130888) (xy 108.428854 -63.123022) (xy 108.484012 -63.123099)
			(xy 108.538583 -63.131118) (xy 108.591432 -63.146912) (xy 108.641455 -63.170152) (xy 108.68761 -63.200352)
			(xy 108.728935 -63.236885) (xy 108.748043 -63.259462) (xy 114.972082 -63.259462) (xy 114.976153 -63.20384)
			(xy 114.988279 -63.149403) (xy 115.008202 -63.097312) (xy 115.035498 -63.048677) (xy 115.069584 -63.004534)
			(xy 115.109733 -62.965825) (xy 115.155091 -62.933374) (xy 115.204691 -62.907873) (xy 115.257475 -62.889866)
			(xy 115.312318 -62.879736) (xy 115.368052 -62.877699) (xy 115.423489 -62.883799) (xy 115.477446 -62.897905)
			(xy 115.528775 -62.919717) (xy 115.576381 -62.948771) (xy 115.619249 -62.984446) (xy 115.656466 -63.025983)
			(xy 115.687239 -63.072496) (xy 115.710911 -63.122993) (xy 115.726979 -63.1764) (xy 115.735099 -63.231576)
			(xy 115.735608 -63.259462) (xy 115.735099 -63.287348) (xy 115.726979 -63.342524) (xy 115.710911 -63.395931)
			(xy 115.687239 -63.446428) (xy 115.656466 -63.492941) (xy 115.619249 -63.534478) (xy 115.576381 -63.570153)
			(xy 115.528775 -63.599207) (xy 115.477446 -63.621019) (xy 115.423489 -63.635125) (xy 115.368052 -63.641225)
			(xy 115.312318 -63.639188) (xy 115.257475 -63.629058) (xy 115.204691 -63.611051) (xy 115.155091 -63.58555)
			(xy 115.109733 -63.553099) (xy 115.069584 -63.51439) (xy 115.035498 -63.470247) (xy 115.008202 -63.421612)
			(xy 114.988279 -63.369521) (xy 114.976153 -63.315084) (xy 114.972082 -63.259462) (xy 108.748043 -63.259462)
			(xy 108.764569 -63.278988) (xy 108.793769 -63.325783) (xy 108.815925 -63.376295) (xy 108.830577 -63.429471)
			(xy 108.837418 -63.484203) (xy 108.836307 -63.53935) (xy 108.827266 -63.593762) (xy 108.810484 -63.646305)
			(xy 108.791413 -63.68542) (xy 111.779302 -63.68542) (xy 111.783373 -63.629798) (xy 111.795499 -63.575361)
			(xy 111.815422 -63.52327) (xy 111.842718 -63.474635) (xy 111.876804 -63.430492) (xy 111.916953 -63.391783)
			(xy 111.962311 -63.359332) (xy 112.011911 -63.333831) (xy 112.064695 -63.315824) (xy 112.119538 -63.305694)
			(xy 112.175272 -63.303657) (xy 112.230709 -63.309757) (xy 112.284666 -63.323863) (xy 112.335995 -63.345675)
			(xy 112.383601 -63.374729) (xy 112.426469 -63.410404) (xy 112.463686 -63.451941) (xy 112.494459 -63.498454)
			(xy 112.518131 -63.548951) (xy 112.534199 -63.602358) (xy 112.542319 -63.657534) (xy 112.542828 -63.68542)
			(xy 112.542319 -63.713306) (xy 112.534199 -63.768482) (xy 112.518131 -63.821889) (xy 112.494459 -63.872386)
			(xy 112.463686 -63.918899) (xy 112.426469 -63.960436) (xy 112.383601 -63.996111) (xy 112.335995 -64.025165)
			(xy 112.284666 -64.046977) (xy 112.230709 -64.061083) (xy 112.175272 -64.067183) (xy 112.119538 -64.065146)
			(xy 112.064695 -64.055016) (xy 112.011911 -64.037009) (xy 111.962311 -64.011508) (xy 111.916953 -63.979057)
			(xy 111.876804 -63.940348) (xy 111.842718 -63.896205) (xy 111.815422 -63.84757) (xy 111.795499 -63.795479)
			(xy 111.783373 -63.741042) (xy 111.779302 -63.68542) (xy 108.791413 -63.68542) (xy 108.786311 -63.695884)
			(xy 108.771182 -63.718948) (xy 108.758616 -63.738189) (xy 108.739992 -63.780198) (xy 108.729219 -63.82487)
			(xy 108.726649 -63.870751) (xy 108.732364 -63.916347) (xy 108.746179 -63.960174) (xy 108.767644 -64.000805)
			(xy 108.79606 -64.036918) (xy 108.830503 -64.067337) (xy 108.849922 -64.079628) (xy 108.873267 -64.094318)
			(xy 108.915927 -64.129276) (xy 108.953108 -64.170013) (xy 108.984036 -64.21568) (xy 109.008065 -64.265324)
			(xy 109.024695 -64.317911) (xy 109.033579 -64.372345) (xy 109.034532 -64.427491) (xy 109.027534 -64.482199)
			(xy 109.01273 -64.535329) (xy 108.99043 -64.585774) (xy 108.961099 -64.632482) (xy 108.925347 -64.674479)
			(xy 108.88392 -64.71089) (xy 108.837681 -64.740956) (xy 108.787595 -64.76405) (xy 108.734705 -64.779691)
			(xy 108.680114 -64.787553) (xy 108.62496 -64.787471) (xy 108.570393 -64.779448) (xy 108.51755 -64.763651)
			(xy 108.467532 -64.740409) (xy 108.421383 -64.710207) (xy 108.380063 -64.673674) (xy 108.344435 -64.631571)
			(xy 108.315242 -64.584777) (xy 108.293091 -64.534267) (xy 108.278445 -64.481093) (xy 108.271608 -64.426365)
			(xy 108.272723 -64.371222) (xy 108.281768 -64.316815) (xy 108.298553 -64.264277) (xy 108.322729 -64.214704)
			(xy 108.337858 -64.191642) (xy 108.350423 -64.172401) (xy 108.369043 -64.130392) (xy 108.379812 -64.08572)
			(xy 108.38238 -64.039841) (xy 108.376664 -63.994246) (xy 108.36285 -63.950421) (xy 108.341387 -63.90979)
			(xy 108.312974 -63.873676) (xy 108.278535 -63.843254) (xy 108.259118 -63.830962) (xy 108.235741 -63.816321)
			(xy 108.193075 -63.781364) (xy 108.155888 -63.740627) (xy 108.124954 -63.694959) (xy 108.10092 -63.645313)
			(xy 108.084285 -63.592724) (xy 108.075396 -63.538287) (xy 108.074439 -63.483137) (xy 107.594388 -63.483137)
			(xy 107.610441 -63.513267) (xy 107.62918 -63.565589) (xy 107.640129 -63.620077) (xy 107.643057 -63.675577)
			(xy 107.637902 -63.730915) (xy 107.624771 -63.784919) (xy 107.603945 -63.836446) (xy 107.590336 -63.86068)
			(xy 107.579433 -63.880105) (xy 107.563961 -63.921876) (xy 107.556013 -63.965706) (xy 107.555833 -64.010249)
			(xy 107.563427 -64.054142) (xy 107.578562 -64.096036) (xy 107.600772 -64.134648) (xy 107.61472 -64.152018)
			(xy 107.632105 -64.173702) (xy 107.661209 -64.221044) (xy 107.683136 -64.272109) (xy 107.697422 -64.325814)
			(xy 107.703765 -64.381024) (xy 107.702029 -64.43657) (xy 107.692253 -64.491276) (xy 107.674642 -64.543985)
			(xy 107.64957 -64.59358) (xy 107.617568 -64.639013) (xy 107.579311 -64.679322) (xy 107.535611 -64.713654)
			(xy 107.487392 -64.741281) (xy 107.435675 -64.76162) (xy 107.381554 -64.77424) (xy 107.326174 -64.778873)
			(xy 107.270709 -64.775422) (xy 107.216331 -64.76396) (xy 107.164191 -64.744729) (xy 107.115394 -64.718136)
			(xy 107.070971 -64.684745) (xy 107.031864 -64.645261) (xy 106.998899 -64.600521) (xy 106.972775 -64.551471)
			(xy 106.954044 -64.49915) (xy 106.943103 -64.444665) (xy 106.940183 -64.389168) (xy 106.945347 -64.333836)
			(xy 106.958484 -64.279838) (xy 106.979317 -64.228318) (xy 106.992928 -64.204088) (xy 107.003759 -64.184625)
			(xy 107.019234 -64.142865) (xy 107.027188 -64.099045) (xy 107.027377 -64.05451) (xy 107.019796 -64.010624)
			(xy 107.004677 -63.968733) (xy 106.982483 -63.930122) (xy 106.968544 -63.91275) (xy 106.951073 -63.891135)
			(xy 106.921965 -63.84379) (xy 106.900033 -63.792723) (xy 106.885743 -63.739015) (xy 106.879397 -63.683801)
			(xy 101.845375 -63.683801) (xy 101.81628 -63.713385) (xy 101.772481 -63.746654) (xy 101.72436 -63.77329)
			(xy 101.698806 -63.783464) (xy 101.676534 -63.792565) (xy 101.635552 -63.817753) (xy 101.600041 -63.850203)
			(xy 101.571272 -63.888755) (xy 101.550271 -63.932032) (xy 101.537788 -63.978488) (xy 101.534271 -64.026463)
			(xy 101.5365 -64.050418) (xy 101.539258 -64.077783) (xy 101.537717 -64.132762) (xy 101.528298 -64.18695)
			(xy 101.511195 -64.239224) (xy 101.486762 -64.288501) (xy 101.473442 -64.307788) (xy 101.967174 -64.307788)
			(xy 101.973818 -64.252569) (xy 101.98841 -64.198901) (xy 102.010638 -64.147919) (xy 102.040034 -64.100705)
			(xy 102.075973 -64.058259) (xy 102.117693 -64.021481) (xy 102.164312 -63.99115) (xy 102.21484 -63.967909)
			(xy 102.268208 -63.952251) (xy 102.323283 -63.944507) (xy 102.378899 -63.944841) (xy 102.433877 -63.953247)
			(xy 102.487052 -63.969546) (xy 102.537297 -63.993393) (xy 102.583548 -64.024282) (xy 102.624823 -64.061559)
			(xy 102.642924 -64.082676) (xy 102.653556 -64.094792) (xy 102.679651 -64.113699) (xy 102.709649 -64.125468)
			(xy 102.741639 -64.12935) (xy 102.773581 -64.125098) (xy 102.803441 -64.112982) (xy 102.81666 -64.103758)
			(xy 102.839028 -64.087754) (xy 102.887382 -64.061552) (xy 102.938999 -64.042567) (xy 102.992807 -64.031191)
			(xy 103.04769 -64.027661) (xy 103.102512 -64.03205) (xy 103.156135 -64.044267) (xy 103.207448 -64.064058)
			(xy 103.255387 -64.091013) (xy 103.298957 -64.124574) (xy 103.337255 -64.164044) (xy 103.369488 -64.208606)
			(xy 103.394988 -64.257335) (xy 103.413224 -64.30922) (xy 103.42382 -64.363187) (xy 103.426556 -64.418116)
			(xy 103.421374 -64.472869) (xy 103.408383 -64.526309) (xy 103.387851 -64.57733) (xy 103.374444 -64.601344)
			(xy 103.36352 -64.621174) (xy 103.348055 -64.663719) (xy 103.340377 -64.708331) (xy 103.340727 -64.753598)
			(xy 103.349097 -64.798085) (xy 103.365219 -64.840385) (xy 103.388585 -64.879157) (xy 103.403146 -64.896492)
			(xy 103.421233 -64.917758) (xy 103.451553 -64.964636) (xy 103.474716 -65.015433) (xy 103.490228 -65.069063)
			(xy 103.497757 -65.124381) (xy 103.497142 -65.180206) (xy 103.488397 -65.235346) (xy 103.471709 -65.288622)
			(xy 103.447433 -65.338896) (xy 103.416088 -65.385095) (xy 103.378344 -65.426231) (xy 103.335008 -65.461427)
			(xy 103.287004 -65.48993) (xy 103.235358 -65.511132) (xy 103.181173 -65.52458) (xy 103.125607 -65.529986)
			(xy 103.069846 -65.527234) (xy 103.015082 -65.516385) (xy 102.962484 -65.497669) (xy 102.913176 -65.471486)
			(xy 102.868211 -65.438396) (xy 102.828549 -65.399105) (xy 102.795038 -65.354453) (xy 102.768393 -65.305393)
			(xy 102.749184 -65.252973) (xy 102.737821 -65.198314) (xy 102.734546 -65.142581) (xy 102.739429 -65.086967)
			(xy 102.752367 -65.032658) (xy 102.773083 -64.980815) (xy 102.786688 -64.956436) (xy 102.797641 -64.93662)
			(xy 102.813108 -64.894072) (xy 102.820787 -64.849456) (xy 102.820433 -64.804185) (xy 102.812058 -64.759694)
			(xy 102.795927 -64.717393) (xy 102.772552 -64.678622) (xy 102.757986 -64.661288) (xy 102.75062 -64.652652)
			(xy 102.739952 -64.640572) (xy 102.713864 -64.621673) (xy 102.683875 -64.609905) (xy 102.651896 -64.606018)
			(xy 102.619961 -64.610258) (xy 102.590104 -64.622356) (xy 102.576884 -64.63157) (xy 102.554283 -64.647781)
			(xy 102.505343 -64.674202) (xy 102.453085 -64.693238) (xy 102.398617 -64.704484) (xy 102.343093 -64.707704)
			(xy 102.28769 -64.702827) (xy 102.233583 -64.689959) (xy 102.181917 -64.66937) (xy 102.133787 -64.641499)
			(xy 102.090215 -64.606935) (xy 102.052122 -64.566411) (xy 102.020317 -64.520785) (xy 101.995473 -64.471026)
			(xy 101.978117 -64.418186) (xy 101.968617 -64.363386) (xy 101.967174 -64.307788) (xy 101.473442 -64.307788)
			(xy 101.455507 -64.333758) (xy 101.418078 -64.374058) (xy 101.375249 -64.408566) (xy 101.327909 -64.436565)
			(xy 101.277038 -64.457477) (xy 101.223693 -64.470867) (xy 101.168977 -64.476458) (xy 101.114025 -64.474135)
			(xy 101.059977 -64.463944) (xy 101.007952 -64.446098) (xy 100.959029 -64.420966) (xy 100.914221 -64.389069)
			(xy 100.874459 -64.351069) (xy 100.840565 -64.307753) (xy 100.813243 -64.260018) (xy 100.793058 -64.208855)
			(xy 100.780429 -64.155324) (xy 100.775618 -64.100534) (xy 96.757158 -64.100534) (xy 95.297244 -65.560448)
			(xy 87.604854 -65.560448) (xy 87.55899 -65.606312) (xy 99.185537 -65.606312) (xy 99.187913 -65.551858)
			(xy 99.198013 -65.498295) (xy 99.215631 -65.446714) (xy 99.240409 -65.398164) (xy 99.271843 -65.353635)
			(xy 99.309293 -65.31403) (xy 99.351997 -65.280158) (xy 99.399086 -65.252705) (xy 99.449602 -65.232233)
			(xy 99.502517 -65.219155) (xy 99.556754 -65.21374) (xy 99.61121 -65.216097) (xy 99.664776 -65.226179)
			(xy 99.716363 -65.243779) (xy 99.764921 -65.26854) (xy 99.809462 -65.299958) (xy 99.83319 -65.32238)
			(xy 101.039936 -65.32238) (xy 101.045899 -65.267988) (xy 101.059574 -65.215006) (xy 101.080679 -65.164522)
			(xy 101.108782 -65.117572) (xy 101.143305 -65.075119) (xy 101.183541 -65.038036) (xy 101.228663 -65.007083)
			(xy 101.277745 -64.982895) (xy 101.329779 -64.965969) (xy 101.383699 -64.956653) (xy 101.438396 -64.955137)
			(xy 101.492748 -64.961453) (xy 101.545641 -64.975471) (xy 101.595987 -64.996903) (xy 101.642754 -65.02531)
			(xy 101.684981 -65.060109) (xy 101.721803 -65.100584) (xy 101.752462 -65.145906) (xy 101.776331 -65.195144)
			(xy 101.792919 -65.247287) (xy 101.801885 -65.301266) (xy 101.803046 -65.355972) (xy 101.796377 -65.410282)
			(xy 101.782016 -65.463082) (xy 101.760258 -65.513288) (xy 101.746304 -65.536826) (xy 101.734309 -65.557231)
			(xy 101.717367 -65.601423) (xy 101.708894 -65.647988) (xy 101.709183 -65.695315) (xy 101.718225 -65.741772)
			(xy 101.726365 -65.762249) (xy 108.284051 -65.762249) (xy 108.28514 -65.707582) (xy 108.29402 -65.653629)
			(xy 108.310512 -65.601497) (xy 108.334276 -65.552253) (xy 108.364827 -65.506905) (xy 108.401537 -65.466383)
			(xy 108.443657 -65.431517) (xy 108.490322 -65.403019) (xy 108.540577 -65.381475) (xy 108.593393 -65.367326)
			(xy 108.647688 -65.360861) (xy 108.70235 -65.362212) (xy 108.756259 -65.371353) (xy 108.808311 -65.388095)
			(xy 108.85744 -65.412096) (xy 108.90264 -65.442864) (xy 108.942985 -65.47977) (xy 108.977648 -65.522057)
			(xy 109.005921 -65.568859) (xy 109.027222 -65.619217) (xy 109.041117 -65.6721) (xy 109.047321 -65.726426)
			(xy 109.045707 -65.78108) (xy 109.036307 -65.834945) (xy 109.019314 -65.886916) (xy 109.009807 -65.906142)
			(xy 111.83315 -65.906142) (xy 111.837221 -65.85052) (xy 111.849347 -65.796083) (xy 111.86927 -65.743992)
			(xy 111.896566 -65.695357) (xy 111.930652 -65.651214) (xy 111.970801 -65.612505) (xy 112.016159 -65.580054)
			(xy 112.065759 -65.554553) (xy 112.118543 -65.536546) (xy 112.173386 -65.526416) (xy 112.22912 -65.524379)
			(xy 112.284557 -65.530479) (xy 112.338514 -65.544585) (xy 112.389843 -65.566397) (xy 112.437449 -65.595451)
			(xy 112.480317 -65.631126) (xy 112.517534 -65.672663) (xy 112.548307 -65.719176) (xy 112.571979 -65.769673)
			(xy 112.588047 -65.82308) (xy 112.596167 -65.878256) (xy 112.596676 -65.906142) (xy 112.596167 -65.934028)
			(xy 112.588047 -65.989204) (xy 112.571979 -66.042611) (xy 112.548307 -66.093108) (xy 112.517534 -66.139621)
			(xy 112.480317 -66.181158) (xy 112.437449 -66.216833) (xy 112.389843 -66.245887) (xy 112.338514 -66.267699)
			(xy 112.284557 -66.281805) (xy 112.22912 -66.287905) (xy 112.173386 -66.285868) (xy 112.118543 -66.275738)
			(xy 112.065759 -66.257731) (xy 112.016159 -66.23223) (xy 111.970801 -66.199779) (xy 111.930652 -66.16107)
			(xy 111.896566 -66.116927) (xy 111.86927 -66.068292) (xy 111.849347 -66.016201) (xy 111.837221 -65.961764)
			(xy 111.83315 -65.906142) (xy 109.009807 -65.906142) (xy 108.995077 -65.935929) (xy 108.97997 -65.95872)
			(xy 108.967341 -65.97784) (xy 108.948582 -66.019643) (xy 108.937615 -66.064131) (xy 108.934797 -66.109865)
			(xy 108.940219 -66.155363) (xy 108.953704 -66.199153) (xy 108.974816 -66.239819) (xy 109.002873 -66.276045)
			(xy 109.019594 -66.291714) (xy 109.039648 -66.3103) (xy 109.074717 -66.352251) (xy 109.103439 -66.398777)
			(xy 109.125226 -66.448927) (xy 109.139631 -66.501673) (xy 109.14636 -66.555936) (xy 109.145274 -66.610603)
			(xy 109.140194 -66.641472) (xy 115.737892 -66.641472) (xy 115.741963 -66.58585) (xy 115.754089 -66.531413)
			(xy 115.774012 -66.479322) (xy 115.801308 -66.430687) (xy 115.835394 -66.386544) (xy 115.875543 -66.347835)
			(xy 115.920901 -66.315384) (xy 115.970501 -66.289883) (xy 116.023285 -66.271876) (xy 116.078128 -66.261746)
			(xy 116.133862 -66.259709) (xy 116.189299 -66.265809) (xy 116.243256 -66.279915) (xy 116.294585 -66.301727)
			(xy 116.342191 -66.330781) (xy 116.385059 -66.366456) (xy 116.422276 -66.407993) (xy 116.453049 -66.454506)
			(xy 116.476721 -66.505003) (xy 116.492789 -66.55841) (xy 116.500909 -66.613586) (xy 116.501418 -66.641472)
			(xy 116.500909 -66.669358) (xy 116.492789 -66.724534) (xy 116.476721 -66.777941) (xy 116.453049 -66.828438)
			(xy 116.422276 -66.874951) (xy 116.385059 -66.916488) (xy 116.342191 -66.952163) (xy 116.294585 -66.981217)
			(xy 116.243256 -67.003029) (xy 116.189299 -67.017135) (xy 116.133862 -67.023235) (xy 116.078128 -67.021198)
			(xy 116.023285 -67.011068) (xy 115.970501 -66.993061) (xy 115.920901 -66.96756) (xy 115.875543 -66.935109)
			(xy 115.835394 -66.8964) (xy 115.801308 -66.852257) (xy 115.774012 -66.803622) (xy 115.754089 -66.751531)
			(xy 115.741963 -66.697094) (xy 115.737892 -66.641472) (xy 109.140194 -66.641472) (xy 109.136395 -66.664555)
			(xy 109.119907 -66.716688) (xy 109.096145 -66.765933) (xy 109.065598 -66.811282) (xy 109.02889 -66.851806)
			(xy 108.986774 -66.886676) (xy 108.940111 -66.915177) (xy 108.889858 -66.936725) (xy 108.837044 -66.950879)
			(xy 108.78275 -66.957349) (xy 108.728089 -66.956003) (xy 108.67418 -66.946869) (xy 108.622126 -66.930133)
			(xy 108.572994 -66.906138) (xy 108.527791 -66.875375) (xy 108.487442 -66.838475) (xy 108.452773 -66.796193)
			(xy 108.424494 -66.749396) (xy 108.403185 -66.699041) (xy 108.389282 -66.64616) (xy 108.38307 -66.591836)
			(xy 108.384675 -66.537182) (xy 108.394066 -66.483316) (xy 108.411049 -66.431343) (xy 108.435278 -66.382326)
			(xy 108.45038 -66.359532) (xy 108.462945 -66.340374) (xy 108.481705 -66.298579) (xy 108.492674 -66.2541)
			(xy 108.495498 -66.208375) (xy 108.490086 -66.162884) (xy 108.476612 -66.119099) (xy 108.455512 -66.078435)
			(xy 108.427469 -66.042209) (xy 108.410756 -66.026538) (xy 108.390758 -66.007889) (xy 108.355689 -65.965938)
			(xy 108.326967 -65.91941) (xy 108.305182 -65.86926) (xy 108.290778 -65.816512) (xy 108.284051 -65.762249)
			(xy 101.726365 -65.762249) (xy 101.735708 -65.785754) (xy 101.761027 -65.825741) (xy 101.776784 -65.843404)
			(xy 101.795118 -65.863716) (xy 101.826361 -65.908635) (xy 101.850866 -65.957558) (xy 101.868127 -66.009481)
			(xy 101.877793 -66.063337) (xy 101.879663 -66.118022) (xy 101.876493 -66.146934) (xy 102.421434 -66.146934)
			(xy 102.425505 -66.091312) (xy 102.437631 -66.036875) (xy 102.457554 -65.984784) (xy 102.48485 -65.936149)
			(xy 102.518936 -65.892006) (xy 102.559085 -65.853297) (xy 102.604443 -65.820846) (xy 102.654043 -65.795345)
			(xy 102.706827 -65.777338) (xy 102.76167 -65.767208) (xy 102.817404 -65.765171) (xy 102.872841 -65.771271)
			(xy 102.926798 -65.785377) (xy 102.978127 -65.807189) (xy 103.025733 -65.836243) (xy 103.068601 -65.871918)
			(xy 103.105818 -65.913455) (xy 103.136591 -65.959968) (xy 103.160263 -66.010465) (xy 103.176331 -66.063872)
			(xy 103.184451 -66.119048) (xy 103.18496 -66.146934) (xy 103.184451 -66.17482) (xy 103.176331 -66.229996)
			(xy 103.160263 -66.283403) (xy 103.136591 -66.3339) (xy 103.105818 -66.380413) (xy 103.068601 -66.42195)
			(xy 103.025733 -66.457625) (xy 102.978127 -66.486679) (xy 102.926798 -66.508491) (xy 102.872841 -66.522597)
			(xy 102.817404 -66.528697) (xy 102.76167 -66.52666) (xy 102.706827 -66.51653) (xy 102.654043 -66.498523)
			(xy 102.604443 -66.473022) (xy 102.559085 -66.440571) (xy 102.518936 -66.401862) (xy 102.48485 -66.357719)
			(xy 102.457554 -66.309084) (xy 102.437631 -66.256993) (xy 102.425505 -66.202556) (xy 102.421434 -66.146934)
			(xy 101.876493 -66.146934) (xy 101.8737 -66.172413) (xy 101.860025 -66.225393) (xy 101.838921 -66.275876)
			(xy 101.810819 -66.322825) (xy 101.776297 -66.365277) (xy 101.736063 -66.40236) (xy 101.690943 -66.433313)
			(xy 101.641863 -66.457501) (xy 101.58983 -66.474427) (xy 101.535912 -66.483745) (xy 101.481217 -66.485262)
			(xy 101.426866 -66.478949) (xy 101.373974 -66.464933) (xy 101.323629 -66.443503) (xy 101.276862 -66.415099)
			(xy 101.234634 -66.380304) (xy 101.197811 -66.339832) (xy 101.16715 -66.294513) (xy 101.143279 -66.245278)
			(xy 101.126688 -66.193137) (xy 101.117718 -66.13916) (xy 101.116554 -66.084456) (xy 101.123218 -66.030147)
			(xy 101.137575 -65.977347) (xy 101.159329 -65.92714) (xy 101.17328 -65.903602) (xy 101.185249 -65.883183)
			(xy 101.202196 -65.838995) (xy 101.210674 -65.792434) (xy 101.210388 -65.745108) (xy 101.20135 -65.698653)
			(xy 101.183871 -65.654673) (xy 101.158556 -65.614687) (xy 101.1428 -65.597024) (xy 101.124487 -65.576692)
			(xy 101.093241 -65.531772) (xy 101.068736 -65.482848) (xy 101.051473 -65.430924) (xy 101.041807 -65.377067)
			(xy 101.039936 -65.32238) (xy 99.83319 -65.32238) (xy 99.849079 -65.337394) (xy 99.882967 -65.380086)
			(xy 99.910436 -65.427166) (xy 99.930926 -65.477675) (xy 99.944022 -65.530585) (xy 99.947222 -65.557654)
			(xy 99.949995 -65.580151) (xy 99.962461 -65.623726) (xy 99.982457 -65.6644) (xy 100.009349 -65.700883)
			(xy 100.042285 -65.732019) (xy 100.08022 -65.756821) (xy 100.121952 -65.774502) (xy 100.166158 -65.784502)
			(xy 100.188776 -65.786) (xy 100.215979 -65.787732) (xy 100.269538 -65.797851) (xy 100.321111 -65.815488)
			(xy 100.369651 -65.840283) (xy 100.414169 -65.871732) (xy 100.453759 -65.909195) (xy 100.487616 -65.951911)
			(xy 100.515051 -65.999009) (xy 100.535506 -66.049531) (xy 100.548564 -66.10245) (xy 100.55396 -66.156688)
			(xy 100.551584 -66.211142) (xy 100.541484 -66.264704) (xy 100.523866 -66.316284) (xy 100.499089 -66.364833)
			(xy 100.467656 -66.409362) (xy 100.430206 -66.448966) (xy 100.387503 -66.482838) (xy 100.340415 -66.51029)
			(xy 100.2899 -66.530763) (xy 100.236987 -66.543841) (xy 100.18275 -66.549256) (xy 100.128295 -66.5469)
			(xy 100.07473 -66.536819) (xy 100.023143 -66.51922) (xy 99.974586 -66.49446) (xy 99.930045 -66.463043)
			(xy 99.890428 -66.425608) (xy 99.85654 -66.382918) (xy 99.82907 -66.335839) (xy 99.808579 -66.285332)
			(xy 99.795483 -66.232423) (xy 99.792282 -66.205354) (xy 99.789498 -66.182859) (xy 99.777034 -66.139284)
			(xy 99.75704 -66.09861) (xy 99.730149 -66.062127) (xy 99.697215 -66.030991) (xy 99.659281 -66.006189)
			(xy 99.61755 -65.988507) (xy 99.573345 -65.978506) (xy 99.550728 -65.977008) (xy 99.523525 -65.975272)
			(xy 99.469965 -65.965153) (xy 99.418391 -65.947517) (xy 99.36985 -65.922722) (xy 99.325331 -65.891272)
			(xy 99.28574 -65.853808) (xy 99.251882 -65.811093) (xy 99.224446 -65.763994) (xy 99.203991 -65.713471)
			(xy 99.190933 -65.660552) (xy 99.185537 -65.606312) (xy 87.55899 -65.606312) (xy 86.181687 -66.983615)
			(xy 105.936346 -66.983615) (xy 105.939367 -66.929173) (xy 105.95011 -66.875716) (xy 105.968357 -66.824334)
			(xy 105.993735 -66.776075) (xy 106.025726 -66.731921) (xy 106.06368 -66.692773) (xy 106.106822 -66.659429)
			(xy 106.154273 -66.632569) (xy 106.205065 -66.612739) (xy 106.258163 -66.600346) (xy 106.285284 -66.59753)
			(xy 106.307906 -66.595074) (xy 106.351816 -66.583151) (xy 106.392898 -66.563595) (xy 106.429837 -66.53703)
			(xy 106.461451 -66.504307) (xy 106.486726 -66.466474) (xy 106.504855 -66.424742) (xy 106.515256 -66.380448)
			(xy 106.516932 -66.357754) (xy 106.51877 -66.330542) (xy 106.529393 -66.277045) (xy 106.547526 -66.225607)
			(xy 106.5728 -66.177275) (xy 106.6047 -66.133035) (xy 106.642575 -66.093789) (xy 106.685654 -66.060337)
			(xy 106.733057 -66.033362) (xy 106.783819 -66.013412) (xy 106.836905 -66.000896) (xy 106.891232 -65.996067)
			(xy 106.945694 -65.999025) (xy 106.999178 -66.009709) (xy 107.050596 -66.027901) (xy 107.098899 -66.053231)
			(xy 107.143102 -66.085182) (xy 107.182305 -66.123102) (xy 107.215707 -66.166219) (xy 107.242628 -66.213654)
			(xy 107.262518 -66.264439) (xy 107.274974 -66.317539) (xy 107.27974 -66.371872) (xy 107.27672 -66.42633)
			(xy 107.265974 -66.479802) (xy 107.247723 -66.531199) (xy 107.222337 -66.579473) (xy 107.190336 -66.623639)
			(xy 107.15237 -66.662798) (xy 107.109215 -66.69615) (xy 107.061749 -66.723016) (xy 107.010942 -66.742849)
			(xy 106.957827 -66.755243) (xy 106.930698 -66.758058) (xy 106.908075 -66.760511) (xy 106.864167 -66.772435)
			(xy 106.823085 -66.791993) (xy 106.786147 -66.818559) (xy 106.754534 -66.851282) (xy 106.729259 -66.889115)
			(xy 106.71113 -66.930846) (xy 106.700727 -66.975141) (xy 106.69905 -66.997834) (xy 106.697133 -67.025033)
			(xy 106.686502 -67.078512) (xy 106.668363 -67.129932) (xy 106.643087 -67.178245) (xy 106.611187 -67.222466)
			(xy 106.573316 -67.261693) (xy 106.530244 -67.295128) (xy 106.48285 -67.322087) (xy 106.432099 -67.342023)
			(xy 106.379027 -67.354528) (xy 106.324715 -67.359347) (xy 106.27027 -67.356383) (xy 106.216802 -67.345696)
			(xy 106.165401 -67.327503) (xy 106.117115 -67.302176) (xy 106.072927 -67.270231) (xy 106.03374 -67.232318)
			(xy 106.00035 -67.189211) (xy 105.97344 -67.141789) (xy 105.953558 -67.091017) (xy 105.941109 -67.037932)
			(xy 105.936346 -66.983615) (xy 86.181687 -66.983615) (xy 85.765169 -67.400133) (xy 113.384991 -67.400133)
			(xy 113.386669 -67.345206) (xy 113.396211 -67.291089) (xy 113.413421 -67.238901) (xy 113.437942 -67.189724)
			(xy 113.469266 -67.144574) (xy 113.506745 -67.104386) (xy 113.549604 -67.069993) (xy 113.596954 -67.042106)
			(xy 113.647816 -67.021303) (xy 113.701137 -67.008014) (xy 113.755814 -67.002515) (xy 113.810713 -67.004919)
			(xy 113.864699 -67.015176) (xy 113.916655 -67.033074) (xy 113.965504 -67.058243) (xy 114.010236 -67.090161)
			(xy 114.049925 -67.128168) (xy 114.083748 -67.171478) (xy 114.111006 -67.219193) (xy 114.131135 -67.270326)
			(xy 114.143718 -67.323818) (xy 114.146584 -67.351148) (xy 114.148304 -67.366628) (xy 114.158412 -67.396084)
			(xy 114.175361 -67.422209) (xy 114.198141 -67.443443) (xy 114.22539 -67.458519) (xy 114.255482 -67.466536)
			(xy 114.271044 -67.467226) (xy 114.298514 -67.46812) (xy 114.352764 -67.47694) (xy 114.405188 -67.493454)
			(xy 114.454698 -67.51732) (xy 114.500271 -67.548044) (xy 114.540963 -67.584991) (xy 114.575932 -67.627394)
			(xy 114.604454 -67.674378) (xy 114.625937 -67.724967) (xy 114.639939 -67.778117) (xy 114.646167 -67.832725)
			(xy 114.644495 -67.887663) (xy 114.634956 -67.941791) (xy 114.617747 -67.993991) (xy 114.593226 -68.04318)
			(xy 114.561899 -68.088341) (xy 114.524416 -68.128539) (xy 114.481551 -68.162942) (xy 114.434194 -68.190837)
			(xy 114.383323 -68.211647) (xy 114.329992 -68.224941) (xy 114.275306 -68.230445) (xy 114.220396 -68.228043)
			(xy 114.166398 -68.217786) (xy 114.114432 -68.199886) (xy 114.065573 -68.174713) (xy 114.020831 -68.14279)
			(xy 113.981135 -68.104776) (xy 113.947304 -68.061459) (xy 113.92004 -68.013735) (xy 113.899907 -67.962592)
			(xy 113.887322 -67.90909) (xy 113.884456 -67.881754) (xy 113.882697 -67.86628) (xy 113.872593 -67.836829)
			(xy 113.85565 -67.810707) (xy 113.832879 -67.789473) (xy 113.805639 -67.774394) (xy 113.775555 -67.766371)
			(xy 113.759996 -67.765676) (xy 113.732532 -67.764715) (xy 113.678294 -67.755889) (xy 113.625883 -67.73937)
			(xy 113.576386 -67.715502) (xy 113.530825 -67.684777) (xy 113.490146 -67.647833) (xy 113.455189 -67.605432)
			(xy 113.426679 -67.558455) (xy 113.405205 -67.507872) (xy 113.391213 -67.454731) (xy 113.384991 -67.400133)
			(xy 85.765169 -67.400133) (xy 85.265402 -67.8999) (xy 101.629096 -67.8999) (xy 101.634005 -67.845643)
			(xy 101.646582 -67.792637) (xy 101.666572 -67.741959) (xy 101.693568 -67.69464) (xy 101.727021 -67.651643)
			(xy 101.76625 -67.613842) (xy 101.810459 -67.582007) (xy 101.858746 -67.556784) (xy 101.910131 -67.538688)
			(xy 101.963567 -67.528085) (xy 102.017968 -67.525192) (xy 102.072228 -67.530067) (xy 102.125242 -67.542612)
			(xy 102.175932 -67.562571) (xy 102.223267 -67.589539) (xy 102.266284 -67.622966) (xy 102.285546 -67.642232)
			(xy 102.302607 -67.659044) (xy 102.341725 -67.686671) (xy 102.385324 -67.706485) (xy 102.431862 -67.717784)
			(xy 102.479693 -67.720168) (xy 102.527124 -67.713554) (xy 102.572478 -67.698176) (xy 102.61415 -67.674577)
			(xy 102.632764 -67.659504) (xy 102.654002 -67.64202) (xy 102.700619 -67.612814) (xy 102.750948 -67.590606)
			(xy 102.803945 -67.575857) (xy 102.858511 -67.568873) (xy 102.913514 -67.569799) (xy 102.967814 -67.578615)
			(xy 103.020285 -67.59514) (xy 103.069838 -67.619029) (xy 103.115446 -67.649787) (xy 103.156163 -67.686778)
			(xy 103.191146 -67.729233) (xy 103.219667 -67.776273) (xy 103.225619 -67.790314) (xy 106.851194 -67.790314)
			(xy 106.855265 -67.734692) (xy 106.867391 -67.680255) (xy 106.887314 -67.628164) (xy 106.91461 -67.579529)
			(xy 106.948696 -67.535386) (xy 106.988845 -67.496677) (xy 107.034203 -67.464226) (xy 107.083803 -67.438725)
			(xy 107.136587 -67.420718) (xy 107.19143 -67.410588) (xy 107.247164 -67.408551) (xy 107.302601 -67.414651)
			(xy 107.356558 -67.428757) (xy 107.407887 -67.450569) (xy 107.455493 -67.479623) (xy 107.498361 -67.515298)
			(xy 107.535578 -67.556835) (xy 107.566351 -67.603348) (xy 107.590023 -67.653845) (xy 107.606091 -67.707252)
			(xy 107.614211 -67.762428) (xy 107.61472 -67.790314) (xy 107.614211 -67.8182) (xy 107.611923 -67.833748)
			(xy 107.907072 -67.833748) (xy 107.911143 -67.778126) (xy 107.923269 -67.723689) (xy 107.943192 -67.671598)
			(xy 107.970488 -67.622963) (xy 108.004574 -67.57882) (xy 108.044723 -67.540111) (xy 108.090081 -67.50766)
			(xy 108.139681 -67.482159) (xy 108.192465 -67.464152) (xy 108.247308 -67.454022) (xy 108.303042 -67.451985)
			(xy 108.358479 -67.458085) (xy 108.412436 -67.472191) (xy 108.463765 -67.494003) (xy 108.511371 -67.523057)
			(xy 108.554239 -67.558732) (xy 108.591456 -67.600269) (xy 108.622229 -67.646782) (xy 108.645901 -67.697279)
			(xy 108.661969 -67.750686) (xy 108.670089 -67.805862) (xy 108.670598 -67.833748) (xy 108.670089 -67.861634)
			(xy 108.661969 -67.91681) (xy 108.645901 -67.970217) (xy 108.622229 -68.020714) (xy 108.591456 -68.067227)
			(xy 108.554239 -68.108764) (xy 108.511371 -68.144439) (xy 108.463765 -68.173493) (xy 108.412436 -68.195305)
			(xy 108.358479 -68.209411) (xy 108.303042 -68.215511) (xy 108.247308 -68.213474) (xy 108.192465 -68.203344)
			(xy 108.139681 -68.185337) (xy 108.090081 -68.159836) (xy 108.044723 -68.127385) (xy 108.004574 -68.088676)
			(xy 107.970488 -68.044533) (xy 107.943192 -67.995898) (xy 107.923269 -67.943807) (xy 107.911143 -67.88937)
			(xy 107.907072 -67.833748) (xy 107.611923 -67.833748) (xy 107.606091 -67.873376) (xy 107.590023 -67.926783)
			(xy 107.566351 -67.97728) (xy 107.535578 -68.023793) (xy 107.498361 -68.06533) (xy 107.455493 -68.101005)
			(xy 107.407887 -68.130059) (xy 107.356558 -68.151871) (xy 107.302601 -68.165977) (xy 107.247164 -68.172077)
			(xy 107.19143 -68.17004) (xy 107.136587 -68.15991) (xy 107.083803 -68.141903) (xy 107.034203 -68.116402)
			(xy 106.988845 -68.083951) (xy 106.948696 -68.045242) (xy 106.91461 -68.001099) (xy 106.887314 -67.952464)
			(xy 106.867391 -67.900373) (xy 106.855265 -67.845936) (xy 106.851194 -67.790314) (xy 103.225619 -67.790314)
			(xy 103.241137 -67.826921) (xy 103.255109 -67.880128) (xy 103.261294 -67.93479) (xy 103.259564 -67.989774)
			(xy 103.249955 -68.043939) (xy 103.232665 -68.096163) (xy 103.208054 -68.145361) (xy 103.176632 -68.190515)
			(xy 103.13905 -68.230687) (xy 103.096088 -68.265045) (xy 103.048636 -68.292875) (xy 102.997679 -68.313602)
			(xy 102.971092 -68.320666) (xy 102.949252 -68.326597) (xy 102.907959 -68.345107) (xy 102.870592 -68.370631)
			(xy 102.838331 -68.402364) (xy 102.812193 -68.439303) (xy 102.793003 -68.480285) (xy 102.781367 -68.524015)
			(xy 102.777651 -68.569114) (xy 102.779322 -68.591684) (xy 102.780351 -68.603529) (xy 102.78111 -68.627295)
			(xy 102.780846 -68.639182) (xy 102.780767 -68.662033) (xy 102.787703 -68.707192) (xy 102.802594 -68.750387)
			(xy 102.824962 -68.790226) (xy 102.854087 -68.825428) (xy 102.889032 -68.854862) (xy 102.928673 -68.877579)
			(xy 102.971735 -68.89285) (xy 102.994206 -68.896992) (xy 103.021099 -68.901757) (xy 103.035057 -68.906136)
			(xy 111.927892 -68.906136) (xy 111.931963 -68.850514) (xy 111.944089 -68.796077) (xy 111.964012 -68.743986)
			(xy 111.991308 -68.695351) (xy 112.025394 -68.651208) (xy 112.065543 -68.612499) (xy 112.110901 -68.580048)
			(xy 112.160501 -68.554547) (xy 112.213285 -68.53654) (xy 112.268128 -68.52641) (xy 112.323862 -68.524373)
			(xy 112.379299 -68.530473) (xy 112.433256 -68.544579) (xy 112.484585 -68.566391) (xy 112.532191 -68.595445)
			(xy 112.575059 -68.63112) (xy 112.612276 -68.672657) (xy 112.643049 -68.71917) (xy 112.666721 -68.769667)
			(xy 112.682789 -68.823074) (xy 112.690909 -68.87825) (xy 112.691418 -68.906136) (xy 112.690909 -68.934022)
			(xy 112.682789 -68.989198) (xy 112.666721 -69.042605) (xy 112.643049 -69.093102) (xy 112.626091 -69.118734)
			(xy 113.882422 -69.118734) (xy 113.886493 -69.063112) (xy 113.898619 -69.008675) (xy 113.918542 -68.956584)
			(xy 113.945838 -68.907949) (xy 113.979924 -68.863806) (xy 114.020073 -68.825097) (xy 114.065431 -68.792646)
			(xy 114.115031 -68.767145) (xy 114.167815 -68.749138) (xy 114.222658 -68.739008) (xy 114.278392 -68.736971)
			(xy 114.333829 -68.743071) (xy 114.387786 -68.757177) (xy 114.439115 -68.778989) (xy 114.486721 -68.808043)
			(xy 114.529589 -68.843718) (xy 114.566806 -68.885255) (xy 114.597579 -68.931768) (xy 114.621251 -68.982265)
			(xy 114.637319 -69.035672) (xy 114.645439 -69.090848) (xy 114.645948 -69.118734) (xy 114.645439 -69.14662)
			(xy 114.637319 -69.201796) (xy 114.621251 -69.255203) (xy 114.597579 -69.3057) (xy 114.566806 -69.352213)
			(xy 114.529589 -69.39375) (xy 114.486721 -69.429425) (xy 114.439115 -69.458479) (xy 114.387786 -69.480291)
			(xy 114.333829 -69.494397) (xy 114.278392 -69.500497) (xy 114.222658 -69.49846) (xy 114.167815 -69.48833)
			(xy 114.115031 -69.470323) (xy 114.065431 -69.444822) (xy 114.020073 -69.412371) (xy 113.979924 -69.373662)
			(xy 113.945838 -69.329519) (xy 113.918542 -69.280884) (xy 113.898619 -69.228793) (xy 113.886493 -69.174356)
			(xy 113.882422 -69.118734) (xy 112.626091 -69.118734) (xy 112.612276 -69.139615) (xy 112.575059 -69.181152)
			(xy 112.532191 -69.216827) (xy 112.484585 -69.245881) (xy 112.433256 -69.267693) (xy 112.379299 -69.281799)
			(xy 112.323862 -69.287899) (xy 112.268128 -69.285862) (xy 112.213285 -69.275732) (xy 112.160501 -69.257725)
			(xy 112.110901 -69.232224) (xy 112.065543 -69.199773) (xy 112.025394 -69.161064) (xy 111.991308 -69.116921)
			(xy 111.964012 -69.068286) (xy 111.944089 -69.016195) (xy 111.931963 -68.961758) (xy 111.927892 -68.906136)
			(xy 103.035057 -68.906136) (xy 103.073212 -68.918106) (xy 103.122462 -68.941719) (xy 103.16784 -68.972114)
			(xy 103.20842 -69.00867) (xy 103.243373 -69.050639) (xy 103.271983 -69.097163) (xy 103.293666 -69.147292)
			(xy 103.307979 -69.200001) (xy 103.314629 -69.254212) (xy 103.31348 -69.308818) (xy 103.304556 -69.362702)
			(xy 103.288039 -69.414762) (xy 103.264266 -69.463934) (xy 103.254339 -69.478652) (xy 105.94162 -69.478652)
			(xy 105.945691 -69.42303) (xy 105.957817 -69.368593) (xy 105.97774 -69.316502) (xy 106.005036 -69.267867)
			(xy 106.039122 -69.223724) (xy 106.079271 -69.185015) (xy 106.124629 -69.152564) (xy 106.174229 -69.127063)
			(xy 106.227013 -69.109056) (xy 106.281856 -69.098926) (xy 106.33759 -69.096889) (xy 106.393027 -69.102989)
			(xy 106.446984 -69.117095) (xy 106.498313 -69.138907) (xy 106.545919 -69.167961) (xy 106.588787 -69.203636)
			(xy 106.626004 -69.245173) (xy 106.656777 -69.291686) (xy 106.680449 -69.342183) (xy 106.696517 -69.39559)
			(xy 106.704637 -69.450766) (xy 106.705146 -69.478652) (xy 106.704637 -69.506538) (xy 106.696517 -69.561714)
			(xy 106.680449 -69.615121) (xy 106.656777 -69.665618) (xy 106.626004 -69.712131) (xy 106.588787 -69.753668)
			(xy 106.545919 -69.789343) (xy 106.498313 -69.818397) (xy 106.446984 -69.840209) (xy 106.393027 -69.854315)
			(xy 106.33759 -69.860415) (xy 106.281856 -69.858378) (xy 106.227013 -69.848248) (xy 106.174229 -69.830241)
			(xy 106.124629 -69.80474) (xy 106.079271 -69.772289) (xy 106.039122 -69.73358) (xy 106.005036 -69.689437)
			(xy 105.97774 -69.640802) (xy 105.957817 -69.588711) (xy 105.945691 -69.534274) (xy 105.94162 -69.478652)
			(xy 103.254339 -69.478652) (xy 103.233725 -69.509214) (xy 103.197038 -69.549676) (xy 103.154956 -69.584493)
			(xy 103.108339 -69.612952) (xy 103.05814 -69.634473) (xy 103.005385 -69.648615) (xy 102.951153 -69.65509)
			(xy 102.896551 -69.653764) (xy 102.842697 -69.644665) (xy 102.79069 -69.62798) (xy 102.741595 -69.604048)
			(xy 102.696414 -69.57336) (xy 102.656071 -69.536543) (xy 102.621391 -69.494348) (xy 102.593082 -69.447639)
			(xy 102.571724 -69.397371) (xy 102.557753 -69.34457) (xy 102.551454 -69.290317) (xy 102.551738 -69.263006)
			(xy 102.551841 -69.240155) (xy 102.544903 -69.194993) (xy 102.530009 -69.151797) (xy 102.507637 -69.111957)
			(xy 102.478509 -69.076754) (xy 102.44356 -69.047321) (xy 102.403915 -69.024605) (xy 102.360851 -69.009337)
			(xy 102.338378 -69.005196) (xy 102.310777 -69.000212) (xy 102.257339 -68.983182) (xy 102.206968 -68.958516)
			(xy 102.160749 -68.926744) (xy 102.119678 -68.88855) (xy 102.084637 -68.844757) (xy 102.056383 -68.796308)
			(xy 102.035523 -68.744245) (xy 102.022506 -68.68969) (xy 102.017614 -68.633818) (xy 102.02095 -68.577831)
			(xy 102.026212 -68.550282) (xy 102.030317 -68.528398) (xy 102.031677 -68.483898) (xy 102.025266 -68.43984)
			(xy 102.011281 -68.397572) (xy 101.99015 -68.358385) (xy 101.962517 -68.323476) (xy 101.929228 -68.293913)
			(xy 101.891299 -68.270598) (xy 101.870764 -68.261992) (xy 101.84565 -68.251428) (xy 101.798347 -68.224403)
			(xy 101.755371 -68.190924) (xy 101.717594 -68.151671) (xy 101.685785 -68.107444) (xy 101.660592 -68.059141)
			(xy 101.642526 -68.007746) (xy 101.631956 -67.954303) (xy 101.629096 -67.8999) (xy 85.265402 -67.8999)
			(xy 84.282788 -68.882514) (xy 72.102472 -68.882514) (xy 72.088299 -68.882896) (xy 72.060653 -68.889153)
			(xy 72.035078 -68.901373) (xy 72.012841 -68.91895) (xy 72.003666 -68.929758) (xy 71.987856 -68.948765)
			(xy 71.952138 -68.982948) (xy 71.912312 -69.012242) (xy 71.869042 -69.036158) (xy 71.846186 -69.045582)
			(xy 71.812404 -69.05879) (xy 71.72452 -69.176646) (xy 71.726298 -69.221604) (xy 71.726957 -69.255657)
			(xy 71.717627 -69.323118) (xy 71.707756 -69.355716) (xy 71.698559 -69.382253) (xy 71.673476 -69.432503)
			(xy 71.641296 -69.478533) (xy 71.602716 -69.519348) (xy 71.55857 -69.554067) (xy 71.509811 -69.581938)
			(xy 71.457493 -69.60236) (xy 71.402746 -69.614892) (xy 71.346753 -69.619262) (xy 71.290725 -69.615376)
			(xy 71.235872 -69.603319) (xy 71.183378 -69.58335) (xy 71.13438 -69.555902) (xy 71.111872 -69.539104)
			(xy 71.093246 -69.526371) (xy 71.052503 -69.507001) (xy 71.00898 -69.49513) (xy 70.964044 -69.491131)
			(xy 70.919108 -69.49513) (xy 70.875585 -69.507001) (xy 70.834842 -69.526371) (xy 70.816216 -69.539104)
			(xy 70.793833 -69.555743) (xy 70.745196 -69.583036) (xy 70.693104 -69.602958) (xy 70.638667 -69.615083)
			(xy 70.583044 -69.619154) (xy 70.527421 -69.615083) (xy 70.472984 -69.602958) (xy 70.420892 -69.583036)
			(xy 70.372255 -69.555743) (xy 70.349872 -69.539104) (xy 70.331246 -69.526371) (xy 70.290503 -69.507001)
			(xy 70.24698 -69.49513) (xy 70.202044 -69.491131) (xy 70.157108 -69.49513) (xy 70.113585 -69.507001)
			(xy 70.072842 -69.526371) (xy 70.054216 -69.539104) (xy 70.031833 -69.555743) (xy 69.983196 -69.583036)
			(xy 69.931104 -69.602958) (xy 69.876667 -69.615083) (xy 69.821044 -69.619154) (xy 69.765421 -69.615083)
			(xy 69.710984 -69.602958) (xy 69.658892 -69.583036) (xy 69.610255 -69.555743) (xy 69.587872 -69.539104)
			(xy 69.569246 -69.526371) (xy 69.528503 -69.507001) (xy 69.48498 -69.49513) (xy 69.440044 -69.491131)
			(xy 69.395108 -69.49513) (xy 69.351585 -69.507001) (xy 69.310842 -69.526371) (xy 69.292216 -69.539104)
			(xy 69.269833 -69.555743) (xy 69.221196 -69.583036) (xy 69.169104 -69.602958) (xy 69.114667 -69.615083)
			(xy 69.059044 -69.619154) (xy 69.003421 -69.615083) (xy 68.948984 -69.602958) (xy 68.896892 -69.583036)
			(xy 68.848255 -69.555743) (xy 68.825872 -69.539104) (xy 68.807246 -69.526371) (xy 68.766503 -69.507001)
			(xy 68.72298 -69.49513) (xy 68.678044 -69.491131) (xy 68.633108 -69.49513) (xy 68.589585 -69.507001)
			(xy 68.548842 -69.526371) (xy 68.530216 -69.539104) (xy 68.507622 -69.555908) (xy 68.458475 -69.583389)
			(xy 68.405823 -69.603347) (xy 68.35081 -69.61535) (xy 68.29463 -69.619136) (xy 68.238503 -69.614624)
			(xy 68.183649 -69.601911) (xy 68.13126 -69.581273) (xy 68.082473 -69.553159) (xy 68.038348 -69.518179)
			(xy 67.999844 -69.477094) (xy 67.983354 -69.454268) (xy 67.970549 -69.437372) (xy 67.940279 -69.407696)
			(xy 67.9055 -69.38346) (xy 67.867179 -69.365339) (xy 67.826379 -69.353834) (xy 67.784235 -69.349266)
			(xy 67.741919 -69.351762) (xy 67.700604 -69.361253) (xy 67.68084 -69.368924) (xy 67.653874 -69.379493)
			(xy 67.597622 -69.393282) (xy 67.539933 -69.398415) (xy 67.48213 -69.394773) (xy 67.425541 -69.382439)
			(xy 67.371465 -69.361698) (xy 67.321144 -69.333025) (xy 67.275732 -69.297078) (xy 67.255644 -69.276214)
			(xy 67.240149 -69.260251) (xy 67.204632 -69.233467) (xy 67.165 -69.213266) (xy 67.122459 -69.200262)
			(xy 67.078305 -69.194852) (xy 67.033883 -69.197201) (xy 66.990546 -69.207236) (xy 66.969894 -69.215508)
			(xy 66.956232 -69.221668) (xy 66.928133 -69.232093) (xy 66.91376 -69.236336) (xy 66.887637 -69.243279)
			(xy 66.834082 -69.250587) (xy 66.780031 -69.250269) (xy 66.753232 -69.24675) (xy 66.734173 -69.243668)
			(xy 66.696761 -69.234128) (xy 66.678556 -69.2277) (xy 66.652771 -69.217797) (xy 66.604133 -69.191624)
			(xy 66.559778 -69.15871) (xy 66.539872 -69.139562) (xy 66.515234 -69.112384) (xy 66.496079 -69.08822)
			(xy 66.464942 -69.035002) (xy 66.453258 -69.006466) (xy 66.440304 -68.972684) (xy 66.32067 -68.882514)
			(xy 65.835022 -68.882514) (xy 65.714372 -68.976494) (xy 65.701926 -69.011546) (xy 65.692042 -69.037911)
			(xy 65.665643 -69.087643) (xy 65.649348 -69.110606) (xy 65.633229 -69.131644) (xy 65.596138 -69.169499)
			(xy 65.575434 -69.186044) (xy 65.556602 -69.20015) (xy 65.5161 -69.2241) (xy 65.494662 -69.233796)
			(xy 65.467673 -69.244929) (xy 65.411217 -69.259793) (xy 65.353156 -69.265896) (xy 65.323974 -69.265038)
			(xy 65.309193 -69.264781) (xy 65.280148 -69.270248) (xy 65.253141 -69.282253) (xy 65.229624 -69.300153)
			(xy 65.210858 -69.322985) (xy 65.197851 -69.349524) (xy 65.19418 -69.363844) (xy 65.187549 -69.390985)
			(xy 65.167422 -69.443103) (xy 65.139908 -69.491728) (xy 65.105595 -69.53582) (xy 65.065217 -69.574434)
			(xy 65.019639 -69.606746) (xy 64.969835 -69.632064) (xy 64.91687 -69.649846) (xy 64.861879 -69.659712)
			(xy 64.806036 -69.661451) (xy 64.750537 -69.655025) (xy 64.696569 -69.640573) (xy 64.645286 -69.618403)
			(xy 64.597785 -69.58899) (xy 64.555083 -69.552962) (xy 64.518094 -69.511091) (xy 64.487607 -69.464272)
			(xy 64.464276 -69.413507) (xy 64.4486 -69.359882) (xy 64.440914 -69.304543) (xy 64.441381 -69.248675)
			(xy 64.449994 -69.193473) (xy 64.466566 -69.140118) (xy 64.490744 -69.089751) (xy 64.522011 -69.043449)
			(xy 64.559697 -69.002203) (xy 64.602996 -68.966896) (xy 64.650982 -68.938283) (xy 64.702629 -68.916975)
			(xy 64.756832 -68.903429) (xy 64.812431 -68.897934) (xy 64.840358 -68.89877) (xy 64.855137 -68.899023)
			(xy 64.884177 -68.893551) (xy 64.911178 -68.881543) (xy 64.93469 -68.863643) (xy 64.953452 -68.840812)
			(xy 64.966456 -68.814276) (xy 64.970152 -68.799964) (xy 64.972438 -68.790566) (xy 64.972946 -68.788026)
			(xy 64.974978 -68.78066) (xy 64.983752 -68.751453) (xy 65.009271 -68.696067) (xy 65.025778 -68.670424)
			(xy 65.035684 -68.655692) (xy 65.047876 -68.617846) (xy 65.052732 -68.601041) (xy 65.054075 -68.5661)
			(xy 65.045912 -68.532098) (xy 65.028851 -68.501575) (xy 65.016888 -68.488814) (xy 64.977772 -68.449698)
			(xy 63.006986 -68.449698) (xy 62.983618 -68.45935) (xy 62.955563 -68.47043) (xy 62.896934 -68.484595)
			(xy 62.836806 -68.489357) (xy 62.776678 -68.484595) (xy 62.718049 -68.47043) (xy 62.689994 -68.45935)
			(xy 62.666626 -68.449698) (xy 61.952632 -68.449698) (xy 61.931159 -68.450151) (xy 61.888827 -68.457382)
			(xy 61.848313 -68.471626) (xy 61.810769 -68.492477) (xy 61.777265 -68.519343) (xy 61.748754 -68.551459)
			(xy 61.726048 -68.58791) (xy 61.709792 -68.62766) (xy 61.700449 -68.669577) (xy 61.698886 -68.690998)
			(xy 61.712985 -68.716072) (xy 61.734307 -68.769497) (xy 61.747366 -68.825517) (xy 61.751867 -68.882863)
			(xy 61.747707 -68.940235) (xy 61.734982 -68.996332) (xy 61.713979 -69.049883) (xy 61.685174 -69.099674)
			(xy 61.649221 -69.144576) (xy 61.606935 -69.183572) (xy 61.559273 -69.215777) (xy 61.507316 -69.240462)
			(xy 61.479938 -69.24929) (xy 61.466638 -69.265854) (xy 61.445176 -69.30251) (xy 61.430106 -69.342224)
			(xy 61.421847 -69.38389) (xy 61.420628 -69.42635) (xy 61.426484 -69.468421) (xy 61.43244 -69.488812)
			(xy 61.453715 -69.506831) (xy 61.491317 -69.547993) (xy 61.522528 -69.594189) (xy 61.546684 -69.644435)
			(xy 61.563269 -69.697662) (xy 61.571931 -69.752737) (xy 61.572486 -69.808485) (xy 61.564921 -69.863721)
			(xy 61.557662 -69.89064) (xy 61.549514 -69.917018) (xy 61.526674 -69.967277) (xy 61.496828 -70.01372)
			(xy 61.4606 -70.055376) (xy 61.418746 -70.091376) (xy 61.382062 -70.114668) (xy 72.264522 -70.114668)
			(xy 72.268593 -70.059046) (xy 72.280719 -70.004609) (xy 72.300642 -69.952518) (xy 72.327938 -69.903883)
			(xy 72.362024 -69.85974) (xy 72.402173 -69.821031) (xy 72.447531 -69.78858) (xy 72.497131 -69.763079)
			(xy 72.549915 -69.745072) (xy 72.604758 -69.734942) (xy 72.660492 -69.732905) (xy 72.715929 -69.739005)
			(xy 72.769886 -69.753111) (xy 72.821215 -69.774923) (xy 72.868821 -69.803977) (xy 72.911689 -69.839652)
			(xy 72.948906 -69.881189) (xy 72.979679 -69.927702) (xy 72.995526 -69.961506) (xy 74.62596 -69.961506)
			(xy 74.630031 -69.905884) (xy 74.642157 -69.851447) (xy 74.66208 -69.799356) (xy 74.689376 -69.750721)
			(xy 74.723462 -69.706578) (xy 74.763611 -69.667869) (xy 74.808969 -69.635418) (xy 74.858569 -69.609917)
			(xy 74.911353 -69.59191) (xy 74.966196 -69.58178) (xy 75.02193 -69.579743) (xy 75.077367 -69.585843)
			(xy 75.131324 -69.599949) (xy 75.182653 -69.621761) (xy 75.230259 -69.650815) (xy 75.273127 -69.68649)
			(xy 75.310344 -69.728027) (xy 75.341117 -69.77454) (xy 75.364789 -69.825037) (xy 75.380857 -69.878444)
			(xy 75.388977 -69.93362) (xy 75.389486 -69.961506) (xy 75.389282 -69.972704) (xy 99.315759 -69.972704)
			(xy 99.32328 -69.918233) (xy 99.33854 -69.865405) (xy 99.361224 -69.815314) (xy 99.390862 -69.768998)
			(xy 99.408488 -69.747892) (xy 99.42377 -69.729353) (xy 99.447814 -69.687765) (xy 99.463625 -69.642402)
			(xy 99.47064 -69.594879) (xy 99.46861 -69.546883) (xy 99.457607 -69.500122) (xy 99.438022 -69.456257)
			(xy 99.424744 -69.436234) (xy 99.409351 -69.413452) (xy 99.38467 -69.364319) (xy 99.367296 -69.312153)
			(xy 99.357589 -69.258033) (xy 99.355749 -69.20308) (xy 99.361814 -69.148432) (xy 99.375659 -69.09522)
			(xy 99.396997 -69.044546) (xy 99.425387 -68.997459) (xy 99.46024 -68.954934) (xy 99.500836 -68.91785)
			(xy 99.546333 -68.886977) (xy 99.59579 -68.862952) (xy 99.648183 -68.846274) (xy 99.702427 -68.837287)
			(xy 99.757399 -68.836178) (xy 99.811962 -68.84297) (xy 99.864985 -68.857522) (xy 99.91537 -68.879532)
			(xy 99.962076 -68.908546) (xy 100.004134 -68.943962) (xy 100.040674 -68.985048) (xy 100.070939 -69.030952)
			(xy 100.094304 -69.080724) (xy 100.110283 -69.133334) (xy 100.118547 -69.187693) (xy 100.118925 -69.242675)
			(xy 100.111407 -69.297143) (xy 100.096151 -69.349967) (xy 100.073472 -69.400056) (xy 100.04384 -69.446371)
			(xy 100.026216 -69.467476) (xy 100.010963 -69.486038) (xy 99.986916 -69.527621) (xy 99.971102 -69.572978)
			(xy 99.964083 -69.620497) (xy 99.966108 -69.668489) (xy 99.977105 -69.715248) (xy 99.996684 -69.759111)
			(xy 100.00996 -69.779134) (xy 100.025353 -69.801919) (xy 100.050038 -69.851054) (xy 100.067416 -69.903224)
			(xy 100.070247 -69.919003) (xy 101.118584 -69.919003) (xy 101.120431 -69.863052) (xy 101.130432 -69.807972)
			(xy 101.148374 -69.754943) (xy 101.173871 -69.705106) (xy 101.206377 -69.659528) (xy 101.245192 -69.619189)
			(xy 101.289485 -69.584953) (xy 101.338304 -69.557557) (xy 101.390603 -69.537587) (xy 101.445258 -69.525473)
			(xy 101.501096 -69.521474) (xy 101.556919 -69.525676) (xy 101.61153 -69.537989) (xy 101.663755 -69.558149)
			(xy 101.712474 -69.585724) (xy 101.756642 -69.62012) (xy 101.79531 -69.6606) (xy 101.827649 -69.706296)
			(xy 101.852965 -69.756227) (xy 101.870714 -69.80932) (xy 101.876098 -69.836792) (xy 101.880511 -69.859184)
			(xy 101.896408 -69.901963) (xy 101.899033 -69.906388) (xy 108.519974 -69.906388) (xy 108.524045 -69.850766)
			(xy 108.536171 -69.796329) (xy 108.556094 -69.744238) (xy 108.58339 -69.695603) (xy 108.617476 -69.65146)
			(xy 108.657625 -69.612751) (xy 108.702983 -69.5803) (xy 108.752583 -69.554799) (xy 108.805367 -69.536792)
			(xy 108.86021 -69.526662) (xy 108.915944 -69.524625) (xy 108.971381 -69.530725) (xy 109.025338 -69.544831)
			(xy 109.076667 -69.566643) (xy 109.124273 -69.595697) (xy 109.167141 -69.631372) (xy 109.204358 -69.672909)
			(xy 109.235131 -69.719422) (xy 109.258803 -69.769919) (xy 109.274871 -69.823326) (xy 109.282991 -69.878502)
			(xy 109.2835 -69.906388) (xy 109.282991 -69.934274) (xy 109.274871 -69.98945) (xy 109.258803 -70.042857)
			(xy 109.235131 -70.093354) (xy 109.204358 -70.139867) (xy 109.184833 -70.161658) (xy 113.737642 -70.161658)
			(xy 113.741713 -70.106036) (xy 113.753839 -70.051599) (xy 113.773762 -69.999508) (xy 113.801058 -69.950873)
			(xy 113.835144 -69.90673) (xy 113.875293 -69.868021) (xy 113.920651 -69.83557) (xy 113.970251 -69.810069)
			(xy 114.023035 -69.792062) (xy 114.077878 -69.781932) (xy 114.133612 -69.779895) (xy 114.189049 -69.785995)
			(xy 114.243006 -69.800101) (xy 114.294335 -69.821913) (xy 114.341941 -69.850967) (xy 114.384809 -69.886642)
			(xy 114.422026 -69.928179) (xy 114.452799 -69.974692) (xy 114.476471 -70.025189) (xy 114.492539 -70.078596)
			(xy 114.500659 -70.133772) (xy 114.501168 -70.161658) (xy 114.500659 -70.189544) (xy 114.492539 -70.24472)
			(xy 114.476471 -70.298127) (xy 114.452799 -70.348624) (xy 114.422026 -70.395137) (xy 114.384809 -70.436674)
			(xy 114.341941 -70.472349) (xy 114.294335 -70.501403) (xy 114.243006 -70.523215) (xy 114.189049 -70.537321)
			(xy 114.133612 -70.543421) (xy 114.077878 -70.541384) (xy 114.023035 -70.531254) (xy 113.970251 -70.513247)
			(xy 113.920651 -70.487746) (xy 113.875293 -70.455295) (xy 113.835144 -70.416586) (xy 113.801058 -70.372443)
			(xy 113.773762 -70.323808) (xy 113.753839 -70.271717) (xy 113.741713 -70.21728) (xy 113.737642 -70.161658)
			(xy 109.184833 -70.161658) (xy 109.167141 -70.181404) (xy 109.124273 -70.217079) (xy 109.076667 -70.246133)
			(xy 109.025338 -70.267945) (xy 108.971381 -70.282051) (xy 108.915944 -70.288151) (xy 108.86021 -70.286114)
			(xy 108.805367 -70.275984) (xy 108.752583 -70.257977) (xy 108.702983 -70.232476) (xy 108.657625 -70.200025)
			(xy 108.617476 -70.161316) (xy 108.58339 -70.117173) (xy 108.556094 -70.068538) (xy 108.536171 -70.016447)
			(xy 108.524045 -69.96201) (xy 108.519974 -69.906388) (xy 101.899033 -69.906388) (xy 101.919692 -69.941214)
			(xy 101.949613 -69.975674) (xy 101.985209 -70.004234) (xy 102.025334 -70.025977) (xy 102.068698 -70.040201)
			(xy 102.091236 -70.043802) (xy 102.118882 -70.048191) (xy 102.172611 -70.063886) (xy 102.223469 -70.087263)
			(xy 102.270367 -70.11782) (xy 102.312296 -70.1549) (xy 102.348358 -70.197709) (xy 102.377778 -70.245328)
			(xy 102.399925 -70.296734) (xy 102.414324 -70.350824) (xy 102.420665 -70.406438) (xy 102.418813 -70.462381)
			(xy 102.408807 -70.517453) (xy 102.390862 -70.570473) (xy 102.365363 -70.620301) (xy 102.332858 -70.665869)
			(xy 102.294043 -70.706199) (xy 102.249752 -70.740425) (xy 102.200937 -70.767813) (xy 102.148643 -70.787774)
			(xy 102.093994 -70.799881) (xy 102.038163 -70.803874) (xy 101.982347 -70.799666) (xy 101.927746 -70.787348)
			(xy 101.87553 -70.767185) (xy 101.82682 -70.739609) (xy 101.782662 -70.705213) (xy 101.744003 -70.664733)
			(xy 101.711673 -70.61904) (xy 101.686367 -70.569113) (xy 101.668627 -70.516025) (xy 101.663246 -70.488556)
			(xy 101.658763 -70.46618) (xy 101.642878 -70.423404) (xy 101.619606 -70.384154) (xy 101.589696 -70.349693)
			(xy 101.554112 -70.321129) (xy 101.513997 -70.299382) (xy 101.470642 -70.285151) (xy 101.448108 -70.281546)
			(xy 101.420443 -70.277268) (xy 101.366706 -70.261576) (xy 101.315838 -70.238201) (xy 101.268931 -70.207645)
			(xy 101.226993 -70.170563) (xy 101.190922 -70.127752) (xy 101.161493 -70.08013) (xy 101.139338 -70.028719)
			(xy 101.124932 -69.974623) (xy 101.118584 -69.919003) (xy 100.070247 -69.919003) (xy 100.077127 -69.957347)
			(xy 100.07897 -70.012304) (xy 100.072907 -70.066956) (xy 100.059062 -70.120173) (xy 100.037724 -70.170851)
			(xy 100.009334 -70.217943) (xy 99.974479 -70.260473) (xy 99.933881 -70.29756) (xy 99.88838 -70.328436)
			(xy 99.83892 -70.352463) (xy 99.786523 -70.369143) (xy 99.732275 -70.378131) (xy 99.677298 -70.37924)
			(xy 99.622732 -70.372447) (xy 99.569705 -70.357893) (xy 99.519316 -70.33588) (xy 99.472607 -70.306864)
			(xy 99.430547 -70.271444) (xy 99.394005 -70.230354) (xy 99.363739 -70.184446) (xy 99.340375 -70.134669)
			(xy 99.324396 -70.082054) (xy 99.316134 -70.02769) (xy 99.315759 -69.972704) (xy 75.389282 -69.972704)
			(xy 75.388977 -69.989392) (xy 75.380857 -70.044568) (xy 75.364789 -70.097975) (xy 75.341117 -70.148472)
			(xy 75.310344 -70.194985) (xy 75.273127 -70.236522) (xy 75.230259 -70.272197) (xy 75.182653 -70.301251)
			(xy 75.131324 -70.323063) (xy 75.077367 -70.337169) (xy 75.02193 -70.343269) (xy 74.966196 -70.341232)
			(xy 74.911353 -70.331102) (xy 74.858569 -70.313095) (xy 74.808969 -70.287594) (xy 74.763611 -70.255143)
			(xy 74.723462 -70.216434) (xy 74.689376 -70.172291) (xy 74.66208 -70.123656) (xy 74.642157 -70.071565)
			(xy 74.630031 -70.017128) (xy 74.62596 -69.961506) (xy 72.995526 -69.961506) (xy 73.003351 -69.978199)
			(xy 73.019419 -70.031606) (xy 73.027539 -70.086782) (xy 73.028048 -70.114668) (xy 73.027539 -70.142554)
			(xy 73.019419 -70.19773) (xy 73.003351 -70.251137) (xy 72.979679 -70.301634) (xy 72.948906 -70.348147)
			(xy 72.911689 -70.389684) (xy 72.868821 -70.425359) (xy 72.821215 -70.454413) (xy 72.769886 -70.476225)
			(xy 72.715929 -70.490331) (xy 72.660492 -70.496431) (xy 72.604758 -70.494394) (xy 72.549915 -70.484264)
			(xy 72.497131 -70.466257) (xy 72.447531 -70.440756) (xy 72.402173 -70.408305) (xy 72.362024 -70.369596)
			(xy 72.327938 -70.325453) (xy 72.300642 -70.276818) (xy 72.280719 -70.224727) (xy 72.268593 -70.17029)
			(xy 72.264522 -70.114668) (xy 61.382062 -70.114668) (xy 61.372141 -70.120967) (xy 61.321758 -70.143533)
			(xy 61.268648 -70.158601) (xy 61.213921 -70.165858) (xy 61.186314 -70.165976) (xy 61.17536 -70.16577)
			(xy 61.153502 -70.164248) (xy 61.142626 -70.162928) (xy 61.113479 -70.158622) (xy 61.056895 -70.142207)
			(xy 61.003505 -70.117293) (xy 60.954576 -70.084472) (xy 60.932568 -70.064884) (xy 60.930536 -70.063106)
			(xy 60.918414 -70.051542) (xy 60.896031 -70.026612) (xy 60.885832 -70.013322) (xy 60.869323 -69.990452)
			(xy 60.842507 -69.94083) (xy 60.823288 -69.887801) (xy 60.812087 -69.832521) (xy 60.809148 -69.776194)
			(xy 60.814533 -69.720047) (xy 60.828127 -69.665306) (xy 60.849632 -69.613163) (xy 60.878581 -69.564754)
			(xy 60.914341 -69.521135) (xy 60.956133 -69.483257) (xy 61.003048 -69.451945) (xy 61.054061 -69.427881)
			(xy 61.080904 -69.419216) (xy 61.094207 -69.402653) (xy 61.115675 -69.365998) (xy 61.13075 -69.326284)
			(xy 61.139012 -69.284616) (xy 61.140232 -69.242154) (xy 61.134375 -69.200081) (xy 61.128402 -69.179694)
			(xy 61.11371 -69.167387) (xy 61.086607 -69.140284) (xy 61.0743 -69.125592) (xy 61.053192 -69.098527)
			(xy 61.019973 -69.038474) (xy 61.00826 -69.006212) (xy 61.001656 -68.984622) (xy 60.998862 -68.973954)
			(xy 60.997592 -68.968366) (xy 60.993924 -68.954054) (xy 60.980967 -68.92751) (xy 60.962257 -68.904654)
			(xy 60.938794 -68.886711) (xy 60.911836 -68.87464) (xy 60.882825 -68.869089) (xy 60.868052 -68.869306)
			(xy 60.840546 -68.870083) (xy 60.785787 -68.864677) (xy 60.732372 -68.85146) (xy 60.681411 -68.830707)
			(xy 60.633959 -68.802847) (xy 60.591003 -68.768459) (xy 60.553432 -68.728256) (xy 60.522027 -68.683073)
			(xy 60.497439 -68.633847) (xy 60.480178 -68.581599) (xy 60.47486 -68.5546) (xy 60.471852 -68.540101)
			(xy 60.460102 -68.512929) (xy 60.442404 -68.489199) (xy 60.419712 -68.470187) (xy 60.393249 -68.456919)
			(xy 60.36444 -68.450108) (xy 60.349638 -68.449698) (xy 59.886596 -68.449698) (xy 59.871477 -68.450131)
			(xy 59.842089 -68.457248) (xy 59.815202 -68.471083) (xy 59.792326 -68.490857) (xy 59.774747 -68.515459)
			(xy 59.763452 -68.543508) (xy 59.760866 -68.55841) (xy 59.756352 -68.585904) (xy 59.740339 -68.639268)
			(xy 59.716727 -68.689732) (xy 59.686019 -68.73622) (xy 59.648869 -68.777742) (xy 59.606069 -68.813412)
			(xy 59.558531 -68.842469) (xy 59.507269 -68.864295) (xy 59.48045 -68.871846) (xy 59.443366 -68.881752)
			(xy 59.341258 -68.997068) (xy 59.335924 -69.035168) (xy 59.331755 -69.062163) (xy 59.316693 -69.114666)
			(xy 59.294287 -69.164481) (xy 59.264996 -69.210584) (xy 59.22942 -69.252032) (xy 59.209178 -69.270372)
			(xy 59.190128 -69.287136) (xy 59.14136 -69.385942) (xy 59.16041 -69.451982) (xy 59.176412 -69.479922)
			(xy 59.181238 -69.489574) (xy 59.190884 -69.510073) (xy 59.205779 -69.552862) (xy 59.210956 -69.574918)
			(xy 59.216715 -69.603445) (xy 59.220542 -69.661513) (xy 59.215529 -69.719491) (xy 59.209178 -69.747892)
			(xy 59.201821 -69.775944) (xy 59.179785 -69.829587) (xy 59.149884 -69.879276) (xy 59.112808 -69.923868)
			(xy 59.06941 -69.962335) (xy 59.045348 -69.978524) (xy 59.02184 -69.993093) (xy 58.971518 -70.016033)
			(xy 58.918412 -70.031469) (xy 58.863634 -70.039077) (xy 58.808331 -70.038697) (xy 58.753662 -70.030337)
			(xy 58.700773 -70.014174) (xy 58.650771 -69.990544) (xy 58.604704 -69.959944) (xy 58.563537 -69.923014)
			(xy 58.545476 -69.90207) (xy 58.522644 -69.895698) (xy 58.475522 -69.890593) (xy 58.428271 -69.894317)
			(xy 58.405268 -69.900038) (xy 58.387387 -69.919414) (xy 58.347205 -69.953551) (xy 58.302705 -69.981829)
			(xy 58.254735 -70.003709) (xy 58.204208 -70.018774) (xy 58.152088 -70.026737) (xy 58.099368 -70.027447)
			(xy 58.047053 -70.020889) (xy 57.996139 -70.00719) (xy 57.97169 -69.99732) (xy 57.945706 -69.985736)
			(xy 57.897205 -69.956005) (xy 57.853655 -69.919402) (xy 57.816022 -69.876739) (xy 57.78514 -69.828962)
			(xy 57.761694 -69.77713) (xy 57.746203 -69.722391) (xy 57.739011 -69.665958) (xy 57.740277 -69.609083)
			(xy 57.749973 -69.553027) (xy 57.767884 -69.499031) (xy 57.793613 -69.448293) (xy 57.82659 -69.401937)
			(xy 57.866084 -69.360991) (xy 57.911219 -69.326363) (xy 57.960995 -69.298819) (xy 58.014309 -69.27897)
			(xy 58.042048 -69.272658) (xy 58.071064 -69.267129) (xy 58.13005 -69.264039) (xy 58.188808 -69.270071)
			(xy 58.245936 -69.28508) (xy 58.300071 -69.308708) (xy 58.349921 -69.340391) (xy 58.394297 -69.379374)
			(xy 58.41365 -69.40169) (xy 58.436482 -69.40806) (xy 58.483603 -69.413161) (xy 58.530852 -69.409432)
			(xy 58.553858 -69.403722) (xy 58.561787 -69.394959) (xy 58.578565 -69.378313) (xy 58.587386 -69.370448)
			(xy 58.606436 -69.353684) (xy 58.655204 -69.254878) (xy 58.6359 -69.188076) (xy 58.628026 -69.174614)
			(xy 58.627264 -69.17309) (xy 58.611008 -69.142102) (xy 58.597551 -69.11091) (xy 58.580691 -69.045111)
			(xy 58.57748 -69.011292) (xy 58.576464 -68.9864) (xy 58.576722 -68.959109) (xy 58.584033 -68.905026)
			(xy 58.598965 -68.852533) (xy 58.621213 -68.802698) (xy 58.650324 -68.756535) (xy 58.66765 -68.735448)
			(xy 58.669892 -68.714007) (xy 58.667984 -68.670944) (xy 58.658835 -68.62882) (xy 58.642709 -68.588844)
			(xy 58.620068 -68.552163) (xy 58.591561 -68.51983) (xy 58.558006 -68.492771) (xy 58.520366 -68.471763)
			(xy 58.47972 -68.457409) (xy 58.437235 -68.450121) (xy 58.415682 -68.449698) (xy 55.873904 -68.449698)
			(xy 55.856871 -68.450253) (xy 55.824022 -68.459278) (xy 55.794724 -68.47666) (xy 55.771059 -68.501164)
			(xy 55.754708 -68.53105) (xy 55.750206 -68.547488) (xy 55.74376 -68.572756) (xy 55.724478 -68.621206)
			(xy 55.69833 -68.666323) (xy 55.665875 -68.707139) (xy 55.62781 -68.74278) (xy 55.58495 -68.772482)
			(xy 55.538212 -68.79561) (xy 55.4886 -68.811667) (xy 55.437175 -68.82031) (xy 55.411116 -68.8213)
			(xy 55.365904 -68.822316) (xy 55.274464 -68.90004) (xy 55.265828 -68.943474) (xy 55.26011 -68.969889)
			(xy 55.242221 -69.02089) (xy 55.217318 -69.068857) (xy 55.185898 -69.112832) (xy 55.148589 -69.151935)
			(xy 55.127652 -69.169026) (xy 55.121414 -69.188764) (xy 55.114701 -69.229609) (xy 55.114702 -69.271002)
			(xy 55.121417 -69.311847) (xy 55.127652 -69.331586) (xy 55.149153 -69.349149) (xy 55.187336 -69.389451)
			(xy 55.194693 -69.399912) (xy 56.60466 -69.399912) (xy 56.608731 -69.34429) (xy 56.620857 -69.289853)
			(xy 56.64078 -69.237762) (xy 56.668076 -69.189127) (xy 56.702162 -69.144984) (xy 56.742311 -69.106275)
			(xy 56.787669 -69.073824) (xy 56.837269 -69.048323) (xy 56.890053 -69.030316) (xy 56.944896 -69.020186)
			(xy 57.00063 -69.018149) (xy 57.056067 -69.024249) (xy 57.110024 -69.038355) (xy 57.161353 -69.060167)
			(xy 57.208959 -69.089221) (xy 57.251827 -69.124896) (xy 57.289044 -69.166433) (xy 57.319817 -69.212946)
			(xy 57.343489 -69.263443) (xy 57.359557 -69.31685) (xy 57.367677 -69.372026) (xy 57.368186 -69.399912)
			(xy 57.367677 -69.427798) (xy 57.359557 -69.482974) (xy 57.343489 -69.536381) (xy 57.319817 -69.586878)
			(xy 57.289044 -69.633391) (xy 57.251827 -69.674928) (xy 57.208959 -69.710603) (xy 57.161353 -69.739657)
			(xy 57.110024 -69.761469) (xy 57.056067 -69.775575) (xy 57.00063 -69.781675) (xy 56.944896 -69.779638)
			(xy 56.890053 -69.769508) (xy 56.837269 -69.751501) (xy 56.787669 -69.726) (xy 56.742311 -69.693549)
			(xy 56.702162 -69.65484) (xy 56.668076 -69.610697) (xy 56.64078 -69.562062) (xy 56.620857 -69.509971)
			(xy 56.608731 -69.455534) (xy 56.60466 -69.399912) (xy 55.194693 -69.399912) (xy 55.219272 -69.434863)
			(xy 55.244288 -69.484424) (xy 55.261856 -69.537088) (xy 55.271603 -69.591742) (xy 55.273325 -69.647233)
			(xy 55.266984 -69.702386) (xy 55.252715 -69.756038) (xy 55.230819 -69.807055) (xy 55.201758 -69.854358)
			(xy 55.166148 -69.896949) (xy 55.124739 -69.933928) (xy 55.078407 -69.964514) (xy 55.053484 -69.976746)
			(xy 55.033418 -69.986144) (xy 54.655974 -70.363588) (xy 51.31054 -70.363588) (xy 51.288256 -70.364048)
			(xy 51.244371 -70.371815) (xy 51.202514 -70.387117) (xy 51.163967 -70.409486) (xy 51.129913 -70.438236)
			(xy 51.101395 -70.472485) (xy 51.079289 -70.511183) (xy 51.064271 -70.553143) (xy 51.056803 -70.59708)
			(xy 51.056639 -70.610984) (xy 61.621668 -70.610984) (xy 61.625739 -70.555362) (xy 61.637865 -70.500925)
			(xy 61.657788 -70.448834) (xy 61.685084 -70.400199) (xy 61.71917 -70.356056) (xy 61.759319 -70.317347)
			(xy 61.804677 -70.284896) (xy 61.854277 -70.259395) (xy 61.907061 -70.241388) (xy 61.961904 -70.231258)
			(xy 62.017638 -70.229221) (xy 62.073075 -70.235321) (xy 62.127032 -70.249427) (xy 62.178361 -70.271239)
			(xy 62.225967 -70.300293) (xy 62.268835 -70.335968) (xy 62.306052 -70.377505) (xy 62.336825 -70.424018)
			(xy 62.360497 -70.474515) (xy 62.376565 -70.527922) (xy 62.384685 -70.583098) (xy 62.385194 -70.610984)
			(xy 62.384685 -70.63887) (xy 62.376565 -70.694046) (xy 62.360497 -70.747453) (xy 62.336825 -70.79795)
			(xy 62.306052 -70.844463) (xy 62.268835 -70.886) (xy 62.225967 -70.921675) (xy 62.178361 -70.950729)
			(xy 62.127032 -70.972541) (xy 62.073075 -70.986647) (xy 62.017638 -70.992747) (xy 61.961904 -70.99071)
			(xy 61.907061 -70.98058) (xy 61.854277 -70.962573) (xy 61.804677 -70.937072) (xy 61.759319 -70.904621)
			(xy 61.71917 -70.865912) (xy 61.685084 -70.821769) (xy 61.657788 -70.773134) (xy 61.637865 -70.721043)
			(xy 61.625739 -70.666606) (xy 61.621668 -70.610984) (xy 51.056639 -70.610984) (xy 51.05654 -70.619366)
			(xy 51.057259 -70.647373) (xy 51.051474 -70.703097) (xy 51.037603 -70.757376) (xy 51.015945 -70.809044)
			(xy 50.986966 -70.85699) (xy 50.951288 -70.900184) (xy 50.909678 -70.937698) (xy 50.86303 -70.968724)
			(xy 50.812348 -70.992597) (xy 50.758719 -71.008803) (xy 50.703298 -71.016994) (xy 50.647274 -71.016994)
			(xy 50.591853 -71.008803) (xy 50.538224 -70.992597) (xy 50.487542 -70.968724) (xy 50.440894 -70.937698)
			(xy 50.399284 -70.900184) (xy 50.363606 -70.85699) (xy 50.334627 -70.809044) (xy 50.312969 -70.757376)
			(xy 50.299098 -70.703097) (xy 50.293313 -70.647373) (xy 50.294032 -70.619366) (xy 50.293723 -70.597082)
			(xy 50.286257 -70.553148) (xy 50.271243 -70.51119) (xy 50.249142 -70.472493) (xy 50.220631 -70.438243)
			(xy 50.186584 -70.40949) (xy 50.148044 -70.387116) (xy 50.106193 -70.371805) (xy 50.062314 -70.364028)
			(xy 50.040032 -70.363588) (xy 49.122838 -70.363588) (xy 49.100408 -70.364063) (xy 49.056246 -70.371938)
			(xy 49.014154 -70.38745) (xy 48.975442 -70.410116) (xy 48.941315 -70.439231) (xy 48.912834 -70.473889)
			(xy 48.890885 -70.513012) (xy 48.876152 -70.555383) (xy 48.87214 -70.577456) (xy 48.868379 -70.604937)
			(xy 48.853941 -70.658489) (xy 48.831902 -70.709387) (xy 48.802727 -70.756559) (xy 48.767031 -70.79901)
			(xy 48.725566 -70.835847) (xy 48.679205 -70.866294) (xy 48.628925 -70.889708) (xy 48.575785 -70.905597)
			(xy 48.520904 -70.913626) (xy 48.46544 -70.913626) (xy 48.410559 -70.905597) (xy 48.357419 -70.889708)
			(xy 48.307139 -70.866294) (xy 48.260778 -70.835847) (xy 48.219313 -70.79901) (xy 48.183617 -70.756559)
			(xy 48.154442 -70.709387) (xy 48.132403 -70.658489) (xy 48.117965 -70.604937) (xy 48.114204 -70.577456)
			(xy 48.110183 -70.55539) (xy 48.09542 -70.513039) (xy 48.073456 -70.473936) (xy 48.044972 -70.439293)
			(xy 48.010852 -70.410186) (xy 47.972153 -70.387516) (xy 47.930078 -70.371988) (xy 47.88593 -70.364083)
			(xy 47.863506 -70.363588) (xy 47.822104 -70.363588) (xy 47.799107 -70.364076) (xy 47.75386 -70.372337)
			(xy 47.71084 -70.388608) (xy 47.671452 -70.412358) (xy 47.636982 -70.442811) (xy 47.608558 -70.478971)
			(xy 47.587107 -70.519657) (xy 47.573331 -70.563539) (xy 47.56768 -70.609185) (xy 47.570338 -70.655103)
			(xy 47.581218 -70.699792) (xy 47.590202 -70.720966) (xy 47.600373 -70.74482) (xy 47.614898 -70.794599)
			(xy 47.622543 -70.845887) (xy 47.623168 -70.897739) (xy 47.61676 -70.949197) (xy 47.603438 -70.999311)
			(xy 47.583447 -71.047158) (xy 47.570644 -71.069708) (xy 47.556289 -71.093174) (xy 47.521893 -71.1361)
			(xy 47.481694 -71.173649) (xy 47.436524 -71.205042) (xy 47.412148 -71.21779) (xy 47.38661 -71.229963)
			(xy 47.332817 -71.24748) (xy 47.277028 -71.256863) (xy 47.220465 -71.257909) (xy 47.164367 -71.250594)
			(xy 47.109964 -71.235079) (xy 47.058446 -71.211702) (xy 47.010944 -71.180978) (xy 46.968498 -71.143577)
			(xy 46.949868 -71.122286) (xy 46.922747 -71.117456) (xy 46.870325 -71.100535) (xy 46.821135 -71.075738)
			(xy 46.776354 -71.043659) (xy 46.75632 -71.02475) (xy 46.742511 -71.011817) (xy 46.711774 -70.98976)
			(xy 46.695106 -70.980808) (xy 46.631352 -70.98919) (xy 46.624494 -70.990968) (xy 46.623224 -70.991222)
			(xy 46.598914 -70.996768) (xy 46.549353 -71.002244) (xy 46.524418 -71.002144) (xy 46.495716 -71.00062)
			(xy 46.491144 -71.000112) (xy 46.481746 -70.999858) (xy 46.464516 -70.999938) (xy 46.431086 -71.008218)
			(xy 46.401104 -71.025164) (xy 46.388528 -71.036942) (xy 46.026565 -71.398905) (xy 51.217679 -71.398905)
			(xy 51.221704 -71.34358) (xy 51.233698 -71.28942) (xy 51.253406 -71.237568) (xy 51.280414 -71.189115)
			(xy 51.314153 -71.145084) (xy 51.353912 -71.106401) (xy 51.398852 -71.073882) (xy 51.448027 -71.048212)
			(xy 51.5004 -71.029933) (xy 51.554868 -71.019429) (xy 51.610283 -71.016922) (xy 51.665477 -71.022465)
			(xy 51.719287 -71.035941) (xy 51.770579 -71.057065) (xy 51.818272 -71.085393) (xy 51.84013 -71.102474)
			(xy 51.857204 -71.115736) (xy 51.894924 -71.136855) (xy 51.935675 -71.151282) (xy 51.978281 -71.158601)
			(xy 52.021511 -71.158601) (xy 52.064117 -71.151282) (xy 52.104868 -71.136855) (xy 52.142588 -71.115736)
			(xy 52.159662 -71.102474) (xy 52.181525 -71.085411) (xy 52.22921 -71.057099) (xy 52.280492 -71.035989)
			(xy 52.334289 -71.022525) (xy 52.389469 -71.016991) (xy 52.444869 -71.019505) (xy 52.499321 -71.030012)
			(xy 52.551679 -71.048292) (xy 52.600838 -71.073959) (xy 52.645764 -71.106472) (xy 52.685509 -71.145148)
			(xy 52.719237 -71.189169) (xy 52.746236 -71.23761) (xy 52.765938 -71.289449) (xy 52.777927 -71.343594)
			(xy 52.781951 -71.398905) (xy 53.617979 -71.398905) (xy 53.622004 -71.34358) (xy 53.633998 -71.28942)
			(xy 53.653706 -71.237568) (xy 53.680714 -71.189115) (xy 53.714453 -71.145084) (xy 53.754212 -71.106401)
			(xy 53.799152 -71.073882) (xy 53.848327 -71.048212) (xy 53.9007 -71.029933) (xy 53.955168 -71.019429)
			(xy 54.010583 -71.016922) (xy 54.065777 -71.022465) (xy 54.119587 -71.035941) (xy 54.170879 -71.057065)
			(xy 54.218572 -71.085393) (xy 54.24043 -71.102474) (xy 54.257504 -71.115736) (xy 54.295224 -71.136855)
			(xy 54.335975 -71.151282) (xy 54.378581 -71.158601) (xy 54.421811 -71.158601) (xy 54.464417 -71.151282)
			(xy 54.505168 -71.136855) (xy 54.542888 -71.115736) (xy 54.559962 -71.102474) (xy 54.582191 -71.085085)
			(xy 54.630783 -71.056382) (xy 54.683076 -71.035157) (xy 54.737926 -71.021874) (xy 54.794136 -71.016823)
			(xy 54.850476 -71.020115) (xy 54.905715 -71.031678) (xy 54.958645 -71.051259) (xy 55.00811 -71.07843)
			(xy 55.030878 -71.095108) (xy 55.048067 -71.107578) (xy 55.085688 -71.12727) (xy 55.12606 -71.140428)
			(xy 55.16806 -71.146684) (xy 55.210514 -71.145865) (xy 55.252241 -71.137994) (xy 55.292076 -71.123289)
			(xy 55.32891 -71.102162) (xy 55.345584 -71.089012) (xy 55.367785 -71.071411) (xy 55.416178 -71.041953)
			(xy 55.468234 -71.019597) (xy 55.522919 -71.004788) (xy 55.579143 -70.997821) (xy 55.635788 -70.998834)
			(xy 55.691726 -71.007807) (xy 55.745846 -71.024562) (xy 55.79707 -71.048766) (xy 55.844378 -71.079936)
			(xy 55.88683 -71.117453) (xy 55.923581 -71.160569) (xy 55.9539 -71.208428) (xy 55.977182 -71.260077)
			(xy 55.992966 -71.314488) (xy 56.000937 -71.370578) (xy 56.000937 -71.398892) (xy 56.818528 -71.398892)
			(xy 56.822599 -71.34327) (xy 56.834725 -71.288833) (xy 56.854648 -71.236742) (xy 56.881944 -71.188107)
			(xy 56.91603 -71.143964) (xy 56.956179 -71.105255) (xy 57.001537 -71.072804) (xy 57.051137 -71.047303)
			(xy 57.103921 -71.029296) (xy 57.158764 -71.019166) (xy 57.214498 -71.017129) (xy 57.242207 -71.020178)
			(xy 64.907666 -71.020178) (xy 64.911737 -70.964556) (xy 64.923863 -70.910119) (xy 64.943786 -70.858028)
			(xy 64.971082 -70.809393) (xy 65.005168 -70.76525) (xy 65.045317 -70.726541) (xy 65.090675 -70.69409)
			(xy 65.140275 -70.668589) (xy 65.193059 -70.650582) (xy 65.247902 -70.640452) (xy 65.303636 -70.638415)
			(xy 65.359073 -70.644515) (xy 65.41303 -70.658621) (xy 65.464359 -70.680433) (xy 65.511965 -70.709487)
			(xy 65.554833 -70.745162) (xy 65.59205 -70.786699) (xy 65.622823 -70.833212) (xy 65.646495 -70.883709)
			(xy 65.662563 -70.937116) (xy 65.670683 -70.992292) (xy 65.671192 -71.020178) (xy 65.670683 -71.048064)
			(xy 65.662563 -71.10324) (xy 65.646495 -71.156647) (xy 65.622823 -71.207144) (xy 65.610781 -71.225345)
			(xy 66.772059 -71.225345) (xy 66.775637 -71.171097) (xy 66.786882 -71.117907) (xy 66.805564 -71.066852)
			(xy 66.831306 -71.018967) (xy 66.863586 -70.975221) (xy 66.901749 -70.936502) (xy 66.945024 -70.903593)
			(xy 66.992532 -70.877162) (xy 67.043311 -70.857744) (xy 67.069716 -70.851268) (xy 67.084051 -70.847662)
			(xy 67.110619 -70.834719) (xy 67.133491 -70.816005) (xy 67.151438 -70.792525) (xy 67.163493 -70.765542)
			(xy 67.169009 -70.736509) (xy 67.168776 -70.721728) (xy 67.168038 -70.694793) (xy 67.173162 -70.641155)
			(xy 67.185785 -70.588773) (xy 67.205654 -70.538689) (xy 67.232375 -70.491899) (xy 67.265415 -70.449337)
			(xy 67.304116 -70.411848) (xy 67.347709 -70.380179) (xy 67.395325 -70.354961) (xy 67.446016 -70.336696)
			(xy 67.498773 -70.325747) (xy 67.552547 -70.322332) (xy 67.606265 -70.32652) (xy 67.65886 -70.338227)
			(xy 67.709283 -70.357219) (xy 67.756531 -70.38312) (xy 67.778376 -70.398894) (xy 67.797388 -70.41249)
			(xy 67.839271 -70.433222) (xy 67.884239 -70.445948) (xy 67.930776 -70.450238) (xy 67.977313 -70.445948)
			(xy 68.022281 -70.433222) (xy 68.064164 -70.41249) (xy 68.083176 -70.398894) (xy 68.105267 -70.382932)
			(xy 68.153098 -70.356809) (xy 68.204161 -70.33776) (xy 68.257415 -70.326174) (xy 68.311776 -70.322285)
			(xy 68.366137 -70.326174) (xy 68.419391 -70.33776) (xy 68.470454 -70.356809) (xy 68.518285 -70.382932)
			(xy 68.540376 -70.398894) (xy 68.559388 -70.41249) (xy 68.601271 -70.433222) (xy 68.646239 -70.445948)
			(xy 68.692776 -70.450238) (xy 68.739313 -70.445948) (xy 68.784281 -70.433222) (xy 68.826164 -70.41249)
			(xy 68.845176 -70.398894) (xy 68.867267 -70.382932) (xy 68.915098 -70.356809) (xy 68.966161 -70.33776)
			(xy 69.019415 -70.326174) (xy 69.073776 -70.322285) (xy 69.128137 -70.326174) (xy 69.181391 -70.33776)
			(xy 69.232454 -70.356809) (xy 69.280285 -70.382932) (xy 69.302376 -70.398894) (xy 69.321388 -70.41249)
			(xy 69.363271 -70.433222) (xy 69.408239 -70.445948) (xy 69.454776 -70.450238) (xy 69.501313 -70.445948)
			(xy 69.546281 -70.433222) (xy 69.588164 -70.41249) (xy 69.607176 -70.398894) (xy 69.629267 -70.382932)
			(xy 69.677098 -70.356809) (xy 69.728161 -70.33776) (xy 69.781415 -70.326174) (xy 69.835776 -70.322285)
			(xy 69.890137 -70.326174) (xy 69.943391 -70.33776) (xy 69.994454 -70.356809) (xy 70.042285 -70.382932)
			(xy 70.064376 -70.398894) (xy 70.083388 -70.41249) (xy 70.125271 -70.433222) (xy 70.170239 -70.445948)
			(xy 70.216776 -70.450238) (xy 70.263313 -70.445948) (xy 70.308281 -70.433222) (xy 70.350164 -70.41249)
			(xy 70.369176 -70.398894) (xy 70.392664 -70.381905) (xy 70.443781 -70.354566) (xy 70.498447 -70.335279)
			(xy 70.555403 -70.324489) (xy 70.613336 -70.322444) (xy 70.67091 -70.329192) (xy 70.7268 -70.344577)
			(xy 70.779717 -70.368244) (xy 70.828443 -70.399648) (xy 70.850506 -70.418452) (xy 70.867717 -70.432942)
			(xy 70.906141 -70.456331) (xy 70.948082 -70.472594) (xy 70.99223 -70.481222) (xy 71.037207 -70.481946)
			(xy 71.08161 -70.474743) (xy 71.124052 -70.459839) (xy 71.163209 -70.437698) (xy 71.197859 -70.409012)
			(xy 71.226919 -70.374676) (xy 71.238618 -70.35546) (xy 71.25309 -70.331277) (xy 71.288167 -70.287165)
			(xy 71.32935 -70.248693) (xy 71.375745 -70.216696) (xy 71.426341 -70.191871) (xy 71.480038 -70.174759)
			(xy 71.535668 -70.16573) (xy 71.592021 -70.164983) (xy 71.647872 -70.172532) (xy 71.702004 -70.188214)
			(xy 71.753241 -70.211688) (xy 71.800468 -70.242443) (xy 71.842657 -70.279809) (xy 71.878892 -70.322975)
			(xy 71.908383 -70.371001) (xy 71.93049 -70.422842) (xy 71.944731 -70.477372) (xy 71.950796 -70.533402)
			(xy 71.948554 -70.589716) (xy 71.938054 -70.645087) (xy 71.919523 -70.698311) (xy 71.906892 -70.723506)
			(xy 71.896819 -70.74359) (xy 71.883281 -70.786433) (xy 71.877488 -70.830989) (xy 71.87962 -70.875869)
			(xy 71.88961 -70.919675) (xy 71.907147 -70.961041) (xy 71.931685 -70.99868) (xy 71.962459 -71.031417)
			(xy 71.99851 -71.058233) (xy 72.018398 -71.068692) (xy 72.043306 -71.081658) (xy 72.089345 -71.113807)
			(xy 72.130174 -71.152357) (xy 72.164911 -71.196477) (xy 72.192805 -71.245211) (xy 72.203581 -71.272772)
			(xy 74.424362 -71.272772) (xy 74.432164 -71.218658) (xy 74.447608 -71.166211) (xy 74.47038 -71.116504)
			(xy 74.500012 -71.070557) (xy 74.535899 -71.029309) (xy 74.577305 -70.993604) (xy 74.623382 -70.964175)
			(xy 74.673188 -70.941622) (xy 74.725703 -70.926409) (xy 74.779851 -70.918846) (xy 74.834524 -70.919088)
			(xy 74.888604 -70.92713) (xy 74.940982 -70.942808) (xy 74.990586 -70.965801) (xy 75.036401 -70.995637)
			(xy 75.057254 -71.01332) (xy 75.074768 -71.028023) (xy 75.113994 -71.05152) (xy 75.156791 -71.067619)
			(xy 75.201778 -71.0758) (xy 75.247502 -71.0758) (xy 75.292489 -71.067619) (xy 75.335286 -71.05152)
			(xy 75.374512 -71.028023) (xy 75.392026 -71.01332) (xy 75.41289 -70.995661) (xy 75.458698 -70.965839)
			(xy 75.508292 -70.942859) (xy 75.560658 -70.927192) (xy 75.614724 -70.919158) (xy 75.669383 -70.918922)
			(xy 75.723517 -70.926488) (xy 75.776016 -70.941703) (xy 75.825808 -70.964253) (xy 75.871871 -70.993678)
			(xy 75.913264 -71.029376) (xy 75.949139 -71.070615) (xy 75.978762 -71.116551) (xy 76.001526 -71.166245)
			(xy 76.016965 -71.218679) (xy 76.024764 -71.272779) (xy 76.024763 -71.327439) (xy 76.016961 -71.381539)
			(xy 76.001519 -71.433972) (xy 75.978753 -71.483665) (xy 75.949128 -71.5296) (xy 75.913251 -71.570837)
			(xy 75.871856 -71.606533) (xy 75.825791 -71.635956) (xy 75.775999 -71.658504) (xy 75.723499 -71.673715)
			(xy 75.669365 -71.681279) (xy 75.614706 -71.68104) (xy 75.56064 -71.673004) (xy 75.508275 -71.657334)
			(xy 75.458682 -71.634352) (xy 75.412875 -71.604528) (xy 75.392026 -71.586852) (xy 75.374512 -71.572149)
			(xy 75.335286 -71.548652) (xy 75.292489 -71.532553) (xy 75.247502 -71.524372) (xy 75.201778 -71.524372)
			(xy 75.156791 -71.532553) (xy 75.113994 -71.548652) (xy 75.074768 -71.572149) (xy 75.057254 -71.586852)
			(xy 75.036416 -71.604551) (xy 74.990602 -71.63439) (xy 74.940999 -71.657385) (xy 74.888622 -71.673066)
			(xy 74.834543 -71.681111) (xy 74.779869 -71.681356) (xy 74.725721 -71.673795) (xy 74.673205 -71.658584)
			(xy 74.623398 -71.636034) (xy 74.577319 -71.606607) (xy 74.535912 -71.570904) (xy 74.500023 -71.529658)
			(xy 74.470389 -71.483712) (xy 74.447615 -71.434007) (xy 74.432168 -71.38156) (xy 74.424364 -71.327446)
			(xy 74.424362 -71.272772) (xy 72.203581 -71.272772) (xy 72.213253 -71.297509) (xy 72.225815 -71.352239)
			(xy 72.230217 -71.408219) (xy 72.226366 -71.464239) (xy 72.214345 -71.51909) (xy 72.194412 -71.571587)
			(xy 72.166999 -71.620594) (xy 72.132699 -71.665053) (xy 72.092252 -71.704004) (xy 72.046532 -71.736605)
			(xy 71.996526 -71.762151) (xy 71.951745 -71.777249) (xy 76.192399 -71.777249) (xy 76.198819 -71.721607)
			(xy 76.213306 -71.667502) (xy 76.235549 -71.616097) (xy 76.265069 -71.568497) (xy 76.301232 -71.525724)
			(xy 76.32192 -71.506842) (xy 76.338118 -71.492017) (xy 76.365596 -71.457771) (xy 76.386775 -71.419309)
			(xy 76.401025 -71.377779) (xy 76.40792 -71.334416) (xy 76.407256 -71.290514) (xy 76.399051 -71.24738)
			(xy 76.383552 -71.2063) (xy 76.361218 -71.168497) (xy 76.34732 -71.151496) (xy 76.329529 -71.129863)
			(xy 76.29983 -71.082376) (xy 76.277394 -71.031057) (xy 76.262702 -70.977008) (xy 76.256072 -70.921393)
			(xy 76.257645 -70.865405) (xy 76.267388 -70.81025) (xy 76.285091 -70.757112) (xy 76.310373 -70.707133)
			(xy 76.342692 -70.661388) (xy 76.381352 -70.620861) (xy 76.425522 -70.586422) (xy 76.474253 -70.558812)
			(xy 76.526498 -70.538624) (xy 76.581133 -70.526292) (xy 76.636984 -70.522081) (xy 76.69285 -70.526082)
			(xy 76.747531 -70.538209) (xy 76.799851 -70.558201) (xy 76.848686 -70.585629) (xy 76.892985 -70.619902)
			(xy 76.931796 -70.660284) (xy 76.964286 -70.705907) (xy 76.989756 -70.755791) (xy 77.007658 -70.808862)
			(xy 77.017607 -70.863981) (xy 77.01939 -70.919962) (xy 77.012968 -70.975602) (xy 76.99848 -71.029705)
			(xy 76.997232 -71.032588) (xy 105.967355 -71.032588) (xy 105.970403 -70.977734) (xy 105.981289 -70.923885)
			(xy 105.999786 -70.872153) (xy 106.025513 -70.823611) (xy 106.057937 -70.77926) (xy 106.096387 -70.74002)
			(xy 106.140069 -70.706701) (xy 106.188079 -70.679992) (xy 106.239423 -70.660447) (xy 106.29304 -70.648469)
			(xy 106.347821 -70.644306) (xy 106.402632 -70.648045) (xy 106.456341 -70.659607) (xy 106.507835 -70.678754)
			(xy 106.532172 -70.691502) (xy 106.553463 -70.702554) (xy 106.599124 -70.717245) (xy 106.646731 -70.723108)
			(xy 106.694592 -70.719935) (xy 106.741008 -70.707839) (xy 106.78433 -70.687248) (xy 106.823019 -70.658894)
			(xy 106.839766 -70.641718) (xy 106.858876 -70.62198) (xy 106.901705 -70.587574) (xy 106.949025 -70.559668)
			(xy 106.99986 -70.538838) (xy 107.053157 -70.525516) (xy 107.107814 -70.519977) (xy 107.1627 -70.522335)
			(xy 107.21668 -70.532543) (xy 107.268637 -70.550388) (xy 107.317498 -70.575502) (xy 107.36225 -70.607364)
			(xy 107.401969 -70.645317) (xy 107.435834 -70.688575) (xy 107.463142 -70.736244) (xy 107.483331 -70.787336)
			(xy 107.495981 -70.840796) (xy 107.500832 -70.895519) (xy 107.497783 -70.950371) (xy 107.496303 -70.957694)
			(xy 111.923574 -70.957694) (xy 111.927645 -70.902072) (xy 111.939771 -70.847635) (xy 111.959694 -70.795544)
			(xy 111.98699 -70.746909) (xy 112.021076 -70.702766) (xy 112.061225 -70.664057) (xy 112.106583 -70.631606)
			(xy 112.156183 -70.606105) (xy 112.208967 -70.588098) (xy 112.26381 -70.577968) (xy 112.319544 -70.575931)
			(xy 112.374981 -70.582031) (xy 112.428938 -70.596137) (xy 112.480267 -70.617949) (xy 112.527873 -70.647003)
			(xy 112.570741 -70.682678) (xy 112.607958 -70.724215) (xy 112.638731 -70.770728) (xy 112.662403 -70.821225)
			(xy 112.678471 -70.874632) (xy 112.686591 -70.929808) (xy 112.6871 -70.957694) (xy 112.686591 -70.98558)
			(xy 112.678471 -71.040756) (xy 112.662403 -71.094163) (xy 112.638731 -71.14466) (xy 112.607958 -71.191173)
			(xy 112.570741 -71.23271) (xy 112.527873 -71.268385) (xy 112.480267 -71.297439) (xy 112.428938 -71.319251)
			(xy 112.374981 -71.333357) (xy 112.319544 -71.339457) (xy 112.26381 -71.33742) (xy 112.208967 -71.32729)
			(xy 112.156183 -71.309283) (xy 112.106583 -71.283782) (xy 112.061225 -71.251331) (xy 112.021076 -71.212622)
			(xy 111.98699 -71.168479) (xy 111.959694 -71.119844) (xy 111.939771 -71.067753) (xy 111.927645 -71.013316)
			(xy 111.923574 -70.957694) (xy 107.496303 -70.957694) (xy 107.486898 -71.004218) (xy 107.4684 -71.055947)
			(xy 107.442674 -71.104487) (xy 107.410251 -71.148836) (xy 107.371801 -71.188074) (xy 107.32812 -71.221391)
			(xy 107.280112 -71.248098) (xy 107.22877 -71.267642) (xy 107.175154 -71.279619) (xy 107.120376 -71.283781)
			(xy 107.065566 -71.280042) (xy 107.01186 -71.26848) (xy 106.960368 -71.249333) (xy 106.936032 -71.236586)
			(xy 106.914738 -71.225541) (xy 106.869078 -71.21085) (xy 106.821472 -71.204986) (xy 106.773612 -71.208159)
			(xy 106.727197 -71.220254) (xy 106.683875 -71.240843) (xy 106.645186 -71.269195) (xy 106.628438 -71.28637)
			(xy 106.609341 -71.306121) (xy 106.566512 -71.34053) (xy 106.51919 -71.368438) (xy 106.474006 -71.386954)
			(xy 108.062774 -71.386954) (xy 108.066845 -71.331332) (xy 108.078971 -71.276895) (xy 108.098894 -71.224804)
			(xy 108.12619 -71.176169) (xy 108.160276 -71.132026) (xy 108.200425 -71.093317) (xy 108.245783 -71.060866)
			(xy 108.295383 -71.035365) (xy 108.348167 -71.017358) (xy 108.40301 -71.007228) (xy 108.458744 -71.005191)
			(xy 108.514181 -71.011291) (xy 108.568138 -71.025397) (xy 108.619467 -71.047209) (xy 108.667073 -71.076263)
			(xy 108.709941 -71.111938) (xy 108.747158 -71.153475) (xy 108.777931 -71.199988) (xy 108.801603 -71.250485)
			(xy 108.817671 -71.303892) (xy 108.825791 -71.359068) (xy 108.8263 -71.386954) (xy 108.825791 -71.41484)
			(xy 108.817671 -71.470016) (xy 108.801603 -71.523423) (xy 108.794611 -71.538338) (xy 114.654582 -71.538338)
			(xy 114.658653 -71.482716) (xy 114.670779 -71.428279) (xy 114.690702 -71.376188) (xy 114.717998 -71.327553)
			(xy 114.752084 -71.28341) (xy 114.792233 -71.244701) (xy 114.837591 -71.21225) (xy 114.887191 -71.186749)
			(xy 114.939975 -71.168742) (xy 114.994818 -71.158612) (xy 115.050552 -71.156575) (xy 115.105989 -71.162675)
			(xy 115.159946 -71.176781) (xy 115.211275 -71.198593) (xy 115.258881 -71.227647) (xy 115.301749 -71.263322)
			(xy 115.338966 -71.304859) (xy 115.369739 -71.351372) (xy 115.393411 -71.401869) (xy 115.409479 -71.455276)
			(xy 115.417599 -71.510452) (xy 115.418108 -71.538338) (xy 115.417599 -71.566224) (xy 115.409479 -71.6214)
			(xy 115.393411 -71.674807) (xy 115.369739 -71.725304) (xy 115.338966 -71.771817) (xy 115.301749 -71.813354)
			(xy 115.258881 -71.849029) (xy 115.211275 -71.878083) (xy 115.159946 -71.899895) (xy 115.105989 -71.914001)
			(xy 115.050552 -71.920101) (xy 114.994818 -71.918064) (xy 114.939975 -71.907934) (xy 114.887191 -71.889927)
			(xy 114.837591 -71.864426) (xy 114.792233 -71.831975) (xy 114.752084 -71.793266) (xy 114.717998 -71.749123)
			(xy 114.690702 -71.700488) (xy 114.670779 -71.648397) (xy 114.658653 -71.59396) (xy 114.654582 -71.538338)
			(xy 108.794611 -71.538338) (xy 108.777931 -71.57392) (xy 108.747158 -71.620433) (xy 108.709941 -71.66197)
			(xy 108.667073 -71.697645) (xy 108.619467 -71.726699) (xy 108.568138 -71.748511) (xy 108.514181 -71.762617)
			(xy 108.458744 -71.768717) (xy 108.40301 -71.76668) (xy 108.348167 -71.75655) (xy 108.295383 -71.738543)
			(xy 108.245783 -71.713042) (xy 108.200425 -71.680591) (xy 108.160276 -71.641882) (xy 108.12619 -71.597739)
			(xy 108.098894 -71.549104) (xy 108.078971 -71.497013) (xy 108.066845 -71.442576) (xy 108.062774 -71.386954)
			(xy 106.474006 -71.386954) (xy 106.468354 -71.38927) (xy 106.415055 -71.402594) (xy 106.360397 -71.408135)
			(xy 106.305508 -71.405778) (xy 106.251526 -71.395572) (xy 106.199566 -71.377727) (xy 106.150703 -71.352614)
			(xy 106.105948 -71.320751) (xy 106.066227 -71.282797) (xy 106.03236 -71.239538) (xy 106.00505 -71.191869)
			(xy 105.98486 -71.140774) (xy 105.972208 -71.087312) (xy 105.967355 -71.032588) (xy 76.997232 -71.032588)
			(xy 76.976236 -71.081108) (xy 76.946716 -71.128707) (xy 76.910552 -71.171477) (xy 76.889864 -71.190358)
			(xy 76.873666 -71.205182) (xy 76.846189 -71.239429) (xy 76.825011 -71.277891) (xy 76.810762 -71.319421)
			(xy 76.803867 -71.362784) (xy 76.804532 -71.406686) (xy 76.812736 -71.449819) (xy 76.828235 -71.4909)
			(xy 76.850567 -71.528703) (xy 76.864464 -71.545704) (xy 76.882274 -71.567322) (xy 76.911975 -71.61481)
			(xy 76.934413 -71.66613) (xy 76.949106 -71.720179) (xy 76.955738 -71.775796) (xy 76.954166 -71.831785)
			(xy 76.944425 -71.886942) (xy 76.943579 -71.889481) (xy 99.55704 -71.889481) (xy 99.557347 -71.83503)
			(xy 99.56539 -71.781176) (xy 99.581008 -71.729011) (xy 99.603881 -71.679597) (xy 99.633547 -71.633936)
			(xy 99.669403 -71.592955) (xy 99.71072 -71.557488) (xy 99.756659 -71.528254) (xy 99.806287 -71.505847)
			(xy 99.858596 -71.490722) (xy 99.912524 -71.483187) (xy 99.966976 -71.483394) (xy 100.020845 -71.491339)
			(xy 100.073037 -71.506861) (xy 100.122494 -71.529645) (xy 100.168209 -71.559228) (xy 100.209254 -71.595009)
			(xy 100.244797 -71.636261) (xy 100.274115 -71.682146) (xy 100.285804 -71.70674) (xy 100.293136 -71.721625)
			(xy 100.31415 -71.747286) (xy 100.341075 -71.766656) (xy 100.372087 -71.778421) (xy 100.405084 -71.781784)
			(xy 100.437831 -71.776519) (xy 100.45319 -71.77024) (xy 100.479034 -71.759259) (xy 100.533102 -71.744106)
			(xy 100.588807 -71.737041) (xy 100.644945 -71.738216) (xy 100.700305 -71.747606) (xy 100.753692 -71.765009)
			(xy 100.803951 -71.790048) (xy 100.849997 -71.822183) (xy 100.890837 -71.860719) (xy 100.925588 -71.904825)
			(xy 100.953499 -71.953547) (xy 100.973969 -72.005834) (xy 100.986554 -72.060557) (xy 100.990982 -72.116533)
			(xy 100.987159 -72.172554) (xy 100.975167 -72.227409) (xy 100.955265 -72.279915) (xy 100.950383 -72.288654)
			(xy 107.105194 -72.288654) (xy 107.109265 -72.233032) (xy 107.121391 -72.178595) (xy 107.141314 -72.126504)
			(xy 107.16861 -72.077869) (xy 107.202696 -72.033726) (xy 107.242845 -71.995017) (xy 107.288203 -71.962566)
			(xy 107.337803 -71.937065) (xy 107.390587 -71.919058) (xy 107.44543 -71.908928) (xy 107.501164 -71.906891)
			(xy 107.556601 -71.912991) (xy 107.610558 -71.927097) (xy 107.661887 -71.948909) (xy 107.684186 -71.962518)
			(xy 112.874042 -71.962518) (xy 112.878113 -71.906896) (xy 112.890239 -71.852459) (xy 112.910162 -71.800368)
			(xy 112.937458 -71.751733) (xy 112.971544 -71.70759) (xy 113.011693 -71.668881) (xy 113.057051 -71.63643)
			(xy 113.106651 -71.610929) (xy 113.159435 -71.592922) (xy 113.214278 -71.582792) (xy 113.270012 -71.580755)
			(xy 113.325449 -71.586855) (xy 113.379406 -71.600961) (xy 113.430735 -71.622773) (xy 113.478341 -71.651827)
			(xy 113.521209 -71.687502) (xy 113.558426 -71.729039) (xy 113.589199 -71.775552) (xy 113.612871 -71.826049)
			(xy 113.628939 -71.879456) (xy 113.637059 -71.934632) (xy 113.637568 -71.962518) (xy 113.637059 -71.990404)
			(xy 113.628939 -72.04558) (xy 113.612871 -72.098987) (xy 113.589199 -72.149484) (xy 113.558426 -72.195997)
			(xy 113.521209 -72.237534) (xy 113.478341 -72.273209) (xy 113.430735 -72.302263) (xy 113.379406 -72.324075)
			(xy 113.325449 -72.338181) (xy 113.270012 -72.344281) (xy 113.214278 -72.342244) (xy 113.159435 -72.332114)
			(xy 113.106651 -72.314107) (xy 113.057051 -72.288606) (xy 113.011693 -72.256155) (xy 112.971544 -72.217446)
			(xy 112.937458 -72.173303) (xy 112.910162 -72.124668) (xy 112.890239 -72.072577) (xy 112.878113 -72.01814)
			(xy 112.874042 -71.962518) (xy 107.684186 -71.962518) (xy 107.709493 -71.977963) (xy 107.752361 -72.013638)
			(xy 107.789578 -72.055175) (xy 107.820351 -72.101688) (xy 107.844023 -72.152185) (xy 107.860091 -72.205592)
			(xy 107.868211 -72.260768) (xy 107.86872 -72.288654) (xy 107.868211 -72.31654) (xy 107.860091 -72.371716)
			(xy 107.844023 -72.425123) (xy 107.820351 -72.47562) (xy 107.789578 -72.522133) (xy 107.752361 -72.56367)
			(xy 107.709493 -72.599345) (xy 107.661887 -72.628399) (xy 107.610558 -72.650211) (xy 107.556601 -72.664317)
			(xy 107.501164 -72.670417) (xy 107.44543 -72.66838) (xy 107.390587 -72.65825) (xy 107.337803 -72.640243)
			(xy 107.288203 -72.614742) (xy 107.242845 -72.582291) (xy 107.202696 -72.543582) (xy 107.16861 -72.499439)
			(xy 107.141314 -72.450804) (xy 107.121391 -72.398713) (xy 107.109265 -72.344276) (xy 107.105194 -72.288654)
			(xy 100.950383 -72.288654) (xy 100.927882 -72.328936) (xy 100.893611 -72.373415) (xy 100.85319 -72.412391)
			(xy 100.807494 -72.445022) (xy 100.757509 -72.470604) (xy 100.704314 -72.488583) (xy 100.649059 -72.498572)
			(xy 100.592936 -72.500354) (xy 100.537158 -72.493892) (xy 100.48293 -72.479325) (xy 100.431422 -72.456968)
			(xy 100.383747 -72.427302) (xy 100.340934 -72.39097) (xy 100.303909 -72.348756) (xy 100.273471 -72.301571)
			(xy 100.26142 -72.276208) (xy 100.254044 -72.261346) (xy 100.233042 -72.235681) (xy 100.206127 -72.216307)
			(xy 100.175124 -72.204538) (xy 100.142133 -72.201169) (xy 100.10939 -72.206431) (xy 100.094034 -72.212708)
			(xy 100.069005 -72.223432) (xy 100.016641 -72.238366) (xy 99.962686 -72.245705) (xy 99.908236 -72.245299)
			(xy 99.854396 -72.237157) (xy 99.80226 -72.221445) (xy 99.752888 -72.198481) (xy 99.70728 -72.168732)
			(xy 99.666365 -72.132802) (xy 99.630973 -72.091421) (xy 99.601823 -72.045428) (xy 99.579507 -71.99576)
			(xy 99.564477 -71.943423) (xy 99.55704 -71.889481) (xy 76.943579 -71.889481) (xy 76.926723 -71.940083)
			(xy 76.901441 -71.990063) (xy 76.869123 -72.03581) (xy 76.830463 -72.07634) (xy 76.786293 -72.110781)
			(xy 76.737561 -72.138393) (xy 76.685316 -72.158583) (xy 76.63068 -72.170917) (xy 76.574827 -72.175129)
			(xy 76.518959 -72.17113) (xy 76.464277 -72.159004) (xy 76.411955 -72.139013) (xy 76.363118 -72.111586)
			(xy 76.318817 -72.077314) (xy 76.280003 -72.036931) (xy 76.247511 -71.991308) (xy 76.222039 -71.941424)
			(xy 76.204135 -71.888352) (xy 76.194184 -71.833232) (xy 76.192399 -71.777249) (xy 71.951745 -71.777249)
			(xy 71.943316 -71.780091) (xy 71.888051 -71.790038) (xy 71.831925 -71.791775) (xy 71.776151 -71.785266)
			(xy 71.721933 -71.770651) (xy 71.670443 -71.748247) (xy 71.622794 -71.718536) (xy 71.580015 -71.682162)
			(xy 71.543031 -71.639909) (xy 71.527416 -71.61657) (xy 71.514916 -71.598058) (xy 71.484557 -71.5653)
			(xy 71.448938 -71.538354) (xy 71.409158 -71.51805) (xy 71.36644 -71.505013) (xy 71.322101 -71.499645)
			(xy 71.277506 -71.50211) (xy 71.234029 -71.512334) (xy 71.193009 -71.530002) (xy 71.174102 -71.541894)
			(xy 71.14939 -71.557525) (xy 71.096218 -71.581851) (xy 71.03996 -71.597784) (xy 70.981929 -71.604953)
			(xy 70.923484 -71.603191) (xy 70.865991 -71.592537) (xy 70.810794 -71.573242) (xy 70.759185 -71.545756)
			(xy 70.735444 -71.528686) (xy 70.716432 -71.51509) (xy 70.674549 -71.494358) (xy 70.629581 -71.481632)
			(xy 70.583044 -71.477342) (xy 70.536507 -71.481632) (xy 70.491539 -71.494358) (xy 70.449656 -71.51509)
			(xy 70.430644 -71.528686) (xy 70.408553 -71.544648) (xy 70.360722 -71.570771) (xy 70.309659 -71.58982)
			(xy 70.256405 -71.601406) (xy 70.202044 -71.605295) (xy 70.147683 -71.601406) (xy 70.094429 -71.58982)
			(xy 70.043366 -71.570771) (xy 69.995535 -71.544648) (xy 69.973444 -71.528686) (xy 69.954432 -71.51509)
			(xy 69.912549 -71.494358) (xy 69.867581 -71.481632) (xy 69.821044 -71.477342) (xy 69.774507 -71.481632)
			(xy 69.729539 -71.494358) (xy 69.687656 -71.51509) (xy 69.668644 -71.528686) (xy 69.646553 -71.544648)
			(xy 69.598722 -71.570771) (xy 69.547659 -71.58982) (xy 69.494405 -71.601406) (xy 69.440044 -71.605295)
			(xy 69.385683 -71.601406) (xy 69.332429 -71.58982) (xy 69.281366 -71.570771) (xy 69.233535 -71.544648)
			(xy 69.211444 -71.528686) (xy 69.192432 -71.51509) (xy 69.150549 -71.494358) (xy 69.105581 -71.481632)
			(xy 69.059044 -71.477342) (xy 69.012507 -71.481632) (xy 68.967539 -71.494358) (xy 68.925656 -71.51509)
			(xy 68.906644 -71.528686) (xy 68.884553 -71.544648) (xy 68.836722 -71.570771) (xy 68.785659 -71.58982)
			(xy 68.732405 -71.601406) (xy 68.678044 -71.605295) (xy 68.623683 -71.601406) (xy 68.570429 -71.58982)
			(xy 68.519366 -71.570771) (xy 68.471535 -71.544648) (xy 68.449444 -71.528686) (xy 68.430432 -71.51509)
			(xy 68.388549 -71.494358) (xy 68.343581 -71.481632) (xy 68.297044 -71.477342) (xy 68.250507 -71.481632)
			(xy 68.205539 -71.494358) (xy 68.163656 -71.51509) (xy 68.144644 -71.528686) (xy 68.122553 -71.544648)
			(xy 68.074722 -71.570771) (xy 68.023659 -71.58982) (xy 67.970405 -71.601406) (xy 67.916044 -71.605295)
			(xy 67.861683 -71.601406) (xy 67.808429 -71.58982) (xy 67.757366 -71.570771) (xy 67.709535 -71.544648)
			(xy 67.687444 -71.528686) (xy 67.668432 -71.51509) (xy 67.626549 -71.494358) (xy 67.581581 -71.481632)
			(xy 67.535044 -71.477342) (xy 67.488507 -71.481632) (xy 67.443539 -71.494358) (xy 67.401656 -71.51509)
			(xy 67.382644 -71.528686) (xy 67.360574 -71.544564) (xy 67.312869 -71.570638) (xy 67.261946 -71.589676)
			(xy 67.208835 -71.60129) (xy 67.154614 -71.605246) (xy 67.100379 -71.601464) (xy 67.047232 -71.590021)
			(xy 66.996247 -71.571147) (xy 66.948459 -71.545226) (xy 66.904835 -71.512782) (xy 66.866259 -71.474474)
			(xy 66.833513 -71.431077) (xy 66.807259 -71.38347) (xy 66.788031 -71.332618) (xy 66.776218 -71.279551)
			(xy 66.772059 -71.225345) (xy 65.610781 -71.225345) (xy 65.59205 -71.253657) (xy 65.554833 -71.295194)
			(xy 65.511965 -71.330869) (xy 65.464359 -71.359923) (xy 65.41303 -71.381735) (xy 65.359073 -71.395841)
			(xy 65.303636 -71.401941) (xy 65.247902 -71.399904) (xy 65.193059 -71.389774) (xy 65.140275 -71.371767)
			(xy 65.090675 -71.346266) (xy 65.045317 -71.313815) (xy 65.005168 -71.275106) (xy 64.971082 -71.230963)
			(xy 64.943786 -71.182328) (xy 64.923863 -71.130237) (xy 64.911737 -71.0758) (xy 64.907666 -71.020178)
			(xy 57.242207 -71.020178) (xy 57.269935 -71.023229) (xy 57.323892 -71.037335) (xy 57.375221 -71.059147)
			(xy 57.422827 -71.088201) (xy 57.465695 -71.123876) (xy 57.502912 -71.165413) (xy 57.533685 -71.211926)
			(xy 57.557357 -71.262423) (xy 57.573425 -71.31583) (xy 57.581545 -71.371006) (xy 57.582054 -71.398892)
			(xy 57.581545 -71.426778) (xy 57.573425 -71.481954) (xy 57.557357 -71.535361) (xy 57.533685 -71.585858)
			(xy 57.502912 -71.632371) (xy 57.465695 -71.673908) (xy 57.422827 -71.709583) (xy 57.375221 -71.738637)
			(xy 57.323892 -71.760449) (xy 57.269935 -71.774555) (xy 57.214498 -71.780655) (xy 57.158764 -71.778618)
			(xy 57.103921 -71.768488) (xy 57.051137 -71.750481) (xy 57.001537 -71.72498) (xy 56.956179 -71.692529)
			(xy 56.91603 -71.65382) (xy 56.881944 -71.609677) (xy 56.854648 -71.561042) (xy 56.834725 -71.508951)
			(xy 56.822599 -71.454514) (xy 56.818528 -71.398892) (xy 56.000937 -71.398892) (xy 56.000937 -71.427232)
			(xy 55.992964 -71.483322) (xy 55.977179 -71.537733) (xy 55.953895 -71.589381) (xy 55.923575 -71.637239)
			(xy 55.886823 -71.680355) (xy 55.84437 -71.71787) (xy 55.797061 -71.749039) (xy 55.745837 -71.773241)
			(xy 55.691716 -71.789995) (xy 55.635777 -71.798967) (xy 55.579132 -71.799979) (xy 55.522909 -71.79301)
			(xy 55.468225 -71.7782) (xy 55.416169 -71.755843) (xy 55.367777 -71.726383) (xy 55.345584 -71.708772)
			(xy 55.328926 -71.695606) (xy 55.292079 -71.674509) (xy 55.252239 -71.659827) (xy 55.210513 -71.651967)
			(xy 55.168062 -71.65115) (xy 55.126065 -71.657396) (xy 55.085689 -71.670533) (xy 55.048057 -71.690196)
			(xy 55.030878 -71.702676) (xy 55.008084 -71.719303) (xy 54.958609 -71.746417) (xy 54.905683 -71.765956)
			(xy 54.850458 -71.777493) (xy 54.794136 -71.780777) (xy 54.737945 -71.775738) (xy 54.683106 -71.762484)
			(xy 54.630815 -71.741304) (xy 54.582211 -71.712659) (xy 54.559962 -71.69531) (xy 54.542888 -71.682048)
			(xy 54.505168 -71.660929) (xy 54.464417 -71.646502) (xy 54.421811 -71.639183) (xy 54.378581 -71.639183)
			(xy 54.335975 -71.646502) (xy 54.295224 -71.660929) (xy 54.257504 -71.682048) (xy 54.24043 -71.69531)
			(xy 54.218581 -71.712401) (xy 54.170888 -71.740731) (xy 54.119597 -71.761856) (xy 54.065787 -71.775333)
			(xy 54.010594 -71.780877) (xy 53.955179 -71.778372) (xy 53.90071 -71.767869) (xy 53.848336 -71.749592)
			(xy 53.799161 -71.723923) (xy 53.75422 -71.691406) (xy 53.71446 -71.652724) (xy 53.68072 -71.608693)
			(xy 53.65371 -71.560241) (xy 53.634001 -71.50839) (xy 53.622006 -71.45423) (xy 53.617979 -71.398905)
			(xy 52.781951 -71.398905) (xy 52.777925 -71.454216) (xy 52.765935 -71.50836) (xy 52.746232 -71.560199)
			(xy 52.719231 -71.608639) (xy 52.685503 -71.65266) (xy 52.645756 -71.691334) (xy 52.60083 -71.723847)
			(xy 52.55167 -71.749512) (xy 52.499312 -71.767791) (xy 52.444859 -71.778296) (xy 52.389459 -71.780808)
			(xy 52.334279 -71.775273) (xy 52.280482 -71.761808) (xy 52.229201 -71.740696) (xy 52.181517 -71.712383)
			(xy 52.159662 -71.69531) (xy 52.142588 -71.682048) (xy 52.104868 -71.660929) (xy 52.064117 -71.646502)
			(xy 52.021511 -71.639183) (xy 51.978281 -71.639183) (xy 51.935675 -71.646502) (xy 51.894924 -71.660929)
			(xy 51.857204 -71.682048) (xy 51.84013 -71.69531) (xy 51.818281 -71.712401) (xy 51.770588 -71.740731)
			(xy 51.719297 -71.761856) (xy 51.665487 -71.775333) (xy 51.610294 -71.780877) (xy 51.554879 -71.778372)
			(xy 51.50041 -71.767869) (xy 51.448036 -71.749592) (xy 51.398861 -71.723923) (xy 51.35392 -71.691406)
			(xy 51.31416 -71.652724) (xy 51.28042 -71.608693) (xy 51.25341 -71.560241) (xy 51.233701 -71.50839)
			(xy 51.221706 -71.45423) (xy 51.217679 -71.398905) (xy 46.026565 -71.398905) (xy 44.93641 -72.48906)
			(xy 44.924202 -72.502069) (xy 44.906898 -72.533248) (xy 44.899364 -72.566022) (xy 46.277274 -72.566022)
			(xy 46.281345 -72.5104) (xy 46.293471 -72.455963) (xy 46.313394 -72.403872) (xy 46.34069 -72.355237)
			(xy 46.374776 -72.311094) (xy 46.414925 -72.272385) (xy 46.460283 -72.239934) (xy 46.509883 -72.214433)
			(xy 46.562667 -72.196426) (xy 46.61751 -72.186296) (xy 46.673244 -72.184259) (xy 46.728681 -72.190359)
			(xy 46.761703 -72.198992) (xy 60.018928 -72.198992) (xy 60.022999 -72.14337) (xy 60.035125 -72.088933)
			(xy 60.055048 -72.036842) (xy 60.082344 -71.988207) (xy 60.11643 -71.944064) (xy 60.156579 -71.905355)
			(xy 60.201937 -71.872904) (xy 60.251537 -71.847403) (xy 60.304321 -71.829396) (xy 60.359164 -71.819266)
			(xy 60.414898 -71.817229) (xy 60.470335 -71.823329) (xy 60.524292 -71.837435) (xy 60.575621 -71.859247)
			(xy 60.623227 -71.888301) (xy 60.666095 -71.923976) (xy 60.703312 -71.965513) (xy 60.734085 -72.012026)
			(xy 60.757757 -72.062523) (xy 60.773825 -72.11593) (xy 60.781945 -72.171106) (xy 60.782454 -72.198992)
			(xy 61.619128 -72.198992) (xy 61.623199 -72.14337) (xy 61.635325 -72.088933) (xy 61.655248 -72.036842)
			(xy 61.682544 -71.988207) (xy 61.71663 -71.944064) (xy 61.756779 -71.905355) (xy 61.802137 -71.872904)
			(xy 61.851737 -71.847403) (xy 61.904521 -71.829396) (xy 61.959364 -71.819266) (xy 62.015098 -71.817229)
			(xy 62.070535 -71.823329) (xy 62.124492 -71.837435) (xy 62.175821 -71.859247) (xy 62.223427 -71.888301)
			(xy 62.266295 -71.923976) (xy 62.303512 -71.965513) (xy 62.334285 -72.012026) (xy 62.357957 -72.062523)
			(xy 62.374025 -72.11593) (xy 62.382145 -72.171106) (xy 62.382654 -72.198992) (xy 63.219328 -72.198992)
			(xy 63.223399 -72.14337) (xy 63.235525 -72.088933) (xy 63.255448 -72.036842) (xy 63.282744 -71.988207)
			(xy 63.31683 -71.944064) (xy 63.356979 -71.905355) (xy 63.402337 -71.872904) (xy 63.451937 -71.847403)
			(xy 63.504721 -71.829396) (xy 63.559564 -71.819266) (xy 63.615298 -71.817229) (xy 63.670735 -71.823329)
			(xy 63.724692 -71.837435) (xy 63.776021 -71.859247) (xy 63.823627 -71.888301) (xy 63.866495 -71.923976)
			(xy 63.903712 -71.965513) (xy 63.934485 -72.012026) (xy 63.958157 -72.062523) (xy 63.974225 -72.11593)
			(xy 63.982345 -72.171106) (xy 63.982854 -72.198992) (xy 63.982345 -72.226878) (xy 63.974225 -72.282054)
			(xy 63.958157 -72.335461) (xy 63.934485 -72.385958) (xy 63.903712 -72.432471) (xy 63.866495 -72.474008)
			(xy 63.823627 -72.509683) (xy 63.776021 -72.538737) (xy 63.724692 -72.560549) (xy 63.670735 -72.574655)
			(xy 63.615298 -72.580755) (xy 63.559564 -72.578718) (xy 63.504721 -72.568588) (xy 63.451937 -72.550581)
			(xy 63.402337 -72.52508) (xy 63.356979 -72.492629) (xy 63.31683 -72.45392) (xy 63.282744 -72.409777)
			(xy 63.255448 -72.361142) (xy 63.235525 -72.309051) (xy 63.223399 -72.254614) (xy 63.219328 -72.198992)
			(xy 62.382654 -72.198992) (xy 62.382145 -72.226878) (xy 62.374025 -72.282054) (xy 62.357957 -72.335461)
			(xy 62.334285 -72.385958) (xy 62.303512 -72.432471) (xy 62.266295 -72.474008) (xy 62.223427 -72.509683)
			(xy 62.175821 -72.538737) (xy 62.124492 -72.560549) (xy 62.070535 -72.574655) (xy 62.015098 -72.580755)
			(xy 61.959364 -72.578718) (xy 61.904521 -72.568588) (xy 61.851737 -72.550581) (xy 61.802137 -72.52508)
			(xy 61.756779 -72.492629) (xy 61.71663 -72.45392) (xy 61.682544 -72.409777) (xy 61.655248 -72.361142)
			(xy 61.635325 -72.309051) (xy 61.623199 -72.254614) (xy 61.619128 -72.198992) (xy 60.782454 -72.198992)
			(xy 60.781945 -72.226878) (xy 60.773825 -72.282054) (xy 60.757757 -72.335461) (xy 60.734085 -72.385958)
			(xy 60.703312 -72.432471) (xy 60.666095 -72.474008) (xy 60.623227 -72.509683) (xy 60.575621 -72.538737)
			(xy 60.524292 -72.560549) (xy 60.470335 -72.574655) (xy 60.414898 -72.580755) (xy 60.359164 -72.578718)
			(xy 60.304321 -72.568588) (xy 60.251537 -72.550581) (xy 60.201937 -72.52508) (xy 60.156579 -72.492629)
			(xy 60.11643 -72.45392) (xy 60.082344 -72.409777) (xy 60.055048 -72.361142) (xy 60.035125 -72.309051)
			(xy 60.022999 -72.254614) (xy 60.018928 -72.198992) (xy 46.761703 -72.198992) (xy 46.782638 -72.204465)
			(xy 46.833967 -72.226277) (xy 46.881573 -72.255331) (xy 46.924441 -72.291006) (xy 46.961658 -72.332543)
			(xy 46.992431 -72.379056) (xy 47.016103 -72.429553) (xy 47.032171 -72.48296) (xy 47.040291 -72.538136)
			(xy 47.0408 -72.566022) (xy 47.040291 -72.593908) (xy 47.032171 -72.649084) (xy 47.016103 -72.702491)
			(xy 47.00161 -72.733408) (xy 47.32223 -72.733408) (xy 47.326301 -72.677786) (xy 47.338427 -72.623349)
			(xy 47.35835 -72.571258) (xy 47.385646 -72.522623) (xy 47.419732 -72.47848) (xy 47.459881 -72.439771)
			(xy 47.505239 -72.40732) (xy 47.554839 -72.381819) (xy 47.607623 -72.363812) (xy 47.662466 -72.353682)
			(xy 47.7182 -72.351645) (xy 47.773637 -72.357745) (xy 47.827594 -72.371851) (xy 47.878923 -72.393663)
			(xy 47.926529 -72.422717) (xy 47.969397 -72.458392) (xy 48.006614 -72.499929) (xy 48.037387 -72.546442)
			(xy 48.061059 -72.596939) (xy 48.077127 -72.650346) (xy 48.083034 -72.690482) (xy 48.461674 -72.690482)
			(xy 48.465745 -72.63486) (xy 48.477871 -72.580423) (xy 48.497794 -72.528332) (xy 48.52509 -72.479697)
			(xy 48.559176 -72.435554) (xy 48.599325 -72.396845) (xy 48.644683 -72.364394) (xy 48.694283 -72.338893)
			(xy 48.747067 -72.320886) (xy 48.80191 -72.310756) (xy 48.857644 -72.308719) (xy 48.913081 -72.314819)
			(xy 48.967038 -72.328925) (xy 49.018367 -72.350737) (xy 49.065973 -72.379791) (xy 49.108841 -72.415466)
			(xy 49.146058 -72.457003) (xy 49.176831 -72.503516) (xy 49.200503 -72.554013) (xy 49.216571 -72.60742)
			(xy 49.224691 -72.662596) (xy 49.2252 -72.690482) (xy 49.224691 -72.718368) (xy 49.216571 -72.773544)
			(xy 49.200503 -72.826951) (xy 49.176831 -72.877448) (xy 49.146058 -72.923961) (xy 49.108841 -72.965498)
			(xy 49.068474 -72.999092) (xy 54.418228 -72.999092) (xy 54.422299 -72.94347) (xy 54.434425 -72.889033)
			(xy 54.454348 -72.836942) (xy 54.481644 -72.788307) (xy 54.51573 -72.744164) (xy 54.555879 -72.705455)
			(xy 54.601237 -72.673004) (xy 54.650837 -72.647503) (xy 54.703621 -72.629496) (xy 54.758464 -72.619366)
			(xy 54.814198 -72.617329) (xy 54.869635 -72.623429) (xy 54.923592 -72.637535) (xy 54.974921 -72.659347)
			(xy 55.022527 -72.688401) (xy 55.065395 -72.724076) (xy 55.102612 -72.765613) (xy 55.133385 -72.812126)
			(xy 55.157057 -72.862623) (xy 55.173125 -72.91603) (xy 55.181245 -72.971206) (xy 55.181754 -72.999092)
			(xy 56.818528 -72.999092) (xy 56.822599 -72.94347) (xy 56.834725 -72.889033) (xy 56.854648 -72.836942)
			(xy 56.881944 -72.788307) (xy 56.91603 -72.744164) (xy 56.956179 -72.705455) (xy 57.001537 -72.673004)
			(xy 57.051137 -72.647503) (xy 57.103921 -72.629496) (xy 57.158764 -72.619366) (xy 57.214498 -72.617329)
			(xy 57.269935 -72.623429) (xy 57.323892 -72.637535) (xy 57.375221 -72.659347) (xy 57.422827 -72.688401)
			(xy 57.465695 -72.724076) (xy 57.502912 -72.765613) (xy 57.533685 -72.812126) (xy 57.557357 -72.862623)
			(xy 57.573425 -72.91603) (xy 57.581545 -72.971206) (xy 57.582054 -72.999092) (xy 58.418728 -72.999092)
			(xy 58.422799 -72.94347) (xy 58.434925 -72.889033) (xy 58.454848 -72.836942) (xy 58.482144 -72.788307)
			(xy 58.51623 -72.744164) (xy 58.556379 -72.705455) (xy 58.601737 -72.673004) (xy 58.651337 -72.647503)
			(xy 58.704121 -72.629496) (xy 58.758964 -72.619366) (xy 58.814698 -72.617329) (xy 58.870135 -72.623429)
			(xy 58.924092 -72.637535) (xy 58.975421 -72.659347) (xy 59.023027 -72.688401) (xy 59.065895 -72.724076)
			(xy 59.103112 -72.765613) (xy 59.133885 -72.812126) (xy 59.157557 -72.862623) (xy 59.173625 -72.91603)
			(xy 59.181745 -72.971206) (xy 59.182254 -72.999092) (xy 59.181745 -73.026978) (xy 59.173625 -73.082154)
			(xy 59.157557 -73.135561) (xy 59.133885 -73.186058) (xy 59.115448 -73.213925) (xy 66.390912 -73.213925)
			(xy 66.394396 -73.157937) (xy 66.40604 -73.103062) (xy 66.425593 -73.050483) (xy 66.452633 -73.001333)
			(xy 66.486578 -72.956672) (xy 66.526695 -72.917463) (xy 66.572122 -72.884549) (xy 66.621877 -72.858641)
			(xy 66.67489 -72.840297) (xy 66.730017 -72.829912) (xy 66.786071 -72.827711) (xy 66.841843 -72.83374)
			(xy 66.896131 -72.847869) (xy 66.922142 -72.858376) (xy 66.943504 -72.866912) (xy 66.988389 -72.876975)
			(xy 67.034352 -72.878795) (xy 67.079892 -72.872313) (xy 67.123521 -72.85774) (xy 67.163815 -72.835552)
			(xy 67.199458 -72.806475) (xy 67.21475 -72.789288) (xy 67.233357 -72.768293) (xy 67.275602 -72.731383)
			(xy 67.322796 -72.701057) (xy 67.373921 -72.677968) (xy 67.427876 -72.662613) (xy 67.483498 -72.655325)
			(xy 67.539588 -72.656258) (xy 67.594937 -72.665395) (xy 67.648351 -72.682537) (xy 67.664547 -72.690511)
			(xy 68.310883 -72.690511) (xy 68.314769 -72.636157) (xy 68.326351 -72.58291) (xy 68.345394 -72.531852)
			(xy 68.371508 -72.484025) (xy 68.404164 -72.440401) (xy 68.442696 -72.401869) (xy 68.486319 -72.369212)
			(xy 68.534146 -72.343097) (xy 68.585203 -72.324053) (xy 68.63845 -72.31247) (xy 68.692804 -72.308583)
			(xy 68.747157 -72.312472) (xy 68.800404 -72.324056) (xy 68.851461 -72.3431) (xy 68.899287 -72.369216)
			(xy 68.921376 -72.385174) (xy 68.940388 -72.39877) (xy 68.982271 -72.419502) (xy 69.027239 -72.432228)
			(xy 69.073776 -72.436518) (xy 69.120313 -72.432228) (xy 69.165281 -72.419502) (xy 69.207164 -72.39877)
			(xy 69.226176 -72.385174) (xy 69.248267 -72.369212) (xy 69.296098 -72.343089) (xy 69.347161 -72.32404)
			(xy 69.400415 -72.312454) (xy 69.454776 -72.308565) (xy 69.509137 -72.312454) (xy 69.562391 -72.32404)
			(xy 69.613454 -72.343089) (xy 69.661285 -72.369212) (xy 69.683376 -72.385174) (xy 69.702388 -72.39877)
			(xy 69.744271 -72.419502) (xy 69.789239 -72.432228) (xy 69.835776 -72.436518) (xy 69.882313 -72.432228)
			(xy 69.927281 -72.419502) (xy 69.969164 -72.39877) (xy 69.988176 -72.385174) (xy 70.010899 -72.368699)
			(xy 70.060267 -72.341998) (xy 70.113015 -72.322819) (xy 70.168005 -72.311578) (xy 70.224048 -72.308518)
			(xy 70.279935 -72.313703) (xy 70.334458 -72.327022) (xy 70.386441 -72.348188) (xy 70.43476 -72.376744)
			(xy 70.478373 -72.412073) (xy 70.516338 -72.453411) (xy 70.532498 -72.47636) (xy 70.541179 -72.488335)
			(xy 70.562966 -72.508324) (xy 70.588771 -72.522758) (xy 70.617206 -72.530861) (xy 70.646743 -72.532198)
			(xy 70.675794 -72.526696) (xy 70.68947 -72.521064) (xy 70.715154 -72.510076) (xy 70.768931 -72.494951)
			(xy 70.824339 -72.487831) (xy 70.880193 -72.488867) (xy 70.935298 -72.498037) (xy 70.988478 -72.515145)
			(xy 71.038593 -72.539826) (xy 71.084574 -72.571552) (xy 71.125437 -72.609644) (xy 71.143349 -72.632062)
			(xy 72.29551 -72.632062) (xy 72.299581 -72.57644) (xy 72.311707 -72.522003) (xy 72.33163 -72.469912)
			(xy 72.358926 -72.421277) (xy 72.393012 -72.377134) (xy 72.433161 -72.338425) (xy 72.478519 -72.305974)
			(xy 72.528119 -72.280473) (xy 72.580903 -72.262466) (xy 72.635746 -72.252336) (xy 72.69148 -72.250299)
			(xy 72.746917 -72.256399) (xy 72.800874 -72.270505) (xy 72.852203 -72.292317) (xy 72.899809 -72.321371)
			(xy 72.942677 -72.357046) (xy 72.979894 -72.398583) (xy 73.010667 -72.445096) (xy 73.034339 -72.495593)
			(xy 73.050407 -72.549) (xy 73.058527 -72.604176) (xy 73.059036 -72.632062) (xy 73.058527 -72.659948)
			(xy 73.057809 -72.664828) (xy 73.370184 -72.664828) (xy 73.374255 -72.609206) (xy 73.386381 -72.554769)
			(xy 73.406304 -72.502678) (xy 73.4336 -72.454043) (xy 73.467686 -72.4099) (xy 73.507835 -72.371191)
			(xy 73.553193 -72.33874) (xy 73.602793 -72.313239) (xy 73.655577 -72.295232) (xy 73.71042 -72.285102)
			(xy 73.766154 -72.283065) (xy 73.821591 -72.289165) (xy 73.875548 -72.303271) (xy 73.926877 -72.325083)
			(xy 73.974483 -72.354137) (xy 74.017351 -72.389812) (xy 74.054568 -72.431349) (xy 74.085341 -72.477862)
			(xy 74.109013 -72.528359) (xy 74.125081 -72.581766) (xy 74.133201 -72.636942) (xy 74.13371 -72.664828)
			(xy 74.133201 -72.692714) (xy 74.125081 -72.74789) (xy 74.109013 -72.801297) (xy 74.085341 -72.851794)
			(xy 74.083437 -72.854672) (xy 74.550846 -72.854672) (xy 74.552503 -72.799897) (xy 74.56198 -72.745923)
			(xy 74.579083 -72.693861) (xy 74.603459 -72.644781) (xy 74.634607 -72.599695) (xy 74.671887 -72.559529)
			(xy 74.71453 -72.525112) (xy 74.761659 -72.49715) (xy 74.812304 -72.47622) (xy 74.865423 -72.462752)
			(xy 74.919923 -72.457024) (xy 74.974681 -72.459153) (xy 75.028571 -72.469095) (xy 75.080484 -72.486647)
			(xy 75.129352 -72.511446) (xy 75.174168 -72.542982) (xy 75.194414 -72.56145) (xy 75.211559 -72.576912)
			(xy 75.25031 -72.602) (xy 75.292953 -72.619681) (xy 75.338087 -72.629377) (xy 75.384229 -72.630767)
			(xy 75.429864 -72.623808) (xy 75.473495 -72.608726) (xy 75.513687 -72.586018) (xy 75.531726 -72.57161)
			(xy 75.553193 -72.554347) (xy 75.600099 -72.525466) (xy 75.65067 -72.503629) (xy 75.703855 -72.489288)
			(xy 75.758549 -72.482742) (xy 75.813617 -72.484127) (xy 75.867913 -72.493414) (xy 75.92031 -72.510409)
			(xy 75.969719 -72.534761) (xy 76.015115 -72.565963) (xy 76.035662 -72.58431) (xy 76.053433 -72.600027)
			(xy 76.093627 -72.625219) (xy 76.137797 -72.642517) (xy 76.18441 -72.651318) (xy 76.231846 -72.651318)
			(xy 76.278459 -72.642517) (xy 76.322629 -72.625219) (xy 76.362823 -72.600027) (xy 76.380594 -72.58431)
			(xy 76.401881 -72.565312) (xy 76.449041 -72.533199) (xy 76.500457 -72.508467) (xy 76.554982 -72.491666)
			(xy 76.611401 -72.48317) (xy 76.668455 -72.48317) (xy 76.724874 -72.491666) (xy 76.779399 -72.508467)
			(xy 76.830815 -72.533199) (xy 76.877975 -72.565312) (xy 76.899262 -72.58431) (xy 76.917033 -72.600027)
			(xy 76.957227 -72.625219) (xy 77.001397 -72.642517) (xy 77.04801 -72.651318) (xy 77.095446 -72.651318)
			(xy 77.142059 -72.642517) (xy 77.186229 -72.625219) (xy 77.226423 -72.600027) (xy 77.244194 -72.58431)
			(xy 77.264795 -72.565858) (xy 77.310368 -72.534522) (xy 77.359986 -72.510093) (xy 77.412612 -72.493084)
			(xy 77.467142 -72.48385) (xy 77.522433 -72.482586) (xy 77.577328 -72.489317) (xy 77.630676 -72.503903)
			(xy 77.68136 -72.526038) (xy 77.728317 -72.555258) (xy 77.770563 -72.590951) (xy 77.804266 -72.629038)
			(xy 86.4084 -72.629038) (xy 86.414776 -72.574872) (xy 86.428801 -72.522167) (xy 86.450189 -72.471996)
			(xy 86.478503 -72.425382) (xy 86.513167 -72.383276) (xy 86.553475 -72.346535) (xy 86.598603 -72.315909)
			(xy 86.647634 -72.292021) (xy 86.699566 -72.27536) (xy 86.753342 -72.266264) (xy 86.807864 -72.264919)
			(xy 86.862023 -72.271352) (xy 86.914714 -72.285432) (xy 86.964862 -72.306873) (xy 86.988396 -72.320658)
			(xy 87.007248 -72.331625) (xy 87.047837 -72.347578) (xy 87.090554 -72.356368) (xy 87.134145 -72.357735)
			(xy 87.177329 -72.35164) (xy 87.218839 -72.338262) (xy 87.257455 -72.317994) (xy 87.292044 -72.291431)
			(xy 87.32159 -72.259352) (xy 87.345225 -72.2227) (xy 87.354156 -72.202802) (xy 87.365158 -72.177844)
			(xy 87.393369 -72.131162) (xy 87.427941 -72.088974) (xy 87.468169 -72.052138) (xy 87.513232 -72.021407)
			(xy 87.562212 -71.997406) (xy 87.614111 -71.980625) (xy 87.667871 -71.971406) (xy 87.722395 -71.969936)
			(xy 87.776574 -71.976246) (xy 87.829301 -71.990208) (xy 87.879503 -72.011535) (xy 87.926156 -72.039794)
			(xy 87.96831 -72.074409) (xy 88.005104 -72.114675) (xy 88.035789 -72.159769) (xy 88.05974 -72.208774)
			(xy 88.076468 -72.26069) (xy 88.085632 -72.314459) (xy 88.087046 -72.368985) (xy 88.080681 -72.423157)
			(xy 88.066666 -72.47587) (xy 88.045287 -72.52605) (xy 88.01698 -72.572674) (xy 87.982322 -72.614792)
			(xy 87.942019 -72.651546) (xy 87.896894 -72.682185) (xy 87.847864 -72.706085) (xy 87.795931 -72.72276)
			(xy 87.742153 -72.73187) (xy 87.687625 -72.733228) (xy 87.63346 -72.726808) (xy 87.580761 -72.712739)
			(xy 87.530603 -72.691309) (xy 87.507064 -72.677528) (xy 87.488169 -72.666639) (xy 87.44759 -72.650682)
			(xy 87.404882 -72.641887) (xy 87.361299 -72.640512) (xy 87.318122 -72.646599) (xy 87.276617 -72.659968)
			(xy 87.238005 -72.680227) (xy 87.203418 -72.70678) (xy 87.173873 -72.738848) (xy 87.150236 -72.77549)
			(xy 87.141304 -72.795384) (xy 87.130179 -72.820287) (xy 87.127394 -72.824893) (xy 105.939543 -72.824893)
			(xy 105.942476 -72.769111) (xy 105.953513 -72.714354) (xy 105.97242 -72.661792) (xy 105.99879 -72.61255)
			(xy 106.032061 -72.567681) (xy 106.071521 -72.528144) (xy 106.116326 -72.494786) (xy 106.165517 -72.46832)
			(xy 106.218042 -72.449312) (xy 106.272778 -72.438169) (xy 106.328554 -72.435129) (xy 106.384177 -72.440256)
			(xy 106.438458 -72.453442) (xy 106.490234 -72.474404) (xy 106.538399 -72.502694) (xy 106.581923 -72.537707)
			(xy 106.619874 -72.578693) (xy 106.651441 -72.624777) (xy 106.675949 -72.674972) (xy 106.692873 -72.728206)
			(xy 106.701852 -72.783338) (xy 106.702657 -72.836786) (xy 108.306868 -72.836786) (xy 108.310939 -72.781164)
			(xy 108.323065 -72.726727) (xy 108.342988 -72.674636) (xy 108.370284 -72.626001) (xy 108.40437 -72.581858)
			(xy 108.444519 -72.543149) (xy 108.489877 -72.510698) (xy 108.539477 -72.485197) (xy 108.592261 -72.46719)
			(xy 108.647104 -72.45706) (xy 108.702838 -72.455023) (xy 108.758275 -72.461123) (xy 108.812232 -72.475229)
			(xy 108.863561 -72.497041) (xy 108.911167 -72.526095) (xy 108.954035 -72.56177) (xy 108.991252 -72.603307)
			(xy 109.022025 -72.64982) (xy 109.045697 -72.700317) (xy 109.061765 -72.753724) (xy 109.069885 -72.8089)
			(xy 109.070394 -72.836786) (xy 109.069885 -72.864672) (xy 109.061765 -72.919848) (xy 109.045697 -72.973255)
			(xy 109.022025 -73.023752) (xy 108.991252 -73.070265) (xy 108.954035 -73.111802) (xy 108.911167 -73.147477)
			(xy 108.863561 -73.176531) (xy 108.812232 -73.198343) (xy 108.758275 -73.212449) (xy 108.702838 -73.218549)
			(xy 108.647104 -73.216512) (xy 108.592261 -73.206382) (xy 108.539477 -73.188375) (xy 108.489877 -73.162874)
			(xy 108.444519 -73.130423) (xy 108.40437 -73.091714) (xy 108.370284 -73.047571) (xy 108.342988 -72.998936)
			(xy 108.323065 -72.946845) (xy 108.310939 -72.892408) (xy 108.306868 -72.836786) (xy 106.702657 -72.836786)
			(xy 106.702693 -72.839191) (xy 106.695379 -72.894568) (xy 106.680065 -72.948287) (xy 106.65708 -72.999198)
			(xy 106.642408 -73.022968) (xy 106.630804 -73.041873) (xy 106.613728 -73.082812) (xy 106.604015 -73.126093)
			(xy 106.60196 -73.170402) (xy 106.607626 -73.214396) (xy 106.620839 -73.25674) (xy 106.641199 -73.296148)
			(xy 106.668089 -73.331426) (xy 106.684064 -73.346818) (xy 106.702352 -73.364598) (xy 106.718566 -73.380934)
			(xy 106.755744 -73.408059) (xy 106.797201 -73.428042) (xy 106.841579 -73.440231) (xy 106.887426 -73.444227)
			(xy 106.933244 -73.439898) (xy 106.977532 -73.427386) (xy 107.018841 -73.407101) (xy 107.055821 -73.379706)
			(xy 107.087261 -73.346098) (xy 107.100116 -73.327006) (xy 107.115367 -73.304113) (xy 107.151435 -73.262582)
			(xy 107.193094 -73.22666) (xy 107.23948 -73.197094) (xy 107.289631 -73.174495) (xy 107.342507 -73.159333)
			(xy 107.397013 -73.151922) (xy 107.452018 -73.152415) (xy 107.506383 -73.160802) (xy 107.558979 -73.17691)
			(xy 107.608717 -73.200404) (xy 107.654565 -73.230797) (xy 107.695573 -73.26746) (xy 107.730891 -73.309631)
			(xy 107.759786 -73.356438) (xy 107.765084 -73.368662) (xy 112.785142 -73.368662) (xy 112.789213 -73.31304)
			(xy 112.801339 -73.258603) (xy 112.821262 -73.206512) (xy 112.848558 -73.157877) (xy 112.882644 -73.113734)
			(xy 112.922793 -73.075025) (xy 112.968151 -73.042574) (xy 113.017751 -73.017073) (xy 113.070535 -72.999066)
			(xy 113.125378 -72.988936) (xy 113.181112 -72.986899) (xy 113.236549 -72.992999) (xy 113.290506 -73.007105)
			(xy 113.341835 -73.028917) (xy 113.389441 -73.057971) (xy 113.432309 -73.093646) (xy 113.469526 -73.135183)
			(xy 113.500299 -73.181696) (xy 113.523971 -73.232193) (xy 113.540039 -73.2856) (xy 113.548159 -73.340776)
			(xy 113.548668 -73.368662) (xy 113.548159 -73.396548) (xy 113.540039 -73.451724) (xy 113.523971 -73.505131)
			(xy 113.500299 -73.555628) (xy 113.469526 -73.602141) (xy 113.432309 -73.643678) (xy 113.389441 -73.679353)
			(xy 113.341835 -73.708407) (xy 113.290506 -73.730219) (xy 113.236549 -73.744325) (xy 113.181112 -73.750425)
			(xy 113.125378 -73.748388) (xy 113.070535 -73.738258) (xy 113.017751 -73.720251) (xy 112.968151 -73.69475)
			(xy 112.922793 -73.662299) (xy 112.882644 -73.62359) (xy 112.848558 -73.579447) (xy 112.821262 -73.530812)
			(xy 112.801339 -73.478721) (xy 112.789213 -73.424284) (xy 112.785142 -73.368662) (xy 107.765084 -73.368662)
			(xy 107.781661 -73.406909) (xy 107.79606 -73.459998) (xy 107.802686 -73.514605) (xy 107.801401 -73.569598)
			(xy 107.792231 -73.623836) (xy 107.775368 -73.676194) (xy 107.75116 -73.725589) (xy 107.72011 -73.770995)
			(xy 107.682861 -73.811471) (xy 107.640185 -73.846178) (xy 107.592967 -73.874396) (xy 107.542186 -73.895542)
			(xy 107.51566 -73.902824) (xy 107.493947 -73.908822) (xy 107.452939 -73.927456) (xy 107.415858 -73.953028)
			(xy 107.383868 -73.984738) (xy 107.35797 -74.021591) (xy 107.338975 -74.062433) (xy 107.327479 -74.105985)
			(xy 107.323841 -74.150881) (xy 107.328177 -74.195715) (xy 107.333796 -74.21753) (xy 107.339855 -74.240898)
			(xy 108.194854 -74.240898) (xy 108.198925 -74.185276) (xy 108.211051 -74.130839) (xy 108.230974 -74.078748)
			(xy 108.25827 -74.030113) (xy 108.292356 -73.98597) (xy 108.332505 -73.947261) (xy 108.377863 -73.91481)
			(xy 108.427463 -73.889309) (xy 108.480247 -73.871302) (xy 108.53509 -73.861172) (xy 108.590824 -73.859135)
			(xy 108.646261 -73.865235) (xy 108.700218 -73.879341) (xy 108.751547 -73.901153) (xy 108.799153 -73.930207)
			(xy 108.842021 -73.965882) (xy 108.879238 -74.007419) (xy 108.910011 -74.053932) (xy 108.933683 -74.104429)
			(xy 108.949751 -74.157836) (xy 108.957871 -74.213012) (xy 108.95838 -74.240898) (xy 108.957983 -74.26265)
			(xy 114.878238 -74.26265) (xy 114.883604 -74.207865) (xy 114.89679 -74.15442) (xy 114.91752 -74.103425)
			(xy 114.945365 -74.055939) (xy 114.962178 -74.034142) (xy 114.976794 -74.014939) (xy 114.999271 -73.972242)
			(xy 115.013283 -73.926069) (xy 115.018327 -73.878081) (xy 115.01422 -73.830004) (xy 115.001111 -73.783567)
			(xy 114.979471 -73.74044) (xy 114.965226 -73.72096) (xy 114.948778 -73.69888) (xy 114.92185 -73.650853)
			(xy 114.902105 -73.599455) (xy 114.889953 -73.545752) (xy 114.885646 -73.49086) (xy 114.889274 -73.435919)
			(xy 114.900762 -73.382071) (xy 114.91987 -73.330432) (xy 114.946203 -73.282077) (xy 114.979213 -73.238009)
			(xy 115.018214 -73.199143) (xy 115.062397 -73.166286) (xy 115.110844 -73.140122) (xy 115.162548 -73.121194)
			(xy 115.216437 -73.109893) (xy 115.27139 -73.106456) (xy 115.326266 -73.110954) (xy 115.379926 -73.123293)
			(xy 115.431256 -73.143217) (xy 115.479188 -73.170312) (xy 115.522728 -73.204015) (xy 115.560972 -73.243627)
			(xy 115.593124 -73.288325) (xy 115.618518 -73.33718) (xy 115.636625 -73.389178) (xy 115.647071 -73.443238)
			(xy 115.649637 -73.498239) (xy 115.644271 -73.553037) (xy 115.631084 -73.606495) (xy 115.61035 -73.657503)
			(xy 115.582499 -73.705) (xy 115.565682 -73.726802) (xy 115.551022 -73.745974) (xy 115.528543 -73.788678)
			(xy 115.514532 -73.834858) (xy 115.509493 -73.882853) (xy 115.513608 -73.930936) (xy 115.526728 -73.977377)
			(xy 115.548382 -74.020505) (xy 115.562634 -74.039984) (xy 115.578998 -74.06212) (xy 115.605911 -74.11014)
			(xy 115.625643 -74.16153) (xy 115.637783 -74.215222) (xy 115.64208 -74.270102) (xy 115.638444 -74.325029)
			(xy 115.626951 -74.378863) (xy 115.607839 -74.430487) (xy 115.581506 -74.478827) (xy 115.548498 -74.522881)
			(xy 115.509501 -74.561732) (xy 115.465324 -74.594575) (xy 115.416886 -74.620728) (xy 115.365191 -74.639646)
			(xy 115.311314 -74.650938) (xy 115.256374 -74.654368) (xy 115.201511 -74.649867) (xy 115.147864 -74.637526)
			(xy 115.096549 -74.617602) (xy 115.04863 -74.59051) (xy 115.005102 -74.556811) (xy 114.96687 -74.517206)
			(xy 114.934728 -74.472517) (xy 114.909343 -74.423672) (xy 114.891242 -74.371686) (xy 114.880802 -74.317638)
			(xy 114.878238 -74.26265) (xy 108.957983 -74.26265) (xy 108.957871 -74.268784) (xy 108.949751 -74.32396)
			(xy 108.933683 -74.377367) (xy 108.910011 -74.427864) (xy 108.879238 -74.474377) (xy 108.842021 -74.515914)
			(xy 108.799153 -74.551589) (xy 108.751547 -74.580643) (xy 108.700218 -74.602455) (xy 108.646261 -74.616561)
			(xy 108.590824 -74.622661) (xy 108.53509 -74.620624) (xy 108.480247 -74.610494) (xy 108.427463 -74.592487)
			(xy 108.377863 -74.566986) (xy 108.332505 -74.534535) (xy 108.292356 -74.495826) (xy 108.25827 -74.451683)
			(xy 108.230974 -74.403048) (xy 108.211051 -74.350957) (xy 108.198925 -74.29652) (xy 108.194854 -74.240898)
			(xy 107.339855 -74.240898) (xy 107.340814 -74.244597) (xy 107.3479 -74.300059) (xy 107.346812 -74.355961)
			(xy 107.337575 -74.411106) (xy 107.320386 -74.464311) (xy 107.295613 -74.514436) (xy 107.263788 -74.560408)
			(xy 107.225592 -74.601241) (xy 107.181844 -74.63606) (xy 107.133481 -74.664119) (xy 107.08154 -74.684816)
			(xy 107.027134 -74.697709) (xy 106.971429 -74.702521) (xy 106.915618 -74.699148) (xy 106.860897 -74.687664)
			(xy 106.80844 -74.668313) (xy 106.759369 -74.641512) (xy 106.714737 -74.607834) (xy 106.6755 -74.568)
			(xy 106.642499 -74.522865) (xy 106.616441 -74.473396) (xy 106.597885 -74.420652) (xy 106.587227 -74.365764)
			(xy 106.584697 -74.309909) (xy 106.587036 -74.282046) (xy 106.58878 -74.260509) (xy 106.585859 -74.217403)
			(xy 106.57569 -74.175412) (xy 106.558564 -74.135747) (xy 106.534977 -74.099549) (xy 106.505607 -74.067862)
			(xy 106.4713 -74.0416) (xy 106.433046 -74.021518) (xy 106.391946 -74.008196) (xy 106.370628 -74.004678)
			(xy 106.343775 -74.000223) (xy 106.29157 -73.984829) (xy 106.242084 -73.962169) (xy 106.196322 -73.932703)
			(xy 106.155214 -73.897031) (xy 106.119596 -73.855876) (xy 106.09019 -73.810075) (xy 106.067595 -73.760559)
			(xy 106.052269 -73.708334) (xy 106.044525 -73.65446) (xy 106.044518 -73.600032) (xy 106.05225 -73.546156)
			(xy 106.067563 -73.493927) (xy 106.090146 -73.444405) (xy 106.104436 -73.42124) (xy 106.116024 -73.402326)
			(xy 106.133097 -73.361389) (xy 106.142808 -73.318111) (xy 106.144864 -73.273804) (xy 106.139201 -73.229812)
			(xy 106.125991 -73.18747) (xy 106.105636 -73.148062) (xy 106.078752 -73.112784) (xy 106.06278 -73.09739)
			(xy 106.042611 -73.078063) (xy 106.007514 -73.034607) (xy 105.979131 -72.986496) (xy 105.958069 -72.934761)
			(xy 105.944778 -72.880506) (xy 105.939543 -72.824893) (xy 87.127394 -72.824893) (xy 87.101963 -72.86696)
			(xy 87.067387 -72.90914) (xy 87.027158 -72.945966) (xy 86.982094 -72.976687) (xy 86.933114 -73.000678)
			(xy 86.881217 -73.017449) (xy 86.827461 -73.026658) (xy 86.772941 -73.028118) (xy 86.718768 -73.021799)
			(xy 86.666048 -73.00783) (xy 86.615855 -72.986495) (xy 86.569211 -72.95823) (xy 86.527068 -72.92361)
			(xy 86.490284 -72.883342) (xy 86.459611 -72.838245) (xy 86.435672 -72.78924) (xy 86.418955 -72.737326)
			(xy 86.409803 -72.68356) (xy 86.4084 -72.629038) (xy 77.804266 -72.629038) (xy 77.807214 -72.632369)
			(xy 77.837502 -72.678645) (xy 77.860791 -72.728808) (xy 77.876595 -72.781808) (xy 77.884581 -72.836535)
			(xy 77.884583 -72.891841) (xy 77.8766 -72.946568) (xy 77.8608 -72.999569) (xy 77.837514 -73.049734)
			(xy 77.807229 -73.096012) (xy 77.770581 -73.137432) (xy 77.728337 -73.173128) (xy 77.681382 -73.202351)
			(xy 77.6307 -73.224489) (xy 77.577352 -73.239078) (xy 77.522458 -73.245813) (xy 77.467166 -73.244552)
			(xy 77.412636 -73.235322) (xy 77.360009 -73.218316) (xy 77.310389 -73.193891) (xy 77.264815 -73.162558)
			(xy 77.244194 -73.144126) (xy 77.226423 -73.128409) (xy 77.186229 -73.103217) (xy 77.142059 -73.085919)
			(xy 77.095446 -73.077118) (xy 77.04801 -73.077118) (xy 77.001397 -73.085919) (xy 76.957227 -73.103217)
			(xy 76.917033 -73.128409) (xy 76.899262 -73.144126) (xy 76.877975 -73.163124) (xy 76.830815 -73.195237)
			(xy 76.779399 -73.219969) (xy 76.724874 -73.23677) (xy 76.668455 -73.245266) (xy 76.611401 -73.245266)
			(xy 76.554982 -73.23677) (xy 76.500457 -73.219969) (xy 76.449041 -73.195237) (xy 76.401881 -73.163124)
			(xy 76.380594 -73.144126) (xy 76.362823 -73.128409) (xy 76.322629 -73.103217) (xy 76.278459 -73.085919)
			(xy 76.231846 -73.077118) (xy 76.18441 -73.077118) (xy 76.137797 -73.085919) (xy 76.093627 -73.103217)
			(xy 76.053433 -73.128409) (xy 76.035662 -73.144126) (xy 76.014231 -73.163224) (xy 75.966741 -73.195465)
			(xy 75.914957 -73.220231) (xy 75.860049 -73.236963) (xy 75.803255 -73.245284) (xy 75.745855 -73.245006)
			(xy 75.689144 -73.236136) (xy 75.6344 -73.218873) (xy 75.582859 -73.193607) (xy 75.535683 -73.160907)
			(xy 75.514454 -73.141586) (xy 75.497335 -73.126095) (xy 75.458577 -73.101015) (xy 75.415929 -73.08334)
			(xy 75.370791 -73.073651) (xy 75.324647 -73.072264) (xy 75.279009 -73.079227) (xy 75.235377 -73.09431)
			(xy 75.195183 -73.117018) (xy 75.177142 -73.131426) (xy 75.155852 -73.148679) (xy 75.109213 -73.17745)
			(xy 75.058936 -73.199251) (xy 75.006058 -73.213634) (xy 74.951665 -73.220302) (xy 74.896878 -73.219119)
			(xy 74.842824 -73.210108) (xy 74.790616 -73.193455) (xy 74.741328 -73.169503) (xy 74.695975 -73.138745)
			(xy 74.655489 -73.101814) (xy 74.620705 -73.059469) (xy 74.592337 -73.012583) (xy 74.570971 -72.962121)
			(xy 74.557045 -72.90912) (xy 74.550846 -72.854672) (xy 74.083437 -72.854672) (xy 74.054568 -72.898307)
			(xy 74.017351 -72.939844) (xy 73.974483 -72.975519) (xy 73.926877 -73.004573) (xy 73.875548 -73.026385)
			(xy 73.821591 -73.040491) (xy 73.766154 -73.046591) (xy 73.71042 -73.044554) (xy 73.655577 -73.034424)
			(xy 73.602793 -73.016417) (xy 73.553193 -72.990916) (xy 73.507835 -72.958465) (xy 73.467686 -72.919756)
			(xy 73.4336 -72.875613) (xy 73.406304 -72.826978) (xy 73.386381 -72.774887) (xy 73.374255 -72.72045)
			(xy 73.370184 -72.664828) (xy 73.057809 -72.664828) (xy 73.050407 -72.715124) (xy 73.034339 -72.768531)
			(xy 73.010667 -72.819028) (xy 72.979894 -72.865541) (xy 72.942677 -72.907078) (xy 72.899809 -72.942753)
			(xy 72.852203 -72.971807) (xy 72.800874 -72.993619) (xy 72.746917 -73.007725) (xy 72.69148 -73.013825)
			(xy 72.635746 -73.011788) (xy 72.580903 -73.001658) (xy 72.528119 -72.983651) (xy 72.478519 -72.95815)
			(xy 72.433161 -72.925699) (xy 72.393012 -72.88699) (xy 72.358926 -72.842847) (xy 72.33163 -72.794212)
			(xy 72.311707 -72.742121) (xy 72.299581 -72.687684) (xy 72.29551 -72.632062) (xy 71.143349 -72.632062)
			(xy 71.160307 -72.653287) (xy 71.18844 -72.70155) (xy 71.209234 -72.753399) (xy 71.222245 -72.807727)
			(xy 71.227193 -72.86337) (xy 71.223974 -72.919141) (xy 71.212656 -72.973846) (xy 71.193481 -73.026316)
			(xy 71.16686 -73.075428) (xy 71.133361 -73.120133) (xy 71.0937 -73.159475) (xy 71.048726 -73.192612)
			(xy 70.999401 -73.218837) (xy 70.946778 -73.237588) (xy 70.891984 -73.248464) (xy 70.836189 -73.251233)
			(xy 70.780586 -73.245836) (xy 70.726366 -73.232387) (xy 70.674686 -73.211176) (xy 70.626652 -73.182654)
			(xy 70.583291 -73.147432) (xy 70.54553 -73.106264) (xy 70.52945 -73.08342) (xy 70.5208 -73.071419)
			(xy 70.49901 -73.051422) (xy 70.473198 -73.036985) (xy 70.444754 -73.028885) (xy 70.415209 -73.027557)
			(xy 70.386154 -73.033075) (xy 70.372478 -73.038716) (xy 70.345782 -73.050002) (xy 70.289902 -73.065371)
			(xy 70.23234 -73.072112) (xy 70.174421 -73.070071) (xy 70.117476 -73.059294) (xy 70.062817 -73.04003)
			(xy 70.011699 -73.012721) (xy 69.988176 -72.99579) (xy 69.969164 -72.982194) (xy 69.927281 -72.961462)
			(xy 69.882313 -72.948736) (xy 69.835776 -72.944446) (xy 69.789239 -72.948736) (xy 69.744271 -72.961462)
			(xy 69.702388 -72.982194) (xy 69.683376 -72.99579) (xy 69.661285 -73.011752) (xy 69.613454 -73.037875)
			(xy 69.562391 -73.056924) (xy 69.509137 -73.06851) (xy 69.454776 -73.072399) (xy 69.400415 -73.06851)
			(xy 69.347161 -73.056924) (xy 69.296098 -73.037875) (xy 69.248267 -73.011752) (xy 69.226176 -72.99579)
			(xy 69.207164 -72.982194) (xy 69.165281 -72.961462) (xy 69.120313 -72.948736) (xy 69.073776 -72.944446)
			(xy 69.027239 -72.948736) (xy 68.982271 -72.961462) (xy 68.940388 -72.982194) (xy 68.921376 -72.99579)
			(xy 68.899305 -73.011772) (xy 68.85148 -73.037891) (xy 68.800425 -73.056938) (xy 68.747179 -73.068525)
			(xy 68.692825 -73.072417) (xy 68.638471 -73.068533) (xy 68.585223 -73.056953) (xy 68.534165 -73.037912)
			(xy 68.486337 -73.011799) (xy 68.442712 -72.979145) (xy 68.404178 -72.940615) (xy 68.37152 -72.896993)
			(xy 68.345403 -72.849167) (xy 68.326358 -72.798111) (xy 68.314773 -72.744864) (xy 68.310883 -72.690511)
			(xy 67.664547 -72.690511) (xy 67.698679 -72.707315) (xy 67.744837 -72.739195) (xy 67.78583 -72.777491)
			(xy 67.820774 -72.821375) (xy 67.848915 -72.869904) (xy 67.869648 -72.922029) (xy 67.882525 -72.976629)
			(xy 67.887268 -73.032525) (xy 67.883777 -73.088514) (xy 67.872124 -73.143388) (xy 67.852563 -73.195964)
			(xy 67.825515 -73.24511) (xy 67.791562 -73.289766) (xy 67.751436 -73.328968) (xy 67.706003 -73.361874)
			(xy 67.656241 -73.387772) (xy 67.603224 -73.406105) (xy 67.548094 -73.416477) (xy 67.492039 -73.418666)
			(xy 67.436268 -73.412623) (xy 67.381983 -73.398479) (xy 67.355974 -73.387966) (xy 67.33461 -73.379434)
			(xy 67.289726 -73.369366) (xy 67.243762 -73.367543) (xy 67.198222 -73.374024) (xy 67.154592 -73.388597)
			(xy 67.114298 -73.410786) (xy 67.078657 -73.439866) (xy 67.063366 -73.457054) (xy 67.044851 -73.478128)
			(xy 67.002606 -73.515036) (xy 66.955413 -73.545361) (xy 66.904288 -73.56845) (xy 66.850334 -73.583805)
			(xy 66.794713 -73.591095) (xy 66.738624 -73.590163) (xy 66.683275 -73.581029) (xy 66.629861 -73.56389)
			(xy 66.579532 -73.539115) (xy 66.533372 -73.507238) (xy 66.492377 -73.468947) (xy 66.457429 -73.425066)
			(xy 66.429284 -73.376541) (xy 66.408546 -73.324418) (xy 66.395662 -73.269821) (xy 66.390912 -73.213925)
			(xy 59.115448 -73.213925) (xy 59.103112 -73.232571) (xy 59.065895 -73.274108) (xy 59.023027 -73.309783)
			(xy 58.975421 -73.338837) (xy 58.924092 -73.360649) (xy 58.870135 -73.374755) (xy 58.814698 -73.380855)
			(xy 58.758964 -73.378818) (xy 58.704121 -73.368688) (xy 58.651337 -73.350681) (xy 58.601737 -73.32518)
			(xy 58.556379 -73.292729) (xy 58.51623 -73.25402) (xy 58.482144 -73.209877) (xy 58.454848 -73.161242)
			(xy 58.434925 -73.109151) (xy 58.422799 -73.054714) (xy 58.418728 -72.999092) (xy 57.582054 -72.999092)
			(xy 57.581545 -73.026978) (xy 57.573425 -73.082154) (xy 57.557357 -73.135561) (xy 57.533685 -73.186058)
			(xy 57.502912 -73.232571) (xy 57.465695 -73.274108) (xy 57.422827 -73.309783) (xy 57.375221 -73.338837)
			(xy 57.323892 -73.360649) (xy 57.269935 -73.374755) (xy 57.214498 -73.380855) (xy 57.158764 -73.378818)
			(xy 57.103921 -73.368688) (xy 57.051137 -73.350681) (xy 57.001537 -73.32518) (xy 56.956179 -73.292729)
			(xy 56.91603 -73.25402) (xy 56.881944 -73.209877) (xy 56.854648 -73.161242) (xy 56.834725 -73.109151)
			(xy 56.822599 -73.054714) (xy 56.818528 -72.999092) (xy 55.181754 -72.999092) (xy 55.181245 -73.026978)
			(xy 55.173125 -73.082154) (xy 55.157057 -73.135561) (xy 55.133385 -73.186058) (xy 55.102612 -73.232571)
			(xy 55.065395 -73.274108) (xy 55.022527 -73.309783) (xy 54.974921 -73.338837) (xy 54.923592 -73.360649)
			(xy 54.869635 -73.374755) (xy 54.814198 -73.380855) (xy 54.758464 -73.378818) (xy 54.703621 -73.368688)
			(xy 54.650837 -73.350681) (xy 54.601237 -73.32518) (xy 54.555879 -73.292729) (xy 54.51573 -73.25402)
			(xy 54.481644 -73.209877) (xy 54.454348 -73.161242) (xy 54.434425 -73.109151) (xy 54.422299 -73.054714)
			(xy 54.418228 -72.999092) (xy 49.068474 -72.999092) (xy 49.065973 -73.001173) (xy 49.018367 -73.030227)
			(xy 48.967038 -73.052039) (xy 48.913081 -73.066145) (xy 48.857644 -73.072245) (xy 48.80191 -73.070208)
			(xy 48.747067 -73.060078) (xy 48.694283 -73.042071) (xy 48.644683 -73.01657) (xy 48.599325 -72.984119)
			(xy 48.559176 -72.94541) (xy 48.52509 -72.901267) (xy 48.497794 -72.852632) (xy 48.477871 -72.800541)
			(xy 48.465745 -72.746104) (xy 48.461674 -72.690482) (xy 48.083034 -72.690482) (xy 48.085247 -72.705522)
			(xy 48.085756 -72.733408) (xy 48.085247 -72.761294) (xy 48.077127 -72.81647) (xy 48.061059 -72.869877)
			(xy 48.037387 -72.920374) (xy 48.006614 -72.966887) (xy 47.969397 -73.008424) (xy 47.926529 -73.044099)
			(xy 47.878923 -73.073153) (xy 47.827594 -73.094965) (xy 47.773637 -73.109071) (xy 47.7182 -73.115171)
			(xy 47.662466 -73.113134) (xy 47.607623 -73.103004) (xy 47.554839 -73.084997) (xy 47.505239 -73.059496)
			(xy 47.459881 -73.027045) (xy 47.419732 -72.988336) (xy 47.385646 -72.944193) (xy 47.35835 -72.895558)
			(xy 47.338427 -72.843467) (xy 47.326301 -72.78903) (xy 47.32223 -72.733408) (xy 47.00161 -72.733408)
			(xy 46.992431 -72.752988) (xy 46.961658 -72.799501) (xy 46.924441 -72.841038) (xy 46.881573 -72.876713)
			(xy 46.833967 -72.905767) (xy 46.782638 -72.927579) (xy 46.728681 -72.941685) (xy 46.673244 -72.947785)
			(xy 46.61751 -72.945748) (xy 46.562667 -72.935618) (xy 46.509883 -72.917611) (xy 46.460283 -72.89211)
			(xy 46.414925 -72.859659) (xy 46.374776 -72.82095) (xy 46.34069 -72.776807) (xy 46.313394 -72.728172)
			(xy 46.293471 -72.676081) (xy 46.281345 -72.621644) (xy 46.277274 -72.566022) (xy 44.899364 -72.566022)
			(xy 44.898909 -72.568001) (xy 44.90086 -72.603606) (xy 44.906184 -72.620632) (xy 44.914566 -72.64527)
			(xy 44.926504 -72.661018) (xy 44.933108 -72.669908) (xy 44.950126 -72.693784) (xy 44.990766 -72.716136)
			(xy 45.003639 -72.722652) (xy 45.031447 -72.730326) (xy 45.060267 -72.731582) (xy 45.088637 -72.726358)
			(xy 45.102018 -72.720962) (xy 45.136562 -72.705976) (xy 45.153072 -72.689974) (xy 45.174299 -72.670274)
			(xy 45.2216 -72.636865) (xy 45.273408 -72.61099) (xy 45.328531 -72.593243) (xy 45.357034 -72.58812)
			(xy 45.384138 -72.584233) (xy 45.438884 -72.583343) (xy 45.493196 -72.590289) (xy 45.545956 -72.604927)
			(xy 45.596083 -72.626957) (xy 45.642545 -72.655927) (xy 45.684389 -72.69124) (xy 45.720755 -72.732173)
			(xy 45.750897 -72.777883) (xy 45.774195 -72.827433) (xy 45.79017 -72.879805) (xy 45.798495 -72.933922)
			(xy 45.798998 -72.988673) (xy 45.791669 -73.042935) (xy 45.776659 -73.095591) (xy 45.754276 -73.145561)
			(xy 45.72498 -73.191818) (xy 45.689372 -73.233412) (xy 45.648184 -73.269488) (xy 45.625512 -73.284842)
			(xy 45.601911 -73.299563) (xy 45.551354 -73.322755) (xy 45.497967 -73.338363) (xy 45.442879 -73.346056)
			(xy 45.387259 -73.345672) (xy 45.332282 -73.337219) (xy 45.279116 -73.320876) (xy 45.228884 -73.296988)
			(xy 45.182652 -73.266062) (xy 45.161708 -73.247758) (xy 45.151548 -73.238106) (xy 45.135546 -73.223158)
			(xy 45.099411 -73.198429) (xy 45.059576 -73.180251) (xy 45.017217 -73.169162) (xy 44.973585 -73.165488)
			(xy 44.929968 -73.169338) (xy 44.887655 -73.180598) (xy 44.867576 -73.189338) (xy 44.848983 -73.204603)
			(xy 44.808708 -73.230913) (xy 44.765494 -73.25205) (xy 44.742862 -73.260204) (xy 44.733972 -73.26503)
			(xy 44.733972 -73.502012) (xy 44.562014 -73.67397) (xy 44.554648 -73.6854) (xy 44.547975 -73.695708)
			(xy 44.533486 -73.715535) (xy 44.525692 -73.725024) (xy 44.512259 -73.740544) (xy 44.482604 -73.768926)
			(xy 44.46651 -73.781666) (xy 44.443855 -73.799205) (xy 51.217679 -73.799205) (xy 51.221704 -73.74388)
			(xy 51.233698 -73.68972) (xy 51.253406 -73.637868) (xy 51.280414 -73.589415) (xy 51.314153 -73.545384)
			(xy 51.353912 -73.506701) (xy 51.398852 -73.474182) (xy 51.448027 -73.448512) (xy 51.5004 -73.430233)
			(xy 51.554868 -73.419729) (xy 51.610283 -73.417222) (xy 51.665477 -73.422765) (xy 51.719287 -73.436241)
			(xy 51.770579 -73.457365) (xy 51.818272 -73.485693) (xy 51.84013 -73.502774) (xy 51.857204 -73.516036)
			(xy 51.894924 -73.537155) (xy 51.935675 -73.551582) (xy 51.978281 -73.558901) (xy 52.021511 -73.558901)
			(xy 52.064117 -73.551582) (xy 52.104868 -73.537155) (xy 52.142588 -73.516036) (xy 52.159662 -73.502774)
			(xy 52.181687 -73.485488) (xy 52.22987 -73.456969) (xy 52.281703 -73.435797) (xy 52.336073 -73.422427)
			(xy 52.391814 -73.417144) (xy 52.447728 -73.420063) (xy 52.502615 -73.431122) (xy 52.555298 -73.450082)
			(xy 52.604644 -73.476536) (xy 52.649595 -73.509918) (xy 52.689186 -73.549509) (xy 52.722567 -73.594461)
			(xy 52.749021 -73.643807) (xy 52.76798 -73.69649) (xy 52.779037 -73.751377) (xy 52.781956 -73.807292)
			(xy 52.776673 -73.863032) (xy 52.763301 -73.917402) (xy 52.742128 -73.969235) (xy 52.713609 -74.017417)
			(xy 52.696364 -74.039476) (xy 52.683061 -74.05652) (xy 52.661943 -74.094246) (xy 52.647518 -74.135004)
			(xy 52.640203 -74.177615) (xy 52.640209 -74.22085) (xy 52.647535 -74.26346) (xy 52.66197 -74.304213)
			(xy 52.683097 -74.341935) (xy 52.696364 -74.359008) (xy 52.71413 -74.381733) (xy 52.743276 -74.43151)
			(xy 52.764599 -74.485107) (xy 52.777614 -74.541302) (xy 52.781438 -74.591173) (xy 53.618106 -74.591173)
			(xy 53.623395 -74.535435) (xy 53.636773 -74.481068) (xy 53.657953 -74.42924) (xy 53.68648 -74.381063)
			(xy 53.703728 -74.359008) (xy 53.716951 -74.341905) (xy 53.738075 -74.304192) (xy 53.752508 -74.263447)
			(xy 53.759833 -74.220846) (xy 53.759838 -74.17762) (xy 53.752524 -74.135017) (xy 53.738102 -74.094268)
			(xy 53.716988 -74.056549) (xy 53.703728 -74.039476) (xy 53.686843 -74.017956) (xy 53.658816 -73.970982)
			(xy 53.637783 -73.920487) (xy 53.624177 -73.867507) (xy 53.618275 -73.813126) (xy 53.6202 -73.75846)
			(xy 53.62991 -73.704629) (xy 53.647208 -73.652736) (xy 53.671739 -73.603846) (xy 53.703 -73.558959)
			(xy 53.740351 -73.518996) (xy 53.783025 -73.484776) (xy 53.830148 -73.457001) (xy 53.880755 -73.436239)
			(xy 53.933807 -73.422916) (xy 53.988219 -73.417306) (xy 54.042874 -73.419523) (xy 54.096652 -73.429522)
			(xy 54.148451 -73.447098) (xy 54.19721 -73.47189) (xy 54.241929 -73.503391) (xy 54.281691 -73.540955)
			(xy 54.315682 -73.583812) (xy 54.343205 -73.631083) (xy 54.363695 -73.6818) (xy 54.376733 -73.734923)
			(xy 54.382052 -73.789364) (xy 54.381601 -73.799192) (xy 56.018428 -73.799192) (xy 56.022499 -73.74357)
			(xy 56.034625 -73.689133) (xy 56.054548 -73.637042) (xy 56.081844 -73.588407) (xy 56.11593 -73.544264)
			(xy 56.156079 -73.505555) (xy 56.201437 -73.473104) (xy 56.251037 -73.447603) (xy 56.303821 -73.429596)
			(xy 56.358664 -73.419466) (xy 56.414398 -73.417429) (xy 56.469835 -73.423529) (xy 56.523792 -73.437635)
			(xy 56.575121 -73.459447) (xy 56.622727 -73.488501) (xy 56.665595 -73.524176) (xy 56.702812 -73.565713)
			(xy 56.733585 -73.612226) (xy 56.757257 -73.662723) (xy 56.773325 -73.71613) (xy 56.781445 -73.771306)
			(xy 56.781954 -73.799192) (xy 60.018928 -73.799192) (xy 60.022999 -73.74357) (xy 60.035125 -73.689133)
			(xy 60.055048 -73.637042) (xy 60.082344 -73.588407) (xy 60.11643 -73.544264) (xy 60.156579 -73.505555)
			(xy 60.201937 -73.473104) (xy 60.251537 -73.447603) (xy 60.304321 -73.429596) (xy 60.359164 -73.419466)
			(xy 60.414898 -73.417429) (xy 60.470335 -73.423529) (xy 60.524292 -73.437635) (xy 60.575621 -73.459447)
			(xy 60.623227 -73.488501) (xy 60.666095 -73.524176) (xy 60.703312 -73.565713) (xy 60.734085 -73.612226)
			(xy 60.757757 -73.662723) (xy 60.773825 -73.71613) (xy 60.781945 -73.771306) (xy 60.782454 -73.799192)
			(xy 63.219328 -73.799192) (xy 63.223399 -73.74357) (xy 63.235525 -73.689133) (xy 63.255448 -73.637042)
			(xy 63.282744 -73.588407) (xy 63.31683 -73.544264) (xy 63.356979 -73.505555) (xy 63.402337 -73.473104)
			(xy 63.451937 -73.447603) (xy 63.504721 -73.429596) (xy 63.559564 -73.419466) (xy 63.615298 -73.417429)
			(xy 63.670735 -73.423529) (xy 63.724692 -73.437635) (xy 63.776021 -73.459447) (xy 63.823627 -73.488501)
			(xy 63.866495 -73.524176) (xy 63.903712 -73.565713) (xy 63.934485 -73.612226) (xy 63.958157 -73.662723)
			(xy 63.974225 -73.71613) (xy 63.982345 -73.771306) (xy 63.982854 -73.799192) (xy 63.982345 -73.827078)
			(xy 63.974225 -73.882254) (xy 63.958157 -73.935661) (xy 63.934485 -73.986158) (xy 63.903712 -74.032671)
			(xy 63.866495 -74.074208) (xy 63.823627 -74.109883) (xy 63.776021 -74.138937) (xy 63.724692 -74.160749)
			(xy 63.670735 -74.174855) (xy 63.615298 -74.180955) (xy 63.559564 -74.178918) (xy 63.504721 -74.168788)
			(xy 63.451937 -74.150781) (xy 63.402337 -74.12528) (xy 63.356979 -74.092829) (xy 63.31683 -74.05412)
			(xy 63.282744 -74.009977) (xy 63.255448 -73.961342) (xy 63.235525 -73.909251) (xy 63.223399 -73.854814)
			(xy 63.219328 -73.799192) (xy 60.782454 -73.799192) (xy 60.781945 -73.827078) (xy 60.773825 -73.882254)
			(xy 60.757757 -73.935661) (xy 60.734085 -73.986158) (xy 60.703312 -74.032671) (xy 60.666095 -74.074208)
			(xy 60.623227 -74.109883) (xy 60.575621 -74.138937) (xy 60.524292 -74.160749) (xy 60.470335 -74.174855)
			(xy 60.414898 -74.180955) (xy 60.359164 -74.178918) (xy 60.304321 -74.168788) (xy 60.251537 -74.150781)
			(xy 60.201937 -74.12528) (xy 60.156579 -74.092829) (xy 60.11643 -74.05412) (xy 60.082344 -74.009977)
			(xy 60.055048 -73.961342) (xy 60.035125 -73.909251) (xy 60.022999 -73.854814) (xy 60.018928 -73.799192)
			(xy 56.781954 -73.799192) (xy 56.781445 -73.827078) (xy 56.773325 -73.882254) (xy 56.757257 -73.935661)
			(xy 56.733585 -73.986158) (xy 56.702812 -74.032671) (xy 56.665595 -74.074208) (xy 56.622727 -74.109883)
			(xy 56.575121 -74.138937) (xy 56.523792 -74.160749) (xy 56.469835 -74.174855) (xy 56.414398 -74.180955)
			(xy 56.358664 -74.178918) (xy 56.303821 -74.168788) (xy 56.251037 -74.150781) (xy 56.201437 -74.12528)
			(xy 56.156079 -74.092829) (xy 56.11593 -74.05412) (xy 56.081844 -74.009977) (xy 56.054548 -73.961342)
			(xy 56.034625 -73.909251) (xy 56.022499 -73.854814) (xy 56.018428 -73.799192) (xy 54.381601 -73.799192)
			(xy 54.379542 -73.844006) (xy 54.369256 -73.89773) (xy 54.351403 -73.949435) (xy 54.326349 -73.99806)
			(xy 54.294609 -74.04261) (xy 54.256833 -74.08217) (xy 54.235604 -74.09942) (xy 54.222963 -74.109936)
			(xy 54.203179 -74.136189) (xy 54.190759 -74.166626) (xy 54.186531 -74.199226) (xy 54.190773 -74.231825)
			(xy 54.203204 -74.262257) (xy 54.223 -74.288501) (xy 54.235604 -74.299064) (xy 54.24043 -74.302874)
			(xy 54.257504 -74.316136) (xy 54.295224 -74.337255) (xy 54.335975 -74.351682) (xy 54.378581 -74.359001)
			(xy 54.421811 -74.359001) (xy 54.464417 -74.351682) (xy 54.505168 -74.337255) (xy 54.542888 -74.316136)
			(xy 54.559962 -74.302874) (xy 54.581825 -74.285811) (xy 54.62951 -74.257499) (xy 54.680792 -74.236389)
			(xy 54.734589 -74.222925) (xy 54.789769 -74.217391) (xy 54.845169 -74.219905) (xy 54.899621 -74.230412)
			(xy 54.951979 -74.248692) (xy 55.001138 -74.274359) (xy 55.046064 -74.306872) (xy 55.085809 -74.345548)
			(xy 55.119537 -74.389569) (xy 55.146536 -74.43801) (xy 55.166238 -74.489849) (xy 55.178227 -74.543994)
			(xy 55.18225 -74.599292) (xy 61.619128 -74.599292) (xy 61.623199 -74.54367) (xy 61.635325 -74.489233)
			(xy 61.655248 -74.437142) (xy 61.682544 -74.388507) (xy 61.71663 -74.344364) (xy 61.756779 -74.305655)
			(xy 61.802137 -74.273204) (xy 61.851737 -74.247703) (xy 61.904521 -74.229696) (xy 61.959364 -74.219566)
			(xy 62.015098 -74.217529) (xy 62.070535 -74.223629) (xy 62.124492 -74.237735) (xy 62.175821 -74.259547)
			(xy 62.223427 -74.288601) (xy 62.266295 -74.324276) (xy 62.303512 -74.365813) (xy 62.334285 -74.412326)
			(xy 62.357957 -74.462823) (xy 62.374025 -74.51623) (xy 62.382145 -74.571406) (xy 62.382654 -74.599292)
			(xy 62.382343 -74.61631) (xy 64.035176 -74.61631) (xy 64.039247 -74.560688) (xy 64.051373 -74.506251)
			(xy 64.071296 -74.45416) (xy 64.098592 -74.405525) (xy 64.132678 -74.361382) (xy 64.172827 -74.322673)
			(xy 64.218185 -74.290222) (xy 64.267785 -74.264721) (xy 64.320569 -74.246714) (xy 64.375412 -74.236584)
			(xy 64.431146 -74.234547) (xy 64.486583 -74.240647) (xy 64.54054 -74.254753) (xy 64.591869 -74.276565)
			(xy 64.639475 -74.305619) (xy 64.682343 -74.341294) (xy 64.71956 -74.382831) (xy 64.750333 -74.429344)
			(xy 64.774005 -74.479841) (xy 64.790073 -74.533248) (xy 64.798193 -74.588424) (xy 64.798702 -74.61631)
			(xy 64.798193 -74.644196) (xy 64.790073 -74.699372) (xy 64.774005 -74.752779) (xy 64.750333 -74.803276)
			(xy 64.71956 -74.849789) (xy 64.682343 -74.891326) (xy 64.639475 -74.927001) (xy 64.591869 -74.956055)
			(xy 64.54054 -74.977867) (xy 64.486583 -74.991973) (xy 64.431146 -74.998073) (xy 64.375412 -74.996036)
			(xy 64.320569 -74.985906) (xy 64.267785 -74.967899) (xy 64.218185 -74.942398) (xy 64.172827 -74.909947)
			(xy 64.132678 -74.871238) (xy 64.098592 -74.827095) (xy 64.071296 -74.77846) (xy 64.051373 -74.726369)
			(xy 64.039247 -74.671932) (xy 64.035176 -74.61631) (xy 62.382343 -74.61631) (xy 62.382145 -74.627178)
			(xy 62.374025 -74.682354) (xy 62.357957 -74.735761) (xy 62.334285 -74.786258) (xy 62.303512 -74.832771)
			(xy 62.266295 -74.874308) (xy 62.223427 -74.909983) (xy 62.175821 -74.939037) (xy 62.124492 -74.960849)
			(xy 62.070535 -74.974955) (xy 62.015098 -74.981055) (xy 61.959364 -74.979018) (xy 61.904521 -74.968888)
			(xy 61.851737 -74.950881) (xy 61.802137 -74.92538) (xy 61.756779 -74.892929) (xy 61.71663 -74.85422)
			(xy 61.682544 -74.810077) (xy 61.655248 -74.761442) (xy 61.635325 -74.709351) (xy 61.623199 -74.654914)
			(xy 61.619128 -74.599292) (xy 55.18225 -74.599292) (xy 55.182251 -74.599305) (xy 55.178225 -74.654616)
			(xy 55.166235 -74.70876) (xy 55.146532 -74.760599) (xy 55.119531 -74.809039) (xy 55.085803 -74.85306)
			(xy 55.046056 -74.891734) (xy 55.00113 -74.924247) (xy 54.95197 -74.949912) (xy 54.899612 -74.968191)
			(xy 54.845159 -74.978696) (xy 54.789759 -74.981208) (xy 54.734579 -74.975673) (xy 54.680782 -74.962208)
			(xy 54.629501 -74.941096) (xy 54.581817 -74.912783) (xy 54.559962 -74.89571) (xy 54.542888 -74.882448)
			(xy 54.505168 -74.861329) (xy 54.464417 -74.846902) (xy 54.421811 -74.839583) (xy 54.378581 -74.839583)
			(xy 54.335975 -74.846902) (xy 54.295224 -74.861329) (xy 54.257504 -74.882448) (xy 54.24043 -74.89571)
			(xy 54.218342 -74.912917) (xy 54.170165 -74.941445) (xy 54.118337 -74.962625) (xy 54.063971 -74.976004)
			(xy 54.008232 -74.981293) (xy 53.952319 -74.978381) (xy 53.897432 -74.967328) (xy 53.84475 -74.948372)
			(xy 53.795403 -74.921921) (xy 53.750452 -74.888542) (xy 53.710862 -74.848952) (xy 53.677482 -74.804002)
			(xy 53.65103 -74.754655) (xy 53.632074 -74.701973) (xy 53.62102 -74.647086) (xy 53.618106 -74.591173)
			(xy 52.781438 -74.591173) (xy 52.782024 -74.598815) (xy 52.77773 -74.656337) (xy 52.764828 -74.712558)
			(xy 52.743613 -74.766198) (xy 52.714568 -74.816034) (xy 52.696872 -74.838814) (xy 52.683561 -74.856025)
			(xy 52.662455 -74.89407) (xy 52.64813 -74.93515) (xy 52.641002 -74.97807) (xy 52.64128 -75.021576)
			(xy 52.648956 -75.0644) (xy 52.663806 -75.105295) (xy 52.685396 -75.143067) (xy 52.698904 -75.160124)
			(xy 52.716271 -75.181798) (xy 52.745088 -75.229278) (xy 52.766715 -75.280435) (xy 52.780694 -75.334188)
			(xy 52.786731 -75.3894) (xy 52.784697 -75.444903) (xy 52.774635 -75.499525) (xy 52.756759 -75.552111)
			(xy 52.731446 -75.601548) (xy 52.699231 -75.646791) (xy 52.660796 -75.686885) (xy 52.616953 -75.720981)
			(xy 52.568628 -75.748359) (xy 52.516845 -75.768439) (xy 52.462696 -75.780798) (xy 52.407328 -75.785173)
			(xy 52.351911 -75.781473) (xy 52.297616 -75.769775) (xy 52.245591 -75.750328) (xy 52.196936 -75.723541)
			(xy 52.152681 -75.689982) (xy 52.11376 -75.65036) (xy 52.080996 -75.605512) (xy 52.055082 -75.556387)
			(xy 52.036566 -75.504023) (xy 52.02584 -75.449528) (xy 52.023129 -75.394054) (xy 52.028493 -75.338772)
			(xy 52.041816 -75.284853) (xy 52.062817 -75.233436) (xy 52.091053 -75.185608) (xy 52.1081 -75.16368)
			(xy 52.121413 -75.146472) (xy 52.142513 -75.108425) (xy 52.156834 -75.067344) (xy 52.163958 -75.024425)
			(xy 52.16368 -74.98092) (xy 52.156005 -74.938096) (xy 52.141159 -74.897202) (xy 52.119573 -74.859428)
			(xy 52.106068 -74.84237) (xy 52.088832 -74.820677) (xy 52.060034 -74.773347) (xy 52.038389 -74.722348)
			(xy 52.024355 -74.668753) (xy 52.018226 -74.61369) (xy 52.020131 -74.558321) (xy 52.030031 -74.50381)
			(xy 52.047716 -74.451306) (xy 52.072815 -74.401915) (xy 52.104799 -74.356677) (xy 52.142994 -74.316545)
			(xy 52.164488 -74.299064) (xy 52.177045 -74.288455) (xy 52.196832 -74.262224) (xy 52.209258 -74.231808)
			(xy 52.213498 -74.199226) (xy 52.209271 -74.166642) (xy 52.196857 -74.136221) (xy 52.177082 -74.109982)
			(xy 52.164488 -74.09942) (xy 52.159662 -74.09561) (xy 52.142588 -74.082348) (xy 52.104868 -74.061229)
			(xy 52.064117 -74.046802) (xy 52.021511 -74.039483) (xy 51.978281 -74.039483) (xy 51.935675 -74.046802)
			(xy 51.894924 -74.061229) (xy 51.857204 -74.082348) (xy 51.84013 -74.09561) (xy 51.818281 -74.112701)
			(xy 51.770588 -74.141031) (xy 51.719297 -74.162156) (xy 51.665487 -74.175633) (xy 51.610294 -74.181177)
			(xy 51.554879 -74.178672) (xy 51.50041 -74.168169) (xy 51.448036 -74.149892) (xy 51.398861 -74.124223)
			(xy 51.35392 -74.091706) (xy 51.31416 -74.053024) (xy 51.28042 -74.008993) (xy 51.25341 -73.960541)
			(xy 51.233701 -73.90869) (xy 51.221706 -73.85453) (xy 51.217679 -73.799205) (xy 44.443855 -73.799205)
			(xy 44.442888 -73.799954) (xy 44.41698 -73.852532) (xy 44.41698 -74.153522) (xy 44.417419 -74.169065)
			(xy 44.424932 -74.199228) (xy 44.439531 -74.226672) (xy 44.460345 -74.24976) (xy 44.486133 -74.267116)
			(xy 44.515359 -74.277707) (xy 44.530772 -74.27976) (xy 44.557394 -74.282995) (xy 44.609426 -74.295976)
			(xy 44.659128 -74.316118) (xy 44.705517 -74.343023) (xy 44.747681 -74.376162) (xy 44.784786 -74.41488)
			(xy 44.802019 -74.438836) (xy 46.560839 -74.438836) (xy 46.561639 -74.38354) (xy 46.570415 -74.328939)
			(xy 46.586982 -74.276178) (xy 46.610994 -74.226362) (xy 46.641947 -74.180534) (xy 46.679193 -74.139656)
			(xy 46.72195 -74.104584) (xy 46.769324 -74.076054) (xy 46.82032 -74.054662) (xy 46.873871 -74.040858)
			(xy 46.928854 -74.03493) (xy 46.984116 -74.037004) (xy 47.0385 -74.047035) (xy 47.090866 -74.064813)
			(xy 47.140116 -74.089966) (xy 47.185219 -74.121966) (xy 47.225228 -74.160143) (xy 47.259306 -74.203697)
			(xy 47.286738 -74.251715) (xy 47.306949 -74.303191) (xy 47.319516 -74.357045) (xy 47.324176 -74.41215)
			(xy 47.322994 -74.43978) (xy 47.322525 -74.456935) (xy 47.329688 -74.490484) (xy 47.345528 -74.520914)
			(xy 47.3689 -74.546026) (xy 47.398115 -74.564006) (xy 47.414434 -74.56932) (xy 47.44084 -74.577522)
			(xy 47.491182 -74.600383) (xy 47.537696 -74.630274) (xy 47.579407 -74.666567) (xy 47.61544 -74.708502)
			(xy 47.645042 -74.7552) (xy 47.658224 -74.784712) (xy 48.78146 -74.784712) (xy 48.785531 -74.72909)
			(xy 48.797657 -74.674653) (xy 48.81758 -74.622562) (xy 48.844876 -74.573927) (xy 48.878962 -74.529784)
			(xy 48.919111 -74.491075) (xy 48.964469 -74.458624) (xy 49.014069 -74.433123) (xy 49.066853 -74.415116)
			(xy 49.121696 -74.404986) (xy 49.17743 -74.402949) (xy 49.232867 -74.409049) (xy 49.286824 -74.423155)
			(xy 49.338153 -74.444967) (xy 49.385759 -74.474021) (xy 49.428627 -74.509696) (xy 49.465844 -74.551233)
			(xy 49.496617 -74.597746) (xy 49.520289 -74.648243) (xy 49.536357 -74.70165) (xy 49.544477 -74.756826)
			(xy 49.544986 -74.784712) (xy 49.544477 -74.812598) (xy 49.536357 -74.867774) (xy 49.520289 -74.921181)
			(xy 49.496617 -74.971678) (xy 49.465844 -75.018191) (xy 49.428627 -75.059728) (xy 49.385759 -75.095403)
			(xy 49.338153 -75.124457) (xy 49.286824 -75.146269) (xy 49.232867 -75.160375) (xy 49.17743 -75.166475)
			(xy 49.121696 -75.164438) (xy 49.066853 -75.154308) (xy 49.014069 -75.136301) (xy 48.964469 -75.1108)
			(xy 48.919111 -75.078349) (xy 48.878962 -75.03964) (xy 48.844876 -74.995497) (xy 48.81758 -74.946862)
			(xy 48.797657 -74.894771) (xy 48.785531 -74.840334) (xy 48.78146 -74.784712) (xy 47.658224 -74.784712)
			(xy 47.667591 -74.805683) (xy 47.682615 -74.858892) (xy 47.689799 -74.913713) (xy 47.688993 -74.968997)
			(xy 47.680213 -75.023585) (xy 47.663644 -75.076334) (xy 47.639632 -75.126138) (xy 47.608681 -75.171953)
			(xy 47.57144 -75.212819) (xy 47.528688 -75.24788) (xy 47.481323 -75.276401) (xy 47.430335 -75.297785)
			(xy 47.376795 -75.311583) (xy 47.321823 -75.317506) (xy 47.266572 -75.31543) (xy 47.2122 -75.305399)
			(xy 47.159846 -75.287622) (xy 47.110607 -75.262473) (xy 47.065515 -75.230478) (xy 47.025514 -75.192308)
			(xy 46.991445 -75.148762) (xy 46.964019 -75.100754) (xy 46.943812 -75.049289) (xy 46.931248 -74.995445)
			(xy 46.926589 -74.940352) (xy 46.92777 -74.912728) (xy 46.928257 -74.895572) (xy 46.921094 -74.862019)
			(xy 46.905251 -74.831587) (xy 46.881874 -74.806475) (xy 46.852652 -74.788498) (xy 46.83633 -74.783188)
			(xy 46.809897 -74.77506) (xy 46.75954 -74.752202) (xy 46.713012 -74.722313) (xy 46.671287 -74.686018)
			(xy 46.63524 -74.64408) (xy 46.605626 -74.597376) (xy 46.583065 -74.546886) (xy 46.568031 -74.493667)
			(xy 46.560839 -74.438836) (xy 44.802019 -74.438836) (xy 44.816102 -74.458414) (xy 44.828968 -74.481944)
			(xy 44.837493 -74.496976) (xy 44.86114 -74.522157) (xy 44.890673 -74.540075) (xy 44.92393 -74.549417)
			(xy 44.958473 -74.549498) (xy 44.975272 -74.545444) (xy 45.002765 -74.538346) (xy 45.05912 -74.531422)
			(xy 45.115878 -74.532927) (xy 45.171787 -74.542828) (xy 45.225611 -74.560907) (xy 45.251116 -74.573384)
			(xy 45.278746 -74.588212) (xy 45.329168 -74.625484) (xy 45.351446 -74.647552) (xy 45.363141 -74.65896)
			(xy 45.391039 -74.675942) (xy 45.422337 -74.685274) (xy 45.454979 -74.686345) (xy 45.486821 -74.679083)
			(xy 45.515771 -74.663966) (xy 45.52823 -74.653394) (xy 45.548769 -74.635394) (xy 45.594038 -74.604845)
			(xy 45.643201 -74.581065) (xy 45.695253 -74.56454) (xy 45.74913 -74.555608) (xy 45.80373 -74.554451)
			(xy 45.857937 -74.561093) (xy 45.910643 -74.575399) (xy 45.960769 -74.597075) (xy 46.007291 -74.625679)
			(xy 46.049259 -74.660625) (xy 46.085813 -74.7012) (xy 46.116206 -74.746574) (xy 46.139817 -74.795818)
			(xy 46.156164 -74.847927) (xy 46.164911 -74.901834) (xy 46.165881 -74.956438) (xy 46.162976 -74.983594)
			(xy 46.159169 -75.010119) (xy 46.145081 -75.06182) (xy 46.123897 -75.111042) (xy 46.096033 -75.156814)
			(xy 46.062038 -75.198236) (xy 46.022581 -75.234493) (xy 45.978438 -75.264872) (xy 45.930478 -75.288774)
			(xy 45.879644 -75.305729) (xy 45.826939 -75.315404) (xy 45.773398 -75.317607) (xy 45.720076 -75.312297)
			(xy 45.668021 -75.299576) (xy 45.618259 -75.279695) (xy 45.571769 -75.253047) (xy 45.529465 -75.220155)
			(xy 45.51045 -75.201272) (xy 45.498756 -75.189862) (xy 45.470859 -75.172879) (xy 45.439561 -75.163545)
			(xy 45.406918 -75.162475) (xy 45.375076 -75.169739) (xy 45.346126 -75.184859) (xy 45.333666 -75.19543)
			(xy 45.313199 -75.213339) (xy 45.268135 -75.24378) (xy 45.219205 -75.267517) (xy 45.167402 -75.284068)
			(xy 45.113773 -75.293097) (xy 45.059406 -75.294422) (xy 45.005402 -75.288017) (xy 44.952853 -75.27401)
			(xy 44.902825 -75.252686) (xy 44.856331 -75.224477) (xy 44.814311 -75.189953) (xy 44.777618 -75.149814)
			(xy 44.761912 -75.127612) (xy 44.755861 -75.118562) (xy 44.744679 -75.099882) (xy 44.73956 -75.090274)
			(xy 44.731034 -75.075247) (xy 44.707388 -75.050077) (xy 44.677856 -75.032173) (xy 44.644603 -75.022847)
			(xy 44.610068 -75.022783) (xy 44.593256 -75.026774) (xy 44.58377 -75.029366) (xy 44.564583 -75.033685)
			(xy 44.554902 -75.03541) (xy 44.530772 -75.038712) (xy 44.515362 -75.040772) (xy 44.486149 -75.051386)
			(xy 44.46037 -75.068749) (xy 44.439554 -75.09183) (xy 44.424936 -75.11926) (xy 44.417385 -75.14941)
			(xy 44.41698 -75.16495) (xy 44.41698 -76.036932) (xy 51.059332 -76.036932) (xy 51.063403 -75.98131)
			(xy 51.075529 -75.926873) (xy 51.095452 -75.874782) (xy 51.122748 -75.826147) (xy 51.156834 -75.782004)
			(xy 51.196983 -75.743295) (xy 51.242341 -75.710844) (xy 51.291941 -75.685343) (xy 51.344725 -75.667336)
			(xy 51.399568 -75.657206) (xy 51.455302 -75.655169) (xy 51.510739 -75.661269) (xy 51.564696 -75.675375)
			(xy 51.616025 -75.697187) (xy 51.663631 -75.726241) (xy 51.706499 -75.761916) (xy 51.743716 -75.803453)
			(xy 51.774489 -75.849966) (xy 51.798161 -75.900463) (xy 51.814229 -75.95387) (xy 51.822349 -76.009046)
			(xy 51.822858 -76.036932) (xy 51.822349 -76.064818) (xy 51.814229 -76.119994) (xy 51.798161 -76.173401)
			(xy 51.774489 -76.223898) (xy 51.743716 -76.270411) (xy 51.706499 -76.311948) (xy 51.663631 -76.347623)
			(xy 51.616025 -76.376677) (xy 51.564696 -76.398489) (xy 51.510739 -76.412595) (xy 51.455302 -76.418695)
			(xy 51.399568 -76.416658) (xy 51.344725 -76.406528) (xy 51.291941 -76.388521) (xy 51.242341 -76.36302)
			(xy 51.196983 -76.330569) (xy 51.156834 -76.29186) (xy 51.122748 -76.247717) (xy 51.095452 -76.199082)
			(xy 51.075529 -76.146991) (xy 51.063403 -76.092554) (xy 51.059332 -76.036932) (xy 44.41698 -76.036932)
			(xy 44.41698 -76.999592) (xy 44.41745 -77.015787) (xy 44.42558 -77.047138) (xy 44.441344 -77.075432)
			(xy 44.463725 -77.098844) (xy 44.491281 -77.115865) (xy 44.522235 -77.125398) (xy 44.538392 -77.126592)
			(xy 46.301914 -77.126592) (xy 46.324753 -77.125403) (xy 46.36947 -77.115838) (xy 46.411754 -77.098423)
			(xy 46.450237 -77.073721) (xy 46.483678 -77.04253) (xy 46.510996 -77.005857) (xy 46.531309 -76.964887)
			(xy 46.54396 -76.920943) (xy 46.54677 -76.898246) (xy 46.548959 -76.870918) (xy 46.560187 -76.817258)
			(xy 46.57898 -76.765758) (xy 46.604951 -76.717478) (xy 46.637566 -76.673413) (xy 46.676153 -76.63447)
			(xy 46.719916 -76.601452) (xy 46.767955 -76.575038) (xy 46.819281 -76.555772) (xy 46.872835 -76.544052)
			(xy 46.927516 -76.540118) (xy 46.982197 -76.544052) (xy 47.035751 -76.555772) (xy 47.087077 -76.575038)
			(xy 47.135116 -76.601452) (xy 47.178879 -76.63447) (xy 47.217466 -76.673413) (xy 47.250081 -76.717478)
			(xy 47.276052 -76.765758) (xy 47.294845 -76.817258) (xy 47.306073 -76.870918) (xy 47.308262 -76.898246)
			(xy 47.311058 -76.920941) (xy 47.323743 -76.964869) (xy 47.344076 -77.005822) (xy 47.371401 -77.042482)
			(xy 47.404837 -77.073668) (xy 47.44331 -77.098375) (xy 47.485579 -77.115809) (xy 47.530283 -77.125407)
			(xy 47.553118 -77.126592) (xy 48.85563 -77.126592) (xy 48.877454 -77.125464) (xy 48.920254 -77.116662)
			(xy 48.960917 -77.100666) (xy 48.998243 -77.077947) (xy 49.03113 -77.049176) (xy 49.058609 -77.015201)
			(xy 49.079868 -76.977025) (xy 49.09428 -76.935774) (xy 49.101421 -76.892665) (xy 49.101079 -76.84897)
			(xy 49.097692 -76.82738) (xy 49.09268 -76.79971) (xy 49.089887 -76.743547) (xy 49.095368 -76.687582)
			(xy 49.109005 -76.633028) (xy 49.130502 -76.581067) (xy 49.159392 -76.532823) (xy 49.195052 -76.489343)
			(xy 49.236707 -76.451569) (xy 49.283456 -76.420317) (xy 49.334285 -76.396267) (xy 49.388094 -76.379937)
			(xy 49.443718 -76.371683) (xy 49.49995 -76.371683) (xy 49.555574 -76.379937) (xy 49.609383 -76.396267)
			(xy 49.660212 -76.420317) (xy 49.706961 -76.451569) (xy 49.748616 -76.489343) (xy 49.784276 -76.532823)
			(xy 49.813166 -76.581067) (xy 49.834663 -76.633028) (xy 49.8483 -76.687582) (xy 49.853781 -76.743547)
			(xy 49.850988 -76.79971) (xy 49.845976 -76.82738) (xy 49.842544 -76.848955) (xy 49.842251 -76.892637)
			(xy 49.849428 -76.935727) (xy 49.863863 -76.976955) (xy 49.885133 -77.015111) (xy 49.912611 -77.049069)
			(xy 49.945488 -77.077831) (xy 49.982798 -77.100552) (xy 50.023442 -77.116561) (xy 50.066224 -77.125388)
			(xy 50.088038 -77.126592) (xy 50.689256 -77.126592) (xy 50.77968 -77.216762) (xy 50.854102 -77.291184)
			(xy 51.638454 -77.291184) (xy 51.661213 -77.290681) (xy 51.706003 -77.282578) (xy 51.748632 -77.266622)
			(xy 51.787736 -77.243325) (xy 51.822062 -77.213433) (xy 51.850512 -77.177902) (xy 51.872174 -77.13787)
			(xy 51.886356 -77.094618) (xy 51.892603 -77.049532) (xy 51.8922 -77.02677) (xy 51.891655 -77.014139)
			(xy 51.891655 -76.988855) (xy 51.8922 -76.976224) (xy 51.894171 -76.943965) (xy 51.905267 -76.880296)
			(xy 51.924346 -76.818546) (xy 51.951099 -76.759714) (xy 51.985095 -76.704748) (xy 52.025786 -76.654536)
			(xy 52.072514 -76.609888) (xy 52.124525 -76.571524) (xy 52.180981 -76.540064) (xy 52.240969 -76.516015)
			(xy 52.303522 -76.499765) (xy 52.367631 -76.491577) (xy 52.399946 -76.491084) (xy 52.672742 -76.491084)
			(xy 53.204618 -77.02296) (xy 53.220729 -77.038412) (xy 53.257321 -77.063977) (xy 53.297817 -77.082754)
			(xy 53.34097 -77.094166) (xy 53.385454 -77.097862) (xy 53.4299 -77.093727) (xy 53.472939 -77.081891)
			(xy 53.513247 -77.062715) (xy 53.549585 -77.036791) (xy 53.580834 -77.004916) (xy 53.606032 -76.968071)
			(xy 53.624404 -76.92739) (xy 53.630322 -76.905866) (xy 53.637535 -76.879274) (xy 53.658577 -76.828354)
			(xy 53.68674 -76.781) (xy 53.703728 -76.759308) (xy 53.716995 -76.742235) (xy 53.738123 -76.704514)
			(xy 53.752559 -76.66376) (xy 53.759885 -76.62115) (xy 53.759891 -76.577915) (xy 53.752575 -76.535303)
			(xy 53.73815 -76.494546) (xy 53.717032 -76.456819) (xy 53.703728 -76.439776) (xy 53.686651 -76.41792)
			(xy 53.65833 -76.370231) (xy 53.637212 -76.318945) (xy 53.623742 -76.265141) (xy 53.618203 -76.209954)
			(xy 53.620712 -76.154547) (xy 53.631217 -76.100086) (xy 53.649496 -76.047721) (xy 53.675164 -75.998553)
			(xy 53.707679 -75.95362) (xy 53.746358 -75.913867) (xy 53.790384 -75.880134) (xy 53.83883 -75.853129)
			(xy 53.890676 -75.833423) (xy 53.944828 -75.821431) (xy 54.000146 -75.817406) (xy 54.055464 -75.821431)
			(xy 54.109616 -75.833423) (xy 54.161462 -75.853129) (xy 54.209908 -75.880134) (xy 54.253934 -75.913867)
			(xy 54.292613 -75.95362) (xy 54.325128 -75.998553) (xy 54.350796 -76.047721) (xy 54.369075 -76.100086)
			(xy 54.37958 -76.154547) (xy 54.382089 -76.209954) (xy 54.37655 -76.265141) (xy 54.36308 -76.318945)
			(xy 54.341962 -76.370231) (xy 54.313641 -76.41792) (xy 54.296564 -76.439776) (xy 54.283304 -76.456849)
			(xy 54.262191 -76.494568) (xy 54.247769 -76.535317) (xy 54.240456 -76.57792) (xy 54.240461 -76.621146)
			(xy 54.247786 -76.663746) (xy 54.262218 -76.704492) (xy 54.283341 -76.742205) (xy 54.296564 -76.759308)
			(xy 54.313226 -76.780646) (xy 54.340995 -76.82712) (xy 54.361917 -76.877051) (xy 54.375574 -76.929437)
			(xy 54.381691 -76.983228) (xy 54.381455 -76.991473) (xy 55.218306 -76.991473) (xy 55.223595 -76.935735)
			(xy 55.236973 -76.881368) (xy 55.258153 -76.82954) (xy 55.28668 -76.781363) (xy 55.303928 -76.759308)
			(xy 55.317151 -76.742205) (xy 55.338275 -76.704492) (xy 55.352708 -76.663747) (xy 55.360033 -76.621146)
			(xy 55.360038 -76.57792) (xy 55.352724 -76.535317) (xy 55.338302 -76.494568) (xy 55.317188 -76.456849)
			(xy 55.303928 -76.439776) (xy 55.287043 -76.418256) (xy 55.259016 -76.371282) (xy 55.237983 -76.320787)
			(xy 55.224377 -76.267807) (xy 55.218475 -76.213426) (xy 55.2204 -76.15876) (xy 55.23011 -76.104929)
			(xy 55.247408 -76.053036) (xy 55.271939 -76.004146) (xy 55.3032 -75.959259) (xy 55.340551 -75.919296)
			(xy 55.383225 -75.885076) (xy 55.430348 -75.857301) (xy 55.480955 -75.836539) (xy 55.534007 -75.823216)
			(xy 55.588419 -75.817606) (xy 55.643074 -75.819823) (xy 55.696852 -75.829822) (xy 55.748651 -75.847398)
			(xy 55.79741 -75.87219) (xy 55.842129 -75.903691) (xy 55.881891 -75.941255) (xy 55.915882 -75.984112)
			(xy 55.943405 -76.031383) (xy 55.963895 -76.0821) (xy 55.976933 -76.135223) (xy 55.982252 -76.189664)
			(xy 55.979742 -76.244306) (xy 55.969456 -76.29803) (xy 55.951603 -76.349735) (xy 55.926549 -76.39836)
			(xy 55.894809 -76.44291) (xy 55.857033 -76.48247) (xy 55.835804 -76.49972) (xy 55.823163 -76.510236)
			(xy 55.803379 -76.536489) (xy 55.790959 -76.566926) (xy 55.786731 -76.599526) (xy 55.790973 -76.632125)
			(xy 55.803404 -76.662557) (xy 55.8232 -76.688801) (xy 55.835804 -76.699364) (xy 55.84063 -76.703174)
			(xy 55.857704 -76.716436) (xy 55.895424 -76.737555) (xy 55.936175 -76.751982) (xy 55.978781 -76.759301)
			(xy 56.022011 -76.759301) (xy 56.064617 -76.751982) (xy 56.105368 -76.737555) (xy 56.143088 -76.716436)
			(xy 56.160162 -76.703174) (xy 56.181838 -76.686185) (xy 56.229165 -76.65802) (xy 56.280049 -76.636951)
			(xy 56.333434 -76.623416) (xy 56.38821 -76.617697) (xy 56.443239 -76.619911) (xy 56.497378 -76.630014)
			(xy 56.549503 -76.647795) (xy 56.598529 -76.672884) (xy 56.64344 -76.704761) (xy 56.683302 -76.742763)
			(xy 56.700674 -76.764134) (xy 56.711236 -76.776733) (xy 56.737478 -76.79652) (xy 56.767905 -76.808943)
			(xy 56.800496 -76.813178) (xy 56.833087 -76.808943) (xy 56.863514 -76.79652) (xy 56.889756 -76.776733)
			(xy 56.900318 -76.764134) (xy 56.904128 -76.759308) (xy 56.917351 -76.742205) (xy 56.938475 -76.704492)
			(xy 56.952908 -76.663747) (xy 56.960233 -76.621146) (xy 56.960238 -76.57792) (xy 56.952924 -76.535317)
			(xy 56.938502 -76.494568) (xy 56.917388 -76.456849) (xy 56.904128 -76.439776) (xy 56.887051 -76.41792)
			(xy 56.85873 -76.370231) (xy 56.837612 -76.318945) (xy 56.824142 -76.265141) (xy 56.818603 -76.209954)
			(xy 56.821112 -76.154547) (xy 56.831617 -76.100086) (xy 56.849896 -76.047721) (xy 56.875564 -75.998553)
			(xy 56.908079 -75.95362) (xy 56.946758 -75.913867) (xy 56.990784 -75.880134) (xy 57.03923 -75.853129)
			(xy 57.091076 -75.833423) (xy 57.145228 -75.821431) (xy 57.200546 -75.817406) (xy 57.255864 -75.821431)
			(xy 57.310016 -75.833423) (xy 57.361862 -75.853129) (xy 57.410308 -75.880134) (xy 57.454334 -75.913867)
			(xy 57.493013 -75.95362) (xy 57.525528 -75.998553) (xy 57.551196 -76.047721) (xy 57.569475 -76.100086)
			(xy 57.57998 -76.154547) (xy 57.582489 -76.209954) (xy 57.57695 -76.265141) (xy 57.56348 -76.318945)
			(xy 57.542362 -76.370231) (xy 57.514041 -76.41792) (xy 57.496964 -76.439776) (xy 57.483661 -76.45682)
			(xy 57.462543 -76.494546) (xy 57.448118 -76.535304) (xy 57.440803 -76.577915) (xy 57.440809 -76.62115)
			(xy 57.448135 -76.66376) (xy 57.46257 -76.704513) (xy 57.483697 -76.742235) (xy 57.496964 -76.759308)
			(xy 57.514148 -76.781411) (xy 57.542665 -76.829585) (xy 57.563835 -76.881409) (xy 57.577206 -76.935771)
			(xy 57.58249 -76.991502) (xy 57.581449 -77.011447) (xy 59.219065 -77.011447) (xy 59.221286 -76.956803)
			(xy 59.231288 -76.903035) (xy 59.248864 -76.851247) (xy 59.273655 -76.802499) (xy 59.305153 -76.757791)
			(xy 59.342712 -76.718038) (xy 59.385562 -76.684056) (xy 59.432826 -76.656541) (xy 59.483534 -76.636057)
			(xy 59.536648 -76.623024) (xy 59.591079 -76.617708) (xy 59.645711 -76.620219) (xy 59.699424 -76.630505)
			(xy 59.751118 -76.648356) (xy 59.799734 -76.673405) (xy 59.844274 -76.70514) (xy 59.883827 -76.742909)
			(xy 59.901074 -76.764134) (xy 59.911636 -76.776733) (xy 59.937878 -76.79652) (xy 59.968305 -76.808943)
			(xy 60.000896 -76.813178) (xy 60.033487 -76.808943) (xy 60.063914 -76.79652) (xy 60.090156 -76.776733)
			(xy 60.100718 -76.764134) (xy 60.104528 -76.759308) (xy 60.117861 -76.742264) (xy 60.139037 -76.704527)
			(xy 60.153514 -76.663748) (xy 60.160873 -76.621105) (xy 60.160902 -76.577833) (xy 60.1536 -76.535181)
			(xy 60.139177 -76.494382) (xy 60.118052 -76.456617) (xy 60.104782 -76.439522) (xy 60.087937 -76.417933)
			(xy 60.059908 -76.370893) (xy 60.038893 -76.320329) (xy 60.025324 -76.26728) (xy 60.01948 -76.212835)
			(xy 60.021482 -76.158114) (xy 60.031287 -76.104242) (xy 60.048695 -76.052326) (xy 60.073348 -76.003432)
			(xy 60.104739 -75.958566) (xy 60.142222 -75.918649) (xy 60.185029 -75.884502) (xy 60.232278 -75.856828)
			(xy 60.282999 -75.836194) (xy 60.336149 -75.823024) (xy 60.390636 -75.81759) (xy 60.44534 -75.820003)
			(xy 60.499137 -75.830213) (xy 60.550921 -75.848011) (xy 60.599628 -75.873031) (xy 60.644257 -75.904758)
			(xy 60.683891 -75.942541) (xy 60.701174 -75.96378) (xy 60.711757 -75.976382) (xy 60.738038 -75.996169)
			(xy 60.7685 -76.008591) (xy 60.801123 -76.012825) (xy 60.833746 -76.008591) (xy 60.864208 -75.996169)
			(xy 60.890489 -75.976382) (xy 60.901072 -75.96378) (xy 60.904628 -75.959208) (xy 60.917851 -75.942105)
			(xy 60.938975 -75.904392) (xy 60.953408 -75.863647) (xy 60.960733 -75.821046) (xy 60.960738 -75.77782)
			(xy 60.953424 -75.735217) (xy 60.939002 -75.694468) (xy 60.917888 -75.656749) (xy 60.904628 -75.639676)
			(xy 60.887743 -75.618156) (xy 60.859716 -75.571182) (xy 60.838683 -75.520687) (xy 60.825077 -75.467707)
			(xy 60.819175 -75.413326) (xy 60.8211 -75.35866) (xy 60.83081 -75.304829) (xy 60.848108 -75.252936)
			(xy 60.872639 -75.204046) (xy 60.9039 -75.159159) (xy 60.941251 -75.119196) (xy 60.983925 -75.084976)
			(xy 61.031048 -75.057201) (xy 61.081655 -75.036439) (xy 61.134707 -75.023116) (xy 61.189119 -75.017506)
			(xy 61.243774 -75.019723) (xy 61.297552 -75.029722) (xy 61.349351 -75.047298) (xy 61.39811 -75.07209)
			(xy 61.442829 -75.103591) (xy 61.482591 -75.141155) (xy 61.516582 -75.184012) (xy 61.544105 -75.231283)
			(xy 61.564595 -75.282) (xy 61.577633 -75.335123) (xy 61.582952 -75.389564) (xy 61.582501 -75.399392)
			(xy 63.219328 -75.399392) (xy 63.223399 -75.34377) (xy 63.235525 -75.289333) (xy 63.255448 -75.237242)
			(xy 63.282744 -75.188607) (xy 63.31683 -75.144464) (xy 63.356979 -75.105755) (xy 63.402337 -75.073304)
			(xy 63.451937 -75.047803) (xy 63.504721 -75.029796) (xy 63.559564 -75.019666) (xy 63.615298 -75.017629)
			(xy 63.670735 -75.023729) (xy 63.724692 -75.037835) (xy 63.776021 -75.059647) (xy 63.823627 -75.088701)
			(xy 63.866495 -75.124376) (xy 63.902402 -75.164451) (xy 65.246739 -75.164451) (xy 65.252951 -75.109748)
			(xy 65.26696 -75.056507) (xy 65.288475 -75.005831) (xy 65.31705 -74.958773) (xy 65.352091 -74.916311)
			(xy 65.392871 -74.879325) (xy 65.438543 -74.848584) (xy 65.488159 -74.824725) (xy 65.540689 -74.808245)
			(xy 65.595041 -74.799486) (xy 65.650089 -74.798628) (xy 65.704688 -74.805691) (xy 65.757705 -74.820527)
			(xy 65.80804 -74.842829) (xy 65.854647 -74.872132) (xy 65.875916 -74.889614) (xy 65.894665 -74.9048)
			(xy 65.936654 -74.928554) (xy 65.982368 -74.943964) (xy 66.030169 -74.950477) (xy 66.07834 -74.94786)
			(xy 66.125153 -74.936207) (xy 66.168929 -74.915935) (xy 66.188844 -74.902314) (xy 66.208218 -74.888818)
			(xy 66.24966 -74.866193) (xy 66.293579 -74.848857) (xy 66.316352 -74.842624) (xy 66.331478 -74.838286)
			(xy 66.359115 -74.823258) (xy 66.382227 -74.801917) (xy 66.399405 -74.775563) (xy 66.409603 -74.745804)
			(xy 66.412197 -74.714453) (xy 66.410078 -74.69886) (xy 66.406001 -74.671173) (xy 66.40519 -74.615216)
			(xy 66.412757 -74.559768) (xy 66.428532 -74.506075) (xy 66.452162 -74.455346) (xy 66.483113 -74.408722)
			(xy 66.520689 -74.367252) (xy 66.564046 -74.331868) (xy 66.612207 -74.303368) (xy 66.66409 -74.282392)
			(xy 66.718526 -74.269412) (xy 66.774291 -74.26472) (xy 66.830131 -74.268422) (xy 66.884789 -74.280434)
			(xy 66.937035 -74.300487) (xy 66.985694 -74.328129) (xy 67.007994 -74.345038) (xy 67.026234 -74.358806)
			(xy 67.066617 -74.380193) (xy 67.110175 -74.394009) (xy 67.155503 -74.39981) (xy 67.201136 -74.397407)
			(xy 67.245604 -74.38688) (xy 67.28747 -74.368566) (xy 67.306698 -74.356214) (xy 67.329793 -74.341293)
			(xy 67.379335 -74.31745) (xy 67.431788 -74.30097) (xy 67.486064 -74.292195) (xy 67.541038 -74.291307)
			(xy 67.595569 -74.298325) (xy 67.648527 -74.313102) (xy 67.698813 -74.335333) (xy 67.745385 -74.364556)
			(xy 67.787276 -74.400165) (xy 67.805808 -74.420476) (xy 67.816522 -74.431919) (xy 67.842365 -74.449644)
			(xy 67.871755 -74.460519) (xy 67.902912 -74.463884) (xy 67.933946 -74.459536) (xy 67.962978 -74.447738)
			(xy 67.988248 -74.429205) (xy 67.998594 -74.417428) (xy 68.007598 -74.40685) (xy 68.026918 -74.386888)
			(xy 68.037202 -74.37755) (xy 68.049512 -74.365778) (xy 68.067872 -74.337101) (xy 68.078 -74.304591)
			(xy 68.079177 -74.27056) (xy 68.07132 -74.237428) (xy 68.054986 -74.20755) (xy 68.043552 -74.194924)
			(xy 68.024911 -74.174982) (xy 67.993096 -74.130627) (xy 67.968092 -74.082104) (xy 67.950435 -74.030452)
			(xy 67.940502 -73.976777) (xy 67.938507 -73.922227) (xy 67.944492 -73.86797) (xy 67.958329 -73.815166)
			(xy 67.979721 -73.764946) (xy 68.008211 -73.718385) (xy 68.04319 -73.676478) (xy 68.083909 -73.640123)
			(xy 68.129495 -73.610098) (xy 68.178975 -73.587045) (xy 68.231288 -73.571458) (xy 68.285316 -73.563669)
			(xy 68.339902 -73.563847) (xy 68.393879 -73.571986) (xy 68.44609 -73.587913) (xy 68.495418 -73.611287)
			(xy 68.540809 -73.641608) (xy 68.58129 -73.678227) (xy 68.615996 -73.72036) (xy 68.644183 -73.767106)
			(xy 68.665249 -73.817464) (xy 68.676074 -73.859898) (xy 71.199754 -73.859898) (xy 71.203825 -73.804276)
			(xy 71.215951 -73.749839) (xy 71.235874 -73.697748) (xy 71.26317 -73.649113) (xy 71.297256 -73.60497)
			(xy 71.337405 -73.566261) (xy 71.382763 -73.53381) (xy 71.432363 -73.508309) (xy 71.485147 -73.490302)
			(xy 71.53999 -73.480172) (xy 71.595724 -73.478135) (xy 71.651161 -73.484235) (xy 71.705118 -73.498341)
			(xy 71.756447 -73.520153) (xy 71.804053 -73.549207) (xy 71.846921 -73.584882) (xy 71.884138 -73.626419)
			(xy 71.914911 -73.672932) (xy 71.938583 -73.723429) (xy 71.954651 -73.776836) (xy 71.962771 -73.832012)
			(xy 71.96328 -73.859898) (xy 71.962771 -73.887784) (xy 71.954651 -73.94296) (xy 71.938583 -73.996367)
			(xy 71.914911 -74.046864) (xy 71.884138 -74.093377) (xy 71.849742 -74.131766) (xy 74.391865 -74.131766)
			(xy 74.399848 -74.077029) (xy 74.41565 -74.024018) (xy 74.43894 -73.973844) (xy 74.46923 -73.927558)
			(xy 74.505885 -73.88613) (xy 74.548137 -73.850428) (xy 74.595101 -73.8212) (xy 74.645792 -73.799059)
			(xy 74.69915 -73.784469) (xy 74.754054 -73.777735) (xy 74.809356 -73.778998) (xy 74.863896 -73.788233)
			(xy 74.916531 -73.805245) (xy 74.966159 -73.829678) (xy 75.011739 -73.86102) (xy 75.032362 -73.879456)
			(xy 75.050133 -73.895173) (xy 75.090327 -73.920365) (xy 75.134497 -73.937663) (xy 75.18111 -73.946464)
			(xy 75.228546 -73.946464) (xy 75.275159 -73.937663) (xy 75.319329 -73.920365) (xy 75.359523 -73.895173)
			(xy 75.377294 -73.879456) (xy 75.398581 -73.860458) (xy 75.445741 -73.828345) (xy 75.497157 -73.803613)
			(xy 75.551682 -73.786812) (xy 75.608101 -73.778316) (xy 75.665155 -73.778316) (xy 75.721574 -73.786812)
			(xy 75.776099 -73.803613) (xy 75.827515 -73.828345) (xy 75.874675 -73.860458) (xy 75.895962 -73.879456)
			(xy 75.913733 -73.895173) (xy 75.953927 -73.920365) (xy 75.998097 -73.937663) (xy 76.04471 -73.946464)
			(xy 76.092146 -73.946464) (xy 76.138759 -73.937663) (xy 76.182929 -73.920365) (xy 76.223123 -73.895173)
			(xy 76.240894 -73.879456) (xy 76.261549 -73.861066) (xy 76.307119 -73.829737) (xy 76.356735 -73.805316)
			(xy 76.409357 -73.788313) (xy 76.463882 -73.779086) (xy 76.519168 -73.777827) (xy 76.574057 -73.784563)
			(xy 76.627398 -73.799152) (xy 76.6397 -73.804526) (xy 85.087712 -73.804526) (xy 85.091783 -73.748904)
			(xy 85.103909 -73.694467) (xy 85.123832 -73.642376) (xy 85.151128 -73.593741) (xy 85.185214 -73.549598)
			(xy 85.225363 -73.510889) (xy 85.270721 -73.478438) (xy 85.320321 -73.452937) (xy 85.373105 -73.43493)
			(xy 85.427948 -73.4248) (xy 85.483682 -73.422763) (xy 85.539119 -73.428863) (xy 85.593076 -73.442969)
			(xy 85.644405 -73.464781) (xy 85.692011 -73.493835) (xy 85.734879 -73.52951) (xy 85.772096 -73.571047)
			(xy 85.802869 -73.61756) (xy 85.826541 -73.668057) (xy 85.842609 -73.721464) (xy 85.850729 -73.77664)
			(xy 85.851238 -73.804526) (xy 85.850729 -73.832412) (xy 85.842609 -73.887588) (xy 85.826541 -73.940995)
			(xy 85.802869 -73.991492) (xy 85.772096 -74.038005) (xy 85.764178 -74.046842) (xy 86.728552 -74.046842)
			(xy 86.732623 -73.99122) (xy 86.744749 -73.936783) (xy 86.764672 -73.884692) (xy 86.791968 -73.836057)
			(xy 86.826054 -73.791914) (xy 86.866203 -73.753205) (xy 86.911561 -73.720754) (xy 86.961161 -73.695253)
			(xy 87.013945 -73.677246) (xy 87.068788 -73.667116) (xy 87.124522 -73.665079) (xy 87.179959 -73.671179)
			(xy 87.233916 -73.685285) (xy 87.285245 -73.707097) (xy 87.332851 -73.736151) (xy 87.375719 -73.771826)
			(xy 87.412936 -73.813363) (xy 87.443709 -73.859876) (xy 87.467381 -73.910373) (xy 87.483449 -73.96378)
			(xy 87.491569 -74.018956) (xy 87.492078 -74.046842) (xy 87.491569 -74.074728) (xy 87.483449 -74.129904)
			(xy 87.467381 -74.183311) (xy 87.443709 -74.233808) (xy 87.412936 -74.280321) (xy 87.375936 -74.321616)
			(xy 100.719786 -74.321616) (xy 100.722644 -74.265696) (xy 100.733645 -74.210794) (xy 100.752554 -74.15809)
			(xy 100.778964 -74.108717) (xy 100.812308 -74.063734) (xy 100.851869 -74.02411) (xy 100.896798 -73.990693)
			(xy 100.946129 -73.964204) (xy 100.998802 -73.94521) (xy 101.053686 -73.93412) (xy 101.109601 -73.931173)
			(xy 101.165347 -73.93643) (xy 101.219725 -73.949781) (xy 101.271568 -73.970937) (xy 101.319761 -73.999444)
			(xy 101.363269 -74.034689) (xy 101.382576 -74.05497) (xy 101.398378 -74.071511) (xy 101.434863 -74.099105)
			(xy 101.475693 -74.11973) (xy 101.519554 -74.132722) (xy 101.56503 -74.137662) (xy 101.610657 -74.134392)
			(xy 101.654964 -74.123016) (xy 101.675946 -74.113898) (xy 101.700518 -74.103111) (xy 101.751923 -74.087713)
			(xy 101.804977 -74.079661) (xy 101.858636 -74.079113) (xy 101.911844 -74.086081) (xy 101.93782 -74.092816)
			(xy 101.959255 -74.098249) (xy 102.003266 -74.102491) (xy 102.047348 -74.099056) (xy 102.09017 -74.088046)
			(xy 102.130442 -74.069794) (xy 102.166949 -74.044849) (xy 102.198589 -74.013964) (xy 102.211886 -73.996296)
			(xy 102.227982 -73.974597) (xy 102.265403 -73.935628) (xy 102.307948 -73.902328) (xy 102.354766 -73.875364)
			(xy 102.404921 -73.855276) (xy 102.457408 -73.842466) (xy 102.511177 -73.83719) (xy 102.565153 -73.839553)
			(xy 102.618255 -73.849508) (xy 102.669422 -73.866857) (xy 102.717629 -73.891251) (xy 102.761911 -73.922204)
			(xy 102.801383 -73.959094) (xy 102.835256 -74.001186) (xy 102.86285 -74.047635) (xy 102.883614 -74.097513)
			(xy 102.890828 -74.12355) (xy 102.896994 -74.145401) (xy 102.91593 -74.186658) (xy 102.941902 -74.22389)
			(xy 102.974081 -74.25591) (xy 103.011442 -74.281696) (xy 103.052793 -74.300427) (xy 103.096816 -74.311505)
			(xy 103.119428 -74.313542) (xy 103.147248 -74.316) (xy 103.201802 -74.327952) (xy 103.254029 -74.347731)
			(xy 103.302815 -74.374914) (xy 103.347115 -74.40892) (xy 103.385983 -74.449022) (xy 103.418588 -74.494363)
			(xy 103.444233 -74.543975) (xy 103.46237 -74.596795) (xy 103.47261 -74.651695) (xy 103.474736 -74.707502)
			(xy 103.468702 -74.763023) (xy 103.454636 -74.81707) (xy 103.43284 -74.868488) (xy 103.409906 -74.906124)
			(xy 111.651286 -74.906124) (xy 111.655357 -74.850502) (xy 111.667483 -74.796065) (xy 111.687406 -74.743974)
			(xy 111.714702 -74.695339) (xy 111.748788 -74.651196) (xy 111.788937 -74.612487) (xy 111.834295 -74.580036)
			(xy 111.883895 -74.554535) (xy 111.936679 -74.536528) (xy 111.991522 -74.526398) (xy 112.047256 -74.524361)
			(xy 112.102693 -74.530461) (xy 112.15665 -74.544567) (xy 112.207979 -74.566379) (xy 112.255585 -74.595433)
			(xy 112.298453 -74.631108) (xy 112.33567 -74.672645) (xy 112.366443 -74.719158) (xy 112.390115 -74.769655)
			(xy 112.406183 -74.823062) (xy 112.414303 -74.878238) (xy 112.414812 -74.906124) (xy 112.414303 -74.93401)
			(xy 112.406183 -74.989186) (xy 112.390115 -75.042593) (xy 112.366443 -75.09309) (xy 112.33567 -75.139603)
			(xy 112.298453 -75.18114) (xy 112.255585 -75.216815) (xy 112.207979 -75.245869) (xy 112.15665 -75.267681)
			(xy 112.102693 -75.281787) (xy 112.047256 -75.287887) (xy 111.991522 -75.28585) (xy 111.936679 -75.27572)
			(xy 111.883895 -75.257713) (xy 111.834295 -75.232212) (xy 111.788937 -75.199761) (xy 111.748788 -75.161052)
			(xy 111.714702 -75.116909) (xy 111.687406 -75.068274) (xy 111.667483 -75.016183) (xy 111.655357 -74.961746)
			(xy 111.651286 -74.906124) (xy 103.409906 -74.906124) (xy 103.403779 -74.916178) (xy 103.368074 -74.959122)
			(xy 103.326489 -74.996399) (xy 103.279913 -75.027215) (xy 103.229342 -75.05091) (xy 103.175856 -75.066977)
			(xy 103.120598 -75.075073) (xy 103.064751 -75.075026) (xy 103.009507 -75.066835) (xy 102.956049 -75.050676)
			(xy 102.905518 -75.026895) (xy 102.858994 -74.996) (xy 102.817473 -74.958651) (xy 102.781842 -74.915647)
			(xy 102.752863 -74.867907) (xy 102.731154 -74.816452) (xy 102.723696 -74.789538) (xy 102.717601 -74.767665)
			(xy 102.698656 -74.726403) (xy 102.672673 -74.689169) (xy 102.640482 -74.657151) (xy 102.603109 -74.631369)
			(xy 102.561746 -74.612645) (xy 102.517712 -74.601577) (xy 102.495096 -74.599546) (xy 102.475922 -74.597994)
			(xy 102.438004 -74.5915) (xy 102.419404 -74.586592) (xy 102.397964 -74.58118) (xy 102.353955 -74.576933)
			(xy 102.309875 -74.580365) (xy 102.267053 -74.591371) (xy 102.226782 -74.609621) (xy 102.190275 -74.634563)
			(xy 102.158635 -74.665445) (xy 102.145338 -74.683112) (xy 102.128453 -74.705735) (xy 102.089096 -74.746203)
			(xy 102.044205 -74.780429) (xy 101.99476 -74.807665) (xy 101.941841 -74.827316) (xy 101.886603 -74.838953)
			(xy 101.830253 -74.842321) (xy 101.774022 -74.837347) (xy 101.719139 -74.82414) (xy 101.666801 -74.802988)
			(xy 101.618153 -74.774353) (xy 101.574256 -74.738861) (xy 101.554788 -74.718418) (xy 101.538938 -74.701925)
			(xy 101.502463 -74.67433) (xy 101.461642 -74.653702) (xy 101.417791 -74.640704) (xy 101.372323 -74.635755)
			(xy 101.326702 -74.639015) (xy 101.282399 -74.650379) (xy 101.261418 -74.65949) (xy 101.235802 -74.670797)
			(xy 101.182073 -74.686558) (xy 101.126617 -74.694296) (xy 101.070626 -74.693843) (xy 101.015302 -74.685211)
			(xy 100.961835 -74.668584) (xy 100.911372 -74.644319) (xy 100.864999 -74.612939) (xy 100.823711 -74.575117)
			(xy 100.788395 -74.531665) (xy 100.75981 -74.483518) (xy 100.738571 -74.43171) (xy 100.725133 -74.377353)
			(xy 100.719786 -74.321616) (xy 87.375936 -74.321616) (xy 87.375719 -74.321858) (xy 87.332851 -74.357533)
			(xy 87.285245 -74.386587) (xy 87.233916 -74.408399) (xy 87.179959 -74.422505) (xy 87.124522 -74.428605)
			(xy 87.068788 -74.426568) (xy 87.013945 -74.416438) (xy 86.961161 -74.398431) (xy 86.911561 -74.37293)
			(xy 86.866203 -74.340479) (xy 86.826054 -74.30177) (xy 86.791968 -74.257627) (xy 86.764672 -74.208992)
			(xy 86.744749 -74.156901) (xy 86.732623 -74.102464) (xy 86.728552 -74.046842) (xy 85.764178 -74.046842)
			(xy 85.734879 -74.079542) (xy 85.692011 -74.115217) (xy 85.644405 -74.144271) (xy 85.593076 -74.166083)
			(xy 85.539119 -74.180189) (xy 85.483682 -74.186289) (xy 85.427948 -74.184252) (xy 85.373105 -74.174122)
			(xy 85.320321 -74.156115) (xy 85.270721 -74.130614) (xy 85.225363 -74.098163) (xy 85.185214 -74.059454)
			(xy 85.151128 -74.015311) (xy 85.123832 -73.966676) (xy 85.103909 -73.914585) (xy 85.091783 -73.860148)
			(xy 85.087712 -73.804526) (xy 76.6397 -73.804526) (xy 76.678074 -73.82129) (xy 76.725023 -73.850511)
			(xy 76.767262 -73.886205) (xy 76.803905 -73.927622) (xy 76.834185 -73.973896) (xy 76.857467 -74.024056)
			(xy 76.873264 -74.077053) (xy 76.881244 -74.131774) (xy 76.88124 -74.187075) (xy 76.873253 -74.241795)
			(xy 76.85745 -74.294789) (xy 76.834161 -74.344947) (xy 76.803875 -74.391217) (xy 76.767227 -74.43263)
			(xy 76.724984 -74.468318) (xy 76.678031 -74.497533) (xy 76.627352 -74.519664) (xy 76.574009 -74.534247)
			(xy 76.519119 -74.540975) (xy 76.463833 -74.539709) (xy 76.409309 -74.530475) (xy 76.35669 -74.513466)
			(xy 76.307077 -74.489038) (xy 76.261511 -74.457704) (xy 76.240894 -74.439272) (xy 76.223123 -74.423555)
			(xy 76.182929 -74.398363) (xy 76.138759 -74.381065) (xy 76.092146 -74.372264) (xy 76.04471 -74.372264)
			(xy 75.998097 -74.381065) (xy 75.953927 -74.398363) (xy 75.913733 -74.423555) (xy 75.895962 -74.439272)
			(xy 75.874675 -74.45827) (xy 75.827515 -74.490383) (xy 75.776099 -74.515115) (xy 75.721574 -74.531916)
			(xy 75.665155 -74.540412) (xy 75.608101 -74.540412) (xy 75.551682 -74.531916) (xy 75.497157 -74.515115)
			(xy 75.445741 -74.490383) (xy 75.398581 -74.45827) (xy 75.377294 -74.439272) (xy 75.359523 -74.423555)
			(xy 75.319329 -74.398363) (xy 75.275159 -74.381065) (xy 75.228546 -74.372264) (xy 75.18111 -74.372264)
			(xy 75.134497 -74.381065) (xy 75.090327 -74.398363) (xy 75.050133 -74.423555) (xy 75.032362 -74.439272)
			(xy 75.011777 -74.45775) (xy 74.966201 -74.489098) (xy 74.916577 -74.513537) (xy 74.863944 -74.530556)
			(xy 74.809405 -74.539797) (xy 74.754103 -74.541068) (xy 74.699198 -74.534341) (xy 74.645839 -74.519757)
			(xy 74.595144 -74.497623) (xy 74.548176 -74.468401) (xy 74.50592 -74.432704) (xy 74.469259 -74.391281)
			(xy 74.438964 -74.344999) (xy 74.415667 -74.294828) (xy 74.399859 -74.241819) (xy 74.391869 -74.187082)
			(xy 74.391865 -74.131766) (xy 71.849742 -74.131766) (xy 71.846921 -74.134914) (xy 71.804053 -74.170589)
			(xy 71.756447 -74.199643) (xy 71.705118 -74.221455) (xy 71.651161 -74.235561) (xy 71.595724 -74.241661)
			(xy 71.53999 -74.239624) (xy 71.485147 -74.229494) (xy 71.432363 -74.211487) (xy 71.382763 -74.185986)
			(xy 71.337405 -74.153535) (xy 71.297256 -74.114826) (xy 71.26317 -74.070683) (xy 71.235874 -74.022048)
			(xy 71.215951 -73.969957) (xy 71.203825 -73.91552) (xy 71.199754 -73.859898) (xy 68.676074 -73.859898)
			(xy 68.678742 -73.870356) (xy 68.684374 -73.924651) (xy 68.682024 -73.979187) (xy 68.671743 -74.032796)
			(xy 68.653751 -74.084332) (xy 68.628432 -74.132691) (xy 68.612766 -74.155046) (xy 68.600033 -74.173292)
			(xy 68.580549 -74.21329) (xy 68.568317 -74.256067) (xy 68.563708 -74.300319) (xy 68.566863 -74.344698)
			(xy 68.577686 -74.387853) (xy 68.595847 -74.428469) (xy 68.60794 -74.447146) (xy 68.623314 -74.470563)
			(xy 68.647648 -74.52102) (xy 68.664343 -74.574493) (xy 68.673037 -74.629833) (xy 68.673546 -74.685849)
			(xy 68.665857 -74.741338) (xy 68.650137 -74.795105) (xy 68.626723 -74.845996) (xy 68.596118 -74.892916)
			(xy 68.558981 -74.934855) (xy 68.51611 -74.970913) (xy 68.468427 -75.000314) (xy 68.416957 -75.022426)
			(xy 68.390008 -75.030076) (xy 68.375856 -75.034301) (xy 68.349859 -75.0483) (xy 68.34137 -75.055837)
			(xy 69.117952 -75.055837) (xy 69.118007 -75.000011) (xy 69.126197 -74.94479) (xy 69.142348 -74.891351)
			(xy 69.166114 -74.840836) (xy 69.196988 -74.794325) (xy 69.23431 -74.752809) (xy 69.277285 -74.717176)
			(xy 69.324994 -74.688186) (xy 69.376418 -74.666458) (xy 69.430459 -74.652457) (xy 69.485964 -74.646481)
			(xy 69.541748 -74.648658) (xy 69.596618 -74.658941) (xy 69.649405 -74.67711) (xy 69.698979 -74.702779)
			(xy 69.744284 -74.735398) (xy 69.764656 -74.754486) (xy 69.781226 -74.769922) (xy 69.81877 -74.795234)
			(xy 69.860207 -74.813492) (xy 69.904223 -74.824118) (xy 69.949425 -74.826776) (xy 69.994383 -74.82138)
			(xy 70.037673 -74.808103) (xy 70.058026 -74.798174) (xy 70.083062 -74.785817) (xy 70.135887 -74.767747)
			(xy 70.190781 -74.757569) (xy 70.246572 -74.755499) (xy 70.30207 -74.761583) (xy 70.356088 -74.77569)
			(xy 70.407474 -74.79752) (xy 70.455129 -74.826605) (xy 70.498036 -74.862325) (xy 70.53528 -74.903917)
			(xy 70.566064 -74.950493) (xy 70.589731 -75.001059) (xy 70.605776 -75.054533) (xy 70.613856 -75.109775)
			(xy 70.613799 -75.165605) (xy 70.605606 -75.220831) (xy 70.589451 -75.274273) (xy 70.56568 -75.324789)
			(xy 70.534801 -75.371302) (xy 70.497472 -75.412818) (xy 70.454492 -75.44845) (xy 70.406777 -75.477438)
			(xy 70.355347 -75.499162) (xy 70.3013 -75.513158) (xy 70.24579 -75.519128) (xy 70.190003 -75.516944)
			(xy 70.135129 -75.506653) (xy 70.082342 -75.488475) (xy 70.032767 -75.462797) (xy 69.987465 -75.430169)
			(xy 69.967094 -75.411076) (xy 69.950483 -75.395686) (xy 69.912949 -75.370366) (xy 69.871522 -75.3521)
			(xy 69.827513 -75.341466) (xy 69.782316 -75.338801) (xy 69.737362 -75.34419) (xy 69.694076 -75.357462)
			(xy 69.673724 -75.367388) (xy 69.648712 -75.379786) (xy 69.59589 -75.397851) (xy 69.540999 -75.408026)
			(xy 69.485211 -75.410093) (xy 69.429718 -75.404007) (xy 69.375704 -75.389899) (xy 69.324323 -75.36807)
			(xy 69.276672 -75.338986) (xy 69.233768 -75.303268) (xy 69.196527 -75.261679) (xy 69.165745 -75.215107)
			(xy 69.142079 -75.164545) (xy 69.126033 -75.111075) (xy 69.117952 -75.055837) (xy 68.34137 -75.055837)
			(xy 68.32778 -75.067904) (xy 68.310802 -75.092062) (xy 68.299836 -75.119477) (xy 68.295471 -75.148679)
			(xy 68.296282 -75.163426) (xy 68.298209 -75.190779) (xy 68.29498 -75.24552) (xy 68.283948 -75.299235)
			(xy 68.265342 -75.350818) (xy 68.239545 -75.399207) (xy 68.207087 -75.443406) (xy 68.168638 -75.482504)
			(xy 68.124988 -75.515696) (xy 68.077037 -75.542299) (xy 68.025773 -75.561765) (xy 67.972249 -75.573693)
			(xy 67.91757 -75.577838) (xy 67.862861 -75.574114) (xy 67.809247 -75.562598) (xy 67.757834 -75.543527)
			(xy 67.70968 -75.517294) (xy 67.687444 -75.501246) (xy 67.668432 -75.48765) (xy 67.626549 -75.466918)
			(xy 67.581581 -75.454192) (xy 67.535044 -75.449902) (xy 67.488507 -75.454192) (xy 67.443539 -75.466918)
			(xy 67.401656 -75.48765) (xy 67.382644 -75.501246) (xy 67.361253 -75.516713) (xy 67.315036 -75.542218)
			(xy 67.265746 -75.561113) (xy 67.214323 -75.573036) (xy 67.161748 -75.577762) (xy 67.109023 -75.575199)
			(xy 67.057154 -75.565396) (xy 67.00713 -75.548541) (xy 66.959905 -75.524956) (xy 66.93789 -75.51039)
			(xy 66.918955 -75.497953) (xy 66.87766 -75.479335) (xy 66.83372 -75.468324) (xy 66.788525 -75.465267)
			(xy 66.743503 -75.470263) (xy 66.700077 -75.483152) (xy 66.65962 -75.503527) (xy 66.641218 -75.51674)
			(xy 66.618041 -75.533609) (xy 66.567625 -75.560888) (xy 66.513695 -75.580314) (xy 66.457464 -75.591449)
			(xy 66.4002 -75.594043) (xy 66.343192 -75.588036) (xy 66.287726 -75.573565) (xy 66.235051 -75.550956)
			(xy 66.186353 -75.520717) (xy 66.164206 -75.502516) (xy 66.145441 -75.487349) (xy 66.103457 -75.463591)
			(xy 66.057746 -75.448177) (xy 66.009948 -75.44166) (xy 65.961779 -75.444274) (xy 65.914967 -75.455925)
			(xy 65.871192 -75.476195) (xy 65.851278 -75.489816) (xy 65.828682 -75.505544) (xy 65.779833 -75.530935)
			(xy 65.727842 -75.549041) (xy 65.673788 -75.559488) (xy 65.618794 -75.562059) (xy 65.564002 -75.556699)
			(xy 65.510548 -75.54352) (xy 65.459544 -75.522796) (xy 65.412047 -75.494957) (xy 65.369044 -75.460581)
			(xy 65.331428 -75.420381) (xy 65.29998 -75.375193) (xy 65.275353 -75.325955) (xy 65.258057 -75.273688)
			(xy 65.248453 -75.219478) (xy 65.246739 -75.164451) (xy 63.902402 -75.164451) (xy 63.903712 -75.165913)
			(xy 63.934485 -75.212426) (xy 63.958157 -75.262923) (xy 63.974225 -75.31633) (xy 63.982345 -75.371506)
			(xy 63.982854 -75.399392) (xy 63.982345 -75.427278) (xy 63.974225 -75.482454) (xy 63.958157 -75.535861)
			(xy 63.934485 -75.586358) (xy 63.903712 -75.632871) (xy 63.866495 -75.674408) (xy 63.823627 -75.710083)
			(xy 63.776021 -75.739137) (xy 63.724692 -75.760949) (xy 63.670735 -75.775055) (xy 63.615298 -75.781155)
			(xy 63.559564 -75.779118) (xy 63.504721 -75.768988) (xy 63.451937 -75.750981) (xy 63.402337 -75.72548)
			(xy 63.356979 -75.693029) (xy 63.31683 -75.65432) (xy 63.282744 -75.610177) (xy 63.255448 -75.561542)
			(xy 63.235525 -75.509451) (xy 63.223399 -75.455014) (xy 63.219328 -75.399392) (xy 61.582501 -75.399392)
			(xy 61.580442 -75.444206) (xy 61.570156 -75.49793) (xy 61.552303 -75.549635) (xy 61.527249 -75.59826)
			(xy 61.495509 -75.64281) (xy 61.457733 -75.68237) (xy 61.436504 -75.69962) (xy 61.423863 -75.710136)
			(xy 61.404079 -75.736389) (xy 61.391659 -75.766826) (xy 61.387431 -75.799426) (xy 61.391673 -75.832025)
			(xy 61.404104 -75.862457) (xy 61.4239 -75.888701) (xy 61.436504 -75.899264) (xy 61.44133 -75.903074)
			(xy 61.458404 -75.916336) (xy 61.496124 -75.937455) (xy 61.536875 -75.951882) (xy 61.579481 -75.959201)
			(xy 61.622711 -75.959201) (xy 61.665317 -75.951882) (xy 61.706068 -75.937455) (xy 61.743788 -75.916336)
			(xy 61.760862 -75.903074) (xy 61.782541 -75.886184) (xy 61.829757 -75.858067) (xy 61.880518 -75.837015)
			(xy 61.933775 -75.823465) (xy 61.988425 -75.817696) (xy 62.043337 -75.819828) (xy 62.097375 -75.829816)
			(xy 62.149421 -75.847455) (xy 62.198397 -75.872378) (xy 62.243291 -75.904071) (xy 62.283173 -75.941877)
			(xy 62.317218 -75.985014) (xy 62.344722 -76.03259) (xy 62.365115 -76.083619) (xy 62.377975 -76.137047)
			(xy 62.383036 -76.191767) (xy 62.380194 -76.246647) (xy 62.369507 -76.300551) (xy 62.351196 -76.352364)
			(xy 62.325641 -76.401014) (xy 62.29337 -76.445494) (xy 62.255051 -76.484884) (xy 62.233556 -76.502006)
			(xy 62.220587 -76.512598) (xy 62.200287 -76.539215) (xy 62.18761 -76.570198) (xy 62.183429 -76.603411)
			(xy 62.188032 -76.636568) (xy 62.201102 -76.667387) (xy 62.221738 -76.693744) (xy 62.234826 -76.70419)
			(xy 62.240922 -76.709016) (xy 62.258133 -76.721894) (xy 62.295965 -76.742294) (xy 62.33669 -76.756036)
			(xy 62.379147 -76.762728) (xy 62.422125 -76.762179) (xy 62.464397 -76.754406) (xy 62.504759 -76.739629)
			(xy 62.542058 -76.71827) (xy 62.55893 -76.704952) (xy 62.580913 -76.687506) (xy 62.62901 -76.658588)
			(xy 62.680824 -76.637028) (xy 62.735237 -76.623291) (xy 62.791076 -76.617673) (xy 62.847135 -76.620296)
			(xy 62.902206 -76.631102) (xy 62.955099 -76.649859) (xy 63.004674 -76.676163) (xy 63.049861 -76.709444)
			(xy 63.089685 -76.748987) (xy 63.123286 -76.793936) (xy 63.149941 -76.843323) (xy 63.169073 -76.896082)
			(xy 63.18027 -76.951074) (xy 63.18329 -77.007113) (xy 63.178068 -77.062991) (xy 63.164717 -77.1175)
			(xy 63.143526 -77.169466) (xy 63.11495 -77.217766) (xy 63.097664 -77.239876) (xy 63.084361 -77.25692)
			(xy 63.063243 -77.294646) (xy 63.048818 -77.335404) (xy 63.041503 -77.378015) (xy 63.041509 -77.42125)
			(xy 63.048835 -77.46386) (xy 63.06327 -77.504613) (xy 63.084397 -77.542335) (xy 63.097664 -77.559408)
			(xy 63.114561 -77.58092) (xy 63.142592 -77.627895) (xy 63.163628 -77.678392) (xy 63.177238 -77.731375)
			(xy 63.183142 -77.785759) (xy 63.181219 -77.840428) (xy 63.17151 -77.894262) (xy 63.154213 -77.946159)
			(xy 63.129682 -77.995053) (xy 63.09842 -78.039943) (xy 63.061069 -78.07991) (xy 63.018394 -78.114133)
			(xy 62.971268 -78.141911) (xy 62.920659 -78.162675) (xy 62.867604 -78.175999) (xy 62.813189 -78.181611)
			(xy 62.758531 -78.179395) (xy 62.70475 -78.169396) (xy 62.652947 -78.15182) (xy 62.604185 -78.127027)
			(xy 62.559463 -78.095525) (xy 62.519699 -78.05796) (xy 62.485705 -78.015101) (xy 62.458181 -77.967827)
			(xy 62.437689 -77.917107) (xy 62.42465 -77.863981) (xy 62.419331 -77.809537) (xy 62.42184 -77.754891)
			(xy 62.432128 -77.701164) (xy 62.449982 -77.649457) (xy 62.475037 -77.600829) (xy 62.506779 -77.556277)
			(xy 62.544557 -77.516715) (xy 62.565788 -77.499464) (xy 62.578345 -77.488855) (xy 62.598132 -77.462624)
			(xy 62.610558 -77.432208) (xy 62.614798 -77.399626) (xy 62.610571 -77.367042) (xy 62.598157 -77.336621)
			(xy 62.578382 -77.310382) (xy 62.565788 -77.29982) (xy 62.54941 -77.286643) (xy 62.51937 -77.257236)
			(xy 62.505844 -77.241146) (xy 62.495111 -77.228839) (xy 62.468757 -77.20958) (xy 62.438375 -77.197651)
			(xy 62.405958 -77.193836) (xy 62.373636 -77.198384) (xy 62.343531 -77.210998) (xy 62.317621 -77.230848)
			(xy 62.307216 -77.243432) (xy 62.290275 -77.264398) (xy 62.251563 -77.301902) (xy 62.207957 -77.333582)
			(xy 62.160324 -77.358805) (xy 62.109613 -77.37707) (xy 62.056836 -77.388013) (xy 62.003044 -77.391415)
			(xy 61.949309 -77.387209) (xy 61.896702 -77.375478) (xy 61.846271 -77.356456) (xy 61.79902 -77.330523)
			(xy 61.755892 -77.298195) (xy 61.717746 -77.260116) (xy 61.701172 -77.23886) (xy 61.69075 -77.22591)
			(xy 61.664603 -77.205407) (xy 61.634045 -77.192359) (xy 61.601154 -77.187653) (xy 61.568163 -77.191608)
			(xy 61.537316 -77.203956) (xy 61.510708 -77.223857) (xy 61.500004 -77.236574) (xy 61.498226 -77.23886)
			(xy 61.485169 -77.255704) (xy 61.464333 -77.292879) (xy 61.449991 -77.333009) (xy 61.442546 -77.37497)
			(xy 61.442206 -77.417584) (xy 61.448981 -77.459659) (xy 61.46268 -77.500013) (xy 61.482921 -77.537515)
			(xy 61.495686 -77.554582) (xy 61.512368 -77.576613) (xy 61.539732 -77.624624) (xy 61.559883 -77.676081)
			(xy 61.5724 -77.729907) (xy 61.57702 -77.784975) (xy 61.573648 -77.840134) (xy 61.562353 -77.894229)
			(xy 61.543371 -77.946129) (xy 61.517101 -77.994748) (xy 61.484092 -78.039068) (xy 61.445034 -78.078162)
			(xy 61.400744 -78.111212) (xy 61.35215 -78.137527) (xy 61.300268 -78.156556) (xy 61.246183 -78.167901)
			(xy 61.191027 -78.171324) (xy 61.135955 -78.166754) (xy 61.082117 -78.154287) (xy 61.030642 -78.134183)
			(xy 60.982605 -78.106864) (xy 60.960508 -78.090268) (xy 60.94332 -78.077455) (xy 60.905574 -78.057136)
			(xy 60.86495 -78.043449) (xy 60.822604 -78.036784) (xy 60.779741 -78.03733) (xy 60.737578 -78.045072)
			(xy 60.697317 -78.05979) (xy 60.660101 -78.081064) (xy 60.643262 -78.094332) (xy 60.621706 -78.11131)
			(xy 60.574745 -78.139684) (xy 60.524202 -78.161037) (xy 60.471122 -78.174929) (xy 60.4166 -78.181073)
			(xy 60.361759 -78.179341) (xy 60.307733 -78.169771) (xy 60.255634 -78.15256) (xy 60.20654 -78.128062)
			(xy 60.161461 -78.096782) (xy 60.121329 -78.059368) (xy 60.086971 -78.016589) (xy 60.059096 -77.969329)
			(xy 60.03828 -77.918564) (xy 60.024951 -77.86534) (xy 60.019386 -77.810755) (xy 60.021698 -77.755936)
			(xy 60.03184 -77.702014) (xy 60.049602 -77.650101) (xy 60.074619 -77.601268) (xy 60.106374 -77.556524)
			(xy 60.144212 -77.51679) (xy 60.165488 -77.499464) (xy 60.178045 -77.488855) (xy 60.197832 -77.462624)
			(xy 60.210258 -77.432208) (xy 60.214498 -77.399626) (xy 60.210271 -77.367042) (xy 60.197857 -77.336621)
			(xy 60.178082 -77.310382) (xy 60.165488 -77.29982) (xy 60.160662 -77.29601) (xy 60.143588 -77.282748)
			(xy 60.105868 -77.261629) (xy 60.065117 -77.247202) (xy 60.022511 -77.239883) (xy 59.979281 -77.239883)
			(xy 59.936675 -77.247202) (xy 59.895924 -77.261629) (xy 59.858204 -77.282748) (xy 59.84113 -77.29601)
			(xy 59.819573 -77.312841) (xy 59.772604 -77.340856) (xy 59.722116 -77.361877) (xy 59.669143 -77.375474)
			(xy 59.614772 -77.381366) (xy 59.560117 -77.379435) (xy 59.506297 -77.369719) (xy 59.454417 -77.352418)
			(xy 59.405538 -77.327886) (xy 59.360663 -77.296626) (xy 59.320712 -77.259278) (xy 59.286503 -77.216609)
			(xy 59.258738 -77.169491) (xy 59.237985 -77.118892) (xy 59.22467 -77.065849) (xy 59.219065 -77.011447)
			(xy 57.581449 -77.011447) (xy 57.579573 -77.047408) (xy 57.568518 -77.102287) (xy 57.549562 -77.154962)
			(xy 57.523113 -77.204302) (xy 57.489737 -77.249247) (xy 57.450153 -77.288832) (xy 57.405208 -77.322208)
			(xy 57.35587 -77.348659) (xy 57.303195 -77.367616) (xy 57.248316 -77.378672) (xy 57.19241 -77.38159)
			(xy 57.136678 -77.376307) (xy 57.082317 -77.362938) (xy 57.030492 -77.341768) (xy 56.982317 -77.313253)
			(xy 56.960262 -77.29601) (xy 56.943188 -77.282748) (xy 56.905468 -77.261629) (xy 56.864717 -77.247202)
			(xy 56.822111 -77.239883) (xy 56.778881 -77.239883) (xy 56.736275 -77.247202) (xy 56.695524 -77.261629)
			(xy 56.657804 -77.282748) (xy 56.64073 -77.29601) (xy 56.617948 -77.313792) (xy 56.56808 -77.342998)
			(xy 56.514379 -77.36435) (xy 56.458071 -77.37736) (xy 56.400446 -77.381729) (xy 56.342821 -77.37736)
			(xy 56.286513 -77.36435) (xy 56.232812 -77.342998) (xy 56.182944 -77.313792) (xy 56.160162 -77.29601)
			(xy 56.143088 -77.282748) (xy 56.105368 -77.261629) (xy 56.064617 -77.247202) (xy 56.022011 -77.239883)
			(xy 55.978781 -77.239883) (xy 55.936175 -77.247202) (xy 55.895424 -77.261629) (xy 55.857704 -77.282748)
			(xy 55.84063 -77.29601) (xy 55.818542 -77.313217) (xy 55.770365 -77.341745) (xy 55.718537 -77.362925)
			(xy 55.664171 -77.376304) (xy 55.608432 -77.381593) (xy 55.552519 -77.378681) (xy 55.497632 -77.367628)
			(xy 55.44495 -77.348672) (xy 55.395603 -77.322221) (xy 55.350652 -77.288842) (xy 55.311062 -77.249252)
			(xy 55.277682 -77.204302) (xy 55.25123 -77.154955) (xy 55.232274 -77.102273) (xy 55.22122 -77.047386)
			(xy 55.218306 -76.991473) (xy 54.381455 -76.991473) (xy 54.380145 -77.037343) (xy 54.376066 -77.064108)
			(xy 54.370981 -77.090831) (xy 54.354241 -77.142587) (xy 54.330324 -77.191443) (xy 54.299712 -77.236409)
			(xy 54.263027 -77.276573) (xy 54.221011 -77.311122) (xy 54.174516 -77.339355) (xy 54.124483 -77.360702)
			(xy 54.071927 -77.37473) (xy 54.017911 -77.381154) (xy 53.963531 -77.379844) (xy 53.909887 -77.370827)
			(xy 53.883814 -77.363066) (xy 53.867069 -77.358256) (xy 53.832266 -77.35697) (xy 53.798412 -77.365144)
			(xy 53.768031 -77.382169) (xy 53.75529 -77.394054) (xy 53.743857 -77.406172) (xy 53.727192 -77.435008)
			(xy 53.718569 -77.467178) (xy 53.718577 -77.500483) (xy 53.727215 -77.532648) (xy 53.743894 -77.561477)
			(xy 53.75529 -77.573632) (xy 53.807868 -77.62621) (xy 53.807868 -78.112366) (xy 54.8132 -79.117698)
			(xy 55.180484 -79.117698) (xy 55.253128 -79.045308) (xy 55.253382 -79.045054) (xy 55.282084 -79.018384)
			(xy 55.30215 -79.001366) (xy 55.350664 -78.902306) (xy 55.343552 -78.881986) (xy 55.323005 -78.862601)
			(xy 55.28728 -78.818845) (xy 55.25839 -78.770304) (xy 55.236965 -78.718037) (xy 55.22976 -78.690724)
			(xy 55.224159 -78.666186) (xy 55.218701 -78.61615) (xy 55.219863 -78.565832) (xy 55.227625 -78.516102)
			(xy 55.234332 -78.491842) (xy 55.242849 -78.464782) (xy 55.266765 -78.413342) (xy 55.298035 -78.366011)
			(xy 55.335969 -78.323832) (xy 55.379729 -78.287734) (xy 55.428352 -78.258513) (xy 55.480766 -78.236814)
			(xy 55.535815 -78.223115) (xy 55.592285 -78.217718) (xy 55.648933 -78.220742) (xy 55.704508 -78.23212)
			(xy 55.757785 -78.251601) (xy 55.807591 -78.278757) (xy 55.852828 -78.312987) (xy 55.892497 -78.353538)
			(xy 55.909464 -78.376272) (xy 55.931375 -78.384112) (xy 55.97713 -78.392581) (xy 56.023662 -78.392581)
			(xy 56.069417 -78.384112) (xy 56.091328 -78.376272) (xy 56.107983 -78.354089) (xy 56.146653 -78.314322)
			(xy 56.190674 -78.280574) (xy 56.23912 -78.253558) (xy 56.290967 -78.233843) (xy 56.345123 -78.221845)
			(xy 56.400446 -78.217818) (xy 56.455769 -78.221845) (xy 56.509925 -78.233843) (xy 56.561772 -78.253558)
			(xy 56.610218 -78.280574) (xy 56.654239 -78.314322) (xy 56.692909 -78.354089) (xy 56.709564 -78.376272)
			(xy 56.731475 -78.384112) (xy 56.77723 -78.392581) (xy 56.823762 -78.392581) (xy 56.869517 -78.384112)
			(xy 56.891428 -78.376272) (xy 56.907886 -78.354327) (xy 56.946067 -78.314943) (xy 56.989496 -78.281434)
			(xy 57.037277 -78.254492) (xy 57.088424 -78.234672) (xy 57.141884 -78.222383) (xy 57.196552 -78.217879)
			(xy 57.251301 -78.221252) (xy 57.305003 -78.232433) (xy 57.35655 -78.251191) (xy 57.404877 -78.27714)
			(xy 57.448989 -78.309744) (xy 57.487976 -78.34833) (xy 57.521034 -78.392104) (xy 57.54748 -78.440161)
			(xy 57.566769 -78.491511) (xy 57.578504 -78.545095) (xy 57.582441 -78.599792) (xy 58.418728 -78.599792)
			(xy 58.422799 -78.54417) (xy 58.434925 -78.489733) (xy 58.454848 -78.437642) (xy 58.482144 -78.389007)
			(xy 58.51623 -78.344864) (xy 58.556379 -78.306155) (xy 58.601737 -78.273704) (xy 58.651337 -78.248203)
			(xy 58.704121 -78.230196) (xy 58.758964 -78.220066) (xy 58.814698 -78.218029) (xy 58.870135 -78.224129)
			(xy 58.924092 -78.238235) (xy 58.975421 -78.260047) (xy 59.023027 -78.289101) (xy 59.065895 -78.324776)
			(xy 59.103112 -78.366313) (xy 59.133885 -78.412826) (xy 59.157557 -78.463323) (xy 59.173625 -78.51673)
			(xy 59.181745 -78.571906) (xy 59.181971 -78.584298) (xy 61.623954 -78.584298) (xy 61.628025 -78.528676)
			(xy 61.640151 -78.474239) (xy 61.660074 -78.422148) (xy 61.68737 -78.373513) (xy 61.721456 -78.32937)
			(xy 61.761605 -78.290661) (xy 61.806963 -78.25821) (xy 61.856563 -78.232709) (xy 61.909347 -78.214702)
			(xy 61.96419 -78.204572) (xy 62.019924 -78.202535) (xy 62.075361 -78.208635) (xy 62.129318 -78.222741)
			(xy 62.180647 -78.244553) (xy 62.228253 -78.273607) (xy 62.271121 -78.309282) (xy 62.308338 -78.350819)
			(xy 62.339111 -78.397332) (xy 62.362783 -78.447829) (xy 62.378851 -78.501236) (xy 62.386971 -78.556412)
			(xy 62.38748 -78.584298) (xy 62.386971 -78.612184) (xy 62.378851 -78.66736) (xy 62.362783 -78.720767)
			(xy 62.339111 -78.771264) (xy 62.308338 -78.817777) (xy 62.271121 -78.859314) (xy 62.228253 -78.894989)
			(xy 62.180647 -78.924043) (xy 62.129318 -78.945855) (xy 62.075361 -78.959961) (xy 62.019924 -78.966061)
			(xy 61.96419 -78.964024) (xy 61.909347 -78.953894) (xy 61.856563 -78.935887) (xy 61.806963 -78.910386)
			(xy 61.761605 -78.877935) (xy 61.721456 -78.839226) (xy 61.68737 -78.795083) (xy 61.660074 -78.746448)
			(xy 61.640151 -78.694357) (xy 61.628025 -78.63992) (xy 61.623954 -78.584298) (xy 59.181971 -78.584298)
			(xy 59.182254 -78.599792) (xy 59.181745 -78.627678) (xy 59.173625 -78.682854) (xy 59.157557 -78.736261)
			(xy 59.133885 -78.786758) (xy 59.103112 -78.833271) (xy 59.065895 -78.874808) (xy 59.023027 -78.910483)
			(xy 58.975421 -78.939537) (xy 58.924092 -78.961349) (xy 58.870135 -78.975455) (xy 58.814698 -78.981555)
			(xy 58.758964 -78.979518) (xy 58.704121 -78.969388) (xy 58.651337 -78.951381) (xy 58.601737 -78.92588)
			(xy 58.556379 -78.893429) (xy 58.51623 -78.85472) (xy 58.482144 -78.810577) (xy 58.454848 -78.761942)
			(xy 58.434925 -78.709851) (xy 58.422799 -78.655414) (xy 58.418728 -78.599792) (xy 57.582441 -78.599792)
			(xy 57.582442 -78.599806) (xy 57.578502 -78.654518) (xy 57.566765 -78.708101) (xy 57.547474 -78.759451)
			(xy 57.521027 -78.807507) (xy 57.487968 -78.851279) (xy 57.44898 -78.889865) (xy 57.404866 -78.922467)
			(xy 57.356538 -78.948414) (xy 57.304991 -78.967171) (xy 57.251289 -78.97835) (xy 57.196539 -78.981721)
			(xy 57.141871 -78.977215) (xy 57.088412 -78.964924) (xy 57.037265 -78.945103) (xy 56.989485 -78.918159)
			(xy 56.946058 -78.884648) (xy 56.907878 -78.845263) (xy 56.891428 -78.823312) (xy 56.869517 -78.815472)
			(xy 56.823762 -78.807003) (xy 56.77723 -78.807003) (xy 56.731475 -78.815472) (xy 56.709564 -78.823312)
			(xy 56.700923 -78.835103) (xy 56.682105 -78.857479) (xy 56.671972 -78.868016) (xy 56.654954 -78.884018)
			(xy 56.608726 -78.925166) (xy 56.602376 -79.02956) (xy 56.635142 -79.097886) (xy 56.654446 -79.114904)
			(xy 56.673147 -79.132156) (xy 56.706273 -79.170775) (xy 56.733977 -79.213451) (xy 56.755769 -79.259428)
			(xy 56.771261 -79.307892) (xy 56.78018 -79.357984) (xy 56.7817 -79.383382) (xy 56.783104 -79.404899)
			(xy 56.792246 -79.447036) (xy 56.808369 -79.487025) (xy 56.831011 -79.523718) (xy 56.859523 -79.556062)
			(xy 56.893085 -79.583129) (xy 56.930735 -79.604143) (xy 56.971391 -79.618499) (xy 57.013888 -79.625786)
			(xy 57.035446 -79.626206) (xy 57.6707 -79.626206) (xy 58.101992 -80.057498) (xy 62.43701 -80.057498)
			(xy 62.457838 -80.046068) (xy 62.468664 -80.021601) (xy 62.496168 -79.975708) (xy 62.529816 -79.934109)
			(xy 62.568946 -79.897621) (xy 62.612792 -79.866959) (xy 62.660493 -79.842725) (xy 62.711112 -79.825396)
			(xy 62.763656 -79.81531) (xy 62.817095 -79.812667) (xy 62.870378 -79.817517) (xy 62.92246 -79.829766)
			(xy 62.94755 -79.839058) (xy 62.968625 -79.834149) (xy 63.008826 -79.818142) (xy 63.045735 -79.795559)
			(xy 63.078285 -79.76705) (xy 63.105537 -79.73344) (xy 63.126704 -79.695701) (xy 63.141172 -79.654921)
			(xy 63.148525 -79.612281) (xy 63.148972 -79.590646) (xy 63.148972 -78.820518) (xy 63.70066 -78.26883)
			(xy 63.70066 -77.493622) (xy 64.546734 -76.647548) (xy 64.562565 -76.631032) (xy 64.588602 -76.59342)
			(xy 64.607489 -76.551755) (xy 64.618614 -76.507384) (xy 64.62162 -76.461737) (xy 64.616409 -76.41629)
			(xy 64.603149 -76.372509) (xy 64.582268 -76.331807) (xy 64.55444 -76.295499) (xy 64.520565 -76.264757)
			(xy 64.481735 -76.240573) (xy 64.460628 -76.23175) (xy 64.435234 -76.221195) (xy 64.387524 -76.193847)
			(xy 64.344235 -76.159933) (xy 64.306262 -76.120155) (xy 64.274393 -76.075339) (xy 64.249288 -76.026412)
			(xy 64.231467 -75.974387) (xy 64.221298 -75.920343) (xy 64.218994 -75.865399) (xy 64.224601 -75.810693)
			(xy 64.238003 -75.757359) (xy 64.258922 -75.706501) (xy 64.286926 -75.659173) (xy 64.321434 -75.616356)
			(xy 64.361731 -75.578935) (xy 64.406983 -75.547688) (xy 64.456252 -75.52326) (xy 64.482218 -75.5142)
			(xy 64.508935 -75.505979) (xy 64.56403 -75.496545) (xy 64.619913 -75.495251) (xy 64.675386 -75.502122)
			(xy 64.729264 -75.517013) (xy 64.780393 -75.539605) (xy 64.827678 -75.569414) (xy 64.87011 -75.605802)
			(xy 64.906778 -75.647992) (xy 64.936899 -75.695079) (xy 64.947053 -75.717654) (xy 89.681302 -75.717654)
			(xy 89.685373 -75.662032) (xy 89.697499 -75.607595) (xy 89.717422 -75.555504) (xy 89.744718 -75.506869)
			(xy 89.778804 -75.462726) (xy 89.818953 -75.424017) (xy 89.864311 -75.391566) (xy 89.913911 -75.366065)
			(xy 89.966695 -75.348058) (xy 90.021538 -75.337928) (xy 90.077272 -75.335891) (xy 90.132709 -75.341991)
			(xy 90.186666 -75.356097) (xy 90.237995 -75.377909) (xy 90.285601 -75.406963) (xy 90.328469 -75.442638)
			(xy 90.365686 -75.484175) (xy 90.396459 -75.530688) (xy 90.420131 -75.581185) (xy 90.436199 -75.634592)
			(xy 90.444319 -75.689768) (xy 90.444828 -75.717654) (xy 90.444319 -75.74554) (xy 90.436199 -75.800716)
			(xy 90.420131 -75.854123) (xy 90.396459 -75.90462) (xy 90.365686 -75.951133) (xy 90.328469 -75.99267)
			(xy 90.285601 -76.028345) (xy 90.237995 -76.057399) (xy 90.186666 -76.079211) (xy 90.132709 -76.093317)
			(xy 90.077272 -76.099417) (xy 90.021538 -76.09738) (xy 89.966695 -76.08725) (xy 89.913911 -76.069243)
			(xy 89.864311 -76.043742) (xy 89.818953 -76.011291) (xy 89.778804 -75.972582) (xy 89.744718 -75.928439)
			(xy 89.717422 -75.879804) (xy 89.697499 -75.827713) (xy 89.685373 -75.773276) (xy 89.681302 -75.717654)
			(xy 64.947053 -75.717654) (xy 64.959829 -75.746057) (xy 64.975076 -75.799835) (xy 64.982315 -75.855262)
			(xy 64.98139 -75.911152) (xy 64.972321 -75.966309) (xy 64.955302 -76.019553) (xy 64.930698 -76.069744)
			(xy 64.915288 -76.093066) (xy 64.903202 -76.112396) (xy 64.885377 -76.154349) (xy 64.875322 -76.198809)
			(xy 64.873358 -76.24435) (xy 64.879549 -76.28951) (xy 64.893696 -76.332842) (xy 64.915346 -76.372955)
			(xy 64.943804 -76.408564) (xy 64.978157 -76.438525) (xy 65.017303 -76.461877) (xy 65.059988 -76.477873)
			(xy 65.104841 -76.485998) (xy 65.127632 -76.486512) (xy 66.164206 -76.486512) (xy 66.181008 -76.485996)
			(xy 66.213445 -76.477215) (xy 66.242462 -76.460265) (xy 66.25463 -76.448666) (xy 66.274281 -76.429404)
			(xy 66.318127 -76.396158) (xy 66.366294 -76.369556) (xy 66.417784 -76.35015) (xy 66.471528 -76.338343)
			(xy 66.52641 -76.33438) (xy 66.581292 -76.338343) (xy 66.635036 -76.35015) (xy 66.686526 -76.369556)
			(xy 66.734693 -76.396158) (xy 66.778539 -76.429404) (xy 66.79819 -76.448666) (xy 66.810354 -76.460269)
			(xy 66.839375 -76.477213) (xy 66.871812 -76.486) (xy 66.888614 -76.486512) (xy 67.345814 -76.486512)
			(xy 67.415156 -76.41717) (xy 67.620896 -76.62291) (xy 67.632089 -76.633473) (xy 67.658396 -76.649424)
			(xy 67.687754 -76.658624) (xy 67.71846 -76.660539) (xy 67.733672 -76.658216) (xy 67.748405 -76.65561)
			(xy 67.778157 -76.65243) (xy 67.793108 -76.651866) (xy 67.806316 -76.651866) (xy 67.821054 -76.652144)
			(xy 67.850424 -76.654684) (xy 67.86499 -76.656946) (xy 67.871848 -76.658216) (xy 67.903855 -76.66479)
			(xy 67.965157 -76.687392) (xy 67.993768 -76.703174) (xy 68.075302 -76.688442) (xy 68.801742 -75.961748)
			(xy 83.81492 -75.961748) (xy 83.864704 -75.939142) (xy 83.882738 -75.918568) (xy 83.899057 -75.900529)
			(xy 83.935515 -75.868324) (xy 83.975778 -75.841026) (xy 84.01919 -75.819078) (xy 84.041996 -75.810618)
			(xy 84.069077 -75.801553) (xy 84.125143 -75.790703) (xy 84.182201 -75.788331) (xy 84.238974 -75.794489)
			(xy 84.294196 -75.809041) (xy 84.346632 -75.83166) (xy 84.395111 -75.861842) (xy 84.43855 -75.898912)
			(xy 84.475979 -75.942043) (xy 84.506562 -75.99027) (xy 84.529614 -76.042517) (xy 84.544622 -76.097617)
			(xy 84.551251 -76.154337) (xy 84.549351 -76.211412) (xy 84.538966 -76.267567) (xy 84.530184 -76.294742)
			(xy 84.526374 -76.305156) (xy 84.5198 -76.326066) (xy 84.513113 -76.369383) (xy 84.513959 -76.413204)
			(xy 84.522313 -76.45623) (xy 84.537926 -76.497184) (xy 84.560335 -76.534851) (xy 84.588877 -76.568114)
			(xy 84.622702 -76.595986) (xy 84.660809 -76.617639) (xy 84.702067 -76.632432) (xy 84.745251 -76.639925)
			(xy 84.767166 -76.640436) (xy 87.44712 -76.640436) (xy 87.778336 -76.971652) (xy 87.883746 -76.971652)
			(xy 87.930228 -76.952602) (xy 87.95385 -76.928726) (xy 87.964264 -76.918312) (xy 87.99576 -76.886816)
			(xy 88.808814 -76.886816) (xy 88.869012 -76.844144) (xy 88.881438 -76.821076) (xy 88.897574 -76.771234)
			(xy 88.903188 -76.719146) (xy 88.90127 -76.693014) (xy 88.899071 -76.665412) (xy 88.901711 -76.610105)
			(xy 88.912318 -76.555761) (xy 88.93067 -76.503521) (xy 88.956379 -76.454482) (xy 88.988907 -76.409674)
			(xy 89.027571 -76.370039) (xy 89.071557 -76.336409) (xy 89.119943 -76.30949) (xy 89.171712 -76.289848)
			(xy 89.225776 -76.277895) (xy 89.281 -76.273883) (xy 89.336224 -76.277895) (xy 89.390288 -76.289848)
			(xy 89.442057 -76.30949) (xy 89.490443 -76.336409) (xy 89.534429 -76.370039) (xy 89.573093 -76.409674)
			(xy 89.605621 -76.454482) (xy 89.63133 -76.503521) (xy 89.649682 -76.555761) (xy 89.660289 -76.610105)
			(xy 89.662929 -76.665412) (xy 89.66073 -76.693014) (xy 89.658779 -76.719147) (xy 89.664375 -76.771244)
			(xy 89.680536 -76.821085) (xy 89.692988 -76.844144) (xy 89.753186 -76.886816) (xy 92.225114 -76.886816)
			(xy 92.699078 -76.413106) (xy 92.8497 -76.262484) (xy 92.854526 -76.257658) (xy 92.985082 -76.127102)
			(xy 92.985336 -76.126848) (xy 93.087952 -76.024232) (xy 93.088206 -76.023978) (xy 93.296232 -75.815952)
			(xy 94.04985 -75.815952) (xy 94.215204 -75.981306) (xy 94.346522 -76.11237) (xy 94.734126 -76.499974)
			(xy 105.972354 -76.499974) (xy 105.976425 -76.444352) (xy 105.988551 -76.389915) (xy 106.008474 -76.337824)
			(xy 106.03577 -76.289189) (xy 106.069856 -76.245046) (xy 106.110005 -76.206337) (xy 106.155363 -76.173886)
			(xy 106.204963 -76.148385) (xy 106.257747 -76.130378) (xy 106.31259 -76.120248) (xy 106.368324 -76.118211)
			(xy 106.423761 -76.124311) (xy 106.477718 -76.138417) (xy 106.529047 -76.160229) (xy 106.576653 -76.189283)
			(xy 106.619521 -76.224958) (xy 106.656738 -76.266495) (xy 106.687511 -76.313008) (xy 106.711183 -76.363505)
			(xy 106.724043 -76.406248) (xy 111.723676 -76.406248) (xy 111.727747 -76.350626) (xy 111.739873 -76.296189)
			(xy 111.759796 -76.244098) (xy 111.787092 -76.195463) (xy 111.821178 -76.15132) (xy 111.861327 -76.112611)
			(xy 111.906685 -76.08016) (xy 111.956285 -76.054659) (xy 112.009069 -76.036652) (xy 112.063912 -76.026522)
			(xy 112.119646 -76.024485) (xy 112.175083 -76.030585) (xy 112.22904 -76.044691) (xy 112.280369 -76.066503)
			(xy 112.327975 -76.095557) (xy 112.370843 -76.131232) (xy 112.40806 -76.172769) (xy 112.438833 -76.219282)
			(xy 112.445154 -76.232766) (xy 114.372642 -76.232766) (xy 114.376713 -76.177144) (xy 114.388839 -76.122707)
			(xy 114.408762 -76.070616) (xy 114.436058 -76.021981) (xy 114.470144 -75.977838) (xy 114.510293 -75.939129)
			(xy 114.555651 -75.906678) (xy 114.605251 -75.881177) (xy 114.658035 -75.86317) (xy 114.712878 -75.85304)
			(xy 114.768612 -75.851003) (xy 114.824049 -75.857103) (xy 114.878006 -75.871209) (xy 114.929335 -75.893021)
			(xy 114.976941 -75.922075) (xy 115.019809 -75.95775) (xy 115.057026 -75.999287) (xy 115.087799 -76.0458)
			(xy 115.111471 -76.096297) (xy 115.127539 -76.149704) (xy 115.135659 -76.20488) (xy 115.136168 -76.232766)
			(xy 115.135659 -76.260652) (xy 115.127539 -76.315828) (xy 115.111471 -76.369235) (xy 115.087799 -76.419732)
			(xy 115.057026 -76.466245) (xy 115.019809 -76.507782) (xy 114.976941 -76.543457) (xy 114.929335 -76.572511)
			(xy 114.878006 -76.594323) (xy 114.824049 -76.608429) (xy 114.768612 -76.614529) (xy 114.712878 -76.612492)
			(xy 114.658035 -76.602362) (xy 114.605251 -76.584355) (xy 114.555651 -76.558854) (xy 114.510293 -76.526403)
			(xy 114.470144 -76.487694) (xy 114.436058 -76.443551) (xy 114.408762 -76.394916) (xy 114.388839 -76.342825)
			(xy 114.376713 -76.288388) (xy 114.372642 -76.232766) (xy 112.445154 -76.232766) (xy 112.462505 -76.269779)
			(xy 112.478573 -76.323186) (xy 112.486693 -76.378362) (xy 112.487202 -76.406248) (xy 112.486693 -76.434134)
			(xy 112.478573 -76.48931) (xy 112.462505 -76.542717) (xy 112.438833 -76.593214) (xy 112.40806 -76.639727)
			(xy 112.370843 -76.681264) (xy 112.327975 -76.716939) (xy 112.280369 -76.745993) (xy 112.22904 -76.767805)
			(xy 112.175083 -76.781911) (xy 112.119646 -76.788011) (xy 112.063912 -76.785974) (xy 112.009069 -76.775844)
			(xy 111.956285 -76.757837) (xy 111.906685 -76.732336) (xy 111.861327 -76.699885) (xy 111.821178 -76.661176)
			(xy 111.787092 -76.617033) (xy 111.759796 -76.568398) (xy 111.739873 -76.516307) (xy 111.727747 -76.46187)
			(xy 111.723676 -76.406248) (xy 106.724043 -76.406248) (xy 106.727251 -76.416912) (xy 106.735371 -76.472088)
			(xy 106.73588 -76.499974) (xy 106.735371 -76.52786) (xy 106.727251 -76.583036) (xy 106.711183 -76.636443)
			(xy 106.687511 -76.68694) (xy 106.656738 -76.733453) (xy 106.619521 -76.77499) (xy 106.576653 -76.810665)
			(xy 106.529047 -76.839719) (xy 106.477718 -76.861531) (xy 106.423761 -76.875637) (xy 106.368324 -76.881737)
			(xy 106.31259 -76.8797) (xy 106.257747 -76.86957) (xy 106.204963 -76.851563) (xy 106.155363 -76.826062)
			(xy 106.110005 -76.793611) (xy 106.069856 -76.754902) (xy 106.03577 -76.710759) (xy 106.008474 -76.662124)
			(xy 105.988551 -76.610033) (xy 105.976425 -76.555596) (xy 105.972354 -76.499974) (xy 94.734126 -76.499974)
			(xy 94.935548 -76.701396) (xy 94.935548 -78.3336) (xy 94.653608 -78.615286) (xy 94.119446 -79.149702)
			(xy 94.007828 -79.26132) (xy 109.258606 -79.26132) (xy 109.258606 -79.17118) (xy 109.266686 -79.081404)
			(xy 109.282781 -78.992713) (xy 109.306761 -78.905821) (xy 109.338434 -78.82143) (xy 109.377544 -78.740217)
			(xy 109.423776 -78.662837) (xy 109.476759 -78.589912) (xy 109.536065 -78.522031) (xy 109.601218 -78.459739)
			(xy 109.671692 -78.403537) (xy 109.74692 -78.35388) (xy 109.826296 -78.311166) (xy 109.909182 -78.275738)
			(xy 109.99491 -78.247884) (xy 110.082789 -78.227826) (xy 110.172113 -78.215726) (xy 110.262162 -78.211682)
			(xy 110.352211 -78.215726) (xy 110.441535 -78.227826) (xy 110.529414 -78.247884) (xy 110.615142 -78.275738)
			(xy 110.698028 -78.311166) (xy 110.777404 -78.35388) (xy 110.852632 -78.403537) (xy 110.923106 -78.459739)
			(xy 110.988259 -78.522031) (xy 111.047565 -78.589912) (xy 111.100548 -78.662837) (xy 111.14678 -78.740217)
			(xy 111.18589 -78.82143) (xy 111.217563 -78.905821) (xy 111.241543 -78.992713) (xy 111.253438 -79.058262)
			(xy 117.679722 -79.058262) (xy 117.683793 -79.00264) (xy 117.695919 -78.948203) (xy 117.715842 -78.896112)
			(xy 117.743138 -78.847477) (xy 117.777224 -78.803334) (xy 117.817373 -78.764625) (xy 117.862731 -78.732174)
			(xy 117.912331 -78.706673) (xy 117.965115 -78.688666) (xy 118.019958 -78.678536) (xy 118.075692 -78.676499)
			(xy 118.131129 -78.682599) (xy 118.185086 -78.696705) (xy 118.236415 -78.718517) (xy 118.284021 -78.747571)
			(xy 118.326889 -78.783246) (xy 118.364106 -78.824783) (xy 118.394879 -78.871296) (xy 118.418551 -78.921793)
			(xy 118.418802 -78.922626) (xy 129.429762 -78.922626) (xy 129.433833 -78.867004) (xy 129.445959 -78.812567)
			(xy 129.465882 -78.760476) (xy 129.493178 -78.711841) (xy 129.527264 -78.667698) (xy 129.567413 -78.628989)
			(xy 129.612771 -78.596538) (xy 129.662371 -78.571037) (xy 129.715155 -78.55303) (xy 129.769998 -78.5429)
			(xy 129.825732 -78.540863) (xy 129.881169 -78.546963) (xy 129.935126 -78.561069) (xy 129.986455 -78.582881)
			(xy 130.034061 -78.611935) (xy 130.076929 -78.64761) (xy 130.114146 -78.689147) (xy 130.144919 -78.73566)
			(xy 130.162314 -78.772766) (xy 131.339842 -78.772766) (xy 131.343913 -78.717144) (xy 131.356039 -78.662707)
			(xy 131.375962 -78.610616) (xy 131.403258 -78.561981) (xy 131.437344 -78.517838) (xy 131.477493 -78.479129)
			(xy 131.522851 -78.446678) (xy 131.572451 -78.421177) (xy 131.625235 -78.40317) (xy 131.680078 -78.39304)
			(xy 131.735812 -78.391003) (xy 131.791249 -78.397103) (xy 131.845206 -78.411209) (xy 131.896535 -78.433021)
			(xy 131.944141 -78.462075) (xy 131.987009 -78.49775) (xy 132.024226 -78.539287) (xy 132.054999 -78.5858)
			(xy 132.078671 -78.636297) (xy 132.094739 -78.689704) (xy 132.102859 -78.74488) (xy 132.103368 -78.772766)
			(xy 132.102859 -78.800652) (xy 132.094739 -78.855828) (xy 132.078671 -78.909235) (xy 132.054999 -78.959732)
			(xy 132.04241 -78.97876) (xy 133.285482 -78.97876) (xy 133.289553 -78.923138) (xy 133.301679 -78.868701)
			(xy 133.321602 -78.81661) (xy 133.348898 -78.767975) (xy 133.382984 -78.723832) (xy 133.423133 -78.685123)
			(xy 133.468491 -78.652672) (xy 133.518091 -78.627171) (xy 133.570875 -78.609164) (xy 133.625718 -78.599034)
			(xy 133.681452 -78.596997) (xy 133.736889 -78.603097) (xy 133.790846 -78.617203) (xy 133.842175 -78.639015)
			(xy 133.889781 -78.668069) (xy 133.932649 -78.703744) (xy 133.969866 -78.745281) (xy 134.000639 -78.791794)
			(xy 134.024311 -78.842291) (xy 134.040379 -78.895698) (xy 134.048499 -78.950874) (xy 134.049008 -78.97876)
			(xy 134.048499 -79.006646) (xy 134.040379 -79.061822) (xy 134.024311 -79.115229) (xy 134.000639 -79.165726)
			(xy 133.969866 -79.212239) (xy 133.932649 -79.253776) (xy 133.889781 -79.289451) (xy 133.842175 -79.318505)
			(xy 133.790846 -79.340317) (xy 133.736889 -79.354423) (xy 133.681452 -79.360523) (xy 133.625718 -79.358486)
			(xy 133.570875 -79.348356) (xy 133.518091 -79.330349) (xy 133.468491 -79.304848) (xy 133.423133 -79.272397)
			(xy 133.382984 -79.233688) (xy 133.348898 -79.189545) (xy 133.321602 -79.14091) (xy 133.301679 -79.088819)
			(xy 133.289553 -79.034382) (xy 133.285482 -78.97876) (xy 132.04241 -78.97876) (xy 132.024226 -79.006245)
			(xy 131.987009 -79.047782) (xy 131.944141 -79.083457) (xy 131.896535 -79.112511) (xy 131.845206 -79.134323)
			(xy 131.791249 -79.148429) (xy 131.735812 -79.154529) (xy 131.680078 -79.152492) (xy 131.625235 -79.142362)
			(xy 131.572451 -79.124355) (xy 131.522851 -79.098854) (xy 131.477493 -79.066403) (xy 131.437344 -79.027694)
			(xy 131.403258 -78.983551) (xy 131.375962 -78.934916) (xy 131.356039 -78.882825) (xy 131.343913 -78.828388)
			(xy 131.339842 -78.772766) (xy 130.162314 -78.772766) (xy 130.168591 -78.786157) (xy 130.184659 -78.839564)
			(xy 130.192779 -78.89474) (xy 130.193288 -78.922626) (xy 130.192779 -78.950512) (xy 130.184659 -79.005688)
			(xy 130.168591 -79.059095) (xy 130.144919 -79.109592) (xy 130.114146 -79.156105) (xy 130.076929 -79.197642)
			(xy 130.034061 -79.233317) (xy 129.986455 -79.262371) (xy 129.935126 -79.284183) (xy 129.881169 -79.298289)
			(xy 129.825732 -79.304389) (xy 129.769998 -79.302352) (xy 129.715155 -79.292222) (xy 129.662371 -79.274215)
			(xy 129.612771 -79.248714) (xy 129.567413 -79.216263) (xy 129.527264 -79.177554) (xy 129.493178 -79.133411)
			(xy 129.465882 -79.084776) (xy 129.445959 -79.032685) (xy 129.433833 -78.978248) (xy 129.429762 -78.922626)
			(xy 118.418802 -78.922626) (xy 118.434619 -78.9752) (xy 118.442739 -79.030376) (xy 118.443248 -79.058262)
			(xy 118.442739 -79.086148) (xy 118.434619 -79.141324) (xy 118.418551 -79.194731) (xy 118.394879 -79.245228)
			(xy 118.364106 -79.291741) (xy 118.326889 -79.333278) (xy 118.284021 -79.368953) (xy 118.236415 -79.398007)
			(xy 118.185086 -79.419819) (xy 118.131129 -79.433925) (xy 118.075692 -79.440025) (xy 118.019958 -79.437988)
			(xy 117.965115 -79.427858) (xy 117.912331 -79.409851) (xy 117.862731 -79.38435) (xy 117.817373 -79.351899)
			(xy 117.777224 -79.31319) (xy 117.743138 -79.269047) (xy 117.715842 -79.220412) (xy 117.695919 -79.168321)
			(xy 117.683793 -79.113884) (xy 117.679722 -79.058262) (xy 111.253438 -79.058262) (xy 111.257638 -79.081404)
			(xy 111.265718 -79.17118) (xy 111.266224 -79.21625) (xy 111.265718 -79.26132) (xy 111.257638 -79.351096)
			(xy 111.241543 -79.439787) (xy 111.217563 -79.526679) (xy 111.18589 -79.61107) (xy 111.14678 -79.692283)
			(xy 111.100548 -79.769663) (xy 111.047565 -79.842588) (xy 110.988259 -79.910469) (xy 110.923106 -79.972761)
			(xy 110.852632 -80.028963) (xy 110.777404 -80.07862) (xy 110.698028 -80.121334) (xy 110.615142 -80.156762)
			(xy 110.529414 -80.184616) (xy 110.441535 -80.204674) (xy 110.352211 -80.216774) (xy 110.262162 -80.220818)
			(xy 110.172113 -80.216774) (xy 110.082789 -80.204674) (xy 109.99491 -80.184616) (xy 109.909182 -80.156762)
			(xy 109.826296 -80.121334) (xy 109.74692 -80.07862) (xy 109.671692 -80.028963) (xy 109.601218 -79.972761)
			(xy 109.536065 -79.910469) (xy 109.476759 -79.842588) (xy 109.423776 -79.769663) (xy 109.377544 -79.692283)
			(xy 109.338434 -79.61107) (xy 109.306761 -79.526679) (xy 109.282781 -79.439787) (xy 109.266686 -79.351096)
			(xy 109.258606 -79.26132) (xy 94.007828 -79.26132) (xy 93.97746 -79.291688) (xy 93.948504 -79.36103)
			(xy 93.664786 -79.644748) (xy 93.64885 -79.661397) (xy 93.622677 -79.699326) (xy 93.603768 -79.741351)
			(xy 93.592743 -79.786095) (xy 93.589962 -79.832094) (xy 93.595516 -79.877841) (xy 93.609224 -79.921838)
			(xy 93.630636 -79.962644) (xy 93.659052 -79.998922) (xy 93.693541 -80.029486) (xy 93.732973 -80.053334)
			(xy 93.776058 -80.069685) (xy 93.798644 -80.074262) (xy 93.826075 -80.079328) (xy 93.879189 -80.096371)
			(xy 93.929255 -80.120966) (xy 93.975207 -80.152589) (xy 94.016065 -80.190565) (xy 94.050958 -80.234085)
			(xy 94.079143 -80.282222) (xy 94.100018 -80.333949) (xy 94.11314 -80.388165) (xy 94.118229 -80.443713)
			(xy 94.115175 -80.499411) (xy 94.113735 -80.50648) (xy 103.451446 -80.50648) (xy 103.458931 -80.451581)
			(xy 103.474279 -80.398343) (xy 103.497166 -80.347884) (xy 103.527112 -80.301268) (xy 103.563487 -80.259473)
			(xy 103.605524 -80.22338) (xy 103.652341 -80.193748) (xy 103.702952 -80.1712) (xy 103.756292 -80.15621)
			(xy 103.81124 -80.149094) (xy 103.866639 -80.150001) (xy 103.921324 -80.158913) (xy 103.974145 -80.175641)
			(xy 103.999284 -80.187292) (xy 104.015073 -80.194282) (xy 104.04903 -80.200453) (xy 104.083397 -80.197275)
			(xy 104.115646 -80.18498) (xy 104.143406 -80.164473) (xy 104.154478 -80.151224) (xy 104.171988 -80.129753)
			(xy 104.212089 -80.091528) (xy 104.257297 -80.059506) (xy 104.306662 -80.03436) (xy 104.359146 -80.016619)
			(xy 104.413643 -80.006657) (xy 104.469009 -80.004683) (xy 104.524077 -80.010739) (xy 104.577691 -80.024697)
			(xy 104.628721 -80.046263) (xy 104.676095 -80.074985) (xy 104.718816 -80.110257) (xy 104.755986 -80.151338)
			(xy 104.786822 -80.197364) (xy 104.810676 -80.247366) (xy 104.814092 -80.258412) (xy 131.002022 -80.258412)
			(xy 131.006093 -80.20279) (xy 131.018219 -80.148353) (xy 131.038142 -80.096262) (xy 131.065438 -80.047627)
			(xy 131.099524 -80.003484) (xy 131.139673 -79.964775) (xy 131.185031 -79.932324) (xy 131.234631 -79.906823)
			(xy 131.287415 -79.888816) (xy 131.342258 -79.878686) (xy 131.397992 -79.876649) (xy 131.453429 -79.882749)
			(xy 131.507386 -79.896855) (xy 131.558715 -79.918667) (xy 131.606321 -79.947721) (xy 131.649189 -79.983396)
			(xy 131.686406 -80.024933) (xy 131.717179 -80.071446) (xy 131.740851 -80.121943) (xy 131.743471 -80.13065)
			(xy 132.312662 -80.13065) (xy 132.316733 -80.075028) (xy 132.328859 -80.020591) (xy 132.348782 -79.9685)
			(xy 132.376078 -79.919865) (xy 132.410164 -79.875722) (xy 132.450313 -79.837013) (xy 132.495671 -79.804562)
			(xy 132.545271 -79.779061) (xy 132.598055 -79.761054) (xy 132.652898 -79.750924) (xy 132.708632 -79.748887)
			(xy 132.764069 -79.754987) (xy 132.818026 -79.769093) (xy 132.869355 -79.790905) (xy 132.916961 -79.819959)
			(xy 132.959829 -79.855634) (xy 132.997046 -79.897171) (xy 133.027819 -79.943684) (xy 133.051491 -79.994181)
			(xy 133.067559 -80.047588) (xy 133.075679 -80.102764) (xy 133.076188 -80.13065) (xy 133.075679 -80.158536)
			(xy 133.067559 -80.213712) (xy 133.051491 -80.267119) (xy 133.027819 -80.317616) (xy 132.997046 -80.364129)
			(xy 132.959829 -80.405666) (xy 132.916961 -80.441341) (xy 132.869355 -80.470395) (xy 132.818026 -80.492207)
			(xy 132.764069 -80.506313) (xy 132.708632 -80.512413) (xy 132.652898 -80.510376) (xy 132.598055 -80.500246)
			(xy 132.545271 -80.482239) (xy 132.495671 -80.456738) (xy 132.450313 -80.424287) (xy 132.410164 -80.385578)
			(xy 132.376078 -80.341435) (xy 132.348782 -80.2928) (xy 132.328859 -80.240709) (xy 132.316733 -80.186272)
			(xy 132.312662 -80.13065) (xy 131.743471 -80.13065) (xy 131.756919 -80.17535) (xy 131.765039 -80.230526)
			(xy 131.765548 -80.258412) (xy 131.765039 -80.286298) (xy 131.756919 -80.341474) (xy 131.740851 -80.394881)
			(xy 131.717179 -80.445378) (xy 131.686406 -80.491891) (xy 131.649189 -80.533428) (xy 131.606321 -80.569103)
			(xy 131.558715 -80.598157) (xy 131.538738 -80.606646) (xy 133.902702 -80.606646) (xy 133.906773 -80.551024)
			(xy 133.918899 -80.496587) (xy 133.938822 -80.444496) (xy 133.966118 -80.395861) (xy 134.000204 -80.351718)
			(xy 134.040353 -80.313009) (xy 134.085711 -80.280558) (xy 134.135311 -80.255057) (xy 134.188095 -80.23705)
			(xy 134.242938 -80.22692) (xy 134.298672 -80.224883) (xy 134.354109 -80.230983) (xy 134.408066 -80.245089)
			(xy 134.459395 -80.266901) (xy 134.507001 -80.295955) (xy 134.549869 -80.33163) (xy 134.587086 -80.373167)
			(xy 134.617859 -80.41968) (xy 134.641531 -80.470177) (xy 134.657599 -80.523584) (xy 134.665719 -80.57876)
			(xy 134.666228 -80.606646) (xy 134.665719 -80.634532) (xy 134.657599 -80.689708) (xy 134.641531 -80.743115)
			(xy 134.617859 -80.793612) (xy 134.587086 -80.840125) (xy 134.549869 -80.881662) (xy 134.507001 -80.917337)
			(xy 134.459395 -80.946391) (xy 134.408066 -80.968203) (xy 134.354109 -80.982309) (xy 134.298672 -80.988409)
			(xy 134.242938 -80.986372) (xy 134.188095 -80.976242) (xy 134.135311 -80.958235) (xy 134.085711 -80.932734)
			(xy 134.040353 -80.900283) (xy 134.000204 -80.861574) (xy 133.966118 -80.817431) (xy 133.938822 -80.768796)
			(xy 133.918899 -80.716705) (xy 133.906773 -80.662268) (xy 133.902702 -80.606646) (xy 131.538738 -80.606646)
			(xy 131.507386 -80.619969) (xy 131.453429 -80.634075) (xy 131.397992 -80.640175) (xy 131.342258 -80.638138)
			(xy 131.287415 -80.628008) (xy 131.234631 -80.610001) (xy 131.185031 -80.5845) (xy 131.139673 -80.552049)
			(xy 131.099524 -80.51334) (xy 131.065438 -80.469197) (xy 131.038142 -80.420562) (xy 131.018219 -80.368471)
			(xy 131.006093 -80.314034) (xy 131.002022 -80.258412) (xy 104.814092 -80.258412) (xy 104.827046 -80.300293)
			(xy 104.835587 -80.355031) (xy 104.836121 -80.410429) (xy 104.828636 -80.465321) (xy 104.813288 -80.518554)
			(xy 104.790402 -80.569006) (xy 104.760459 -80.615617) (xy 104.724088 -80.657407) (xy 104.682054 -80.693496)
			(xy 104.635242 -80.723125) (xy 104.584637 -80.74567) (xy 104.531302 -80.760659) (xy 104.476361 -80.767774)
			(xy 104.420967 -80.766867) (xy 104.366288 -80.757957) (xy 104.313473 -80.741231) (xy 104.288336 -80.729582)
			(xy 104.272577 -80.722518) (xy 104.238606 -80.716364) (xy 104.20423 -80.71956) (xy 104.171976 -80.731872)
			(xy 104.144214 -80.752394) (xy 104.133142 -80.76565) (xy 104.115657 -80.787145) (xy 104.075555 -80.825377)
			(xy 104.030345 -80.857407) (xy 103.980976 -80.882559) (xy 103.928489 -80.900305) (xy 103.873986 -80.910272)
			(xy 103.818615 -80.91225) (xy 103.76354 -80.906197) (xy 103.70992 -80.892241) (xy 103.658883 -80.870675)
			(xy 103.611502 -80.841953) (xy 103.568775 -80.806679) (xy 103.531599 -80.765595) (xy 103.500758 -80.719566)
			(xy 103.4769 -80.669559) (xy 103.460526 -80.616627) (xy 103.451982 -80.561884) (xy 103.451446 -80.50648)
			(xy 94.113735 -80.50648) (xy 94.104044 -80.55407) (xy 94.085074 -80.606526) (xy 94.058668 -80.655662)
			(xy 94.025389 -80.700428) (xy 93.985947 -80.739873) (xy 93.941182 -80.773154) (xy 93.892049 -80.799564)
			(xy 93.839594 -80.818537) (xy 93.784935 -80.829672) (xy 93.729238 -80.832729) (xy 93.673689 -80.827644)
			(xy 93.619473 -80.814526) (xy 93.567744 -80.793654) (xy 93.519605 -80.765472) (xy 93.476083 -80.730582)
			(xy 93.438104 -80.689726) (xy 93.406479 -80.643777) (xy 93.381881 -80.593712) (xy 93.364834 -80.540599)
			(xy 93.359732 -80.513174) (xy 93.355099 -80.490594) (xy 93.338777 -80.447491) (xy 93.314949 -80.408038)
			(xy 93.284397 -80.37353) (xy 93.248122 -80.345097) (xy 93.207314 -80.323673) (xy 93.163312 -80.30996)
			(xy 93.117557 -80.304407) (xy 93.071552 -80.307198) (xy 93.026804 -80.318239) (xy 92.984782 -80.33717)
			(xy 92.946862 -80.363369) (xy 92.930218 -80.379316) (xy 92.629228 -80.68056) (xy 92.629228 -81.065878)
			(xy 97.216974 -81.065878) (xy 97.221045 -81.010256) (xy 97.233171 -80.955819) (xy 97.253094 -80.903728)
			(xy 97.28039 -80.855093) (xy 97.314476 -80.81095) (xy 97.354625 -80.772241) (xy 97.399983 -80.73979)
			(xy 97.449583 -80.714289) (xy 97.502367 -80.696282) (xy 97.55721 -80.686152) (xy 97.612944 -80.684115)
			(xy 97.668381 -80.690215) (xy 97.722338 -80.704321) (xy 97.773667 -80.726133) (xy 97.821273 -80.755187)
			(xy 97.864141 -80.790862) (xy 97.901358 -80.832399) (xy 97.932131 -80.878912) (xy 97.955803 -80.929409)
			(xy 97.971871 -80.982816) (xy 97.979991 -81.037992) (xy 97.9805 -81.065878) (xy 97.979991 -81.093764)
			(xy 97.971871 -81.14894) (xy 97.965453 -81.170272) (xy 101.187502 -81.170272) (xy 101.191573 -81.11465)
			(xy 101.203699 -81.060213) (xy 101.223622 -81.008122) (xy 101.250918 -80.959487) (xy 101.285004 -80.915344)
			(xy 101.325153 -80.876635) (xy 101.370511 -80.844184) (xy 101.420111 -80.818683) (xy 101.472895 -80.800676)
			(xy 101.527738 -80.790546) (xy 101.583472 -80.788509) (xy 101.638909 -80.794609) (xy 101.692866 -80.808715)
			(xy 101.744195 -80.830527) (xy 101.791801 -80.859581) (xy 101.834669 -80.895256) (xy 101.871886 -80.936793)
			(xy 101.902659 -80.983306) (xy 101.926331 -81.033803) (xy 101.942399 -81.08721) (xy 101.950519 -81.142386)
			(xy 101.951028 -81.170272) (xy 101.950519 -81.198158) (xy 101.942399 -81.253334) (xy 101.926331 -81.306741)
			(xy 101.902659 -81.357238) (xy 101.88923 -81.377536) (xy 131.609082 -81.377536) (xy 131.613153 -81.321914)
			(xy 131.625279 -81.267477) (xy 131.645202 -81.215386) (xy 131.672498 -81.166751) (xy 131.706584 -81.122608)
			(xy 131.746733 -81.083899) (xy 131.792091 -81.051448) (xy 131.841691 -81.025947) (xy 131.894475 -81.00794)
			(xy 131.949318 -80.99781) (xy 132.005052 -80.995773) (xy 132.060489 -81.001873) (xy 132.114446 -81.015979)
			(xy 132.165775 -81.037791) (xy 132.213381 -81.066845) (xy 132.256249 -81.10252) (xy 132.293466 -81.144057)
			(xy 132.324239 -81.19057) (xy 132.347911 -81.241067) (xy 132.363979 -81.294474) (xy 132.372099 -81.34965)
			(xy 132.372608 -81.377536) (xy 132.372099 -81.405422) (xy 132.363979 -81.460598) (xy 132.347911 -81.514005)
			(xy 132.324239 -81.564502) (xy 132.293466 -81.611015) (xy 132.256249 -81.652552) (xy 132.213381 -81.688227)
			(xy 132.198895 -81.697068) (xy 132.696202 -81.697068) (xy 132.700273 -81.641446) (xy 132.712399 -81.587009)
			(xy 132.732322 -81.534918) (xy 132.759618 -81.486283) (xy 132.793704 -81.44214) (xy 132.833853 -81.403431)
			(xy 132.879211 -81.37098) (xy 132.928811 -81.345479) (xy 132.981595 -81.327472) (xy 133.036438 -81.317342)
			(xy 133.092172 -81.315305) (xy 133.147609 -81.321405) (xy 133.201566 -81.335511) (xy 133.252895 -81.357323)
			(xy 133.300501 -81.386377) (xy 133.343369 -81.422052) (xy 133.380586 -81.463589) (xy 133.411359 -81.510102)
			(xy 133.435031 -81.560599) (xy 133.451099 -81.614006) (xy 133.459219 -81.669182) (xy 133.459728 -81.697068)
			(xy 133.459219 -81.724954) (xy 133.451099 -81.78013) (xy 133.435031 -81.833537) (xy 133.411359 -81.884034)
			(xy 133.380586 -81.930547) (xy 133.343369 -81.972084) (xy 133.300501 -82.007759) (xy 133.252895 -82.036813)
			(xy 133.201566 -82.058625) (xy 133.147609 -82.072731) (xy 133.092172 -82.078831) (xy 133.036438 -82.076794)
			(xy 132.981595 -82.066664) (xy 132.928811 -82.048657) (xy 132.879211 -82.023156) (xy 132.833853 -81.990705)
			(xy 132.793704 -81.951996) (xy 132.759618 -81.907853) (xy 132.732322 -81.859218) (xy 132.712399 -81.807127)
			(xy 132.700273 -81.75269) (xy 132.696202 -81.697068) (xy 132.198895 -81.697068) (xy 132.165775 -81.717281)
			(xy 132.114446 -81.739093) (xy 132.060489 -81.753199) (xy 132.005052 -81.759299) (xy 131.949318 -81.757262)
			(xy 131.894475 -81.747132) (xy 131.841691 -81.729125) (xy 131.792091 -81.703624) (xy 131.746733 -81.671173)
			(xy 131.706584 -81.632464) (xy 131.672498 -81.588321) (xy 131.645202 -81.539686) (xy 131.625279 -81.487595)
			(xy 131.613153 -81.433158) (xy 131.609082 -81.377536) (xy 101.88923 -81.377536) (xy 101.871886 -81.403751)
			(xy 101.834669 -81.445288) (xy 101.791801 -81.480963) (xy 101.744195 -81.510017) (xy 101.692866 -81.531829)
			(xy 101.638909 -81.545935) (xy 101.583472 -81.552035) (xy 101.527738 -81.549998) (xy 101.472895 -81.539868)
			(xy 101.420111 -81.521861) (xy 101.370511 -81.49636) (xy 101.325153 -81.463909) (xy 101.285004 -81.4252)
			(xy 101.250918 -81.381057) (xy 101.223622 -81.332422) (xy 101.203699 -81.280331) (xy 101.191573 -81.225894)
			(xy 101.187502 -81.170272) (xy 97.965453 -81.170272) (xy 97.955803 -81.202347) (xy 97.932131 -81.252844)
			(xy 97.901358 -81.299357) (xy 97.864141 -81.340894) (xy 97.821273 -81.376569) (xy 97.773667 -81.405623)
			(xy 97.722338 -81.427435) (xy 97.668381 -81.441541) (xy 97.612944 -81.447641) (xy 97.55721 -81.445604)
			(xy 97.502367 -81.435474) (xy 97.449583 -81.417467) (xy 97.399983 -81.391966) (xy 97.354625 -81.359515)
			(xy 97.314476 -81.320806) (xy 97.28039 -81.276663) (xy 97.253094 -81.228028) (xy 97.233171 -81.175937)
			(xy 97.221045 -81.1215) (xy 97.216974 -81.065878) (xy 92.629228 -81.065878) (xy 92.629228 -82.028284)
			(xy 93.581218 -82.028284) (xy 93.585289 -81.972662) (xy 93.597415 -81.918225) (xy 93.617338 -81.866134)
			(xy 93.644634 -81.817499) (xy 93.67872 -81.773356) (xy 93.718869 -81.734647) (xy 93.764227 -81.702196)
			(xy 93.813827 -81.676695) (xy 93.866611 -81.658688) (xy 93.921454 -81.648558) (xy 93.977188 -81.646521)
			(xy 94.032625 -81.652621) (xy 94.086582 -81.666727) (xy 94.137911 -81.688539) (xy 94.185517 -81.717593)
			(xy 94.228385 -81.753268) (xy 94.265602 -81.794805) (xy 94.296375 -81.841318) (xy 94.320047 -81.891815)
			(xy 94.336115 -81.945222) (xy 94.344235 -82.000398) (xy 94.344744 -82.028284) (xy 94.344235 -82.05617)
			(xy 94.336115 -82.111346) (xy 94.320047 -82.164753) (xy 94.296375 -82.21525) (xy 94.265602 -82.261763)
			(xy 94.228385 -82.3033) (xy 94.185517 -82.338975) (xy 94.137911 -82.368029) (xy 94.086582 -82.389841)
			(xy 94.032625 -82.403947) (xy 93.977188 -82.410047) (xy 93.921454 -82.40801) (xy 93.866611 -82.39788)
			(xy 93.813827 -82.379873) (xy 93.764227 -82.354372) (xy 93.718869 -82.321921) (xy 93.67872 -82.283212)
			(xy 93.644634 -82.239069) (xy 93.617338 -82.190434) (xy 93.597415 -82.138343) (xy 93.585289 -82.083906)
			(xy 93.581218 -82.028284) (xy 92.629228 -82.028284) (xy 92.629228 -83.965796) (xy 94.126302 -83.965796)
			(xy 94.130373 -83.910174) (xy 94.142499 -83.855737) (xy 94.162422 -83.803646) (xy 94.189718 -83.755011)
			(xy 94.223804 -83.710868) (xy 94.263953 -83.672159) (xy 94.309311 -83.639708) (xy 94.358911 -83.614207)
			(xy 94.411695 -83.5962) (xy 94.466538 -83.58607) (xy 94.522272 -83.584033) (xy 94.577709 -83.590133)
			(xy 94.631666 -83.604239) (xy 94.682995 -83.626051) (xy 94.730601 -83.655105) (xy 94.773469 -83.69078)
			(xy 94.810686 -83.732317) (xy 94.841459 -83.77883) (xy 94.865131 -83.829327) (xy 94.881199 -83.882734)
			(xy 94.889319 -83.93791) (xy 94.889828 -83.965796) (xy 94.889319 -83.993682) (xy 94.881199 -84.048858)
			(xy 94.865131 -84.102265) (xy 94.841459 -84.152762) (xy 94.810686 -84.199275) (xy 94.792072 -84.22005)
			(xy 98.698302 -84.22005) (xy 98.702373 -84.164428) (xy 98.714499 -84.109991) (xy 98.734422 -84.0579)
			(xy 98.761718 -84.009265) (xy 98.795804 -83.965122) (xy 98.835953 -83.926413) (xy 98.881311 -83.893962)
			(xy 98.930911 -83.868461) (xy 98.983695 -83.850454) (xy 99.038538 -83.840324) (xy 99.094272 -83.838287)
			(xy 99.149709 -83.844387) (xy 99.203666 -83.858493) (xy 99.254995 -83.880305) (xy 99.302601 -83.909359)
			(xy 99.345469 -83.945034) (xy 99.382686 -83.986571) (xy 99.413459 -84.033084) (xy 99.437131 -84.083581)
			(xy 99.453199 -84.136988) (xy 99.461319 -84.192164) (xy 99.461828 -84.22005) (xy 99.461319 -84.247936)
			(xy 99.453199 -84.303112) (xy 99.437131 -84.356519) (xy 99.413459 -84.407016) (xy 99.382686 -84.453529)
			(xy 99.345469 -84.495066) (xy 99.302601 -84.530741) (xy 99.254995 -84.559795) (xy 99.203666 -84.581607)
			(xy 99.149709 -84.595713) (xy 99.094272 -84.601813) (xy 99.038538 -84.599776) (xy 98.983695 -84.589646)
			(xy 98.930911 -84.571639) (xy 98.881311 -84.546138) (xy 98.835953 -84.513687) (xy 98.795804 -84.474978)
			(xy 98.761718 -84.430835) (xy 98.734422 -84.3822) (xy 98.714499 -84.330109) (xy 98.702373 -84.275672)
			(xy 98.698302 -84.22005) (xy 94.792072 -84.22005) (xy 94.773469 -84.240812) (xy 94.730601 -84.276487)
			(xy 94.682995 -84.305541) (xy 94.631666 -84.327353) (xy 94.577709 -84.341459) (xy 94.522272 -84.347559)
			(xy 94.466538 -84.345522) (xy 94.411695 -84.335392) (xy 94.358911 -84.317385) (xy 94.309311 -84.291884)
			(xy 94.263953 -84.259433) (xy 94.223804 -84.220724) (xy 94.189718 -84.176581) (xy 94.162422 -84.127946)
			(xy 94.142499 -84.075855) (xy 94.130373 -84.021418) (xy 94.126302 -83.965796) (xy 92.629228 -83.965796)
			(xy 92.629228 -84.863686) (xy 92.629721 -84.880341) (xy 92.63834 -84.912515) (xy 92.654995 -84.941362)
			(xy 92.678549 -84.964914) (xy 92.707398 -84.981565) (xy 92.739573 -84.990181) (xy 92.756228 -84.990686)
			(xy 94.520512 -84.990686) (xy 94.58452 -84.926678) (xy 118.78183 -84.926678) (xy 118.804518 -84.926175)
			(xy 118.849172 -84.918112) (xy 118.891685 -84.902246) (xy 118.930703 -84.879082) (xy 118.964988 -84.849358)
			(xy 118.99345 -84.814017) (xy 119.015182 -84.774183) (xy 119.029495 -84.731123) (xy 119.035933 -84.686206)
			(xy 119.034292 -84.640859) (xy 119.029988 -84.618576) (xy 119.024633 -84.591835) (xy 119.020721 -84.53744)
			(xy 119.024593 -84.483041) (xy 119.036168 -84.429748) (xy 119.055211 -84.378645) (xy 119.081335 -84.330773)
			(xy 119.114008 -84.287108) (xy 119.152563 -84.248538) (xy 119.196216 -84.215849) (xy 119.244078 -84.189707)
			(xy 119.295174 -84.170644) (xy 119.348463 -84.159049) (xy 119.40286 -84.155157) (xy 119.457257 -84.159049)
			(xy 119.510546 -84.170644) (xy 119.561642 -84.189707) (xy 119.609504 -84.215849) (xy 119.653157 -84.248538)
			(xy 119.691712 -84.287108) (xy 119.724385 -84.330773) (xy 119.750509 -84.378645) (xy 119.769552 -84.429748)
			(xy 119.781127 -84.483041) (xy 119.784999 -84.53744) (xy 119.781087 -84.591835) (xy 119.775732 -84.618576)
			(xy 119.771385 -84.640853) (xy 119.769744 -84.686206) (xy 119.776183 -84.73113) (xy 119.790498 -84.774196)
			(xy 119.812235 -84.814035) (xy 119.840701 -84.849381) (xy 119.874992 -84.879108) (xy 119.914018 -84.902273)
			(xy 119.956537 -84.918139) (xy 120.001199 -84.926201) (xy 120.02389 -84.926678) (xy 121.622566 -84.926678)
			(xy 121.638875 -84.926172) (xy 121.670424 -84.917887) (xy 121.698843 -84.901875) (xy 121.722275 -84.879183)
			(xy 121.73919 -84.851292) (xy 121.748482 -84.820025) (xy 121.749566 -84.803742) (xy 121.75095 -84.775806)
			(xy 121.760882 -84.720763) (xy 121.778745 -84.667761) (xy 121.804157 -84.617936) (xy 121.836573 -84.572356)
			(xy 121.875297 -84.531997) (xy 121.9195 -84.497727) (xy 121.968234 -84.470279) (xy 122.020453 -84.450242)
			(xy 122.075038 -84.438045) (xy 122.13082 -84.43395) (xy 122.186602 -84.438045) (xy 122.241187 -84.450242)
			(xy 122.293406 -84.470279) (xy 122.34214 -84.497727) (xy 122.386343 -84.531997) (xy 122.425067 -84.572356)
			(xy 122.457483 -84.617936) (xy 122.482895 -84.667761) (xy 122.500758 -84.720763) (xy 122.51069 -84.775806)
			(xy 122.511759 -84.797392) (xy 137.567922 -84.797392) (xy 137.571993 -84.74177) (xy 137.584119 -84.687333)
			(xy 137.604042 -84.635242) (xy 137.631338 -84.586607) (xy 137.665424 -84.542464) (xy 137.705573 -84.503755)
			(xy 137.750931 -84.471304) (xy 137.800531 -84.445803) (xy 137.853315 -84.427796) (xy 137.908158 -84.417666)
			(xy 137.963892 -84.415629) (xy 138.019329 -84.421729) (xy 138.073286 -84.435835) (xy 138.124615 -84.457647)
			(xy 138.172221 -84.486701) (xy 138.215089 -84.522376) (xy 138.252306 -84.563913) (xy 138.283079 -84.610426)
			(xy 138.306751 -84.660923) (xy 138.322819 -84.71433) (xy 138.330939 -84.769506) (xy 138.331448 -84.797392)
			(xy 138.330939 -84.825278) (xy 138.322819 -84.880454) (xy 138.306751 -84.933861) (xy 138.283079 -84.984358)
			(xy 138.252306 -85.030871) (xy 138.215089 -85.072408) (xy 138.172221 -85.108083) (xy 138.124615 -85.137137)
			(xy 138.073286 -85.158949) (xy 138.019329 -85.173055) (xy 137.963892 -85.179155) (xy 137.908158 -85.177118)
			(xy 137.853315 -85.166988) (xy 137.800531 -85.148981) (xy 137.750931 -85.12348) (xy 137.705573 -85.091029)
			(xy 137.665424 -85.05232) (xy 137.631338 -85.008177) (xy 137.604042 -84.959542) (xy 137.584119 -84.907451)
			(xy 137.571993 -84.853014) (xy 137.567922 -84.797392) (xy 122.511759 -84.797392) (xy 122.512074 -84.803742)
			(xy 122.513093 -84.820036) (xy 122.522376 -84.851323) (xy 122.539295 -84.87923) (xy 122.562743 -84.90193)
			(xy 122.591184 -84.917936) (xy 122.622756 -84.9262) (xy 122.639074 -84.926678) (xy 134.933182 -84.926678)
			(xy 135.42645 -85.419946) (xy 135.442631 -85.435446) (xy 135.479385 -85.461067) (xy 135.520065 -85.479841)
			(xy 135.563408 -85.491187) (xy 135.608069 -85.494752) (xy 135.652663 -85.490426) (xy 135.695806 -85.478343)
			(xy 135.73616 -85.458877) (xy 135.772472 -85.432633) (xy 135.803616 -85.400425) (xy 135.828627 -85.363252)
			(xy 135.838184 -85.342984) (xy 135.849706 -85.318085) (xy 135.878839 -85.271595) (xy 135.914329 -85.229756)
			(xy 135.955446 -85.193432) (xy 136.001342 -85.163372) (xy 136.051069 -85.140194) (xy 136.103604 -85.124378)
			(xy 136.157862 -85.116249) (xy 136.212725 -85.115974) (xy 136.267062 -85.12356) (xy 136.319752 -85.13885)
			(xy 136.369709 -85.161529) (xy 136.415903 -85.191129) (xy 136.457381 -85.22704) (xy 136.493289 -85.268521)
			(xy 136.522885 -85.314717) (xy 136.54556 -85.364676) (xy 136.560846 -85.417367) (xy 136.568428 -85.471704)
			(xy 136.568149 -85.526568) (xy 136.560016 -85.580825) (xy 136.544195 -85.633358) (xy 136.521014 -85.683084)
			(xy 136.49095 -85.728977) (xy 136.454623 -85.770092) (xy 136.412781 -85.805579) (xy 136.366289 -85.834708)
			(xy 136.341358 -85.846158) (xy 136.321078 -85.85567) (xy 136.283948 -85.88072) (xy 136.25178 -85.911888)
			(xy 136.225571 -85.94821) (xy 136.20613 -85.988561) (xy 136.194058 -86.031694) (xy 136.18973 -86.076274)
			(xy 136.193279 -86.120924) (xy 136.204594 -86.164261) (xy 136.223327 -86.204946) (xy 136.248898 -86.24172)
			(xy 136.264396 -86.257892) (xy 136.457436 -86.450932) (xy 137.128502 -86.450932) (xy 137.132573 -86.39531)
			(xy 137.144699 -86.340873) (xy 137.164622 -86.288782) (xy 137.191918 -86.240147) (xy 137.226004 -86.196004)
			(xy 137.266153 -86.157295) (xy 137.311511 -86.124844) (xy 137.361111 -86.099343) (xy 137.413895 -86.081336)
			(xy 137.468738 -86.071206) (xy 137.524472 -86.069169) (xy 137.579909 -86.075269) (xy 137.633866 -86.089375)
			(xy 137.685195 -86.111187) (xy 137.719563 -86.132162) (xy 138.642342 -86.132162) (xy 138.646413 -86.07654)
			(xy 138.658539 -86.022103) (xy 138.678462 -85.970012) (xy 138.705758 -85.921377) (xy 138.739844 -85.877234)
			(xy 138.779993 -85.838525) (xy 138.825351 -85.806074) (xy 138.874951 -85.780573) (xy 138.927735 -85.762566)
			(xy 138.982578 -85.752436) (xy 139.038312 -85.750399) (xy 139.093749 -85.756499) (xy 139.147706 -85.770605)
			(xy 139.199035 -85.792417) (xy 139.246641 -85.821471) (xy 139.289509 -85.857146) (xy 139.326726 -85.898683)
			(xy 139.357499 -85.945196) (xy 139.381171 -85.995693) (xy 139.397239 -86.0491) (xy 139.405359 -86.104276)
			(xy 139.405868 -86.132162) (xy 139.405359 -86.160048) (xy 139.397239 -86.215224) (xy 139.381171 -86.268631)
			(xy 139.357499 -86.319128) (xy 139.326726 -86.365641) (xy 139.289509 -86.407178) (xy 139.246641 -86.442853)
			(xy 139.199035 -86.471907) (xy 139.147706 -86.493719) (xy 139.093749 -86.507825) (xy 139.038312 -86.513925)
			(xy 138.982578 -86.511888) (xy 138.927735 -86.501758) (xy 138.874951 -86.483751) (xy 138.825351 -86.45825)
			(xy 138.779993 -86.425799) (xy 138.739844 -86.38709) (xy 138.705758 -86.342947) (xy 138.678462 -86.294312)
			(xy 138.658539 -86.242221) (xy 138.646413 -86.187784) (xy 138.642342 -86.132162) (xy 137.719563 -86.132162)
			(xy 137.732801 -86.140241) (xy 137.775669 -86.175916) (xy 137.812886 -86.217453) (xy 137.843659 -86.263966)
			(xy 137.867331 -86.314463) (xy 137.883399 -86.36787) (xy 137.891519 -86.423046) (xy 137.892028 -86.450932)
			(xy 137.891519 -86.478818) (xy 137.883399 -86.533994) (xy 137.872396 -86.570566) (xy 140.255242 -86.570566)
			(xy 140.259313 -86.514944) (xy 140.271439 -86.460507) (xy 140.291362 -86.408416) (xy 140.318658 -86.359781)
			(xy 140.352744 -86.315638) (xy 140.392893 -86.276929) (xy 140.438251 -86.244478) (xy 140.487851 -86.218977)
			(xy 140.540635 -86.20097) (xy 140.595478 -86.19084) (xy 140.651212 -86.188803) (xy 140.706649 -86.194903)
			(xy 140.760606 -86.209009) (xy 140.811935 -86.230821) (xy 140.859541 -86.259875) (xy 140.902409 -86.29555)
			(xy 140.939626 -86.337087) (xy 140.970399 -86.3836) (xy 140.994071 -86.434097) (xy 141.010139 -86.487504)
			(xy 141.018259 -86.54268) (xy 141.018768 -86.570566) (xy 141.018259 -86.598452) (xy 141.010139 -86.653628)
			(xy 140.994071 -86.707035) (xy 140.970399 -86.757532) (xy 140.939626 -86.804045) (xy 140.902409 -86.845582)
			(xy 140.859541 -86.881257) (xy 140.811935 -86.910311) (xy 140.760606 -86.932123) (xy 140.706649 -86.946229)
			(xy 140.651212 -86.952329) (xy 140.595478 -86.950292) (xy 140.540635 -86.940162) (xy 140.487851 -86.922155)
			(xy 140.438251 -86.896654) (xy 140.392893 -86.864203) (xy 140.352744 -86.825494) (xy 140.318658 -86.781351)
			(xy 140.291362 -86.732716) (xy 140.271439 -86.680625) (xy 140.259313 -86.626188) (xy 140.255242 -86.570566)
			(xy 137.872396 -86.570566) (xy 137.867331 -86.587401) (xy 137.843659 -86.637898) (xy 137.812886 -86.684411)
			(xy 137.775669 -86.725948) (xy 137.732801 -86.761623) (xy 137.685195 -86.790677) (xy 137.633866 -86.812489)
			(xy 137.579909 -86.826595) (xy 137.524472 -86.832695) (xy 137.468738 -86.830658) (xy 137.413895 -86.820528)
			(xy 137.361111 -86.802521) (xy 137.311511 -86.77702) (xy 137.266153 -86.744569) (xy 137.226004 -86.70586)
			(xy 137.191918 -86.661717) (xy 137.164622 -86.613082) (xy 137.144699 -86.560991) (xy 137.132573 -86.506554)
			(xy 137.128502 -86.450932) (xy 136.457436 -86.450932) (xy 140.111226 -90.104722) (xy 146.884134 -90.104722)
			(xy 146.888205 -90.0491) (xy 146.900331 -89.994663) (xy 146.920254 -89.942572) (xy 146.94755 -89.893937)
			(xy 146.981636 -89.849794) (xy 147.021785 -89.811085) (xy 147.067143 -89.778634) (xy 147.116743 -89.753133)
			(xy 147.169527 -89.735126) (xy 147.22437 -89.724996) (xy 147.280104 -89.722959) (xy 147.335541 -89.729059)
			(xy 147.389498 -89.743165) (xy 147.440827 -89.764977) (xy 147.488433 -89.794031) (xy 147.531301 -89.829706)
			(xy 147.568518 -89.871243) (xy 147.599291 -89.917756) (xy 147.622963 -89.968253) (xy 147.639031 -90.02166)
			(xy 147.647151 -90.076836) (xy 147.64766 -90.104722) (xy 147.647151 -90.132608) (xy 147.639031 -90.187784)
			(xy 147.622963 -90.241191) (xy 147.599291 -90.291688) (xy 147.568518 -90.338201) (xy 147.531301 -90.379738)
			(xy 147.488433 -90.415413) (xy 147.440827 -90.444467) (xy 147.389498 -90.466279) (xy 147.335541 -90.480385)
			(xy 147.280104 -90.486485) (xy 147.22437 -90.484448) (xy 147.169527 -90.474318) (xy 147.116743 -90.456311)
			(xy 147.067143 -90.43081) (xy 147.021785 -90.398359) (xy 146.981636 -90.35965) (xy 146.94755 -90.315507)
			(xy 146.920254 -90.266872) (xy 146.900331 -90.214781) (xy 146.888205 -90.160344) (xy 146.884134 -90.104722)
			(xy 140.111226 -90.104722) (xy 145.982436 -95.975932) (xy 163.507926 -95.975932) (xy 163.511997 -95.92031)
			(xy 163.524123 -95.865873) (xy 163.544046 -95.813782) (xy 163.571342 -95.765147) (xy 163.605428 -95.721004)
			(xy 163.645577 -95.682295) (xy 163.690935 -95.649844) (xy 163.740535 -95.624343) (xy 163.793319 -95.606336)
			(xy 163.848162 -95.596206) (xy 163.903896 -95.594169) (xy 163.959333 -95.600269) (xy 164.01329 -95.614375)
			(xy 164.064619 -95.636187) (xy 164.112225 -95.665241) (xy 164.155093 -95.700916) (xy 164.19231 -95.742453)
			(xy 164.223083 -95.788966) (xy 164.223451 -95.78975) (xy 165.261288 -95.78975) (xy 165.265359 -95.734128)
			(xy 165.277485 -95.679691) (xy 165.297408 -95.6276) (xy 165.324704 -95.578965) (xy 165.35879 -95.534822)
			(xy 165.398939 -95.496113) (xy 165.444297 -95.463662) (xy 165.493897 -95.438161) (xy 165.546681 -95.420154)
			(xy 165.601524 -95.410024) (xy 165.657258 -95.407987) (xy 165.712695 -95.414087) (xy 165.766652 -95.428193)
			(xy 165.817981 -95.450005) (xy 165.865587 -95.479059) (xy 165.908455 -95.514734) (xy 165.945672 -95.556271)
			(xy 165.976445 -95.602784) (xy 166.000117 -95.653281) (xy 166.016185 -95.706688) (xy 166.024305 -95.761864)
			(xy 166.024415 -95.767906) (xy 167.865042 -95.767906) (xy 167.869113 -95.712284) (xy 167.881239 -95.657847)
			(xy 167.901162 -95.605756) (xy 167.928458 -95.557121) (xy 167.962544 -95.512978) (xy 168.002693 -95.474269)
			(xy 168.048051 -95.441818) (xy 168.097651 -95.416317) (xy 168.150435 -95.39831) (xy 168.205278 -95.38818)
			(xy 168.261012 -95.386143) (xy 168.316449 -95.392243) (xy 168.370406 -95.406349) (xy 168.421735 -95.428161)
			(xy 168.469341 -95.457215) (xy 168.512209 -95.49289) (xy 168.549426 -95.534427) (xy 168.580199 -95.58094)
			(xy 168.603871 -95.631437) (xy 168.619939 -95.684844) (xy 168.628059 -95.74002) (xy 168.628568 -95.767906)
			(xy 168.628059 -95.795792) (xy 168.619939 -95.850968) (xy 168.610617 -95.881952) (xy 169.598592 -95.881952)
			(xy 169.602663 -95.82633) (xy 169.614789 -95.771893) (xy 169.634712 -95.719802) (xy 169.662008 -95.671167)
			(xy 169.696094 -95.627024) (xy 169.736243 -95.588315) (xy 169.781601 -95.555864) (xy 169.831201 -95.530363)
			(xy 169.883985 -95.512356) (xy 169.938828 -95.502226) (xy 169.994562 -95.500189) (xy 170.049999 -95.506289)
			(xy 170.103956 -95.520395) (xy 170.155285 -95.542207) (xy 170.202891 -95.571261) (xy 170.245759 -95.606936)
			(xy 170.282976 -95.648473) (xy 170.313749 -95.694986) (xy 170.337421 -95.745483) (xy 170.353489 -95.79889)
			(xy 170.361609 -95.854066) (xy 170.362118 -95.881952) (xy 170.361609 -95.909838) (xy 170.353489 -95.965014)
			(xy 170.337421 -96.018421) (xy 170.313749 -96.068918) (xy 170.282976 -96.115431) (xy 170.245759 -96.156968)
			(xy 170.202891 -96.192643) (xy 170.155285 -96.221697) (xy 170.103956 -96.243509) (xy 170.049999 -96.257615)
			(xy 169.994562 -96.263715) (xy 169.938828 -96.261678) (xy 169.883985 -96.251548) (xy 169.831201 -96.233541)
			(xy 169.781601 -96.20804) (xy 169.736243 -96.175589) (xy 169.696094 -96.13688) (xy 169.662008 -96.092737)
			(xy 169.634712 -96.044102) (xy 169.614789 -95.992011) (xy 169.602663 -95.937574) (xy 169.598592 -95.881952)
			(xy 168.610617 -95.881952) (xy 168.603871 -95.904375) (xy 168.580199 -95.954872) (xy 168.549426 -96.001385)
			(xy 168.512209 -96.042922) (xy 168.469341 -96.078597) (xy 168.421735 -96.107651) (xy 168.370406 -96.129463)
			(xy 168.316449 -96.143569) (xy 168.261012 -96.149669) (xy 168.205278 -96.147632) (xy 168.150435 -96.137502)
			(xy 168.097651 -96.119495) (xy 168.048051 -96.093994) (xy 168.002693 -96.061543) (xy 167.962544 -96.022834)
			(xy 167.928458 -95.978691) (xy 167.901162 -95.930056) (xy 167.881239 -95.877965) (xy 167.869113 -95.823528)
			(xy 167.865042 -95.767906) (xy 166.024415 -95.767906) (xy 166.024814 -95.78975) (xy 166.024305 -95.817636)
			(xy 166.016185 -95.872812) (xy 166.000117 -95.926219) (xy 165.976445 -95.976716) (xy 165.945672 -96.023229)
			(xy 165.908455 -96.064766) (xy 165.865587 -96.100441) (xy 165.817981 -96.129495) (xy 165.766652 -96.151307)
			(xy 165.712695 -96.165413) (xy 165.657258 -96.171513) (xy 165.601524 -96.169476) (xy 165.546681 -96.159346)
			(xy 165.493897 -96.141339) (xy 165.444297 -96.115838) (xy 165.398939 -96.083387) (xy 165.35879 -96.044678)
			(xy 165.324704 -96.000535) (xy 165.297408 -95.9519) (xy 165.277485 -95.899809) (xy 165.265359 -95.845372)
			(xy 165.261288 -95.78975) (xy 164.223451 -95.78975) (xy 164.246755 -95.839463) (xy 164.262823 -95.89287)
			(xy 164.270943 -95.948046) (xy 164.271452 -95.975932) (xy 164.270943 -96.003818) (xy 164.262823 -96.058994)
			(xy 164.246755 -96.112401) (xy 164.223083 -96.162898) (xy 164.19231 -96.209411) (xy 164.155093 -96.250948)
			(xy 164.112225 -96.286623) (xy 164.064619 -96.315677) (xy 164.01329 -96.337489) (xy 163.959333 -96.351595)
			(xy 163.903896 -96.357695) (xy 163.848162 -96.355658) (xy 163.793319 -96.345528) (xy 163.740535 -96.327521)
			(xy 163.690935 -96.30202) (xy 163.645577 -96.269569) (xy 163.605428 -96.23086) (xy 163.571342 -96.186717)
			(xy 163.544046 -96.138082) (xy 163.524123 -96.085991) (xy 163.511997 -96.031554) (xy 163.507926 -95.975932)
			(xy 145.982436 -95.975932) (xy 146.36496 -96.358456) (xy 170.873672 -96.358456) (xy 170.877743 -96.302834)
			(xy 170.889869 -96.248397) (xy 170.909792 -96.196306) (xy 170.937088 -96.147671) (xy 170.971174 -96.103528)
			(xy 171.011323 -96.064819) (xy 171.056681 -96.032368) (xy 171.106281 -96.006867) (xy 171.159065 -95.98886)
			(xy 171.213908 -95.97873) (xy 171.269642 -95.976693) (xy 171.325079 -95.982793) (xy 171.379036 -95.996899)
			(xy 171.430365 -96.018711) (xy 171.477971 -96.047765) (xy 171.520839 -96.08344) (xy 171.558056 -96.124977)
			(xy 171.588829 -96.17149) (xy 171.612501 -96.221987) (xy 171.628569 -96.275394) (xy 171.636689 -96.33057)
			(xy 171.637198 -96.358456) (xy 171.636689 -96.386342) (xy 171.628569 -96.441518) (xy 171.612501 -96.494925)
			(xy 171.588829 -96.545422) (xy 171.558056 -96.591935) (xy 171.520839 -96.633472) (xy 171.477971 -96.669147)
			(xy 171.430365 -96.698201) (xy 171.379036 -96.720013) (xy 171.325079 -96.734119) (xy 171.269642 -96.740219)
			(xy 171.213908 -96.738182) (xy 171.159065 -96.728052) (xy 171.106281 -96.710045) (xy 171.056681 -96.684544)
			(xy 171.011323 -96.652093) (xy 170.971174 -96.613384) (xy 170.937088 -96.569241) (xy 170.909792 -96.520606)
			(xy 170.889869 -96.468515) (xy 170.877743 -96.414078) (xy 170.873672 -96.358456) (xy 146.36496 -96.358456)
			(xy 146.936968 -96.930464) (xy 162.491926 -96.930464) (xy 162.495997 -96.874842) (xy 162.508123 -96.820405)
			(xy 162.528046 -96.768314) (xy 162.555342 -96.719679) (xy 162.589428 -96.675536) (xy 162.629577 -96.636827)
			(xy 162.674935 -96.604376) (xy 162.724535 -96.578875) (xy 162.777319 -96.560868) (xy 162.832162 -96.550738)
			(xy 162.887896 -96.548701) (xy 162.943333 -96.554801) (xy 162.99729 -96.568907) (xy 163.048619 -96.590719)
			(xy 163.096225 -96.619773) (xy 163.139093 -96.655448) (xy 163.17631 -96.696985) (xy 163.207083 -96.743498)
			(xy 163.230755 -96.793995) (xy 163.246823 -96.847402) (xy 163.254943 -96.902578) (xy 163.255452 -96.930464)
			(xy 163.254943 -96.95835) (xy 163.246823 -97.013526) (xy 163.230755 -97.066933) (xy 163.207083 -97.11743)
			(xy 163.17631 -97.163943) (xy 163.139093 -97.20548) (xy 163.096225 -97.241155) (xy 163.048619 -97.270209)
			(xy 162.99729 -97.292021) (xy 162.943333 -97.306127) (xy 162.887896 -97.312227) (xy 162.832162 -97.31019)
			(xy 162.777319 -97.30006) (xy 162.724535 -97.282053) (xy 162.674935 -97.256552) (xy 162.629577 -97.224101)
			(xy 162.589428 -97.185392) (xy 162.555342 -97.141249) (xy 162.528046 -97.092614) (xy 162.508123 -97.040523)
			(xy 162.495997 -96.986086) (xy 162.491926 -96.930464) (xy 146.936968 -96.930464) (xy 147.469606 -97.463102)
			(xy 158.88157 -97.463102) (xy 158.885641 -97.40748) (xy 158.897767 -97.353043) (xy 158.91769 -97.300952)
			(xy 158.944986 -97.252317) (xy 158.979072 -97.208174) (xy 159.019221 -97.169465) (xy 159.064579 -97.137014)
			(xy 159.114179 -97.111513) (xy 159.166963 -97.093506) (xy 159.221806 -97.083376) (xy 159.27754 -97.081339)
			(xy 159.332977 -97.087439) (xy 159.386934 -97.101545) (xy 159.438263 -97.123357) (xy 159.485869 -97.152411)
			(xy 159.528737 -97.188086) (xy 159.565954 -97.229623) (xy 159.596727 -97.276136) (xy 159.620399 -97.326633)
			(xy 159.636467 -97.38004) (xy 159.644587 -97.435216) (xy 159.645096 -97.463102) (xy 159.644587 -97.490988)
			(xy 159.636467 -97.546164) (xy 159.620399 -97.599571) (xy 159.596727 -97.650068) (xy 159.565954 -97.696581)
			(xy 159.528737 -97.738118) (xy 159.485869 -97.773793) (xy 159.438263 -97.802847) (xy 159.386934 -97.824659)
			(xy 159.332977 -97.838765) (xy 159.27754 -97.844865) (xy 159.221806 -97.842828) (xy 159.166963 -97.832698)
			(xy 159.114179 -97.814691) (xy 159.064579 -97.78919) (xy 159.019221 -97.756739) (xy 158.979072 -97.71803)
			(xy 158.944986 -97.673887) (xy 158.91769 -97.625252) (xy 158.897767 -97.573161) (xy 158.885641 -97.518724)
			(xy 158.88157 -97.463102) (xy 147.469606 -97.463102) (xy 148.518963 -98.512459) (xy 153.477524 -98.512459)
			(xy 153.481264 -98.457245) (xy 153.492943 -98.403152) (xy 153.512316 -98.351313) (xy 153.538975 -98.302818)
			(xy 153.572363 -98.258684) (xy 153.611777 -98.219838) (xy 153.65639 -98.187095) (xy 153.705267 -98.161141)
			(xy 153.757381 -98.142523) (xy 153.811638 -98.13163) (xy 153.8669 -98.128691) (xy 153.922007 -98.133768)
			(xy 153.975801 -98.146755) (xy 154.027155 -98.167378) (xy 154.07499 -98.195206) (xy 154.118301 -98.229653)
			(xy 154.156181 -98.269997) (xy 154.172412 -98.292412) (xy 154.186469 -98.311647) (xy 154.220508 -98.344972)
			(xy 154.260157 -98.371377) (xy 154.304028 -98.389937) (xy 154.350589 -98.400004) (xy 154.39821 -98.401225)
			(xy 154.445225 -98.393558) (xy 154.48999 -98.37727) (xy 154.51074 -98.365564) (xy 154.534753 -98.351803)
			(xy 154.585907 -98.330673) (xy 154.639578 -98.317155) (xy 154.694638 -98.311535) (xy 154.749932 -98.31393)
			(xy 154.8043 -98.324289) (xy 154.856601 -98.342395) (xy 154.905737 -98.367869) (xy 154.950676 -98.400175)
			(xy 154.990476 -98.438635) (xy 155.0243 -98.482443) (xy 155.05144 -98.530678) (xy 155.071325 -98.582329)
			(xy 155.083538 -98.63631) (xy 155.087823 -98.691491) (xy 155.08409 -98.746711) (xy 155.072417 -98.800812)
			(xy 155.061816 -98.82919) (xy 160.784251 -98.82919) (xy 160.790621 -98.774251) (xy 160.804857 -98.720807)
			(xy 160.826662 -98.669979) (xy 160.855578 -98.622833) (xy 160.890999 -98.580356) (xy 160.932182 -98.543439)
			(xy 160.978265 -98.512857) (xy 161.028281 -98.489249) (xy 161.081181 -98.473111) (xy 161.135858 -98.464782)
			(xy 161.163508 -98.464116) (xy 161.186659 -98.463419) (xy 161.232143 -98.454704) (xy 161.275295 -98.437893)
			(xy 161.314686 -98.413542) (xy 161.349014 -98.382456) (xy 161.377142 -98.345666) (xy 161.398138 -98.304388)
			(xy 161.411308 -98.25999) (xy 161.416216 -98.213939) (xy 161.414968 -98.190812) (xy 161.413321 -98.163196)
			(xy 161.417124 -98.108004) (xy 161.428859 -98.05394) (xy 161.448277 -98.002137) (xy 161.474973 -97.953682)
			(xy 161.508387 -97.90959) (xy 161.547818 -97.870785) (xy 161.59244 -97.838082) (xy 161.641317 -97.812165)
			(xy 161.693424 -97.793578) (xy 161.747669 -97.782711) (xy 161.802914 -97.779792) (xy 161.858003 -97.784882)
			(xy 161.911778 -97.797873) (xy 161.963114 -97.818495) (xy 162.010934 -97.846314) (xy 162.054235 -97.880747)
			(xy 162.092109 -97.921072) (xy 162.123763 -97.966444) (xy 162.148533 -98.015912) (xy 162.1659 -98.068438)
			(xy 162.175499 -98.122922) (xy 162.17604 -98.141282) (xy 164.067742 -98.141282) (xy 164.071813 -98.08566)
			(xy 164.083939 -98.031223) (xy 164.103862 -97.979132) (xy 164.131158 -97.930497) (xy 164.165244 -97.886354)
			(xy 164.205393 -97.847645) (xy 164.250751 -97.815194) (xy 164.300351 -97.789693) (xy 164.353135 -97.771686)
			(xy 164.407978 -97.761556) (xy 164.463712 -97.759519) (xy 164.519149 -97.765619) (xy 164.573106 -97.779725)
			(xy 164.624435 -97.801537) (xy 164.672041 -97.830591) (xy 164.714909 -97.866266) (xy 164.752126 -97.907803)
			(xy 164.782899 -97.954316) (xy 164.806571 -98.004813) (xy 164.822639 -98.05822) (xy 164.830759 -98.113396)
			(xy 164.830804 -98.115882) (xy 165.820342 -98.115882) (xy 165.824413 -98.06026) (xy 165.836539 -98.005823)
			(xy 165.856462 -97.953732) (xy 165.883758 -97.905097) (xy 165.917844 -97.860954) (xy 165.957993 -97.822245)
			(xy 166.003351 -97.789794) (xy 166.052951 -97.764293) (xy 166.105735 -97.746286) (xy 166.160578 -97.736156)
			(xy 166.216312 -97.734119) (xy 166.271749 -97.740219) (xy 166.325706 -97.754325) (xy 166.377035 -97.776137)
			(xy 166.424641 -97.805191) (xy 166.467509 -97.840866) (xy 166.504726 -97.882403) (xy 166.535499 -97.928916)
			(xy 166.559171 -97.979413) (xy 166.575239 -98.03282) (xy 166.583359 -98.087996) (xy 166.583868 -98.115882)
			(xy 167.547542 -98.115882) (xy 167.551613 -98.06026) (xy 167.563739 -98.005823) (xy 167.583662 -97.953732)
			(xy 167.610958 -97.905097) (xy 167.645044 -97.860954) (xy 167.685193 -97.822245) (xy 167.730551 -97.789794)
			(xy 167.780151 -97.764293) (xy 167.832935 -97.746286) (xy 167.887778 -97.736156) (xy 167.943512 -97.734119)
			(xy 167.998949 -97.740219) (xy 168.052906 -97.754325) (xy 168.104235 -97.776137) (xy 168.151841 -97.805191)
			(xy 168.194709 -97.840866) (xy 168.231926 -97.882403) (xy 168.262699 -97.928916) (xy 168.286371 -97.979413)
			(xy 168.302439 -98.03282) (xy 168.310559 -98.087996) (xy 168.311068 -98.115882) (xy 169.681142 -98.115882)
			(xy 169.685213 -98.06026) (xy 169.697339 -98.005823) (xy 169.717262 -97.953732) (xy 169.744558 -97.905097)
			(xy 169.778644 -97.860954) (xy 169.818793 -97.822245) (xy 169.864151 -97.789794) (xy 169.913751 -97.764293)
			(xy 169.966535 -97.746286) (xy 170.021378 -97.736156) (xy 170.077112 -97.734119) (xy 170.132549 -97.740219)
			(xy 170.186506 -97.754325) (xy 170.237835 -97.776137) (xy 170.285441 -97.805191) (xy 170.328309 -97.840866)
			(xy 170.365526 -97.882403) (xy 170.396299 -97.928916) (xy 170.419971 -97.979413) (xy 170.436039 -98.03282)
			(xy 170.444159 -98.087996) (xy 170.444668 -98.115882) (xy 170.444159 -98.143768) (xy 170.436039 -98.198944)
			(xy 170.419971 -98.252351) (xy 170.396299 -98.302848) (xy 170.365526 -98.349361) (xy 170.328309 -98.390898)
			(xy 170.285441 -98.426573) (xy 170.237835 -98.455627) (xy 170.186506 -98.477439) (xy 170.132549 -98.491545)
			(xy 170.077112 -98.497645) (xy 170.021378 -98.495608) (xy 169.966535 -98.485478) (xy 169.913751 -98.467471)
			(xy 169.864151 -98.44197) (xy 169.818793 -98.409519) (xy 169.778644 -98.37081) (xy 169.744558 -98.326667)
			(xy 169.717262 -98.278032) (xy 169.697339 -98.225941) (xy 169.685213 -98.171504) (xy 169.681142 -98.115882)
			(xy 168.311068 -98.115882) (xy 168.310559 -98.143768) (xy 168.302439 -98.198944) (xy 168.286371 -98.252351)
			(xy 168.262699 -98.302848) (xy 168.231926 -98.349361) (xy 168.194709 -98.390898) (xy 168.151841 -98.426573)
			(xy 168.104235 -98.455627) (xy 168.052906 -98.477439) (xy 167.998949 -98.491545) (xy 167.943512 -98.497645)
			(xy 167.887778 -98.495608) (xy 167.832935 -98.485478) (xy 167.780151 -98.467471) (xy 167.730551 -98.44197)
			(xy 167.685193 -98.409519) (xy 167.645044 -98.37081) (xy 167.610958 -98.326667) (xy 167.583662 -98.278032)
			(xy 167.563739 -98.225941) (xy 167.551613 -98.171504) (xy 167.547542 -98.115882) (xy 166.583868 -98.115882)
			(xy 166.583359 -98.143768) (xy 166.575239 -98.198944) (xy 166.559171 -98.252351) (xy 166.535499 -98.302848)
			(xy 166.504726 -98.349361) (xy 166.467509 -98.390898) (xy 166.424641 -98.426573) (xy 166.377035 -98.455627)
			(xy 166.325706 -98.477439) (xy 166.271749 -98.491545) (xy 166.216312 -98.497645) (xy 166.160578 -98.495608)
			(xy 166.105735 -98.485478) (xy 166.052951 -98.467471) (xy 166.003351 -98.44197) (xy 165.957993 -98.409519)
			(xy 165.917844 -98.37081) (xy 165.883758 -98.326667) (xy 165.856462 -98.278032) (xy 165.836539 -98.225941)
			(xy 165.824413 -98.171504) (xy 165.820342 -98.115882) (xy 164.830804 -98.115882) (xy 164.831268 -98.141282)
			(xy 164.830759 -98.169168) (xy 164.822639 -98.224344) (xy 164.806571 -98.277751) (xy 164.782899 -98.328248)
			(xy 164.752126 -98.374761) (xy 164.714909 -98.416298) (xy 164.672041 -98.451973) (xy 164.624435 -98.481027)
			(xy 164.573106 -98.502839) (xy 164.519149 -98.516945) (xy 164.463712 -98.523045) (xy 164.407978 -98.521008)
			(xy 164.353135 -98.510878) (xy 164.300351 -98.492871) (xy 164.250751 -98.46737) (xy 164.205393 -98.434919)
			(xy 164.165244 -98.39621) (xy 164.131158 -98.352067) (xy 164.103862 -98.303432) (xy 164.083939 -98.251341)
			(xy 164.071813 -98.196904) (xy 164.067742 -98.141282) (xy 162.17604 -98.141282) (xy 162.177129 -98.178221)
			(xy 162.170756 -98.233175) (xy 162.156514 -98.286633) (xy 162.134701 -98.337474) (xy 162.105774 -98.384632)
			(xy 162.070341 -98.427118) (xy 162.029143 -98.464042) (xy 161.983046 -98.49463) (xy 161.933014 -98.518239)
			(xy 161.880097 -98.534376) (xy 161.825404 -98.542702) (xy 161.797746 -98.543364) (xy 161.774595 -98.544041)
			(xy 161.729112 -98.552763) (xy 161.685962 -98.569579) (xy 161.646572 -98.593934) (xy 161.612246 -98.625022)
			(xy 161.584119 -98.661813) (xy 161.563122 -98.703091) (xy 161.54995 -98.74749) (xy 161.54504 -98.79354)
			(xy 161.546286 -98.816668) (xy 161.547899 -98.844279) (xy 161.544086 -98.899455) (xy 161.532346 -98.953502)
			(xy 161.512923 -99.005287) (xy 161.498916 -99.030701) (xy 171.855263 -99.030701) (xy 171.860413 -98.975326)
			(xy 171.87355 -98.921286) (xy 171.894393 -98.869726) (xy 171.922502 -98.821738) (xy 171.957281 -98.778341)
			(xy 171.997992 -98.740452) (xy 172.043773 -98.708877) (xy 172.093653 -98.684283) (xy 172.146576 -98.667192)
			(xy 172.201419 -98.657967) (xy 172.257021 -98.656802) (xy 172.312202 -98.663722) (xy 172.365794 -98.678582)
			(xy 172.416661 -98.701065) (xy 172.463724 -98.730695) (xy 172.505986 -98.766845) (xy 172.542552 -98.808748)
			(xy 172.572646 -98.855516) (xy 172.59563 -98.906158) (xy 172.611018 -98.959601) (xy 172.618484 -99.014711)
			(xy 172.617868 -99.070322) (xy 172.609185 -99.125254) (xy 172.601382 -99.151948) (xy 172.595135 -99.173389)
			(xy 172.58947 -99.217684) (xy 172.591634 -99.262287) (xy 172.60156 -99.305825) (xy 172.618942 -99.346959)
			(xy 172.643246 -99.384422) (xy 172.673723 -99.417061) (xy 172.691298 -99.43084) (xy 172.713268 -99.447893)
			(xy 172.752441 -99.487371) (xy 172.785467 -99.532118) (xy 172.811646 -99.581186) (xy 172.830423 -99.633535)
			(xy 172.841401 -99.688056) (xy 172.844346 -99.743593) (xy 172.839196 -99.79897) (xy 172.82606 -99.853011)
			(xy 172.805217 -99.904573) (xy 172.777108 -99.952562) (xy 172.74233 -99.995961) (xy 172.701618 -100.03385)
			(xy 172.655837 -100.065427) (xy 172.605956 -100.090022) (xy 172.553032 -100.107114) (xy 172.498188 -100.116341)
			(xy 172.442585 -100.117507) (xy 172.387402 -100.110587) (xy 172.333809 -100.095728) (xy 172.282941 -100.073246)
			(xy 172.235876 -100.043615) (xy 172.193613 -100.007465) (xy 172.157045 -99.965562) (xy 172.12695 -99.918794)
			(xy 172.103964 -99.868151) (xy 172.088575 -99.814707) (xy 172.081108 -99.759596) (xy 172.081723 -99.703984)
			(xy 172.090405 -99.649051) (xy 172.098208 -99.622356) (xy 172.104418 -99.600907) (xy 172.11008 -99.556616)
			(xy 172.107918 -99.512018) (xy 172.097996 -99.468483) (xy 172.080621 -99.427352) (xy 172.056327 -99.389889)
			(xy 172.025862 -99.357246) (xy 172.008292 -99.343464) (xy 171.986334 -99.326397) (xy 171.947162 -99.286919)
			(xy 171.914137 -99.242173) (xy 171.887959 -99.193105) (xy 171.869183 -99.140757) (xy 171.858207 -99.086237)
			(xy 171.855263 -99.030701) (xy 161.498916 -99.030701) (xy 161.486227 -99.053724) (xy 161.452816 -99.097799)
			(xy 161.41339 -99.136588) (xy 161.368776 -99.169276) (xy 161.31991 -99.19518) (xy 161.267815 -99.213755)
			(xy 161.213584 -99.224614) (xy 161.158354 -99.227527) (xy 161.103281 -99.222434) (xy 161.049521 -99.209442)
			(xy 160.998201 -99.188823) (xy 160.950396 -99.16101) (xy 160.907109 -99.126584) (xy 160.869246 -99.086269)
			(xy 160.837602 -99.040909) (xy 160.812839 -98.991454) (xy 160.795478 -98.938942) (xy 160.785882 -98.884474)
			(xy 160.784251 -98.82919) (xy 155.061816 -98.82919) (xy 155.053049 -98.852659) (xy 155.026393 -98.901163)
			(xy 154.993008 -98.945307) (xy 154.953595 -98.984163) (xy 154.908981 -99.016917) (xy 154.860102 -99.04288)
			(xy 154.807985 -99.061508) (xy 154.753723 -99.07241) (xy 154.698455 -99.075357) (xy 154.643342 -99.070288)
			(xy 154.589539 -99.057308) (xy 154.538177 -99.03669) (xy 154.490332 -99.008866) (xy 154.44701 -98.974422)
			(xy 154.40912 -98.934079) (xy 154.392884 -98.911664) (xy 154.378835 -98.892423) (xy 154.344794 -98.8591)
			(xy 154.305143 -98.832697) (xy 154.26127 -98.814139) (xy 154.214709 -98.804073) (xy 154.167088 -98.802853)
			(xy 154.120072 -98.81052) (xy 154.075306 -98.826806) (xy 154.054556 -98.838512) (xy 154.030487 -98.852174)
			(xy 153.979337 -98.873296) (xy 153.925671 -98.886806) (xy 153.870617 -98.892419) (xy 153.815329 -98.890018)
			(xy 153.760968 -98.879654) (xy 153.708675 -98.861543) (xy 153.659548 -98.836067) (xy 153.614618 -98.803759)
			(xy 153.574828 -98.765298) (xy 153.541013 -98.721491) (xy 153.513882 -98.673258) (xy 153.494006 -98.621611)
			(xy 153.481801 -98.567633) (xy 153.477524 -98.512459) (xy 148.518963 -98.512459) (xy 148.968206 -98.961702)
			(xy 152.35682 -98.961702) (xy 152.35936 -98.958908) (xy 153.25344 -98.958908) (xy 154.046428 -99.751896)
			(xy 154.05227 -99.756468) (xy 154.06944 -99.770461) (xy 154.10076 -99.801783) (xy 154.114754 -99.818952)
			(xy 154.119326 -99.824794) (xy 154.148282 -99.85375) (xy 154.1604 -99.865189) (xy 154.189239 -99.881865)
			(xy 154.221414 -99.890497) (xy 154.254728 -99.890497) (xy 154.286903 -99.881865) (xy 154.315742 -99.865189)
			(xy 154.32786 -99.85375) (xy 154.345132 -99.836224) (xy 154.354784 -99.813872) (xy 154.364959 -99.790993)
			(xy 154.390442 -99.74789) (xy 154.421348 -99.708493) (xy 154.457144 -99.67348) (xy 154.476958 -99.65817)
			(xy 154.499326 -99.642014) (xy 154.547784 -99.615627) (xy 154.599537 -99.596494) (xy 154.653506 -99.585016)
			(xy 154.708566 -99.58143) (xy 154.763568 -99.585813) (xy 154.817366 -99.598071) (xy 154.868836 -99.617951)
			(xy 154.916907 -99.645037) (xy 154.960575 -99.678764) (xy 154.99893 -99.71843) (xy 155.031172 -99.763206)
			(xy 155.056629 -99.812159) (xy 155.074769 -99.864268) (xy 155.080478 -99.893882) (xy 164.042342 -99.893882)
			(xy 164.046413 -99.83826) (xy 164.058539 -99.783823) (xy 164.078462 -99.731732) (xy 164.105758 -99.683097)
			(xy 164.139844 -99.638954) (xy 164.179993 -99.600245) (xy 164.225351 -99.567794) (xy 164.274951 -99.542293)
			(xy 164.327735 -99.524286) (xy 164.382578 -99.514156) (xy 164.438312 -99.512119) (xy 164.493749 -99.518219)
			(xy 164.547706 -99.532325) (xy 164.599035 -99.554137) (xy 164.646641 -99.583191) (xy 164.689509 -99.618866)
			(xy 164.726726 -99.660403) (xy 164.757499 -99.706916) (xy 164.781171 -99.757413) (xy 164.797239 -99.81082)
			(xy 164.805359 -99.865996) (xy 164.805868 -99.893882) (xy 164.805359 -99.921768) (xy 164.797239 -99.976944)
			(xy 164.781171 -100.030351) (xy 164.757499 -100.080848) (xy 164.726726 -100.127361) (xy 164.689509 -100.168898)
			(xy 164.646641 -100.204573) (xy 164.599035 -100.233627) (xy 164.547706 -100.255439) (xy 164.493749 -100.269545)
			(xy 164.438312 -100.275645) (xy 164.382578 -100.273608) (xy 164.327735 -100.263478) (xy 164.274951 -100.245471)
			(xy 164.225351 -100.21997) (xy 164.179993 -100.187519) (xy 164.139844 -100.14881) (xy 164.105758 -100.104667)
			(xy 164.078462 -100.056032) (xy 164.058539 -100.003941) (xy 164.046413 -99.949504) (xy 164.042342 -99.893882)
			(xy 155.080478 -99.893882) (xy 155.085214 -99.918447) (xy 155.087747 -99.973565) (xy 155.085542 -100.00107)
			(xy 155.082381 -100.028075) (xy 155.069392 -100.080871) (xy 155.049043 -100.13129) (xy 155.021746 -100.178311)
			(xy 154.988052 -100.220982) (xy 154.968702 -100.240084) (xy 154.951953 -100.256758) (xy 154.924347 -100.295112)
			(xy 154.9043 -100.337906) (xy 154.894356 -100.376482) (xy 169.655742 -100.376482) (xy 169.659813 -100.32086)
			(xy 169.671939 -100.266423) (xy 169.691862 -100.214332) (xy 169.719158 -100.165697) (xy 169.753244 -100.121554)
			(xy 169.793393 -100.082845) (xy 169.838751 -100.050394) (xy 169.888351 -100.024893) (xy 169.941135 -100.006886)
			(xy 169.995978 -99.996756) (xy 170.051712 -99.994719) (xy 170.107149 -100.000819) (xy 170.161106 -100.014925)
			(xy 170.212435 -100.036737) (xy 170.260041 -100.065791) (xy 170.302909 -100.101466) (xy 170.340126 -100.143003)
			(xy 170.370899 -100.189516) (xy 170.394571 -100.240013) (xy 170.410639 -100.29342) (xy 170.418759 -100.348596)
			(xy 170.419268 -100.376482) (xy 170.418759 -100.404368) (xy 170.410639 -100.459544) (xy 170.394571 -100.512951)
			(xy 170.370899 -100.563448) (xy 170.340126 -100.609961) (xy 170.302909 -100.651498) (xy 170.260041 -100.687173)
			(xy 170.212435 -100.716227) (xy 170.161106 -100.738039) (xy 170.107149 -100.752145) (xy 170.051712 -100.758245)
			(xy 169.995978 -100.756208) (xy 169.941135 -100.746078) (xy 169.888351 -100.728071) (xy 169.838751 -100.70257)
			(xy 169.793393 -100.670119) (xy 169.753244 -100.63141) (xy 169.719158 -100.587267) (xy 169.691862 -100.538632)
			(xy 169.671939 -100.486541) (xy 169.659813 -100.432104) (xy 169.655742 -100.376482) (xy 154.894356 -100.376482)
			(xy 154.892504 -100.383666) (xy 154.889362 -100.430817) (xy 154.894985 -100.477738) (xy 154.909178 -100.522812)
			(xy 154.931453 -100.564489) (xy 154.945842 -100.583238) (xy 154.963823 -100.605613) (xy 154.993542 -100.65472)
			(xy 155.005024 -100.681028) (xy 155.01239 -100.700332) (xy 155.022042 -100.72751) (xy 155.083764 -100.789232)
			(xy 155.084018 -100.789486) (xy 155.09452 -100.799464) (xy 155.119071 -100.814826) (xy 155.146459 -100.824243)
			(xy 155.175266 -100.827228) (xy 155.189682 -100.825808) (xy 155.218638 -100.821998) (xy 155.267914 -100.78974)
			(xy 155.2829 -100.76434) (xy 155.296625 -100.742109) (xy 155.329215 -100.701273) (xy 155.36707 -100.665265)
			(xy 155.409483 -100.634756) (xy 155.455661 -100.610318) (xy 155.504741 -100.592406) (xy 155.555806 -100.581357)
			(xy 155.6079 -100.577377) (xy 155.66005 -100.580539) (xy 155.685744 -100.58527) (xy 155.712639 -100.591144)
			(xy 155.764506 -100.609593) (xy 155.813181 -100.635307) (xy 155.857655 -100.66775) (xy 155.897003 -100.70625)
			(xy 155.930408 -100.750006) (xy 155.957176 -100.798109) (xy 155.976751 -100.849561) (xy 155.988726 -100.903293)
			(xy 155.992853 -100.958188) (xy 155.989046 -101.013106) (xy 155.977384 -101.066906) (xy 155.958109 -101.118471)
			(xy 155.931621 -101.16673) (xy 155.898472 -101.21068) (xy 155.879292 -101.23043) (xy 155.864303 -101.246531)
			(xy 155.83954 -101.282884) (xy 155.8214 -101.322955) (xy 155.810422 -101.365549) (xy 155.806934 -101.409396)
			(xy 155.81104 -101.45319) (xy 155.822617 -101.495625) (xy 155.841321 -101.535436) (xy 155.866593 -101.571436)
			(xy 155.881832 -101.5873) (xy 155.915614 -101.621082) (xy 164.042342 -101.621082) (xy 164.046413 -101.56546)
			(xy 164.058539 -101.511023) (xy 164.078462 -101.458932) (xy 164.105758 -101.410297) (xy 164.139844 -101.366154)
			(xy 164.179993 -101.327445) (xy 164.225351 -101.294994) (xy 164.274951 -101.269493) (xy 164.327735 -101.251486)
			(xy 164.382578 -101.241356) (xy 164.438312 -101.239319) (xy 164.493749 -101.245419) (xy 164.547706 -101.259525)
			(xy 164.599035 -101.281337) (xy 164.646641 -101.310391) (xy 164.689509 -101.346066) (xy 164.726726 -101.387603)
			(xy 164.757499 -101.434116) (xy 164.781171 -101.484613) (xy 164.797239 -101.53802) (xy 164.805359 -101.593196)
			(xy 164.805868 -101.621082) (xy 164.805359 -101.648968) (xy 164.797239 -101.704144) (xy 164.781171 -101.757551)
			(xy 164.757499 -101.808048) (xy 164.726726 -101.854561) (xy 164.689509 -101.896098) (xy 164.646641 -101.931773)
			(xy 164.599035 -101.960827) (xy 164.547706 -101.982639) (xy 164.493749 -101.996745) (xy 164.438312 -102.002845)
			(xy 164.382578 -102.000808) (xy 164.327735 -101.990678) (xy 164.274951 -101.972671) (xy 164.225351 -101.94717)
			(xy 164.179993 -101.914719) (xy 164.139844 -101.87601) (xy 164.105758 -101.831867) (xy 164.078462 -101.783232)
			(xy 164.058539 -101.731141) (xy 164.046413 -101.676704) (xy 164.042342 -101.621082) (xy 155.915614 -101.621082)
			(xy 156.00934 -101.714808) (xy 156.00934 -102.08133) (xy 156.00299 -102.08768) (xy 155.98394 -102.144576)
			(xy 155.988258 -102.174548) (xy 155.991799 -102.202356) (xy 155.991654 -102.258411) (xy 155.983307 -102.313842)
			(xy 155.966936 -102.367454) (xy 155.942895 -102.418092) (xy 155.911701 -102.464667) (xy 155.874026 -102.506174)
			(xy 155.830682 -102.54172) (xy 155.806902 -102.556564) (xy 155.7782 -102.573836) (xy 155.74518 -102.632002)
			(xy 155.74518 -102.861997) (xy 159.813507 -102.861997) (xy 159.819019 -102.806401) (xy 159.832579 -102.752203)
			(xy 159.853897 -102.700562) (xy 159.882518 -102.652581) (xy 159.917828 -102.609286) (xy 159.959075 -102.571603)
			(xy 160.005375 -102.540337) (xy 160.05574 -102.516157) (xy 160.109092 -102.499579) (xy 160.164291 -102.490958)
			(xy 160.220158 -102.490478) (xy 160.275497 -102.498149) (xy 160.302448 -102.50551) (xy 160.323827 -102.511218)
			(xy 160.367809 -102.51603) (xy 160.41196 -102.513154) (xy 160.454947 -102.502678) (xy 160.49547 -102.484918)
			(xy 160.532307 -102.46041) (xy 160.564345 -102.429894) (xy 160.590615 -102.394293) (xy 160.600898 -102.3747)
			(xy 160.613808 -102.349852) (xy 160.645743 -102.303858) (xy 160.684057 -102.263026) (xy 160.727927 -102.228231)
			(xy 160.776411 -102.200221) (xy 160.828468 -102.179597) (xy 160.88298 -102.166803) (xy 160.938777 -102.162113)
			(xy 160.99466 -102.165627) (xy 161.04943 -102.177271) (xy 161.101909 -102.196794) (xy 161.126678 -102.209854)
			(xy 161.147815 -102.220777) (xy 161.193058 -102.23548) (xy 161.240246 -102.241512) (xy 161.287732 -102.238662)
			(xy 161.33386 -102.22703) (xy 161.377019 -102.207021) (xy 161.415704 -102.179335) (xy 161.448564 -102.144936)
			(xy 161.461958 -102.125272) (xy 161.477408 -102.102302) (xy 161.5139 -102.060677) (xy 161.556025 -102.024762)
			(xy 161.602896 -101.995311) (xy 161.653532 -101.972942) (xy 161.706868 -101.958125) (xy 161.761786 -101.951171)
			(xy 161.817133 -101.952226) (xy 161.871746 -101.961267) (xy 161.924479 -101.978105) (xy 161.974226 -102.002386)
			(xy 162.019942 -102.033602) (xy 162.060667 -102.071095) (xy 162.095547 -102.11408) (xy 162.12385 -102.161654)
			(xy 162.14498 -102.212819) (xy 162.158496 -102.2665) (xy 162.162615 -102.306882) (xy 169.681142 -102.306882)
			(xy 169.685213 -102.25126) (xy 169.697339 -102.196823) (xy 169.717262 -102.144732) (xy 169.744558 -102.096097)
			(xy 169.778644 -102.051954) (xy 169.818793 -102.013245) (xy 169.864151 -101.980794) (xy 169.913751 -101.955293)
			(xy 169.966535 -101.937286) (xy 170.021378 -101.927156) (xy 170.077112 -101.925119) (xy 170.132549 -101.931219)
			(xy 170.186506 -101.945325) (xy 170.237835 -101.967137) (xy 170.285441 -101.996191) (xy 170.328309 -102.031866)
			(xy 170.365526 -102.073403) (xy 170.396299 -102.119916) (xy 170.419971 -102.170413) (xy 170.436039 -102.22382)
			(xy 170.444159 -102.278996) (xy 170.444668 -102.306882) (xy 170.444159 -102.334768) (xy 170.436039 -102.389944)
			(xy 170.419971 -102.443351) (xy 170.396299 -102.493848) (xy 170.365526 -102.540361) (xy 170.328309 -102.581898)
			(xy 170.285441 -102.617573) (xy 170.237835 -102.646627) (xy 170.186506 -102.668439) (xy 170.132549 -102.682545)
			(xy 170.077112 -102.688645) (xy 170.021378 -102.686608) (xy 169.966535 -102.676478) (xy 169.913751 -102.658471)
			(xy 169.864151 -102.63297) (xy 169.818793 -102.600519) (xy 169.778644 -102.56181) (xy 169.744558 -102.517667)
			(xy 169.717262 -102.469032) (xy 169.697339 -102.416941) (xy 169.685213 -102.362504) (xy 169.681142 -102.306882)
			(xy 162.162615 -102.306882) (xy 162.164113 -102.321571) (xy 162.161712 -102.376875) (xy 162.151346 -102.431252)
			(xy 162.13323 -102.483561) (xy 162.107746 -102.532702) (xy 162.075428 -102.577645) (xy 162.036955 -102.617447)
			(xy 161.993135 -102.651271) (xy 161.944886 -102.678408) (xy 161.893223 -102.698288) (xy 161.839229 -102.710495)
			(xy 161.784038 -102.71477) (xy 161.728808 -102.711026) (xy 161.6747 -102.69934) (xy 161.622847 -102.679958)
			(xy 161.598356 -102.667054) (xy 161.577256 -102.656055) (xy 161.532002 -102.641359) (xy 161.484805 -102.635335)
			(xy 161.437311 -102.638195) (xy 161.391178 -102.649838) (xy 161.348015 -102.669858) (xy 161.309329 -102.697556)
			(xy 161.276469 -102.731967) (xy 161.263076 -102.751636) (xy 161.247925 -102.774165) (xy 161.212226 -102.81507)
			(xy 161.171091 -102.850504) (xy 161.125352 -102.879754) (xy 161.07593 -102.902229) (xy 161.050778 -102.909588)
			(xy 171.91595 -102.909588) (xy 171.920925 -102.855105) (xy 171.933632 -102.801892) (xy 171.95381 -102.751039)
			(xy 171.981045 -102.70359) (xy 172.014778 -102.660518) (xy 172.054318 -102.622706) (xy 172.098854 -102.59093)
			(xy 172.147472 -102.565841) (xy 172.199175 -102.547955) (xy 172.252903 -102.537637) (xy 172.307554 -102.5351)
			(xy 172.362007 -102.540395) (xy 172.415145 -102.553414) (xy 172.465878 -102.57389) (xy 172.513167 -102.601403)
			(xy 172.55604 -102.635389) (xy 172.593619 -102.67515) (xy 172.625133 -102.719872) (xy 172.649936 -102.768636)
			(xy 172.667519 -102.820444) (xy 172.677521 -102.874231) (xy 172.679737 -102.928896) (xy 172.674122 -102.983317)
			(xy 172.660791 -103.036378) (xy 172.640018 -103.08699) (xy 172.626528 -103.110792) (xy 172.619151 -103.124201)
			(xy 172.610407 -103.153523) (xy 172.608888 -103.184083) (xy 172.61468 -103.214127) (xy 172.627451 -103.241932)
			(xy 172.646469 -103.265901) (xy 172.658278 -103.275638) (xy 172.679614 -103.292766) (xy 172.717659 -103.332084)
			(xy 172.749698 -103.376433) (xy 172.775074 -103.424904) (xy 172.793265 -103.476503) (xy 172.803899 -103.530171)
			(xy 172.806758 -103.584808) (xy 172.801783 -103.639293) (xy 172.789075 -103.692509) (xy 172.768897 -103.743363)
			(xy 172.741661 -103.790814) (xy 172.707927 -103.833888) (xy 172.668385 -103.871701) (xy 172.623847 -103.903478)
			(xy 172.575227 -103.928567) (xy 172.523522 -103.946454) (xy 172.469792 -103.956771) (xy 172.415139 -103.959307)
			(xy 172.360685 -103.954011) (xy 172.307545 -103.94099) (xy 172.25681 -103.920512) (xy 172.209521 -103.892997)
			(xy 172.166647 -103.859009) (xy 172.129068 -103.819245) (xy 172.097554 -103.774521) (xy 172.072752 -103.725754)
			(xy 172.055171 -103.673944) (xy 172.04517 -103.620154) (xy 172.042956 -103.565488) (xy 172.048574 -103.511065)
			(xy 172.061907 -103.458003) (xy 172.082684 -103.40739) (xy 172.096176 -103.383588) (xy 172.103466 -103.370135)
			(xy 172.112222 -103.340829) (xy 172.113755 -103.310283) (xy 172.10798 -103.280248) (xy 172.095226 -103.252448)
			(xy 172.076226 -103.22848) (xy 172.064426 -103.218742) (xy 172.043085 -103.201623) (xy 172.005041 -103.162306)
			(xy 171.973004 -103.117957) (xy 171.94763 -103.069487) (xy 171.929441 -103.01789) (xy 171.918808 -102.964224)
			(xy 171.91595 -102.909588) (xy 161.050778 -102.909588) (xy 161.023822 -102.917475) (xy 160.97008 -102.925186)
			(xy 160.915788 -102.925205) (xy 160.862041 -102.917532) (xy 160.835848 -102.910386) (xy 160.81447 -102.904676)
			(xy 160.770487 -102.899865) (xy 160.726336 -102.902741) (xy 160.68335 -102.913218) (xy 160.642826 -102.930978)
			(xy 160.605989 -102.955486) (xy 160.573952 -102.986002) (xy 160.547681 -103.021603) (xy 160.537398 -103.041196)
			(xy 160.52458 -103.06602) (xy 160.492742 -103.111929) (xy 160.454551 -103.152705) (xy 160.410821 -103.187476)
			(xy 160.362489 -103.2155) (xy 160.310588 -103.236176) (xy 160.256226 -103.249063) (xy 160.200566 -103.253885)
			(xy 160.144798 -103.25054) (xy 160.090114 -103.239099) (xy 160.037682 -103.219806) (xy 159.988624 -103.193074)
			(xy 159.943988 -103.159475) (xy 159.904729 -103.119726) (xy 159.871685 -103.074677) (xy 159.845564 -103.025291)
			(xy 159.826923 -102.972624) (xy 159.81616 -102.917802) (xy 159.813507 -102.861997) (xy 155.74518 -102.861997)
			(xy 155.74518 -103.721662) (xy 156.847538 -103.721662) (xy 156.851609 -103.66604) (xy 156.863735 -103.611603)
			(xy 156.883658 -103.559512) (xy 156.910954 -103.510877) (xy 156.94504 -103.466734) (xy 156.985189 -103.428025)
			(xy 157.030547 -103.395574) (xy 157.080147 -103.370073) (xy 157.132931 -103.352066) (xy 157.187774 -103.341936)
			(xy 157.243508 -103.339899) (xy 157.298945 -103.345999) (xy 157.352902 -103.360105) (xy 157.404231 -103.381917)
			(xy 157.451837 -103.410971) (xy 157.494705 -103.446646) (xy 157.531922 -103.488183) (xy 157.562695 -103.534696)
			(xy 157.586367 -103.585193) (xy 157.602435 -103.6386) (xy 157.610555 -103.693776) (xy 157.611064 -103.721662)
			(xy 157.610925 -103.729282) (xy 164.067742 -103.729282) (xy 164.071813 -103.67366) (xy 164.083939 -103.619223)
			(xy 164.103862 -103.567132) (xy 164.131158 -103.518497) (xy 164.165244 -103.474354) (xy 164.205393 -103.435645)
			(xy 164.250751 -103.403194) (xy 164.300351 -103.377693) (xy 164.353135 -103.359686) (xy 164.407978 -103.349556)
			(xy 164.463712 -103.347519) (xy 164.519149 -103.353619) (xy 164.573106 -103.367725) (xy 164.624435 -103.389537)
			(xy 164.672041 -103.418591) (xy 164.714909 -103.454266) (xy 164.752126 -103.495803) (xy 164.782899 -103.542316)
			(xy 164.806571 -103.592813) (xy 164.822639 -103.64622) (xy 164.830759 -103.701396) (xy 164.831268 -103.729282)
			(xy 164.830804 -103.754682) (xy 165.947342 -103.754682) (xy 165.951413 -103.69906) (xy 165.963539 -103.644623)
			(xy 165.983462 -103.592532) (xy 166.010758 -103.543897) (xy 166.044844 -103.499754) (xy 166.084993 -103.461045)
			(xy 166.130351 -103.428594) (xy 166.179951 -103.403093) (xy 166.232735 -103.385086) (xy 166.287578 -103.374956)
			(xy 166.343312 -103.372919) (xy 166.398749 -103.379019) (xy 166.452706 -103.393125) (xy 166.504035 -103.414937)
			(xy 166.551641 -103.443991) (xy 166.594509 -103.479666) (xy 166.631726 -103.521203) (xy 166.662499 -103.567716)
			(xy 166.686171 -103.618213) (xy 166.702239 -103.67162) (xy 166.710359 -103.726796) (xy 166.710404 -103.729282)
			(xy 167.750742 -103.729282) (xy 167.754813 -103.67366) (xy 167.766939 -103.619223) (xy 167.786862 -103.567132)
			(xy 167.814158 -103.518497) (xy 167.848244 -103.474354) (xy 167.888393 -103.435645) (xy 167.933751 -103.403194)
			(xy 167.983351 -103.377693) (xy 168.036135 -103.359686) (xy 168.090978 -103.349556) (xy 168.146712 -103.347519)
			(xy 168.202149 -103.353619) (xy 168.256106 -103.367725) (xy 168.307435 -103.389537) (xy 168.355041 -103.418591)
			(xy 168.397909 -103.454266) (xy 168.435126 -103.495803) (xy 168.465899 -103.542316) (xy 168.489571 -103.592813)
			(xy 168.505639 -103.64622) (xy 168.513759 -103.701396) (xy 168.514268 -103.729282) (xy 168.513804 -103.754682)
			(xy 169.655742 -103.754682) (xy 169.659813 -103.69906) (xy 169.671939 -103.644623) (xy 169.691862 -103.592532)
			(xy 169.719158 -103.543897) (xy 169.753244 -103.499754) (xy 169.793393 -103.461045) (xy 169.838751 -103.428594)
			(xy 169.888351 -103.403093) (xy 169.941135 -103.385086) (xy 169.995978 -103.374956) (xy 170.051712 -103.372919)
			(xy 170.107149 -103.379019) (xy 170.161106 -103.393125) (xy 170.212435 -103.414937) (xy 170.260041 -103.443991)
			(xy 170.302909 -103.479666) (xy 170.340126 -103.521203) (xy 170.370899 -103.567716) (xy 170.394571 -103.618213)
			(xy 170.410639 -103.67162) (xy 170.418759 -103.726796) (xy 170.419268 -103.754682) (xy 170.418759 -103.782568)
			(xy 170.410639 -103.837744) (xy 170.394571 -103.891151) (xy 170.370899 -103.941648) (xy 170.340126 -103.988161)
			(xy 170.302909 -104.029698) (xy 170.260041 -104.065373) (xy 170.212435 -104.094427) (xy 170.161106 -104.116239)
			(xy 170.107149 -104.130345) (xy 170.051712 -104.136445) (xy 169.995978 -104.134408) (xy 169.941135 -104.124278)
			(xy 169.888351 -104.106271) (xy 169.838751 -104.08077) (xy 169.793393 -104.048319) (xy 169.753244 -104.00961)
			(xy 169.719158 -103.965467) (xy 169.691862 -103.916832) (xy 169.671939 -103.864741) (xy 169.659813 -103.810304)
			(xy 169.655742 -103.754682) (xy 168.513804 -103.754682) (xy 168.513759 -103.757168) (xy 168.505639 -103.812344)
			(xy 168.489571 -103.865751) (xy 168.465899 -103.916248) (xy 168.435126 -103.962761) (xy 168.397909 -104.004298)
			(xy 168.355041 -104.039973) (xy 168.307435 -104.069027) (xy 168.256106 -104.090839) (xy 168.202149 -104.104945)
			(xy 168.146712 -104.111045) (xy 168.090978 -104.109008) (xy 168.036135 -104.098878) (xy 167.983351 -104.080871)
			(xy 167.933751 -104.05537) (xy 167.888393 -104.022919) (xy 167.848244 -103.98421) (xy 167.814158 -103.940067)
			(xy 167.786862 -103.891432) (xy 167.766939 -103.839341) (xy 167.754813 -103.784904) (xy 167.750742 -103.729282)
			(xy 166.710404 -103.729282) (xy 166.710868 -103.754682) (xy 166.710359 -103.782568) (xy 166.702239 -103.837744)
			(xy 166.686171 -103.891151) (xy 166.662499 -103.941648) (xy 166.631726 -103.988161) (xy 166.594509 -104.029698)
			(xy 166.551641 -104.065373) (xy 166.504035 -104.094427) (xy 166.452706 -104.116239) (xy 166.398749 -104.130345)
			(xy 166.343312 -104.136445) (xy 166.287578 -104.134408) (xy 166.232735 -104.124278) (xy 166.179951 -104.106271)
			(xy 166.130351 -104.08077) (xy 166.084993 -104.048319) (xy 166.044844 -104.00961) (xy 166.010758 -103.965467)
			(xy 165.983462 -103.916832) (xy 165.963539 -103.864741) (xy 165.951413 -103.810304) (xy 165.947342 -103.754682)
			(xy 164.830804 -103.754682) (xy 164.830759 -103.757168) (xy 164.822639 -103.812344) (xy 164.806571 -103.865751)
			(xy 164.782899 -103.916248) (xy 164.752126 -103.962761) (xy 164.714909 -104.004298) (xy 164.672041 -104.039973)
			(xy 164.624435 -104.069027) (xy 164.573106 -104.090839) (xy 164.519149 -104.104945) (xy 164.463712 -104.111045)
			(xy 164.407978 -104.109008) (xy 164.353135 -104.098878) (xy 164.300351 -104.080871) (xy 164.250751 -104.05537)
			(xy 164.205393 -104.022919) (xy 164.165244 -103.98421) (xy 164.131158 -103.940067) (xy 164.103862 -103.891432)
			(xy 164.083939 -103.839341) (xy 164.071813 -103.784904) (xy 164.067742 -103.729282) (xy 157.610925 -103.729282)
			(xy 157.610555 -103.749548) (xy 157.602435 -103.804724) (xy 157.586367 -103.858131) (xy 157.562695 -103.908628)
			(xy 157.531922 -103.955141) (xy 157.494705 -103.996678) (xy 157.451837 -104.032353) (xy 157.404231 -104.061407)
			(xy 157.352902 -104.083219) (xy 157.298945 -104.097325) (xy 157.243508 -104.103425) (xy 157.187774 -104.101388)
			(xy 157.132931 -104.091258) (xy 157.080147 -104.073251) (xy 157.030547 -104.04775) (xy 156.985189 -104.015299)
			(xy 156.94504 -103.97659) (xy 156.910954 -103.932447) (xy 156.883658 -103.883812) (xy 156.863735 -103.831721)
			(xy 156.851609 -103.777284) (xy 156.847538 -103.721662) (xy 155.74518 -103.721662) (xy 155.74518 -104.128356)
			(xy 159.813727 -104.128356) (xy 159.81968 -104.073316) (xy 159.833525 -104.019715) (xy 159.854971 -103.968678)
			(xy 159.88357 -103.921276) (xy 159.91872 -103.878506) (xy 159.959682 -103.841266) (xy 160.005597 -103.810337)
			(xy 160.0555 -103.786369) (xy 160.108343 -103.769866) (xy 160.163017 -103.761174) (xy 160.218373 -103.760476)
			(xy 160.273249 -103.767786) (xy 160.326491 -103.782951) (xy 160.376983 -103.805653) (xy 160.423663 -103.835414)
			(xy 160.465552 -103.871609) (xy 160.501769 -103.913479) (xy 160.517078 -103.936546) (xy 160.529055 -103.954427)
			(xy 160.558025 -103.986249) (xy 160.59194 -104.01274) (xy 160.62983 -104.033143) (xy 160.670614 -104.046875)
			(xy 160.713128 -104.053544) (xy 160.756159 -104.05296) (xy 160.798476 -104.045139) (xy 160.81883 -104.038146)
			(xy 160.84309 -104.029682) (xy 160.893262 -104.018597) (xy 160.944467 -104.014346) (xy 160.995779 -104.017005)
			(xy 161.046271 -104.026526) (xy 161.095028 -104.042737) (xy 161.141168 -104.065344) (xy 161.162746 -104.079294)
			(xy 161.18185 -104.091486) (xy 161.223372 -104.109632) (xy 161.267452 -104.120133) (xy 161.312696 -104.122656)
			(xy 161.357671 -104.117121) (xy 161.400953 -104.103705) (xy 161.441173 -104.082831) (xy 161.459418 -104.069388)
			(xy 161.481845 -104.052729) (xy 161.530543 -104.025356) (xy 161.582711 -104.005377) (xy 161.637236 -103.993219)
			(xy 161.692951 -103.989142) (xy 161.748665 -103.993234) (xy 161.803186 -104.005406) (xy 161.85535 -104.025399)
			(xy 161.90404 -104.052785) (xy 161.948216 -104.086979) (xy 161.986934 -104.127249) (xy 162.019365 -104.172735)
			(xy 162.044817 -104.222464) (xy 162.062745 -104.275373) (xy 162.072766 -104.33033) (xy 162.074665 -104.386162)
			(xy 162.068402 -104.441673) (xy 162.054111 -104.495678) (xy 162.032098 -104.547022) (xy 162.002832 -104.594606)
			(xy 161.96694 -104.637414) (xy 161.92519 -104.674531) (xy 161.878473 -104.705162) (xy 161.827789 -104.728654)
			(xy 161.77422 -104.744503) (xy 161.718914 -104.752371) (xy 161.663051 -104.75209) (xy 161.607826 -104.743665)
			(xy 161.55442 -104.727278) (xy 161.503974 -104.703277) (xy 161.4805 -104.688132) (xy 161.461371 -104.675981)
			(xy 161.419856 -104.657829) (xy 161.375781 -104.647322) (xy 161.330542 -104.644792) (xy 161.285571 -104.650319)
			(xy 161.242291 -104.66373) (xy 161.202073 -104.684598) (xy 161.183828 -104.698038) (xy 161.160697 -104.715237)
			(xy 161.11032 -104.743245) (xy 161.056304 -104.763355) (xy 160.999877 -104.77511) (xy 160.942323 -104.778242)
			(xy 160.884953 -104.77268) (xy 160.829074 -104.75855) (xy 160.775956 -104.736174) (xy 160.726808 -104.706061)
			(xy 160.682751 -104.668897) (xy 160.644786 -104.625528) (xy 160.628838 -104.601518) (xy 160.616828 -104.583659)
			(xy 160.587866 -104.551832) (xy 160.553959 -104.525337) (xy 160.516073 -104.50493) (xy 160.475293 -104.491195)
			(xy 160.432782 -104.484523) (xy 160.389754 -104.485105) (xy 160.347439 -104.492925) (xy 160.327086 -104.499918)
			(xy 160.300924 -104.508974) (xy 160.246746 -104.520356) (xy 160.191492 -104.523788) (xy 160.136323 -104.519198)
			(xy 160.082396 -104.506681) (xy 160.030844 -104.486502) (xy 159.982751 -104.459083) (xy 159.939125 -104.425001)
			(xy 159.900884 -104.384972) (xy 159.86883 -104.339835) (xy 159.843637 -104.290539) (xy 159.825833 -104.23812)
			(xy 159.815793 -104.183677) (xy 159.813727 -104.128356) (xy 155.74518 -104.128356) (xy 155.74518 -105.978017)
			(xy 164.335165 -105.978017) (xy 164.338541 -105.923381) (xy 164.34969 -105.869789) (xy 164.368384 -105.81834)
			(xy 164.394238 -105.770091) (xy 164.426722 -105.726031) (xy 164.465169 -105.687067) (xy 164.50879 -105.653996)
			(xy 164.556689 -105.627499) (xy 164.607883 -105.608119) (xy 164.661322 -105.596254) (xy 164.715907 -105.592148)
			(xy 164.770519 -105.595885) (xy 164.824036 -105.607388) (xy 164.875361 -105.626421) (xy 164.923438 -105.652593)
			(xy 164.967282 -105.685367) (xy 164.98697 -105.704386) (xy 164.998135 -105.71488) (xy 165.024336 -105.730745)
			(xy 165.053567 -105.739893) (xy 165.084138 -105.741795) (xy 165.114278 -105.73634) (xy 165.142243 -105.723845)
			(xy 165.15461 -105.7148) (xy 165.176523 -105.698408) (xy 165.22406 -105.671303) (xy 165.274981 -105.651268)
			(xy 165.328243 -105.638716) (xy 165.382752 -105.633904) (xy 165.43739 -105.63693) (xy 165.491034 -105.647734)
			(xy 165.542584 -105.666092) (xy 165.590981 -105.691628) (xy 165.635233 -105.723818) (xy 165.67443 -105.762002)
			(xy 165.707769 -105.805395) (xy 165.734564 -105.853106) (xy 165.754267 -105.904157) (xy 165.766472 -105.9575)
			(xy 165.770929 -106.012039) (xy 165.767547 -106.066656) (xy 165.756394 -106.120229) (xy 165.737701 -106.171658)
			(xy 165.732357 -106.181628) (xy 168.191311 -106.181628) (xy 168.193825 -106.126957) (xy 168.204126 -106.073206)
			(xy 168.222003 -106.021479) (xy 168.247087 -105.972837) (xy 168.278865 -105.928278) (xy 168.316683 -105.888718)
			(xy 168.359767 -105.854968) (xy 168.407231 -105.827721) (xy 168.458101 -105.807536) (xy 168.511334 -105.794827)
			(xy 168.565837 -105.789855) (xy 168.620491 -105.792723) (xy 168.674174 -105.80337) (xy 168.725785 -105.82158)
			(xy 168.774264 -105.846978) (xy 168.796716 -105.862628) (xy 168.809389 -105.871282) (xy 168.837812 -105.882831)
			(xy 168.868172 -105.887248) (xy 168.898707 -105.884279) (xy 168.927647 -105.874094) (xy 168.953313 -105.857286)
			(xy 168.964102 -105.846372) (xy 168.983074 -105.82665) (xy 169.025717 -105.792352) (xy 169.072823 -105.764498)
			(xy 169.123426 -105.743661) (xy 169.176487 -105.730269) (xy 169.230917 -105.724596) (xy 169.285599 -105.726759)
			(xy 169.339411 -105.736713) (xy 169.391249 -105.754254) (xy 169.440048 -105.779023) (xy 169.484807 -105.81051)
			(xy 169.496701 -105.821734) (xy 170.653454 -105.821734) (xy 170.657525 -105.766112) (xy 170.669651 -105.711675)
			(xy 170.689574 -105.659584) (xy 170.71687 -105.610949) (xy 170.750956 -105.566806) (xy 170.791105 -105.528097)
			(xy 170.836463 -105.495646) (xy 170.886063 -105.470145) (xy 170.938847 -105.452138) (xy 170.99369 -105.442008)
			(xy 171.049424 -105.439971) (xy 171.104861 -105.446071) (xy 171.158818 -105.460177) (xy 171.210147 -105.481989)
			(xy 171.257753 -105.511043) (xy 171.300621 -105.546718) (xy 171.337838 -105.588255) (xy 171.368611 -105.634768)
			(xy 171.392283 -105.685265) (xy 171.408351 -105.738672) (xy 171.416471 -105.793848) (xy 171.41698 -105.821734)
			(xy 171.416471 -105.84962) (xy 171.408351 -105.904796) (xy 171.392283 -105.958203) (xy 171.368611 -106.0087)
			(xy 171.337838 -106.055213) (xy 171.300621 -106.09675) (xy 171.257753 -106.132425) (xy 171.210147 -106.161479)
			(xy 171.158818 -106.183291) (xy 171.104861 -106.197397) (xy 171.049424 -106.203497) (xy 170.99369 -106.20146)
			(xy 170.938847 -106.19133) (xy 170.886063 -106.173323) (xy 170.836463 -106.147822) (xy 170.791105 -106.115371)
			(xy 170.750956 -106.076662) (xy 170.71687 -106.032519) (xy 170.689574 -105.983884) (xy 170.669651 -105.931793)
			(xy 170.657525 -105.877356) (xy 170.653454 -105.821734) (xy 169.496701 -105.821734) (xy 169.524608 -105.848069)
			(xy 169.558633 -105.89093) (xy 169.586185 -105.938214) (xy 169.606697 -105.988949) (xy 169.61975 -106.042094)
			(xy 169.625075 -106.09656) (xy 169.622562 -106.151227) (xy 169.612264 -106.204974) (xy 169.594392 -106.256698)
			(xy 169.569312 -106.305338) (xy 169.537539 -106.349895) (xy 169.499726 -106.389454) (xy 169.456648 -106.423205)
			(xy 169.409189 -106.450453) (xy 169.358324 -106.470641) (xy 169.305096 -106.483354) (xy 169.250598 -106.48833)
			(xy 169.195948 -106.485468) (xy 169.142267 -106.474826) (xy 169.090659 -106.456623) (xy 169.04218 -106.431233)
			(xy 169.019728 -106.415586) (xy 169.007028 -106.406974) (xy 168.978614 -106.39542) (xy 168.948261 -106.390995)
			(xy 168.917731 -106.393956) (xy 168.888794 -106.404132) (xy 168.86313 -106.420931) (xy 168.852342 -106.431842)
			(xy 168.833349 -106.451547) (xy 168.790705 -106.485851) (xy 168.743596 -106.513708) (xy 168.69299 -106.534548)
			(xy 168.639926 -106.547943) (xy 168.585492 -106.553618) (xy 168.530806 -106.551456) (xy 168.47699 -106.541502)
			(xy 168.425148 -106.52396) (xy 168.376345 -106.49919) (xy 168.331583 -106.467701) (xy 168.29178 -106.430138)
			(xy 168.257752 -106.387273) (xy 168.230199 -106.339986) (xy 168.209686 -106.289247) (xy 168.196634 -106.236097)
			(xy 168.191311 -106.181628) (xy 165.732357 -106.181628) (xy 165.71185 -106.219888) (xy 165.679372 -106.263929)
			(xy 165.640934 -106.302877) (xy 165.597325 -106.335932) (xy 165.54944 -106.362416) (xy 165.498262 -106.381786)
			(xy 165.444841 -106.393643) (xy 165.390273 -106.397745) (xy 165.33568 -106.394007) (xy 165.282181 -106.382506)
			(xy 165.230875 -106.363478) (xy 165.182814 -106.337314) (xy 165.138986 -106.30455) (xy 165.119304 -106.285538)
			(xy 165.108161 -106.275021) (xy 165.081952 -106.259166) (xy 165.052716 -106.250027) (xy 165.022143 -106.24813)
			(xy 164.992001 -106.253587) (xy 164.964034 -106.266081) (xy 164.951664 -106.275124) (xy 164.929822 -106.291623)
			(xy 164.882277 -106.31875) (xy 164.831343 -106.338805) (xy 164.778066 -106.351374) (xy 164.72354 -106.356201)
			(xy 164.668883 -106.353186) (xy 164.615219 -106.342392) (xy 164.563647 -106.324038) (xy 164.515228 -106.298503)
			(xy 164.470955 -106.266311) (xy 164.431738 -106.228122) (xy 164.39838 -106.184721) (xy 164.371567 -106.136998)
			(xy 164.351849 -106.085932) (xy 164.339632 -106.032574) (xy 164.335165 -105.978017) (xy 155.74518 -105.978017)
			(xy 155.74518 -106.7816) (xy 157.453328 -106.7816) (xy 157.457399 -106.725978) (xy 157.469525 -106.671541)
			(xy 157.489448 -106.61945) (xy 157.516744 -106.570815) (xy 157.55083 -106.526672) (xy 157.590979 -106.487963)
			(xy 157.636337 -106.455512) (xy 157.685937 -106.430011) (xy 157.738721 -106.412004) (xy 157.793564 -106.401874)
			(xy 157.849298 -106.399837) (xy 157.904735 -106.405937) (xy 157.958692 -106.420043) (xy 158.010021 -106.441855)
			(xy 158.057627 -106.470909) (xy 158.100495 -106.506584) (xy 158.137712 -106.548121) (xy 158.168485 -106.594634)
			(xy 158.192157 -106.645131) (xy 158.208225 -106.698538) (xy 158.216345 -106.753714) (xy 158.216854 -106.7816)
			(xy 158.216345 -106.809486) (xy 158.208225 -106.864662) (xy 158.192157 -106.918069) (xy 158.168485 -106.968566)
			(xy 158.137712 -107.015079) (xy 158.100495 -107.056616) (xy 158.057627 -107.092291) (xy 158.010021 -107.121345)
			(xy 157.958692 -107.143157) (xy 157.904735 -107.157263) (xy 157.849298 -107.163363) (xy 157.793564 -107.161326)
			(xy 157.738721 -107.151196) (xy 157.685937 -107.133189) (xy 157.636337 -107.107688) (xy 157.590979 -107.075237)
			(xy 157.55083 -107.036528) (xy 157.516744 -106.992385) (xy 157.489448 -106.94375) (xy 157.469525 -106.891659)
			(xy 157.457399 -106.837222) (xy 157.453328 -106.7816) (xy 155.74518 -106.7816) (xy 155.74518 -107.306364)
			(xy 155.962858 -107.524042) (xy 155.974974 -107.535496) (xy 156.003815 -107.552204) (xy 156.036 -107.560871)
			(xy 156.069331 -107.560907) (xy 156.101534 -107.552308) (xy 156.130411 -107.535661) (xy 156.153991 -107.512103)
			(xy 156.170663 -107.483241) (xy 156.179292 -107.451046) (xy 156.179774 -107.43438) (xy 156.179774 -107.395772)
			(xy 156.1719 -107.374436) (xy 156.16356 -107.350864) (xy 156.152423 -107.302118) (xy 156.147757 -107.252334)
			(xy 156.149641 -107.202368) (xy 156.158045 -107.153077) (xy 156.165042 -107.129072) (xy 156.173649 -107.102842)
			(xy 156.197363 -107.05299) (xy 156.228014 -107.007077) (xy 156.264963 -106.966061) (xy 156.307437 -106.930797)
			(xy 156.354549 -106.902024) (xy 156.405317 -106.88034) (xy 156.458679 -106.8662) (xy 156.513523 -106.859898)
			(xy 156.568702 -106.861566) (xy 156.623065 -106.871169) (xy 156.675476 -106.888506) (xy 156.724841 -106.913216)
			(xy 156.747718 -106.928666) (xy 156.773118 -106.94797) (xy 156.79413 -106.966048) (xy 156.831217 -107.00724)
			(xy 156.861954 -107.053365) (xy 156.885693 -107.103452) (xy 156.901934 -107.156447) (xy 156.910336 -107.211235)
			(xy 156.910722 -107.266661) (xy 156.903083 -107.32156) (xy 156.887581 -107.374776) (xy 156.864542 -107.425189)
			(xy 156.83445 -107.471738) (xy 156.79794 -107.513442) (xy 156.755779 -107.549424) (xy 156.708856 -107.578927)
			(xy 156.68371 -107.59059) (xy 156.664186 -107.598902) (xy 156.623706 -107.611635) (xy 156.602938 -107.61599)
			(xy 156.581152 -107.621645) (xy 156.539866 -107.639563) (xy 156.502379 -107.66447) (xy 156.469862 -107.695586)
			(xy 156.443331 -107.731941) (xy 156.423614 -107.772398) (xy 156.411327 -107.815695) (xy 156.406853 -107.860478)
			(xy 156.410333 -107.90535) (xy 156.421658 -107.948908) (xy 156.440474 -107.989793) (xy 156.466193 -108.026727)
			(xy 156.48178 -108.042964) (xy 157.222698 -108.783882) (xy 159.99714 -108.783882) (xy 160.24606 -109.032802)
		)
		(stroke
			(width 0)
			(type solid)
		)
		(fill yes)
		(layer "In6.Cu")
		(net "P1V05_NODE1")
	)
	(gr_poly
		(pts
			(xy 163.615116 -93.257624) (xy 163.638257 -93.257114) (xy 163.683774 -93.248735) (xy 163.727022 -93.232256)
			(xy 163.766575 -93.208223) (xy 163.801124 -93.177428) (xy 163.82953 -93.140889) (xy 163.850854 -93.099812)
			(xy 163.864392 -93.055555) (xy 163.869696 -93.009578) (xy 163.866592 -92.963401) (xy 163.855182 -92.918548)
			(xy 163.835842 -92.8765) (xy 163.822888 -92.85732) (xy 163.806832 -92.835251) (xy 163.780523 -92.787435)
			(xy 163.761298 -92.736357) (xy 163.74955 -92.683061) (xy 163.745518 -92.628635) (xy 163.749284 -92.574189)
			(xy 163.760773 -92.520836) (xy 163.779749 -92.469666) (xy 163.805825 -92.421722) (xy 163.838468 -92.377985)
			(xy 163.877012 -92.339347) (xy 163.920669 -92.306598) (xy 163.968549 -92.280405) (xy 164.019673 -92.261304)
			(xy 164.072998 -92.249686) (xy 164.127434 -92.245786) (xy 164.18187 -92.249686) (xy 164.235195 -92.261304)
			(xy 164.286319 -92.280405) (xy 164.334199 -92.306598) (xy 164.377856 -92.339347) (xy 164.4164 -92.377985)
			(xy 164.449043 -92.421722) (xy 164.475119 -92.469666) (xy 164.494095 -92.520836) (xy 164.505584 -92.574189)
			(xy 164.50935 -92.628635) (xy 164.505318 -92.683061) (xy 164.49357 -92.736357) (xy 164.474345 -92.787435)
			(xy 164.448036 -92.835251) (xy 164.43198 -92.85732) (xy 164.419068 -92.876532) (xy 164.399704 -92.918569)
			(xy 164.388272 -92.963419) (xy 164.38515 -93.009597) (xy 164.390444 -93.055577) (xy 164.403976 -93.099838)
			(xy 164.4253 -93.140917) (xy 164.45371 -93.177455) (xy 164.488267 -93.208243) (xy 164.527829 -93.232265)
			(xy 164.571087 -93.248725) (xy 164.61661 -93.25708) (xy 164.639752 -93.257624) (xy 166.08044 -93.257624)
			(xy 166.097086 -93.257076) (xy 166.129242 -93.248452) (xy 166.158072 -93.231802) (xy 166.181611 -93.208259)
			(xy 166.198258 -93.179427) (xy 166.206878 -93.14727) (xy 166.20744 -93.130624) (xy 166.20744 -82.773266)
			(xy 166.206921 -82.756435) (xy 166.198126 -82.723943) (xy 166.181155 -82.694873) (xy 166.157184 -82.671241)
			(xy 166.127876 -82.654685) (xy 166.111682 -82.650076) (xy 166.101268 -82.647282) (xy 166.078056 -82.640301)
			(xy 166.033475 -82.621273) (xy 165.991656 -82.596763) (xy 165.972236 -82.582258) (xy 165.95361 -82.569525)
			(xy 165.912867 -82.550155) (xy 165.869344 -82.538284) (xy 165.824408 -82.534285) (xy 165.779472 -82.538284)
			(xy 165.735949 -82.550155) (xy 165.695206 -82.569525) (xy 165.67658 -82.582258) (xy 165.654574 -82.59865)
			(xy 165.606786 -82.62562) (xy 165.555628 -82.645465) (xy 165.502155 -82.657777) (xy 165.447469 -82.662301)
			(xy 165.392699 -82.658943) (xy 165.338975 -82.647773) (xy 165.287406 -82.629022) (xy 165.239055 -82.603076)
			(xy 165.19492 -82.57047) (xy 165.155912 -82.531878) (xy 165.122835 -82.488096) (xy 165.096372 -82.440026)
			(xy 165.077068 -82.388661) (xy 165.065323 -82.33506) (xy 165.061378 -82.280329) (xy 165.065314 -82.225598)
			(xy 165.077052 -82.171996) (xy 165.096347 -82.120627) (xy 165.122803 -82.072554) (xy 165.155873 -82.028766)
			(xy 165.194876 -81.990168) (xy 165.239006 -81.957556) (xy 165.287352 -81.931602) (xy 165.338919 -81.912843)
			(xy 165.392641 -81.901665) (xy 165.44741 -81.898299) (xy 165.502097 -81.902814) (xy 165.555572 -81.915117)
			(xy 165.606733 -81.934955) (xy 165.654525 -81.961918) (xy 165.67658 -81.978246) (xy 165.695206 -81.990979)
			(xy 165.735949 -82.010349) (xy 165.779472 -82.02222) (xy 165.824408 -82.026219) (xy 165.869344 -82.02222)
			(xy 165.912867 -82.010349) (xy 165.95361 -81.990979) (xy 165.972236 -81.978246) (xy 165.991649 -81.96373)
			(xy 166.033463 -81.939207) (xy 166.078051 -81.920189) (xy 166.101268 -81.913222) (xy 166.111682 -81.910428)
			(xy 166.12788 -81.905799) (xy 166.157231 -81.889289) (xy 166.181236 -81.86567) (xy 166.198219 -81.836589)
			(xy 166.206995 -81.804077) (xy 166.20744 -81.787238) (xy 166.20744 -81.506568) (xy 166.206944 -81.483521)
			(xy 166.198642 -81.438182) (xy 166.182298 -81.395083) (xy 166.158447 -81.35564) (xy 166.127873 -81.321146)
			(xy 166.091579 -81.292733) (xy 166.050754 -81.271333) (xy 166.006739 -81.257647) (xy 165.960978 -81.252126)
			(xy 165.937946 -81.253076) (xy 165.909431 -81.25518) (xy 165.852352 -81.251846) (xy 165.79641 -81.240028)
			(xy 165.74286 -81.219992) (xy 165.6929 -81.192186) (xy 165.669976 -81.175098) (xy 165.65135 -81.162365)
			(xy 165.610607 -81.142995) (xy 165.567084 -81.131124) (xy 165.522148 -81.127125) (xy 165.477212 -81.131124)
			(xy 165.433689 -81.142995) (xy 165.392946 -81.162365) (xy 165.37432 -81.175098) (xy 165.35231 -81.191494)
			(xy 165.304514 -81.218469) (xy 165.253347 -81.238319) (xy 165.199863 -81.250633) (xy 165.145167 -81.255157)
			(xy 165.090388 -81.251798) (xy 165.036654 -81.240626) (xy 164.985076 -81.22187) (xy 164.936716 -81.195918)
			(xy 164.892574 -81.163305) (xy 164.85356 -81.124705) (xy 164.820479 -81.080913) (xy 164.794013 -81.032833)
			(xy 164.774708 -80.981457) (xy 164.762964 -80.927846) (xy 164.759021 -80.873105) (xy 164.762962 -80.818364)
			(xy 164.774705 -80.764752) (xy 164.794009 -80.713376) (xy 164.820473 -80.665295) (xy 164.853554 -80.621503)
			(xy 164.892567 -80.582901) (xy 164.936708 -80.550287) (xy 164.985067 -80.524334) (xy 165.036645 -80.505577)
			(xy 165.090378 -80.494403) (xy 165.145158 -80.491043) (xy 165.199854 -80.495566) (xy 165.253337 -80.507878)
			(xy 165.304505 -80.527726) (xy 165.352302 -80.554701) (xy 165.37432 -80.571086) (xy 165.392946 -80.583819)
			(xy 165.433689 -80.603189) (xy 165.477212 -80.61506) (xy 165.522148 -80.619059) (xy 165.567084 -80.61506)
			(xy 165.610607 -80.603189) (xy 165.65135 -80.583819) (xy 165.669976 -80.571086) (xy 165.687742 -80.55774)
			(xy 165.725816 -80.534827) (xy 165.745922 -80.525366) (xy 165.76937 -80.515235) (xy 165.818302 -80.500582)
			(xy 165.843458 -80.496156) (xy 165.865282 -80.492226) (xy 165.907215 -80.477821) (xy 165.946011 -80.456356)
			(xy 165.980492 -80.428481) (xy 166.009611 -80.395044) (xy 166.032482 -80.35706) (xy 166.048413 -80.315682)
			(xy 166.056918 -80.272166) (xy 166.057741 -80.227835) (xy 166.050855 -80.184034) (xy 166.044118 -80.162908)
			(xy 166.034559 -80.136118) (xy 166.022578 -80.080514) (xy 166.018978 -80.023748) (xy 166.023839 -79.967077)
			(xy 166.037054 -79.911754) (xy 166.05833 -79.859003) (xy 166.072312 -79.834232) (xy 166.09019 -79.805277)
			(xy 166.134524 -79.753658) (xy 166.16045 -79.731616) (xy 166.182802 -79.713582) (xy 166.20744 -79.661766)
			(xy 166.20744 -78.547722) (xy 166.177214 -78.491334) (xy 166.15029 -78.473808) (xy 166.138146 -78.465638)
			(xy 166.115009 -78.447709) (xy 166.104062 -78.437994) (xy 166.083393 -78.418512) (xy 166.047484 -78.374507)
			(xy 166.018504 -78.32566) (xy 166.007288 -78.299564) (xy 166.000492 -78.28442) (xy 165.980399 -78.258015)
			(xy 165.954176 -78.237685) (xy 165.923597 -78.224807) (xy 165.890731 -78.220251) (xy 165.857802 -78.224326)
			(xy 165.842188 -78.229968) (xy 165.816827 -78.23965) (xy 165.764099 -78.252555) (xy 165.710074 -78.257855)
			(xy 165.655844 -78.25544) (xy 165.602503 -78.245361) (xy 165.551131 -78.227821) (xy 165.502765 -78.203175)
			(xy 165.458381 -78.171919) (xy 165.418878 -78.134686) (xy 165.385053 -78.092229) (xy 165.35759 -78.045404)
			(xy 165.337043 -77.995159) (xy 165.323828 -77.942508) (xy 165.318212 -77.888515) (xy 165.320307 -77.834271)
			(xy 165.330073 -77.780873) (xy 165.338252 -77.754988) (xy 165.347642 -77.728494) (xy 165.373103 -77.678383)
			(xy 165.405642 -77.632551) (xy 165.444554 -77.591991) (xy 165.488997 -77.557579) (xy 165.538009 -77.530062)
			(xy 165.590529 -77.510036) (xy 165.645418 -77.497933) (xy 165.70149 -77.494016) (xy 165.757529 -77.49837)
			(xy 165.812323 -77.510901) (xy 165.864684 -77.531336) (xy 165.91348 -77.559235) (xy 165.935914 -77.576172)
			(xy 165.949104 -77.585895) (xy 165.979165 -77.598907) (xy 166.011551 -77.60382) (xy 166.044119 -77.600309)
			(xy 166.059612 -77.594968) (xy 166.125906 -77.569568) (xy 166.140053 -77.56366) (xy 166.16523 -77.546182)
			(xy 166.185505 -77.523199) (xy 166.199707 -77.496039) (xy 166.207013 -77.466274) (xy 166.20744 -77.45095)
			(xy 166.20744 -77.3303) (xy 166.206942 -77.314924) (xy 166.199519 -77.285078) (xy 166.185176 -77.257872)
			(xy 166.164745 -77.234885) (xy 166.139411 -77.217448) (xy 166.110643 -77.206574) (xy 166.095426 -77.204316)
			(xy 166.06742 -77.201169) (xy 166.012702 -77.187684) (xy 165.960564 -77.166295) (xy 165.912141 -77.137466)
			(xy 165.868488 -77.101826) (xy 165.830554 -77.06015) (xy 165.799165 -77.013346) (xy 165.775006 -76.962432)
			(xy 165.758601 -76.908518) (xy 165.750309 -76.852776) (xy 165.750309 -76.796421) (xy 165.758602 -76.74068)
			(xy 165.775007 -76.686765) (xy 165.799167 -76.635852) (xy 165.830555 -76.589048) (xy 165.86849 -76.547372)
			(xy 165.912144 -76.511732) (xy 165.960567 -76.482904) (xy 166.012705 -76.461515) (xy 166.067423 -76.448031)
			(xy 166.095426 -76.444856) (xy 166.110659 -76.442631) (xy 166.139469 -76.431804) (xy 166.16484 -76.41438)
			(xy 166.185289 -76.391378) (xy 166.199621 -76.364141) (xy 166.207 -76.334261) (xy 166.20744 -76.318872)
			(xy 166.20744 -74.64806) (xy 166.206978 -74.625836) (xy 166.19924 -74.582068) (xy 166.184007 -74.540313)
			(xy 166.161742 -74.501844) (xy 166.133126 -74.467834) (xy 166.099031 -74.43932) (xy 166.060495 -74.417171)
			(xy 166.018694 -74.402063) (xy 165.974903 -74.394456) (xy 165.952678 -74.39406) (xy 165.924924 -74.393654)
			(xy 165.869979 -74.385796) (xy 165.816752 -74.37006) (xy 165.766367 -74.346779) (xy 165.719886 -74.316442)
			(xy 165.678291 -74.279691) (xy 165.64246 -74.237302) (xy 165.613149 -74.190168) (xy 165.590977 -74.139285)
			(xy 165.57641 -74.085726) (xy 165.569757 -74.030622) (xy 165.571159 -73.975135) (xy 165.580585 -73.920437)
			(xy 165.597836 -73.867682) (xy 165.609778 -73.842626) (xy 165.617363 -73.827978) (xy 165.625536 -73.796034)
			(xy 165.625262 -73.763061) (xy 165.616559 -73.731257) (xy 165.600007 -73.702738) (xy 165.588696 -73.690734)
			(xy 161.93008 -70.032118) (xy 161.93008 -51.36388) (xy 161.929587 -51.340735) (xy 161.921238 -51.295203)
			(xy 161.904785 -51.251936) (xy 161.88077 -51.212363) (xy 161.849987 -51.177791) (xy 161.813454 -51.149364)
			(xy 161.772378 -51.12802) (xy 161.728116 -51.114466) (xy 161.682133 -51.109149) (xy 161.635946 -51.112246)
			(xy 161.591083 -51.123652) (xy 161.549027 -51.142993) (xy 161.529776 -51.155854) (xy 161.509174 -51.171316)
			(xy 161.464801 -51.197478) (xy 161.417482 -51.217834) (xy 161.367973 -51.232059) (xy 161.342578 -51.236372)
			(xy 161.324666 -51.238992) (xy 161.288543 -51.241406) (xy 161.270442 -51.241198) (xy 161.246321 -51.24119)
			(xy 161.198754 -51.249151) (xy 161.15354 -51.265934) (xy 161.112299 -51.290938) (xy 161.07651 -51.323266)
			(xy 161.047454 -51.36176) (xy 161.026174 -51.40504) (xy 161.019236 -51.428142) (xy 161.011379 -51.455032)
			(xy 160.988872 -51.506333) (xy 160.959105 -51.553791) (xy 160.922718 -51.596386) (xy 160.880493 -51.633202)
			(xy 160.833338 -51.663447) (xy 160.782267 -51.686472) (xy 160.728379 -51.701781) (xy 160.672831 -51.709044)
			(xy 160.616818 -51.708107) (xy 160.561544 -51.698989) (xy 160.508198 -51.681885) (xy 160.457926 -51.657165)
			(xy 160.41181 -51.625358) (xy 160.370841 -51.58715) (xy 160.352994 -51.565556) (xy 160.335897 -51.54334)
			(xy 160.307717 -51.494882) (xy 160.286928 -51.442822) (xy 160.273979 -51.388282) (xy 160.269146 -51.332434)
			(xy 160.272535 -51.276479) (xy 160.284073 -51.221623) (xy 160.303511 -51.169044) (xy 160.330431 -51.119874)
			(xy 160.364253 -51.075171) (xy 160.404252 -51.035896) (xy 160.449565 -51.002895) (xy 160.499218 -50.976877)
			(xy 160.552143 -50.958402) (xy 160.607201 -50.947867) (xy 160.635188 -50.946304) (xy 160.65857 -50.944301)
			(xy 160.70407 -50.932833) (xy 160.746697 -50.913218) (xy 160.785004 -50.886119) (xy 160.817694 -50.852457)
			(xy 160.843657 -50.813371) (xy 160.862015 -50.770188) (xy 160.872144 -50.724371) (xy 160.87344 -50.70094)
			(xy 160.87344 -50.048668) (xy 160.53308 -49.708308) (xy 160.53308 -49.685194) (xy 159.75838 -48.910494)
			(xy 159.75838 -34.28873) (xy 159.757963 -34.273721) (xy 159.750949 -34.244533) (xy 159.737302 -34.217796)
			(xy 159.717779 -34.194992) (xy 159.693465 -34.177387) (xy 159.665707 -34.165958) (xy 159.650938 -34.163254)
			(xy 159.623694 -34.159269) (xy 159.570659 -34.144477) (xy 159.520302 -34.122212) (xy 159.473671 -34.092936)
			(xy 159.431734 -34.057259) (xy 159.395364 -34.015922) (xy 159.365317 -33.969784) (xy 159.342217 -33.919805)
			(xy 159.326544 -33.867023) (xy 159.318626 -33.812536) (xy 159.318625 -33.757476) (xy 159.326542 -33.702989)
			(xy 159.342212 -33.650207) (xy 159.365311 -33.600227) (xy 159.395357 -33.554088) (xy 159.431725 -33.51275)
			(xy 159.473661 -33.477071) (xy 159.520291 -33.447794) (xy 159.570647 -33.425527) (xy 159.623682 -33.410734)
			(xy 159.650938 -33.406842) (xy 159.665701 -33.404117) (xy 159.693454 -33.392689) (xy 159.717763 -33.375088)
			(xy 159.737281 -33.352288) (xy 159.750925 -33.325555) (xy 159.757938 -33.296373) (xy 159.75838 -33.281366)
			(xy 159.75838 -31.034482) (xy 159.757803 -31.01714) (xy 159.748475 -30.983733) (xy 159.730488 -30.954078)
			(xy 159.705173 -30.930369) (xy 159.674405 -30.914361) (xy 159.657542 -30.910276) (xy 159.630089 -30.90485)
			(xy 159.577044 -30.887023) (xy 159.527174 -30.861637) (xy 159.48155 -30.829235) (xy 159.44115 -30.790513)
			(xy 159.406842 -30.746304) (xy 159.379363 -30.697555) (xy 159.359303 -30.645314) (xy 159.347093 -30.590703)
			(xy 159.342994 -30.534894) (xy 159.347095 -30.479084) (xy 159.359307 -30.424473) (xy 159.379369 -30.372233)
			(xy 159.406849 -30.323486) (xy 159.441158 -30.279277) (xy 159.48156 -30.240557) (xy 159.527185 -30.208157)
			(xy 159.577056 -30.182772) (xy 159.630101 -30.164947) (xy 159.657542 -30.159452) (xy 159.674381 -30.155301)
			(xy 159.705125 -30.139283) (xy 159.730427 -30.115586) (xy 159.748423 -30.085957) (xy 159.757786 -30.052579)
			(xy 159.75838 -30.035246) (xy 159.75838 -21.457158) (xy 159.146494 -20.845272) (xy 157.596332 -20.845272)
			(xy 157.176724 -21.26488) (xy 157.165637 -21.27661) (xy 157.149239 -21.3044) (xy 157.14034 -21.335416)
			(xy 157.13951 -21.367673) (xy 157.142688 -21.383498) (xy 157.144212 -21.390102) (xy 157.15284 -21.429512)
			(xy 157.162961 -21.509556) (xy 157.164848 -21.590216) (xy 157.158481 -21.670645) (xy 157.143927 -21.750003)
			(xy 157.121338 -21.827457) (xy 157.090952 -21.902198) (xy 157.053085 -21.973441) (xy 157.008135 -22.04044)
			(xy 156.956572 -22.102495) (xy 156.898937 -22.158954) (xy 156.835834 -22.209228) (xy 156.767922 -22.252788)
			(xy 156.695914 -22.289179) (xy 156.620564 -22.318019) (xy 156.54266 -22.339008) (xy 156.46302 -22.351924)
			(xy 156.382476 -22.356632) (xy 156.301873 -22.353084) (xy 156.222054 -22.341316) (xy 156.143857 -22.321452)
			(xy 156.068099 -22.293699) (xy 155.995574 -22.258349) (xy 155.927043 -22.215771) (xy 155.863222 -22.166411)
			(xy 155.80478 -22.110788) (xy 155.752329 -22.049482) (xy 155.706419 -21.983136) (xy 155.66753 -21.912446)
			(xy 155.63607 -21.838151) (xy 155.612369 -21.76103) (xy 155.603956 -21.721572) (xy 155.601083 -21.70697)
			(xy 155.589469 -21.679577) (xy 155.571822 -21.655623) (xy 155.549104 -21.63641) (xy 155.522551 -21.622987)
			(xy 155.49361 -21.616083) (xy 155.478734 -21.615654) (xy 151.01189 -21.615654) (xy 150.994655 -21.616189)
			(xy 150.961428 -21.625349) (xy 150.93187 -21.643078) (xy 150.908144 -21.668078) (xy 150.891985 -21.698523)
			(xy 150.887684 -21.715222) (xy 150.879681 -21.754676) (xy 150.856681 -21.831828) (xy 150.825933 -21.906233)
			(xy 150.787757 -21.977114) (xy 150.742552 -22.043732) (xy 150.690789 -22.105394) (xy 150.633008 -22.161454)
			(xy 150.569811 -22.211331) (xy 150.501857 -22.254502) (xy 150.429854 -22.290519) (xy 150.354554 -22.319005)
			(xy 150.276742 -22.339663) (xy 150.197229 -22.352279) (xy 150.116844 -22.35672) (xy 150.036425 -22.35294)
			(xy 149.95681 -22.340979) (xy 149.878831 -22.320962) (xy 149.803299 -22.293096) (xy 149.731003 -22.257674)
			(xy 149.662696 -22.215063) (xy 149.599091 -22.165708) (xy 149.54085 -22.110125) (xy 149.488581 -22.048891)
			(xy 149.44283 -21.982647) (xy 149.404072 -21.912083) (xy 149.372712 -21.837934) (xy 149.349078 -21.760973)
			(xy 149.340824 -21.721572) (xy 149.33795 -21.706972) (xy 149.326335 -21.679583) (xy 149.308688 -21.655632)
			(xy 149.285969 -21.636425) (xy 149.259416 -21.623008) (xy 149.230477 -21.616111) (xy 149.215602 -21.615654)
			(xy 141.656054 -21.615654) (xy 141.63167 -21.626322) (xy 141.593594 -21.642476) (xy 141.515097 -21.668562)
			(xy 141.434542 -21.687353) (xy 141.352605 -21.698691) (xy 141.269974 -21.702481) (xy 141.187343 -21.698691)
			(xy 141.105406 -21.687353) (xy 141.024851 -21.668562) (xy 140.946354 -21.642476) (xy 140.908278 -21.626322)
			(xy 140.883894 -21.615654) (xy 139.116054 -21.615654) (xy 139.09167 -21.626322) (xy 139.053594 -21.642476)
			(xy 138.975097 -21.668562) (xy 138.894542 -21.687353) (xy 138.812605 -21.698691) (xy 138.729974 -21.702481)
			(xy 138.647343 -21.698691) (xy 138.565406 -21.687353) (xy 138.484851 -21.668562) (xy 138.406354 -21.642476)
			(xy 138.368278 -21.626322) (xy 138.343894 -21.615654) (xy 124.149104 -21.615654) (xy 123.358148 -22.40661)
			(xy 123.358148 -23.743684) (xy 137.331957 -23.743684) (xy 137.338057 -23.688247) (xy 137.352163 -23.63429)
			(xy 137.373975 -23.582961) (xy 137.403029 -23.535355) (xy 137.438704 -23.492487) (xy 137.480241 -23.45527)
			(xy 137.526754 -23.424497) (xy 137.577251 -23.400825) (xy 137.630658 -23.384757) (xy 137.685834 -23.376637)
			(xy 137.71372 -23.376128) (xy 137.741606 -23.376637) (xy 137.796782 -23.384757) (xy 137.850189 -23.400825)
			(xy 137.900686 -23.424497) (xy 137.947199 -23.45527) (xy 137.988736 -23.492487) (xy 138.024411 -23.535355)
			(xy 138.053465 -23.582961) (xy 138.075277 -23.63429) (xy 138.089383 -23.688247) (xy 138.095483 -23.743684)
			(xy 138.093446 -23.799418) (xy 138.083316 -23.854261) (xy 138.065309 -23.907045) (xy 138.039808 -23.956645)
			(xy 138.007357 -24.002003) (xy 137.968648 -24.042152) (xy 137.924505 -24.076238) (xy 137.87587 -24.103534)
			(xy 137.823779 -24.123457) (xy 137.769342 -24.135583) (xy 137.71372 -24.139654) (xy 137.658098 -24.135583)
			(xy 137.603661 -24.123457) (xy 137.55157 -24.103534) (xy 137.502935 -24.076238) (xy 137.458792 -24.042152)
			(xy 137.420083 -24.002003) (xy 137.387632 -23.956645) (xy 137.362131 -23.907045) (xy 137.344124 -23.854261)
			(xy 137.333994 -23.799418) (xy 137.331957 -23.743684) (xy 123.358148 -23.743684) (xy 123.358148 -24.530576)
			(xy 138.678157 -24.530576) (xy 138.684257 -24.475139) (xy 138.698363 -24.421182) (xy 138.720175 -24.369853)
			(xy 138.749229 -24.322247) (xy 138.784904 -24.279379) (xy 138.826441 -24.242162) (xy 138.872954 -24.211389)
			(xy 138.923451 -24.187717) (xy 138.976858 -24.171649) (xy 139.032034 -24.163529) (xy 139.05992 -24.16302)
			(xy 139.087806 -24.163529) (xy 139.142982 -24.171649) (xy 139.196389 -24.187717) (xy 139.246886 -24.211389)
			(xy 139.293399 -24.242162) (xy 139.334936 -24.279379) (xy 139.370611 -24.322247) (xy 139.399665 -24.369853)
			(xy 139.421477 -24.421182) (xy 139.435583 -24.475139) (xy 139.441683 -24.530576) (xy 139.439646 -24.58631)
			(xy 139.429516 -24.641153) (xy 139.411509 -24.693937) (xy 139.409309 -24.698216) (xy 140.826489 -24.698216)
			(xy 140.832589 -24.642779) (xy 140.846695 -24.588822) (xy 140.868507 -24.537493) (xy 140.897561 -24.489887)
			(xy 140.933236 -24.447019) (xy 140.974773 -24.409802) (xy 141.021286 -24.379029) (xy 141.071783 -24.355357)
			(xy 141.12519 -24.339289) (xy 141.180366 -24.331169) (xy 141.208252 -24.33066) (xy 141.236138 -24.331169)
			(xy 141.291314 -24.339289) (xy 141.344721 -24.355357) (xy 141.395218 -24.379029) (xy 141.441731 -24.409802)
			(xy 141.483268 -24.447019) (xy 141.518943 -24.489887) (xy 141.547997 -24.537493) (xy 141.569809 -24.588822)
			(xy 141.583915 -24.642779) (xy 141.587304 -24.673578) (xy 142.096489 -24.673578) (xy 142.102589 -24.618141)
			(xy 142.116695 -24.564184) (xy 142.138507 -24.512855) (xy 142.167561 -24.465249) (xy 142.203236 -24.422381)
			(xy 142.244773 -24.385164) (xy 142.291286 -24.354391) (xy 142.341783 -24.330719) (xy 142.39519 -24.314651)
			(xy 142.450366 -24.306531) (xy 142.478252 -24.306022) (xy 142.506138 -24.306531) (xy 142.561314 -24.314651)
			(xy 142.614721 -24.330719) (xy 142.665218 -24.354391) (xy 142.711731 -24.385164) (xy 142.753268 -24.422381)
			(xy 142.788943 -24.465249) (xy 142.817997 -24.512855) (xy 142.839809 -24.564184) (xy 142.843507 -24.578328)
			(xy 143.366489 -24.578328) (xy 143.372589 -24.522891) (xy 143.386695 -24.468934) (xy 143.408507 -24.417605)
			(xy 143.437561 -24.369999) (xy 143.473236 -24.327131) (xy 143.514773 -24.289914) (xy 143.561286 -24.259141)
			(xy 143.611783 -24.235469) (xy 143.66519 -24.219401) (xy 143.720366 -24.211281) (xy 143.748252 -24.210772)
			(xy 143.776138 -24.211281) (xy 143.831314 -24.219401) (xy 143.884721 -24.235469) (xy 143.935218 -24.259141)
			(xy 143.981731 -24.289914) (xy 144.023268 -24.327131) (xy 144.058943 -24.369999) (xy 144.087997 -24.417605)
			(xy 144.109809 -24.468934) (xy 144.123915 -24.522891) (xy 144.130015 -24.578328) (xy 144.127978 -24.634062)
			(xy 144.117848 -24.688905) (xy 144.099841 -24.741689) (xy 144.07434 -24.791289) (xy 144.041889 -24.836647)
			(xy 144.00318 -24.876796) (xy 143.959037 -24.910882) (xy 143.910402 -24.938178) (xy 143.858311 -24.958101)
			(xy 143.803874 -24.970227) (xy 143.748252 -24.974298) (xy 143.69263 -24.970227) (xy 143.638193 -24.958101)
			(xy 143.586102 -24.938178) (xy 143.537467 -24.910882) (xy 143.493324 -24.876796) (xy 143.454615 -24.836647)
			(xy 143.422164 -24.791289) (xy 143.396663 -24.741689) (xy 143.378656 -24.688905) (xy 143.368526 -24.634062)
			(xy 143.366489 -24.578328) (xy 142.843507 -24.578328) (xy 142.853915 -24.618141) (xy 142.860015 -24.673578)
			(xy 142.857978 -24.729312) (xy 142.847848 -24.784155) (xy 142.829841 -24.836939) (xy 142.80434 -24.886539)
			(xy 142.771889 -24.931897) (xy 142.73318 -24.972046) (xy 142.689037 -25.006132) (xy 142.640402 -25.033428)
			(xy 142.588311 -25.053351) (xy 142.533874 -25.065477) (xy 142.478252 -25.069548) (xy 142.42263 -25.065477)
			(xy 142.368193 -25.053351) (xy 142.316102 -25.033428) (xy 142.267467 -25.006132) (xy 142.223324 -24.972046)
			(xy 142.184615 -24.931897) (xy 142.152164 -24.886539) (xy 142.126663 -24.836939) (xy 142.108656 -24.784155)
			(xy 142.098526 -24.729312) (xy 142.096489 -24.673578) (xy 141.587304 -24.673578) (xy 141.590015 -24.698216)
			(xy 141.587978 -24.75395) (xy 141.577848 -24.808793) (xy 141.559841 -24.861577) (xy 141.53434 -24.911177)
			(xy 141.501889 -24.956535) (xy 141.46318 -24.996684) (xy 141.419037 -25.03077) (xy 141.370402 -25.058066)
			(xy 141.318311 -25.077989) (xy 141.263874 -25.090115) (xy 141.208252 -25.094186) (xy 141.15263 -25.090115)
			(xy 141.098193 -25.077989) (xy 141.046102 -25.058066) (xy 140.997467 -25.03077) (xy 140.953324 -24.996684)
			(xy 140.914615 -24.956535) (xy 140.882164 -24.911177) (xy 140.856663 -24.861577) (xy 140.838656 -24.808793)
			(xy 140.828526 -24.75395) (xy 140.826489 -24.698216) (xy 139.409309 -24.698216) (xy 139.386008 -24.743537)
			(xy 139.353557 -24.788895) (xy 139.314848 -24.829044) (xy 139.270705 -24.86313) (xy 139.22207 -24.890426)
			(xy 139.169979 -24.910349) (xy 139.115542 -24.922475) (xy 139.05992 -24.926546) (xy 139.004298 -24.922475)
			(xy 138.949861 -24.910349) (xy 138.89777 -24.890426) (xy 138.849135 -24.86313) (xy 138.804992 -24.829044)
			(xy 138.766283 -24.788895) (xy 138.733832 -24.743537) (xy 138.708331 -24.693937) (xy 138.690324 -24.641153)
			(xy 138.680194 -24.58631) (xy 138.678157 -24.530576) (xy 123.358148 -24.530576) (xy 123.358148 -25.41729)
			(xy 123.681489 -25.41729) (xy 123.687589 -25.361853) (xy 123.701695 -25.307896) (xy 123.723507 -25.256567)
			(xy 123.752561 -25.208961) (xy 123.788236 -25.166093) (xy 123.829773 -25.128876) (xy 123.876286 -25.098103)
			(xy 123.926783 -25.074431) (xy 123.98019 -25.058363) (xy 124.035366 -25.050243) (xy 124.063252 -25.049734)
			(xy 124.091138 -25.050243) (xy 124.146314 -25.058363) (xy 124.199721 -25.074431) (xy 124.250218 -25.098103)
			(xy 124.296731 -25.128876) (xy 124.338268 -25.166093) (xy 124.373943 -25.208961) (xy 124.402997 -25.256567)
			(xy 124.424809 -25.307896) (xy 124.438915 -25.361853) (xy 124.440403 -25.37538) (xy 125.844807 -25.37538)
			(xy 125.850907 -25.319943) (xy 125.865013 -25.265986) (xy 125.886825 -25.214657) (xy 125.915879 -25.167051)
			(xy 125.951554 -25.124183) (xy 125.993091 -25.086966) (xy 126.039604 -25.056193) (xy 126.090101 -25.032521)
			(xy 126.143508 -25.016453) (xy 126.198684 -25.008333) (xy 126.22657 -25.007824) (xy 126.254456 -25.008333)
			(xy 126.309632 -25.016453) (xy 126.363039 -25.032521) (xy 126.413536 -25.056193) (xy 126.460049 -25.086966)
			(xy 126.501586 -25.124183) (xy 126.537261 -25.167051) (xy 126.566315 -25.214657) (xy 126.588127 -25.265986)
			(xy 126.602233 -25.319943) (xy 126.608333 -25.37538) (xy 126.606653 -25.421354) (xy 126.860807 -25.421354)
			(xy 126.866907 -25.365917) (xy 126.881013 -25.31196) (xy 126.902825 -25.260631) (xy 126.931879 -25.213025)
			(xy 126.967554 -25.170157) (xy 127.009091 -25.13294) (xy 127.055604 -25.102167) (xy 127.106101 -25.078495)
			(xy 127.159508 -25.062427) (xy 127.214684 -25.054307) (xy 127.24257 -25.053798) (xy 127.270456 -25.054307)
			(xy 127.325632 -25.062427) (xy 127.379039 -25.078495) (xy 127.429536 -25.102167) (xy 127.476049 -25.13294)
			(xy 127.517586 -25.170157) (xy 127.553261 -25.213025) (xy 127.582315 -25.260631) (xy 127.604127 -25.31196)
			(xy 127.618233 -25.365917) (xy 127.618756 -25.370672) (xy 127.876888 -25.370672) (xy 127.878971 -25.314636)
			(xy 127.889235 -25.259508) (xy 127.90746 -25.206477) (xy 127.933253 -25.156686) (xy 127.966058 -25.111208)
			(xy 128.005168 -25.071023) (xy 128.04974 -25.036997) (xy 128.098814 -25.009864) (xy 128.151331 -24.990208)
			(xy 128.20616 -24.978453) (xy 128.26212 -24.974853) (xy 128.318003 -24.979484) (xy 128.372607 -24.992247)
			(xy 128.424753 -25.012868) (xy 128.473318 -25.040901) (xy 128.517255 -25.075742) (xy 128.555618 -25.116641)
			(xy 128.572006 -25.139396) (xy 128.58587 -25.158464) (xy 128.619442 -25.191558) (xy 128.658536 -25.217899)
			(xy 128.701816 -25.236584) (xy 128.747798 -25.246973) (xy 128.794906 -25.24871) (xy 128.841528 -25.241737)
			(xy 128.886066 -25.226291) (xy 128.926996 -25.202902) (xy 128.962914 -25.172371) (xy 128.978152 -25.154382)
			(xy 128.996228 -25.13294) (xy 129.037525 -25.095001) (xy 129.083932 -25.063516) (xy 129.134449 -25.039166)
			(xy 129.187986 -25.022475) (xy 129.243391 -25.013803) (xy 129.299468 -25.013336) (xy 129.355009 -25.021085)
			(xy 129.408816 -25.036883) (xy 129.459731 -25.060388) (xy 129.506656 -25.091095) (xy 129.548579 -25.128342)
			(xy 129.584596 -25.171326) (xy 129.613932 -25.21912) (xy 129.635954 -25.270694) (xy 129.650187 -25.324937)
			(xy 129.656324 -25.380679) (xy 129.654234 -25.436719) (xy 129.644357 -25.489725) (xy 129.90915 -25.489725)
			(xy 129.916036 -25.434093) (xy 129.930992 -25.380068) (xy 129.953695 -25.328814) (xy 129.983656 -25.281435)
			(xy 130.020229 -25.238952) (xy 130.062628 -25.202281) (xy 130.109937 -25.172211) (xy 130.161139 -25.14939)
			(xy 130.215129 -25.134309) (xy 130.270746 -25.127295) (xy 130.32679 -25.128497) (xy 130.382054 -25.13789)
			(xy 130.435349 -25.155271) (xy 130.485524 -25.180266) (xy 130.531501 -25.212337) (xy 130.572288 -25.250793)
			(xy 130.590036 -25.272492) (xy 130.605053 -25.29065) (xy 130.640553 -25.321627) (xy 130.681153 -25.345533)
			(xy 130.725462 -25.36155) (xy 130.771963 -25.36913) (xy 130.819065 -25.368012) (xy 130.865154 -25.358236)
			(xy 130.908653 -25.340136) (xy 130.948073 -25.314331) (xy 130.982065 -25.281706) (xy 130.996182 -25.26284)
			(xy 131.012802 -25.240335) (xy 131.051614 -25.200042) (xy 131.095895 -25.165851) (xy 131.144695 -25.138493)
			(xy 131.196968 -25.118556) (xy 131.251592 -25.106468) (xy 131.307396 -25.102488) (xy 131.363182 -25.106701)
			(xy 131.417756 -25.119016) (xy 131.469945 -25.13917) (xy 131.51863 -25.166731) (xy 131.562769 -25.201107)
			(xy 131.601413 -25.241561) (xy 131.617974 -25.26411) (xy 131.631992 -25.283033) (xy 131.665853 -25.315757)
			(xy 131.70516 -25.341686) (xy 131.748571 -25.359933) (xy 131.794599 -25.369873) (xy 131.841671 -25.371167)
			(xy 131.888176 -25.36377) (xy 131.932523 -25.347935) (xy 131.973196 -25.324204) (xy 132.008803 -25.293389)
			(xy 132.023866 -25.275286) (xy 132.04168 -25.253615) (xy 132.082636 -25.215281) (xy 132.128763 -25.183355)
			(xy 132.179067 -25.158526) (xy 132.232463 -25.141329) (xy 132.287802 -25.132134) (xy 132.343891 -25.13114)
			(xy 132.399521 -25.138368) (xy 132.453494 -25.153662) (xy 132.504646 -25.176693) (xy 132.551875 -25.206965)
			(xy 132.570541 -25.223234) (xy 132.956807 -25.223234) (xy 132.962907 -25.167797) (xy 132.977013 -25.11384)
			(xy 132.998825 -25.062511) (xy 133.027879 -25.014905) (xy 133.063554 -24.972037) (xy 133.105091 -24.93482)
			(xy 133.151604 -24.904047) (xy 133.202101 -24.880375) (xy 133.255508 -24.864307) (xy 133.310684 -24.856187)
			(xy 133.33857 -24.855678) (xy 133.366456 -24.856187) (xy 133.421632 -24.864307) (xy 133.475039 -24.880375)
			(xy 133.525536 -24.904047) (xy 133.572049 -24.93482) (xy 133.613586 -24.972037) (xy 133.649261 -25.014905)
			(xy 133.678315 -25.062511) (xy 133.700127 -25.11384) (xy 133.714233 -25.167797) (xy 133.720333 -25.223234)
			(xy 133.718296 -25.278968) (xy 133.708792 -25.330422) (xy 133.972807 -25.330422) (xy 133.978907 -25.274985)
			(xy 133.993013 -25.221028) (xy 134.014825 -25.169699) (xy 134.043879 -25.122093) (xy 134.079554 -25.079225)
			(xy 134.121091 -25.042008) (xy 134.167604 -25.011235) (xy 134.218101 -24.987563) (xy 134.271508 -24.971495)
			(xy 134.326684 -24.963375) (xy 134.35457 -24.962866) (xy 134.382456 -24.963375) (xy 134.437632 -24.971495)
			(xy 134.491039 -24.987563) (xy 134.541536 -25.011235) (xy 134.588049 -25.042008) (xy 134.629586 -25.079225)
			(xy 134.665261 -25.122093) (xy 134.694315 -25.169699) (xy 134.716127 -25.221028) (xy 134.730233 -25.274985)
			(xy 134.736333 -25.330422) (xy 134.734296 -25.386156) (xy 134.724166 -25.440999) (xy 134.706159 -25.493783)
			(xy 134.682673 -25.539464) (xy 134.988807 -25.539464) (xy 134.994907 -25.484027) (xy 135.009013 -25.43007)
			(xy 135.030825 -25.378741) (xy 135.059879 -25.331135) (xy 135.095554 -25.288267) (xy 135.137091 -25.25105)
			(xy 135.183604 -25.220277) (xy 135.234101 -25.196605) (xy 135.287508 -25.180537) (xy 135.342684 -25.172417)
			(xy 135.37057 -25.171908) (xy 135.398456 -25.172417) (xy 135.453632 -25.180537) (xy 135.507039 -25.196605)
			(xy 135.557536 -25.220277) (xy 135.604049 -25.25105) (xy 135.645586 -25.288267) (xy 135.681261 -25.331135)
			(xy 135.710315 -25.378741) (xy 135.732127 -25.43007) (xy 135.737684 -25.451326) (xy 136.004807 -25.451326)
			(xy 136.010907 -25.395889) (xy 136.025013 -25.341932) (xy 136.046825 -25.290603) (xy 136.075879 -25.242997)
			(xy 136.111554 -25.200129) (xy 136.153091 -25.162912) (xy 136.199604 -25.132139) (xy 136.250101 -25.108467)
			(xy 136.303508 -25.092399) (xy 136.358684 -25.084279) (xy 136.38657 -25.08377) (xy 136.414456 -25.084279)
			(xy 136.469632 -25.092399) (xy 136.523039 -25.108467) (xy 136.573536 -25.132139) (xy 136.620049 -25.162912)
			(xy 136.661586 -25.200129) (xy 136.697261 -25.242997) (xy 136.726315 -25.290603) (xy 136.748127 -25.341932)
			(xy 136.762233 -25.395889) (xy 136.768333 -25.451326) (xy 136.766296 -25.50706) (xy 136.756166 -25.561903)
			(xy 136.738159 -25.614687) (xy 136.712658 -25.664287) (xy 136.680207 -25.709645) (xy 136.641498 -25.749794)
			(xy 136.597355 -25.78388) (xy 136.54872 -25.811176) (xy 136.496629 -25.831099) (xy 136.442192 -25.843225)
			(xy 136.38657 -25.847296) (xy 136.330948 -25.843225) (xy 136.276511 -25.831099) (xy 136.22442 -25.811176)
			(xy 136.175785 -25.78388) (xy 136.131642 -25.749794) (xy 136.092933 -25.709645) (xy 136.060482 -25.664287)
			(xy 136.034981 -25.614687) (xy 136.016974 -25.561903) (xy 136.006844 -25.50706) (xy 136.004807 -25.451326)
			(xy 135.737684 -25.451326) (xy 135.746233 -25.484027) (xy 135.752333 -25.539464) (xy 135.750296 -25.595198)
			(xy 135.740166 -25.650041) (xy 135.722159 -25.702825) (xy 135.696658 -25.752425) (xy 135.664207 -25.797783)
			(xy 135.625498 -25.837932) (xy 135.581355 -25.872018) (xy 135.53272 -25.899314) (xy 135.480629 -25.919237)
			(xy 135.426192 -25.931363) (xy 135.37057 -25.935434) (xy 135.314948 -25.931363) (xy 135.260511 -25.919237)
			(xy 135.20842 -25.899314) (xy 135.159785 -25.872018) (xy 135.115642 -25.837932) (xy 135.076933 -25.797783)
			(xy 135.044482 -25.752425) (xy 135.018981 -25.702825) (xy 135.000974 -25.650041) (xy 134.990844 -25.595198)
			(xy 134.988807 -25.539464) (xy 134.682673 -25.539464) (xy 134.680658 -25.543383) (xy 134.648207 -25.588741)
			(xy 134.609498 -25.62889) (xy 134.565355 -25.662976) (xy 134.51672 -25.690272) (xy 134.464629 -25.710195)
			(xy 134.410192 -25.722321) (xy 134.35457 -25.726392) (xy 134.298948 -25.722321) (xy 134.244511 -25.710195)
			(xy 134.19242 -25.690272) (xy 134.143785 -25.662976) (xy 134.099642 -25.62889) (xy 134.060933 -25.588741)
			(xy 134.028482 -25.543383) (xy 134.002981 -25.493783) (xy 133.984974 -25.440999) (xy 133.974844 -25.386156)
			(xy 133.972807 -25.330422) (xy 133.708792 -25.330422) (xy 133.708166 -25.333811) (xy 133.690159 -25.386595)
			(xy 133.664658 -25.436195) (xy 133.632207 -25.481553) (xy 133.593498 -25.521702) (xy 133.549355 -25.555788)
			(xy 133.50072 -25.583084) (xy 133.448629 -25.603007) (xy 133.394192 -25.615133) (xy 133.33857 -25.619204)
			(xy 133.282948 -25.615133) (xy 133.228511 -25.603007) (xy 133.17642 -25.583084) (xy 133.127785 -25.555788)
			(xy 133.083642 -25.521702) (xy 133.044933 -25.481553) (xy 133.012482 -25.436195) (xy 132.986981 -25.386595)
			(xy 132.968974 -25.333811) (xy 132.958844 -25.278968) (xy 132.956807 -25.223234) (xy 132.570541 -25.223234)
			(xy 132.594164 -25.243824) (xy 132.630601 -25.286477) (xy 132.660401 -25.334005) (xy 132.682922 -25.385384)
			(xy 132.697678 -25.439506) (xy 132.704353 -25.495205) (xy 132.702801 -25.551281) (xy 132.693056 -25.606526)
			(xy 132.675329 -25.659749) (xy 132.650001 -25.709804) (xy 132.617618 -25.755611) (xy 132.578878 -25.796183)
			(xy 132.534615 -25.830648) (xy 132.485784 -25.858261) (xy 132.433437 -25.878427) (xy 132.378701 -25.890713)
			(xy 132.322756 -25.894853) (xy 132.266808 -25.890759) (xy 132.212062 -25.878518) (xy 132.159698 -25.858394)
			(xy 132.110845 -25.830821) (xy 132.066554 -25.796393) (xy 132.027781 -25.755852) (xy 132.011166 -25.733248)
			(xy 131.997099 -25.714365) (xy 131.963244 -25.681646) (xy 131.923943 -25.655721) (xy 131.88054 -25.637476)
			(xy 131.83452 -25.627535) (xy 131.787456 -25.626237) (xy 131.740958 -25.633627) (xy 131.696616 -25.649453)
			(xy 131.655946 -25.673172) (xy 131.620339 -25.703975) (xy 131.605274 -25.722072) (xy 131.58703 -25.744175)
			(xy 131.545026 -25.783165) (xy 131.497665 -25.815438) (xy 131.446012 -25.840267) (xy 131.391227 -25.857094)
			(xy 131.334542 -25.865541) (xy 131.277231 -25.865419) (xy 131.220582 -25.856729) (xy 131.165869 -25.839668)
			(xy 131.114322 -25.814619) (xy 131.0671 -25.782145) (xy 131.025263 -25.742975) (xy 131.007104 -25.720802)
			(xy 130.992156 -25.702584) (xy 130.956645 -25.671607) (xy 130.916034 -25.647703) (xy 130.871715 -25.63169)
			(xy 130.825204 -25.624116) (xy 130.778094 -25.62524) (xy 130.731998 -25.635024) (xy 130.688493 -25.653134)
			(xy 130.649069 -25.678948) (xy 130.615076 -25.711583) (xy 130.600958 -25.730454) (xy 130.584217 -25.75294)
			(xy 130.545302 -25.793289) (xy 130.5009 -25.827507) (xy 130.451968 -25.854857) (xy 130.399559 -25.874749)
			(xy 130.344803 -25.886756) (xy 130.288879 -25.890618) (xy 130.232992 -25.886252) (xy 130.178346 -25.873752)
			(xy 130.126119 -25.853388) (xy 130.077435 -25.825599) (xy 130.033343 -25.790982) (xy 129.994794 -25.750284)
			(xy 129.962617 -25.704381) (xy 129.937506 -25.654263) (xy 129.920002 -25.601009) (xy 129.910481 -25.545766)
			(xy 129.90915 -25.489725) (xy 129.644357 -25.489725) (xy 129.643961 -25.491849) (xy 129.625727 -25.54488)
			(xy 129.599924 -25.594671) (xy 129.56711 -25.640147) (xy 129.527991 -25.680328) (xy 129.48341 -25.714348)
			(xy 129.434328 -25.741474) (xy 129.381803 -25.761122) (xy 129.326968 -25.772867) (xy 129.271004 -25.776457)
			(xy 129.215118 -25.771814) (xy 129.160514 -25.759039) (xy 129.108368 -25.738406) (xy 129.059806 -25.710361)
			(xy 129.015873 -25.675507) (xy 128.977518 -25.634596) (xy 128.961134 -25.611836) (xy 128.947221 -25.592805)
			(xy 128.913658 -25.559708) (xy 128.874571 -25.533364) (xy 128.831299 -25.514675) (xy 128.785323 -25.504281)
			(xy 128.738219 -25.502539) (xy 128.691601 -25.509509) (xy 128.647066 -25.52495) (xy 128.60614 -25.548335)
			(xy 128.570225 -25.578862) (xy 128.554988 -25.59685) (xy 128.536975 -25.618341) (xy 128.495682 -25.65628)
			(xy 128.44928 -25.687764) (xy 128.398768 -25.712115) (xy 128.345236 -25.728809) (xy 128.289836 -25.737484)
			(xy 128.233763 -25.737955) (xy 128.178225 -25.730211) (xy 128.124419 -25.714419) (xy 128.073505 -25.69092)
			(xy 128.026581 -25.660219) (xy 127.984657 -25.622979) (xy 127.948637 -25.580003) (xy 127.919298 -25.532215)
			(xy 127.897272 -25.480647) (xy 127.883033 -25.42641) (xy 127.876888 -25.370672) (xy 127.618756 -25.370672)
			(xy 127.624333 -25.421354) (xy 127.622296 -25.477088) (xy 127.612166 -25.531931) (xy 127.594159 -25.584715)
			(xy 127.568658 -25.634315) (xy 127.536207 -25.679673) (xy 127.497498 -25.719822) (xy 127.453355 -25.753908)
			(xy 127.40472 -25.781204) (xy 127.352629 -25.801127) (xy 127.298192 -25.813253) (xy 127.24257 -25.817324)
			(xy 127.186948 -25.813253) (xy 127.132511 -25.801127) (xy 127.08042 -25.781204) (xy 127.031785 -25.753908)
			(xy 126.987642 -25.719822) (xy 126.948933 -25.679673) (xy 126.916482 -25.634315) (xy 126.890981 -25.584715)
			(xy 126.872974 -25.531931) (xy 126.862844 -25.477088) (xy 126.860807 -25.421354) (xy 126.606653 -25.421354)
			(xy 126.606296 -25.431114) (xy 126.596166 -25.485957) (xy 126.578159 -25.538741) (xy 126.552658 -25.588341)
			(xy 126.520207 -25.633699) (xy 126.481498 -25.673848) (xy 126.437355 -25.707934) (xy 126.38872 -25.73523)
			(xy 126.336629 -25.755153) (xy 126.282192 -25.767279) (xy 126.22657 -25.77135) (xy 126.170948 -25.767279)
			(xy 126.116511 -25.755153) (xy 126.06442 -25.73523) (xy 126.015785 -25.707934) (xy 125.971642 -25.673848)
			(xy 125.932933 -25.633699) (xy 125.900482 -25.588341) (xy 125.874981 -25.538741) (xy 125.856974 -25.485957)
			(xy 125.846844 -25.431114) (xy 125.844807 -25.37538) (xy 124.440403 -25.37538) (xy 124.445015 -25.41729)
			(xy 124.442978 -25.473024) (xy 124.432848 -25.527867) (xy 124.414841 -25.580651) (xy 124.38934 -25.630251)
			(xy 124.356889 -25.675609) (xy 124.31818 -25.715758) (xy 124.274037 -25.749844) (xy 124.225402 -25.77714)
			(xy 124.173311 -25.797063) (xy 124.118874 -25.809189) (xy 124.063252 -25.81326) (xy 124.00763 -25.809189)
			(xy 123.953193 -25.797063) (xy 123.901102 -25.77714) (xy 123.852467 -25.749844) (xy 123.808324 -25.715758)
			(xy 123.769615 -25.675609) (xy 123.737164 -25.630251) (xy 123.711663 -25.580651) (xy 123.693656 -25.527867)
			(xy 123.683526 -25.473024) (xy 123.681489 -25.41729) (xy 123.358148 -25.41729) (xy 123.358148 -26.17929)
			(xy 144.286223 -26.17929) (xy 144.292323 -26.123853) (xy 144.306429 -26.069896) (xy 144.328241 -26.018567)
			(xy 144.357295 -25.970961) (xy 144.39297 -25.928093) (xy 144.434507 -25.890876) (xy 144.48102 -25.860103)
			(xy 144.531517 -25.836431) (xy 144.584924 -25.820363) (xy 144.6401 -25.812243) (xy 144.667986 -25.811734)
			(xy 144.695872 -25.812243) (xy 144.751048 -25.820363) (xy 144.804455 -25.836431) (xy 144.854952 -25.860103)
			(xy 144.901465 -25.890876) (xy 144.943002 -25.928093) (xy 144.978677 -25.970961) (xy 145.007731 -26.018567)
			(xy 145.029543 -26.069896) (xy 145.043649 -26.123853) (xy 145.049749 -26.17929) (xy 146.668489 -26.17929)
			(xy 146.674589 -26.123853) (xy 146.688695 -26.069896) (xy 146.710507 -26.018567) (xy 146.739561 -25.970961)
			(xy 146.775236 -25.928093) (xy 146.816773 -25.890876) (xy 146.863286 -25.860103) (xy 146.913783 -25.836431)
			(xy 146.96719 -25.820363) (xy 147.022366 -25.812243) (xy 147.050252 -25.811734) (xy 147.078138 -25.812243)
			(xy 147.133314 -25.820363) (xy 147.186721 -25.836431) (xy 147.237218 -25.860103) (xy 147.283731 -25.890876)
			(xy 147.325268 -25.928093) (xy 147.360943 -25.970961) (xy 147.389997 -26.018567) (xy 147.411809 -26.069896)
			(xy 147.425915 -26.123853) (xy 147.432015 -26.17929) (xy 147.429978 -26.235024) (xy 147.419848 -26.289867)
			(xy 147.401841 -26.342651) (xy 147.37634 -26.392251) (xy 147.343889 -26.437609) (xy 147.30518 -26.477758)
			(xy 147.261037 -26.511844) (xy 147.212402 -26.53914) (xy 147.160311 -26.559063) (xy 147.105874 -26.571189)
			(xy 147.050252 -26.57526) (xy 146.99463 -26.571189) (xy 146.940193 -26.559063) (xy 146.888102 -26.53914)
			(xy 146.839467 -26.511844) (xy 146.795324 -26.477758) (xy 146.756615 -26.437609) (xy 146.724164 -26.392251)
			(xy 146.698663 -26.342651) (xy 146.680656 -26.289867) (xy 146.670526 -26.235024) (xy 146.668489 -26.17929)
			(xy 145.049749 -26.17929) (xy 145.047712 -26.235024) (xy 145.037582 -26.289867) (xy 145.019575 -26.342651)
			(xy 144.994074 -26.392251) (xy 144.961623 -26.437609) (xy 144.922914 -26.477758) (xy 144.878771 -26.511844)
			(xy 144.830136 -26.53914) (xy 144.778045 -26.559063) (xy 144.723608 -26.571189) (xy 144.667986 -26.57526)
			(xy 144.612364 -26.571189) (xy 144.557927 -26.559063) (xy 144.505836 -26.53914) (xy 144.457201 -26.511844)
			(xy 144.413058 -26.477758) (xy 144.374349 -26.437609) (xy 144.341898 -26.392251) (xy 144.316397 -26.342651)
			(xy 144.29839 -26.289867) (xy 144.28826 -26.235024) (xy 144.286223 -26.17929) (xy 123.358148 -26.17929)
			(xy 123.358148 -26.839164) (xy 123.72594 -27.206956) (xy 131.865878 -27.206956) (xy 131.882642 -27.202384)
			(xy 131.907666 -27.195879) (xy 131.958897 -27.188895) (xy 132.010603 -27.188895) (xy 132.061834 -27.195879)
			(xy 132.086858 -27.202384) (xy 132.103622 -27.206956) (xy 133.58368 -27.206956) (xy 133.614668 -27.187906)
			(xy 133.637443 -27.17428) (xy 133.685961 -27.152769) (xy 133.736993 -27.138193) (xy 133.789554 -27.130835)
			(xy 133.842626 -27.130835) (xy 133.895187 -27.138193) (xy 133.946219 -27.152769) (xy 133.994737 -27.17428)
			(xy 134.017512 -27.187906) (xy 134.0485 -27.206956) (xy 135.380984 -27.206956) (xy 135.392922 -27.218894)
			(xy 135.433054 -27.225498) (xy 135.461194 -27.230685) (xy 135.515609 -27.248375) (xy 135.566773 -27.273991)
			(xy 135.613538 -27.306961) (xy 135.654855 -27.346544) (xy 135.689799 -27.391853) (xy 135.717585 -27.441871)
			(xy 135.737591 -27.495478) (xy 135.749367 -27.551472) (xy 135.752651 -27.608596) (xy 135.751602 -27.619913)
			(xy 136.653625 -27.619913) (xy 136.6577 -27.564849) (xy 136.669672 -27.510947) (xy 136.68929 -27.459334)
			(xy 136.716144 -27.411089) (xy 136.749673 -27.36722) (xy 136.789176 -27.328643) (xy 136.833829 -27.296164)
			(xy 136.882698 -27.270463) (xy 136.934761 -27.252075) (xy 136.988932 -27.241386) (xy 137.044078 -27.238619)
			(xy 137.071608 -27.240738) (xy 137.094619 -27.242517) (xy 137.1406 -27.238531) (xy 137.185106 -27.226313)
			(xy 137.226677 -27.206265) (xy 137.263948 -27.179045) (xy 137.295696 -27.145546) (xy 137.320877 -27.106868)
			(xy 137.338666 -27.064281) (xy 137.348478 -27.019183) (xy 137.349738 -26.996136) (xy 137.351172 -26.968563)
			(xy 137.360913 -26.91422) (xy 137.378387 -26.861848) (xy 137.403229 -26.812543) (xy 137.43492 -26.767335)
			(xy 137.472798 -26.727168) (xy 137.516071 -26.692882) (xy 137.563836 -26.665193) (xy 137.615093 -26.64468)
			(xy 137.668772 -26.631772) (xy 137.723752 -26.626737) (xy 137.778883 -26.629682) (xy 137.833014 -26.640544)
			(xy 137.885012 -26.659097) (xy 137.933793 -26.684954) (xy 137.978336 -26.717573) (xy 138.017711 -26.756273)
			(xy 138.051095 -26.800246) (xy 138.07779 -26.848573) (xy 138.097239 -26.900244) (xy 138.109035 -26.954178)
			(xy 138.112931 -27.00925) (xy 138.108847 -27.064309) (xy 138.096868 -27.118203) (xy 138.077243 -27.169807)
			(xy 138.050383 -27.218043) (xy 138.01685 -27.261902) (xy 137.977344 -27.300468) (xy 137.93269 -27.332935)
			(xy 137.883821 -27.358625) (xy 137.831759 -27.377001) (xy 137.777592 -27.387679) (xy 137.722451 -27.390436)
			(xy 137.694924 -27.388312) (xy 137.671909 -27.386614) (xy 137.625936 -27.390594) (xy 137.581436 -27.402804)
			(xy 137.53987 -27.422842) (xy 137.502601 -27.450052) (xy 137.470854 -27.48354) (xy 137.445671 -27.522207)
			(xy 137.427877 -27.564783) (xy 137.418058 -27.609871) (xy 137.416794 -27.632914) (xy 137.415476 -27.660493)
			(xy 137.405741 -27.714844) (xy 137.388272 -27.767222) (xy 137.363434 -27.816536) (xy 137.331746 -27.861753)
			(xy 137.29387 -27.901928) (xy 137.250597 -27.936224) (xy 137.202831 -27.963922) (xy 137.151572 -27.984445)
			(xy 137.13307 -27.988897) (xy 138.379902 -27.988897) (xy 138.383991 -27.933261) (xy 138.396142 -27.878814)
			(xy 138.416096 -27.826719) (xy 138.443427 -27.778086) (xy 138.477551 -27.733953) (xy 138.51774 -27.695263)
			(xy 138.563137 -27.662841) (xy 138.587734 -27.649678) (xy 138.608632 -27.638316) (xy 138.646161 -27.609097)
			(xy 138.677603 -27.573411) (xy 138.701863 -27.532501) (xy 138.718095 -27.487795) (xy 138.725732 -27.44085)
			(xy 138.724509 -27.393304) (xy 138.714468 -27.346814) (xy 138.695959 -27.303002) (xy 138.683238 -27.282902)
			(xy 138.668196 -27.259402) (xy 138.644414 -27.208928) (xy 138.628239 -27.155528) (xy 138.620017 -27.100342)
			(xy 138.619923 -27.044546) (xy 138.627959 -26.989332) (xy 138.643953 -26.935878) (xy 138.667564 -26.885324)
			(xy 138.698288 -26.83875) (xy 138.73547 -26.797149) (xy 138.778316 -26.761409) (xy 138.825913 -26.732292)
			(xy 138.877243 -26.71042) (xy 138.931212 -26.696261) (xy 138.986668 -26.690115) (xy 139.042428 -26.692114)
			(xy 139.097302 -26.702215) (xy 139.150118 -26.720203) (xy 139.19975 -26.745694) (xy 139.245139 -26.778145)
			(xy 139.285316 -26.816861) (xy 139.319424 -26.861018) (xy 139.346734 -26.909673) (xy 139.366664 -26.961788)
			(xy 139.37879 -27.01625) (xy 139.382851 -27.071898) (xy 139.378761 -27.127544) (xy 139.366608 -27.182)
			(xy 139.346651 -27.234104) (xy 139.319316 -27.282745) (xy 139.285185 -27.326884) (xy 139.275446 -27.33626)
			(xy 154.696159 -27.33626) (xy 154.702259 -27.280823) (xy 154.716365 -27.226866) (xy 154.738177 -27.175537)
			(xy 154.767231 -27.127931) (xy 154.802906 -27.085063) (xy 154.844443 -27.047846) (xy 154.890956 -27.017073)
			(xy 154.941453 -26.993401) (xy 154.99486 -26.977333) (xy 155.050036 -26.969213) (xy 155.077922 -26.968704)
			(xy 155.105808 -26.969213) (xy 155.160984 -26.977333) (xy 155.214391 -26.993401) (xy 155.264888 -27.017073)
			(xy 155.311401 -27.047846) (xy 155.352938 -27.085063) (xy 155.388613 -27.127931) (xy 155.417667 -27.175537)
			(xy 155.439479 -27.226866) (xy 155.453585 -27.280823) (xy 155.459685 -27.33626) (xy 155.457648 -27.391994)
			(xy 155.447518 -27.446837) (xy 155.429511 -27.499621) (xy 155.40401 -27.549221) (xy 155.371559 -27.594579)
			(xy 155.33285 -27.634728) (xy 155.311492 -27.65122) (xy 156.748479 -27.65122) (xy 156.754579 -27.595783)
			(xy 156.768685 -27.541826) (xy 156.790497 -27.490497) (xy 156.819551 -27.442891) (xy 156.855226 -27.400023)
			(xy 156.896763 -27.362806) (xy 156.943276 -27.332033) (xy 156.993773 -27.308361) (xy 157.04718 -27.292293)
			(xy 157.102356 -27.284173) (xy 157.130242 -27.283664) (xy 157.158128 -27.284173) (xy 157.213304 -27.292293)
			(xy 157.266711 -27.308361) (xy 157.317208 -27.332033) (xy 157.363721 -27.362806) (xy 157.405258 -27.400023)
			(xy 157.440933 -27.442891) (xy 157.469987 -27.490497) (xy 157.491799 -27.541826) (xy 157.505905 -27.595783)
			(xy 157.512005 -27.65122) (xy 157.509968 -27.706954) (xy 157.499838 -27.761797) (xy 157.481831 -27.814581)
			(xy 157.45633 -27.864181) (xy 157.423879 -27.909539) (xy 157.38517 -27.949688) (xy 157.341027 -27.983774)
			(xy 157.292392 -28.01107) (xy 157.240301 -28.030993) (xy 157.185864 -28.043119) (xy 157.130242 -28.04719)
			(xy 157.07462 -28.043119) (xy 157.020183 -28.030993) (xy 156.968092 -28.01107) (xy 156.919457 -27.983774)
			(xy 156.875314 -27.949688) (xy 156.836605 -27.909539) (xy 156.804154 -27.864181) (xy 156.778653 -27.814581)
			(xy 156.760646 -27.761797) (xy 156.750516 -27.706954) (xy 156.748479 -27.65122) (xy 155.311492 -27.65122)
			(xy 155.288707 -27.668814) (xy 155.240072 -27.69611) (xy 155.187981 -27.716033) (xy 155.133544 -27.728159)
			(xy 155.077922 -27.73223) (xy 155.0223 -27.728159) (xy 154.967863 -27.716033) (xy 154.915772 -27.69611)
			(xy 154.867137 -27.668814) (xy 154.822994 -27.634728) (xy 154.784285 -27.594579) (xy 154.751834 -27.549221)
			(xy 154.726333 -27.499621) (xy 154.708326 -27.446837) (xy 154.698196 -27.391994) (xy 154.696159 -27.33626)
			(xy 139.275446 -27.33626) (xy 139.244989 -27.365581) (xy 139.199583 -27.398007) (xy 139.174982 -27.411172)
			(xy 139.154051 -27.422478) (xy 139.116518 -27.451703) (xy 139.085073 -27.487397) (xy 139.060813 -27.528315)
			(xy 139.044584 -27.57303) (xy 139.036951 -27.619983) (xy 139.038182 -27.667536) (xy 139.048232 -27.714031)
			(xy 139.066752 -27.757847) (xy 139.079478 -27.777948) (xy 139.094483 -27.801467) (xy 139.118254 -27.851935)
			(xy 139.13442 -27.905328) (xy 139.142634 -27.960506) (xy 139.142677 -27.988024) (xy 141.348967 -27.988024)
			(xy 141.355067 -27.932587) (xy 141.369173 -27.87863) (xy 141.390985 -27.827301) (xy 141.420039 -27.779695)
			(xy 141.455714 -27.736827) (xy 141.497251 -27.69961) (xy 141.543764 -27.668837) (xy 141.594261 -27.645165)
			(xy 141.647668 -27.629097) (xy 141.702844 -27.620977) (xy 141.73073 -27.620468) (xy 141.758616 -27.620977)
			(xy 141.813792 -27.629097) (xy 141.867199 -27.645165) (xy 141.917696 -27.668837) (xy 141.964209 -27.69961)
			(xy 141.972001 -27.706592) (xy 143.405097 -27.706592) (xy 143.411197 -27.651155) (xy 143.425303 -27.597198)
			(xy 143.447115 -27.545869) (xy 143.476169 -27.498263) (xy 143.511844 -27.455395) (xy 143.553381 -27.418178)
			(xy 143.599894 -27.387405) (xy 143.650391 -27.363733) (xy 143.703798 -27.347665) (xy 143.758974 -27.339545)
			(xy 143.78686 -27.339036) (xy 143.814746 -27.339545) (xy 143.869922 -27.347665) (xy 143.923329 -27.363733)
			(xy 143.973826 -27.387405) (xy 144.020339 -27.418178) (xy 144.061876 -27.455395) (xy 144.097551 -27.498263)
			(xy 144.126605 -27.545869) (xy 144.148417 -27.597198) (xy 144.162523 -27.651155) (xy 144.168623 -27.706592)
			(xy 144.166586 -27.762326) (xy 144.156456 -27.817169) (xy 144.138449 -27.869953) (xy 144.112948 -27.919553)
			(xy 144.080497 -27.964911) (xy 144.041788 -28.00506) (xy 143.997645 -28.039146) (xy 143.94901 -28.066442)
			(xy 143.896919 -28.086365) (xy 143.842482 -28.098491) (xy 143.78686 -28.102562) (xy 143.731238 -28.098491)
			(xy 143.676801 -28.086365) (xy 143.62471 -28.066442) (xy 143.576075 -28.039146) (xy 143.531932 -28.00506)
			(xy 143.493223 -27.964911) (xy 143.460772 -27.919553) (xy 143.435271 -27.869953) (xy 143.417264 -27.817169)
			(xy 143.407134 -27.762326) (xy 143.405097 -27.706592) (xy 141.972001 -27.706592) (xy 142.005746 -27.736827)
			(xy 142.041421 -27.779695) (xy 142.070475 -27.827301) (xy 142.092287 -27.87863) (xy 142.106393 -27.932587)
			(xy 142.112493 -27.988024) (xy 142.110456 -28.043758) (xy 142.100326 -28.098601) (xy 142.082319 -28.151385)
			(xy 142.056818 -28.200985) (xy 142.024367 -28.246343) (xy 141.985658 -28.286492) (xy 141.941515 -28.320578)
			(xy 141.89288 -28.347874) (xy 141.840789 -28.367797) (xy 141.786352 -28.379923) (xy 141.73073 -28.383994)
			(xy 141.675108 -28.379923) (xy 141.620671 -28.367797) (xy 141.56858 -28.347874) (xy 141.519945 -28.320578)
			(xy 141.475802 -28.286492) (xy 141.437093 -28.246343) (xy 141.404642 -28.200985) (xy 141.379141 -28.151385)
			(xy 141.361134 -28.098601) (xy 141.351004 -28.043758) (xy 141.348967 -27.988024) (xy 139.142677 -27.988024)
			(xy 139.142722 -28.016292) (xy 139.134682 -28.071496) (xy 139.118685 -28.12494) (xy 139.095073 -28.175483)
			(xy 139.064349 -28.222046) (xy 139.027169 -28.263637) (xy 138.984327 -28.299367) (xy 138.936737 -28.328475)
			(xy 138.885414 -28.350339) (xy 138.831453 -28.364493) (xy 138.776005 -28.370634) (xy 138.720255 -28.368632)
			(xy 138.665391 -28.358529) (xy 138.612585 -28.340541) (xy 138.562962 -28.315052) (xy 138.517582 -28.282605)
			(xy 138.477414 -28.243894) (xy 138.443313 -28.199743) (xy 138.416009 -28.151095) (xy 138.396083 -28.098989)
			(xy 138.383961 -28.044536) (xy 138.379902 -27.988897) (xy 137.13307 -27.988897) (xy 137.097889 -27.997362)
			(xy 137.042905 -28.002405) (xy 136.987768 -27.999469) (xy 136.93363 -27.988613) (xy 136.881623 -27.970066)
			(xy 136.832834 -27.944214) (xy 136.788281 -27.911599) (xy 136.748896 -27.8729) (xy 136.715502 -27.828928)
			(xy 136.688796 -27.780601) (xy 136.669337 -27.728928) (xy 136.657531 -27.67499) (xy 136.653625 -27.619913)
			(xy 135.751602 -27.619913) (xy 135.747368 -27.66557) (xy 135.733636 -27.721116) (xy 135.711764 -27.773989)
			(xy 135.697468 -27.798776) (xy 135.67918 -27.829002) (xy 135.67918 -28.003246) (xy 135.032478 -28.649948)
			(xy 135.752077 -28.649948) (xy 135.758177 -28.594511) (xy 135.772283 -28.540554) (xy 135.794095 -28.489225)
			(xy 135.823149 -28.441619) (xy 135.858824 -28.398751) (xy 135.900361 -28.361534) (xy 135.946874 -28.330761)
			(xy 135.997371 -28.307089) (xy 136.050778 -28.291021) (xy 136.105954 -28.282901) (xy 136.13384 -28.282392)
			(xy 136.161726 -28.282901) (xy 136.216902 -28.291021) (xy 136.270309 -28.307089) (xy 136.320806 -28.330761)
			(xy 136.367319 -28.361534) (xy 136.408856 -28.398751) (xy 136.444531 -28.441619) (xy 136.473585 -28.489225)
			(xy 136.495397 -28.540554) (xy 136.509503 -28.594511) (xy 136.515603 -28.649948) (xy 136.515315 -28.657822)
			(xy 137.464037 -28.657822) (xy 137.470137 -28.602385) (xy 137.484243 -28.548428) (xy 137.506055 -28.497099)
			(xy 137.535109 -28.449493) (xy 137.570784 -28.406625) (xy 137.612321 -28.369408) (xy 137.658834 -28.338635)
			(xy 137.709331 -28.314963) (xy 137.762738 -28.298895) (xy 137.817914 -28.290775) (xy 137.8458 -28.290266)
			(xy 137.873686 -28.290775) (xy 137.928862 -28.298895) (xy 137.982269 -28.314963) (xy 138.032766 -28.338635)
			(xy 138.079279 -28.369408) (xy 138.120816 -28.406625) (xy 138.156491 -28.449493) (xy 138.185545 -28.497099)
			(xy 138.207357 -28.548428) (xy 138.221463 -28.602385) (xy 138.227563 -28.657822) (xy 138.22656 -28.685254)
			(xy 139.442697 -28.685254) (xy 139.448797 -28.629817) (xy 139.462903 -28.57586) (xy 139.484715 -28.524531)
			(xy 139.513769 -28.476925) (xy 139.549444 -28.434057) (xy 139.590981 -28.39684) (xy 139.637494 -28.366067)
			(xy 139.687991 -28.342395) (xy 139.741398 -28.326327) (xy 139.796574 -28.318207) (xy 139.82446 -28.317698)
			(xy 139.852346 -28.318207) (xy 139.907522 -28.326327) (xy 139.960929 -28.342395) (xy 140.011426 -28.366067)
			(xy 140.057939 -28.39684) (xy 140.099476 -28.434057) (xy 140.135151 -28.476925) (xy 140.164205 -28.524531)
			(xy 140.186017 -28.57586) (xy 140.18666 -28.57832) (xy 152.048209 -28.57832) (xy 152.054309 -28.522883)
			(xy 152.068415 -28.468926) (xy 152.090227 -28.417597) (xy 152.119281 -28.369991) (xy 152.154956 -28.327123)
			(xy 152.196493 -28.289906) (xy 152.243006 -28.259133) (xy 152.293503 -28.235461) (xy 152.34691 -28.219393)
			(xy 152.402086 -28.211273) (xy 152.429972 -28.210764) (xy 152.457858 -28.211273) (xy 152.513034 -28.219393)
			(xy 152.566441 -28.235461) (xy 152.616938 -28.259133) (xy 152.663451 -28.289906) (xy 152.704988 -28.327123)
			(xy 152.740663 -28.369991) (xy 152.769717 -28.417597) (xy 152.791529 -28.468926) (xy 152.805635 -28.522883)
			(xy 152.811735 -28.57832) (xy 152.809698 -28.634054) (xy 152.799568 -28.688897) (xy 152.781561 -28.741681)
			(xy 152.75606 -28.791281) (xy 152.723609 -28.836639) (xy 152.6849 -28.876788) (xy 152.640757 -28.910874)
			(xy 152.592122 -28.93817) (xy 152.540031 -28.958093) (xy 152.539084 -28.958304) (xy 156.571187 -28.958304)
			(xy 156.577287 -28.902867) (xy 156.591393 -28.84891) (xy 156.613205 -28.797581) (xy 156.642259 -28.749975)
			(xy 156.677934 -28.707107) (xy 156.719471 -28.66989) (xy 156.765984 -28.639117) (xy 156.816481 -28.615445)
			(xy 156.869888 -28.599377) (xy 156.925064 -28.591257) (xy 156.95295 -28.590748) (xy 156.980836 -28.591257)
			(xy 157.036012 -28.599377) (xy 157.089419 -28.615445) (xy 157.139916 -28.639117) (xy 157.186429 -28.66989)
			(xy 157.227966 -28.707107) (xy 157.263641 -28.749975) (xy 157.292695 -28.797581) (xy 157.314507 -28.84891)
			(xy 157.328613 -28.902867) (xy 157.334713 -28.958304) (xy 157.332676 -29.014038) (xy 157.322546 -29.068881)
			(xy 157.304539 -29.121665) (xy 157.279038 -29.171265) (xy 157.246587 -29.216623) (xy 157.207878 -29.256772)
			(xy 157.163735 -29.290858) (xy 157.1151 -29.318154) (xy 157.063009 -29.338077) (xy 157.008572 -29.350203)
			(xy 156.95295 -29.354274) (xy 156.897328 -29.350203) (xy 156.842891 -29.338077) (xy 156.7908 -29.318154)
			(xy 156.742165 -29.290858) (xy 156.698022 -29.256772) (xy 156.659313 -29.216623) (xy 156.626862 -29.171265)
			(xy 156.601361 -29.121665) (xy 156.583354 -29.068881) (xy 156.573224 -29.014038) (xy 156.571187 -28.958304)
			(xy 152.539084 -28.958304) (xy 152.485594 -28.970219) (xy 152.429972 -28.97429) (xy 152.37435 -28.970219)
			(xy 152.319913 -28.958093) (xy 152.267822 -28.93817) (xy 152.219187 -28.910874) (xy 152.175044 -28.876788)
			(xy 152.136335 -28.836639) (xy 152.103884 -28.791281) (xy 152.078383 -28.741681) (xy 152.060376 -28.688897)
			(xy 152.050246 -28.634054) (xy 152.048209 -28.57832) (xy 140.18666 -28.57832) (xy 140.200123 -28.629817)
			(xy 140.206223 -28.685254) (xy 140.204186 -28.740988) (xy 140.194056 -28.795831) (xy 140.176049 -28.848615)
			(xy 140.150548 -28.898215) (xy 140.118097 -28.943573) (xy 140.079388 -28.983722) (xy 140.035245 -29.017808)
			(xy 139.98661 -29.045104) (xy 139.934519 -29.065027) (xy 139.880082 -29.077153) (xy 139.82446 -29.081224)
			(xy 139.768838 -29.077153) (xy 139.714401 -29.065027) (xy 139.66231 -29.045104) (xy 139.613675 -29.017808)
			(xy 139.569532 -28.983722) (xy 139.530823 -28.943573) (xy 139.498372 -28.898215) (xy 139.472871 -28.848615)
			(xy 139.454864 -28.795831) (xy 139.444734 -28.740988) (xy 139.442697 -28.685254) (xy 138.22656 -28.685254)
			(xy 138.225526 -28.713556) (xy 138.215396 -28.768399) (xy 138.197389 -28.821183) (xy 138.171888 -28.870783)
			(xy 138.139437 -28.916141) (xy 138.100728 -28.95629) (xy 138.056585 -28.990376) (xy 138.00795 -29.017672)
			(xy 137.955859 -29.037595) (xy 137.901422 -29.049721) (xy 137.8458 -29.053792) (xy 137.790178 -29.049721)
			(xy 137.735741 -29.037595) (xy 137.68365 -29.017672) (xy 137.635015 -28.990376) (xy 137.590872 -28.95629)
			(xy 137.552163 -28.916141) (xy 137.519712 -28.870783) (xy 137.494211 -28.821183) (xy 137.476204 -28.768399)
			(xy 137.466074 -28.713556) (xy 137.464037 -28.657822) (xy 136.515315 -28.657822) (xy 136.513566 -28.705682)
			(xy 136.503436 -28.760525) (xy 136.485429 -28.813309) (xy 136.459928 -28.862909) (xy 136.427477 -28.908267)
			(xy 136.388768 -28.948416) (xy 136.344625 -28.982502) (xy 136.29599 -29.009798) (xy 136.243899 -29.029721)
			(xy 136.189462 -29.041847) (xy 136.13384 -29.045918) (xy 136.078218 -29.041847) (xy 136.023781 -29.029721)
			(xy 135.97169 -29.009798) (xy 135.923055 -28.982502) (xy 135.878912 -28.948416) (xy 135.840203 -28.908267)
			(xy 135.807752 -28.862909) (xy 135.782251 -28.813309) (xy 135.764244 -28.760525) (xy 135.754114 -28.705682)
			(xy 135.752077 -28.649948) (xy 135.032478 -28.649948) (xy 133.79245 -29.889976) (xy 147.910803 -29.889976)
			(xy 147.916903 -29.834539) (xy 147.931009 -29.780582) (xy 147.952821 -29.729253) (xy 147.981875 -29.681647)
			(xy 148.01755 -29.638779) (xy 148.059087 -29.601562) (xy 148.1056 -29.570789) (xy 148.156097 -29.547117)
			(xy 148.209504 -29.531049) (xy 148.26468 -29.522929) (xy 148.292566 -29.52242) (xy 148.320452 -29.522929)
			(xy 148.375628 -29.531049) (xy 148.429035 -29.547117) (xy 148.479532 -29.570789) (xy 148.526045 -29.601562)
			(xy 148.567582 -29.638779) (xy 148.603257 -29.681647) (xy 148.632311 -29.729253) (xy 148.654123 -29.780582)
			(xy 148.668229 -29.834539) (xy 148.672233 -29.870926) (xy 150.224489 -29.870926) (xy 150.230589 -29.815489)
			(xy 150.244695 -29.761532) (xy 150.266507 -29.710203) (xy 150.295561 -29.662597) (xy 150.331236 -29.619729)
			(xy 150.372773 -29.582512) (xy 150.419286 -29.551739) (xy 150.469783 -29.528067) (xy 150.52319 -29.511999)
			(xy 150.578366 -29.503879) (xy 150.606252 -29.50337) (xy 150.634138 -29.503879) (xy 150.689314 -29.511999)
			(xy 150.742721 -29.528067) (xy 150.793218 -29.551739) (xy 150.839731 -29.582512) (xy 150.881268 -29.619729)
			(xy 150.916943 -29.662597) (xy 150.945997 -29.710203) (xy 150.967809 -29.761532) (xy 150.981915 -29.815489)
			(xy 150.988015 -29.870926) (xy 150.985978 -29.92666) (xy 150.975848 -29.981503) (xy 150.957841 -30.034287)
			(xy 150.93234 -30.083887) (xy 150.899889 -30.129245) (xy 150.86118 -30.169394) (xy 150.817037 -30.20348)
			(xy 150.768402 -30.230776) (xy 150.716311 -30.250699) (xy 150.661874 -30.262825) (xy 150.606252 -30.266896)
			(xy 150.55063 -30.262825) (xy 150.496193 -30.250699) (xy 150.444102 -30.230776) (xy 150.395467 -30.20348)
			(xy 150.351324 -30.169394) (xy 150.312615 -30.129245) (xy 150.280164 -30.083887) (xy 150.254663 -30.034287)
			(xy 150.236656 -29.981503) (xy 150.226526 -29.92666) (xy 150.224489 -29.870926) (xy 148.672233 -29.870926)
			(xy 148.674329 -29.889976) (xy 148.672292 -29.94571) (xy 148.662162 -30.000553) (xy 148.644155 -30.053337)
			(xy 148.618654 -30.102937) (xy 148.586203 -30.148295) (xy 148.547494 -30.188444) (xy 148.503351 -30.22253)
			(xy 148.454716 -30.249826) (xy 148.402625 -30.269749) (xy 148.348188 -30.281875) (xy 148.292566 -30.285946)
			(xy 148.236944 -30.281875) (xy 148.182507 -30.269749) (xy 148.130416 -30.249826) (xy 148.081781 -30.22253)
			(xy 148.037638 -30.188444) (xy 147.998929 -30.148295) (xy 147.966478 -30.102937) (xy 147.940977 -30.053337)
			(xy 147.92297 -30.000553) (xy 147.91284 -29.94571) (xy 147.910803 -29.889976) (xy 133.79245 -29.889976)
			(xy 133.344158 -30.338268) (xy 127.154686 -30.338268) (xy 126.7841 -30.708854) (xy 126.7841 -30.932392)
			(xy 147.868131 -30.932392) (xy 147.874231 -30.876955) (xy 147.888337 -30.822998) (xy 147.910149 -30.771669)
			(xy 147.939203 -30.724063) (xy 147.974878 -30.681195) (xy 148.016415 -30.643978) (xy 148.062928 -30.613205)
			(xy 148.113425 -30.589533) (xy 148.166832 -30.573465) (xy 148.222008 -30.565345) (xy 148.249894 -30.564836)
			(xy 148.27778 -30.565345) (xy 148.332956 -30.573465) (xy 148.386363 -30.589533) (xy 148.43686 -30.613205)
			(xy 148.483373 -30.643978) (xy 148.52491 -30.681195) (xy 148.560585 -30.724063) (xy 148.589639 -30.771669)
			(xy 148.611451 -30.822998) (xy 148.625557 -30.876955) (xy 148.631657 -30.932392) (xy 148.62962 -30.988126)
			(xy 148.61949 -31.042969) (xy 148.601483 -31.095753) (xy 148.575982 -31.145353) (xy 148.543531 -31.190711)
			(xy 148.504822 -31.23086) (xy 148.460679 -31.264946) (xy 148.412044 -31.292242) (xy 148.359953 -31.312165)
			(xy 148.315675 -31.322028) (xy 150.727917 -31.322028) (xy 150.734017 -31.266591) (xy 150.748123 -31.212634)
			(xy 150.769935 -31.161305) (xy 150.798989 -31.113699) (xy 150.834664 -31.070831) (xy 150.876201 -31.033614)
			(xy 150.922714 -31.002841) (xy 150.973211 -30.979169) (xy 151.026618 -30.963101) (xy 151.081794 -30.954981)
			(xy 151.10968 -30.954472) (xy 151.137566 -30.954981) (xy 151.192742 -30.963101) (xy 151.246149 -30.979169)
			(xy 151.296646 -31.002841) (xy 151.343159 -31.033614) (xy 151.384696 -31.070831) (xy 151.420371 -31.113699)
			(xy 151.449425 -31.161305) (xy 151.471237 -31.212634) (xy 151.485343 -31.266591) (xy 151.491443 -31.322028)
			(xy 151.489406 -31.377762) (xy 151.479276 -31.432605) (xy 151.463189 -31.479762) (xy 153.306017 -31.479762)
			(xy 153.312117 -31.424325) (xy 153.326223 -31.370368) (xy 153.348035 -31.319039) (xy 153.377089 -31.271433)
			(xy 153.412764 -31.228565) (xy 153.454301 -31.191348) (xy 153.500814 -31.160575) (xy 153.551311 -31.136903)
			(xy 153.604718 -31.120835) (xy 153.659894 -31.112715) (xy 153.68778 -31.112206) (xy 153.715666 -31.112715)
			(xy 153.770842 -31.120835) (xy 153.824249 -31.136903) (xy 153.874746 -31.160575) (xy 153.921259 -31.191348)
			(xy 153.962796 -31.228565) (xy 153.998471 -31.271433) (xy 154.027525 -31.319039) (xy 154.049337 -31.370368)
			(xy 154.063443 -31.424325) (xy 154.069543 -31.479762) (xy 154.067506 -31.535496) (xy 154.057376 -31.590339)
			(xy 154.039369 -31.643123) (xy 154.013868 -31.692723) (xy 153.981417 -31.738081) (xy 153.942708 -31.77823)
			(xy 153.898565 -31.812316) (xy 153.84993 -31.839612) (xy 153.797839 -31.859535) (xy 153.743402 -31.871661)
			(xy 153.68778 -31.875732) (xy 153.632158 -31.871661) (xy 153.577721 -31.859535) (xy 153.52563 -31.839612)
			(xy 153.476995 -31.812316) (xy 153.432852 -31.77823) (xy 153.394143 -31.738081) (xy 153.361692 -31.692723)
			(xy 153.336191 -31.643123) (xy 153.318184 -31.590339) (xy 153.308054 -31.535496) (xy 153.306017 -31.479762)
			(xy 151.463189 -31.479762) (xy 151.461269 -31.485389) (xy 151.435768 -31.534989) (xy 151.403317 -31.580347)
			(xy 151.364608 -31.620496) (xy 151.320465 -31.654582) (xy 151.27183 -31.681878) (xy 151.219739 -31.701801)
			(xy 151.165302 -31.713927) (xy 151.10968 -31.717998) (xy 151.054058 -31.713927) (xy 150.999621 -31.701801)
			(xy 150.94753 -31.681878) (xy 150.898895 -31.654582) (xy 150.854752 -31.620496) (xy 150.816043 -31.580347)
			(xy 150.783592 -31.534989) (xy 150.758091 -31.485389) (xy 150.740084 -31.432605) (xy 150.729954 -31.377762)
			(xy 150.727917 -31.322028) (xy 148.315675 -31.322028) (xy 148.305516 -31.324291) (xy 148.249894 -31.328362)
			(xy 148.194272 -31.324291) (xy 148.139835 -31.312165) (xy 148.087744 -31.292242) (xy 148.039109 -31.264946)
			(xy 147.994966 -31.23086) (xy 147.956257 -31.190711) (xy 147.923806 -31.145353) (xy 147.898305 -31.095753)
			(xy 147.880298 -31.042969) (xy 147.870168 -30.988126) (xy 147.868131 -30.932392) (xy 126.7841 -30.932392)
			(xy 126.7841 -31.526068) (xy 128.879832 -31.526068) (xy 128.881748 -31.471435) (xy 128.891444 -31.417635)
			(xy 128.908721 -31.365771) (xy 128.933226 -31.316904) (xy 128.964457 -31.272036) (xy 129.001773 -31.232087)
			(xy 129.04441 -31.197875) (xy 129.091496 -31.1701) (xy 129.142064 -31.149332) (xy 129.195079 -31.135997)
			(xy 129.249455 -31.130367) (xy 129.304078 -31.132557) (xy 129.357828 -31.142524) (xy 129.409605 -31.160063)
			(xy 129.458348 -31.184814) (xy 129.503057 -31.21627) (xy 129.542818 -31.253787) (xy 129.576815 -31.296596)
			(xy 129.604352 -31.343821) (xy 129.624865 -31.394493) (xy 129.637933 -31.447575) (xy 129.643289 -31.501978)
			(xy 129.640823 -31.556589) (xy 129.630586 -31.610289) (xy 129.612787 -31.661977) (xy 129.600706 -31.6865)
			(xy 129.590639 -31.707125) (xy 129.577319 -31.751041) (xy 129.572097 -31.796634) (xy 129.575142 -31.842425)
			(xy 129.582835 -31.872954) (xy 131.352797 -31.872954) (xy 131.358897 -31.817517) (xy 131.373003 -31.76356)
			(xy 131.394815 -31.712231) (xy 131.423869 -31.664625) (xy 131.459544 -31.621757) (xy 131.501081 -31.58454)
			(xy 131.547594 -31.553767) (xy 131.598091 -31.530095) (xy 131.651498 -31.514027) (xy 131.706674 -31.505907)
			(xy 131.73456 -31.505398) (xy 131.762446 -31.505907) (xy 131.817622 -31.514027) (xy 131.871029 -31.530095)
			(xy 131.921526 -31.553767) (xy 131.968039 -31.58454) (xy 132.009576 -31.621757) (xy 132.045251 -31.664625)
			(xy 132.074305 -31.712231) (xy 132.096117 -31.76356) (xy 132.110223 -31.817517) (xy 132.116323 -31.872954)
			(xy 132.114286 -31.928688) (xy 132.104156 -31.983531) (xy 132.086149 -32.036315) (xy 132.060648 -32.085915)
			(xy 132.028197 -32.131273) (xy 131.989488 -32.171422) (xy 131.945345 -32.205508) (xy 131.89671 -32.232804)
			(xy 131.844619 -32.252727) (xy 131.790182 -32.264853) (xy 131.73456 -32.268924) (xy 131.678938 -32.264853)
			(xy 131.624501 -32.252727) (xy 131.57241 -32.232804) (xy 131.523775 -32.205508) (xy 131.479632 -32.171422)
			(xy 131.440923 -32.131273) (xy 131.408472 -32.085915) (xy 131.382971 -32.036315) (xy 131.364964 -31.983531)
			(xy 131.354834 -31.928688) (xy 131.352797 -31.872954) (xy 129.582835 -31.872954) (xy 129.586356 -31.886925)
			(xy 129.605373 -31.928691) (xy 129.631577 -31.966365) (xy 129.664117 -31.998726) (xy 129.682748 -32.012128)
			(xy 129.704959 -32.028068) (xy 129.745095 -32.065184) (xy 129.77952 -32.107649) (xy 129.80753 -32.154595)
			(xy 129.828551 -32.205059) (xy 129.842151 -32.258007) (xy 129.848052 -32.312355) (xy 129.846133 -32.366988)
			(xy 129.836433 -32.420788) (xy 129.819745 -32.47087) (xy 150.732489 -32.47087) (xy 150.738589 -32.415433)
			(xy 150.752695 -32.361476) (xy 150.774507 -32.310147) (xy 150.803561 -32.262541) (xy 150.839236 -32.219673)
			(xy 150.880773 -32.182456) (xy 150.927286 -32.151683) (xy 150.977783 -32.128011) (xy 151.03119 -32.111943)
			(xy 151.086366 -32.103823) (xy 151.114252 -32.103314) (xy 151.142138 -32.103823) (xy 151.197314 -32.111943)
			(xy 151.250721 -32.128011) (xy 151.301218 -32.151683) (xy 151.347731 -32.182456) (xy 151.389268 -32.219673)
			(xy 151.424943 -32.262541) (xy 151.453997 -32.310147) (xy 151.475809 -32.361476) (xy 151.489915 -32.415433)
			(xy 151.496015 -32.47087) (xy 151.493978 -32.526604) (xy 151.483848 -32.581447) (xy 151.465841 -32.634231)
			(xy 151.44034 -32.683831) (xy 151.407889 -32.729189) (xy 151.36918 -32.769338) (xy 151.325037 -32.803424)
			(xy 151.276402 -32.83072) (xy 151.224311 -32.850643) (xy 151.169874 -32.862769) (xy 151.114252 -32.86684)
			(xy 151.05863 -32.862769) (xy 151.004193 -32.850643) (xy 150.952102 -32.83072) (xy 150.903467 -32.803424)
			(xy 150.859324 -32.769338) (xy 150.820615 -32.729189) (xy 150.788164 -32.683831) (xy 150.762663 -32.634231)
			(xy 150.744656 -32.581447) (xy 150.734526 -32.526604) (xy 150.732489 -32.47087) (xy 129.819745 -32.47087)
			(xy 129.819152 -32.472651) (xy 129.794643 -32.521516) (xy 129.763408 -32.566381) (xy 129.726088 -32.606326)
			(xy 129.683446 -32.640535) (xy 129.636358 -32.668304) (xy 129.585787 -32.689066) (xy 129.53277 -32.702395)
			(xy 129.478393 -32.708018) (xy 129.42377 -32.70582) (xy 129.370021 -32.695845) (xy 129.318247 -32.678299)
			(xy 129.269508 -32.65354) (xy 129.224803 -32.622076) (xy 129.185049 -32.584552) (xy 129.15106 -32.541736)
			(xy 129.123531 -32.494507) (xy 129.103028 -32.44383) (xy 129.08997 -32.390746) (xy 129.084626 -32.336341)
			(xy 129.087103 -32.28173) (xy 129.097353 -32.228033) (xy 129.115164 -32.176349) (xy 129.12725 -32.151828)
			(xy 129.137301 -32.131195) (xy 129.150627 -32.087281) (xy 129.155854 -32.041689) (xy 129.152813 -31.995899)
			(xy 129.141602 -31.951399) (xy 129.122585 -31.909633) (xy 129.096381 -31.871959) (xy 129.06384 -31.839601)
			(xy 129.045208 -31.8262) (xy 129.022936 -31.810349) (xy 128.982799 -31.773235) (xy 128.948373 -31.73077)
			(xy 128.920361 -31.683825) (xy 128.899339 -31.633362) (xy 128.885736 -31.580415) (xy 128.879832 -31.526068)
			(xy 126.7841 -31.526068) (xy 126.7841 -32.174942) (xy 126.896622 -32.298894) (xy 126.937516 -32.307276)
			(xy 126.964414 -32.313216) (xy 127.016268 -32.331799) (xy 127.064911 -32.357646) (xy 127.109332 -32.39022)
			(xy 127.148606 -32.428843) (xy 127.181917 -32.472713) (xy 127.208572 -32.520918) (xy 127.228018 -32.572455)
			(xy 127.239851 -32.626253) (xy 127.243823 -32.681193) (xy 127.239853 -32.736133) (xy 127.228023 -32.789932)
			(xy 127.208578 -32.841469) (xy 127.181925 -32.889675) (xy 127.148615 -32.933546) (xy 127.109343 -32.972171)
			(xy 127.064924 -33.004746) (xy 127.016282 -33.030595) (xy 126.964428 -33.04918) (xy 126.937516 -33.055052)
			(xy 126.896622 -33.063434) (xy 126.7841 -33.187386) (xy 126.7841 -34.022792) (xy 126.784557 -34.045003)
			(xy 126.792279 -34.088748) (xy 126.80749 -34.130485) (xy 126.829726 -34.168941) (xy 126.858309 -34.202945)
			(xy 126.892369 -34.231462) (xy 126.930869 -34.253622) (xy 126.972636 -34.26875) (xy 127.016396 -34.276386)
			(xy 127.038608 -34.276792) (xy 127.066587 -34.27611) (xy 127.122248 -34.281958) (xy 127.176456 -34.295875)
			(xy 127.22805 -34.317561) (xy 127.275923 -34.346552) (xy 127.319047 -34.382225) (xy 127.344103 -34.410052)
			(xy 138.903371 -34.410052) (xy 138.905212 -34.355184) (xy 138.914897 -34.301146) (xy 138.932225 -34.249054)
			(xy 138.95684 -34.199983) (xy 138.988232 -34.154946) (xy 139.025754 -34.114872) (xy 139.068632 -34.080588)
			(xy 139.11598 -34.052803) (xy 139.166821 -34.03209) (xy 139.220105 -34.018875) (xy 139.247372 -34.01568)
			(xy 139.269837 -34.012919) (xy 139.31336 -34.000513) (xy 139.353998 -33.980595) (xy 139.390466 -33.953796)
			(xy 139.421612 -33.920961) (xy 139.44645 -33.88313) (xy 139.464196 -33.841498) (xy 139.474289 -33.797381)
			(xy 139.47641 -33.752175) (xy 139.47394 -33.729676) (xy 139.470793 -33.702404) (xy 139.471433 -33.64751)
			(xy 139.479932 -33.593274) (xy 139.496117 -33.540816) (xy 139.519651 -33.491219) (xy 139.550051 -33.445506)
			(xy 139.586687 -33.404621) (xy 139.628804 -33.369408) (xy 139.675532 -33.340594) (xy 139.725907 -33.318774)
			(xy 139.77889 -33.304398) (xy 139.833385 -33.297763) (xy 139.888269 -33.299006) (xy 139.942408 -33.3081)
			(xy 139.994685 -33.32486) (xy 140.044021 -33.348938) (xy 140.089398 -33.379837) (xy 140.129878 -33.41692)
			(xy 140.164626 -33.459421) (xy 140.192925 -33.506463) (xy 140.214191 -33.557074) (xy 140.227984 -33.610211)
			(xy 140.234021 -33.664776) (xy 140.232175 -33.719643) (xy 140.222487 -33.773679) (xy 140.205154 -33.825769)
			(xy 140.204548 -33.826976) (xy 150.224489 -33.826976) (xy 150.230589 -33.771539) (xy 150.244695 -33.717582)
			(xy 150.266507 -33.666253) (xy 150.295561 -33.618647) (xy 150.331236 -33.575779) (xy 150.372773 -33.538562)
			(xy 150.419286 -33.507789) (xy 150.469783 -33.484117) (xy 150.52319 -33.468049) (xy 150.578366 -33.459929)
			(xy 150.606252 -33.45942) (xy 150.634138 -33.459929) (xy 150.689314 -33.468049) (xy 150.742721 -33.484117)
			(xy 150.793218 -33.507789) (xy 150.839731 -33.538562) (xy 150.881268 -33.575779) (xy 150.916943 -33.618647)
			(xy 150.945997 -33.666253) (xy 150.967809 -33.717582) (xy 150.981915 -33.771539) (xy 150.988015 -33.826976)
			(xy 150.985978 -33.88271) (xy 150.975848 -33.937553) (xy 150.957841 -33.990337) (xy 150.93234 -34.039937)
			(xy 150.899889 -34.085295) (xy 150.86118 -34.125444) (xy 150.817037 -34.15953) (xy 150.768402 -34.186826)
			(xy 150.716311 -34.206749) (xy 150.661874 -34.218875) (xy 150.606252 -34.222946) (xy 150.55063 -34.218875)
			(xy 150.496193 -34.206749) (xy 150.444102 -34.186826) (xy 150.395467 -34.15953) (xy 150.351324 -34.125444)
			(xy 150.312615 -34.085295) (xy 150.280164 -34.039937) (xy 150.254663 -33.990337) (xy 150.236656 -33.937553)
			(xy 150.226526 -33.88271) (xy 150.224489 -33.826976) (xy 140.204548 -33.826976) (xy 140.180536 -33.874838)
			(xy 140.149141 -33.919872) (xy 140.111616 -33.959943) (xy 140.068736 -33.994222) (xy 140.021386 -34.022003)
			(xy 139.970544 -34.042712) (xy 139.917259 -34.055921) (xy 139.889992 -34.059114) (xy 139.867524 -34.061853)
			(xy 139.824002 -34.074264) (xy 139.783365 -34.094186) (xy 139.746898 -34.12099) (xy 139.715753 -34.153827)
			(xy 139.690916 -34.19166) (xy 139.67317 -34.233293) (xy 139.663077 -34.277411) (xy 139.660955 -34.322619)
			(xy 139.663424 -34.345118) (xy 139.666616 -34.372384) (xy 139.665978 -34.427279) (xy 139.65748 -34.481516)
			(xy 139.641297 -34.533975) (xy 139.617764 -34.583574) (xy 139.587366 -34.629288) (xy 139.550731 -34.670175)
			(xy 139.508615 -34.70539) (xy 139.461887 -34.734206) (xy 139.411513 -34.756029) (xy 139.35853 -34.770408)
			(xy 139.304035 -34.777046) (xy 139.24915 -34.775806) (xy 139.19501 -34.766714) (xy 139.142731 -34.749957)
			(xy 139.093393 -34.725882) (xy 139.048014 -34.694985) (xy 139.007532 -34.657904) (xy 138.97278 -34.615405)
			(xy 138.944478 -34.568364) (xy 138.923209 -34.517753) (xy 138.909411 -34.464617) (xy 138.903371 -34.410052)
			(xy 127.344103 -34.410052) (xy 127.356497 -34.423816) (xy 127.387469 -34.470431) (xy 127.411299 -34.521071)
			(xy 127.427476 -34.574649) (xy 127.435652 -34.630015) (xy 127.435652 -34.685981) (xy 127.427477 -34.741348)
			(xy 127.4113 -34.794926) (xy 127.387471 -34.845566) (xy 127.356499 -34.892181) (xy 127.31905 -34.933772)
			(xy 127.293845 -34.954623) (xy 131.253594 -34.954623) (xy 131.260423 -34.899352) (xy 131.275216 -34.845662)
			(xy 131.297659 -34.794693) (xy 131.327274 -34.747529) (xy 131.363432 -34.705172) (xy 131.405365 -34.668524)
			(xy 131.452182 -34.638362) (xy 131.502886 -34.615329) (xy 131.556401 -34.599913) (xy 131.611589 -34.592442)
			(xy 131.667276 -34.593075) (xy 131.72228 -34.601799) (xy 131.77543 -34.618429) (xy 131.825598 -34.642609)
			(xy 131.871716 -34.673828) (xy 131.912805 -34.711421) (xy 131.947991 -34.754588) (xy 131.976525 -34.802414)
			(xy 131.997803 -34.85388) (xy 132.011371 -34.907893) (xy 132.016941 -34.963305) (xy 132.014394 -35.018937)
			(xy 132.003785 -35.073609) (xy 131.985339 -35.126156) (xy 131.959449 -35.175463) (xy 131.926664 -35.220481)
			(xy 131.907534 -35.240722) (xy 131.891367 -35.257999) (xy 131.865024 -35.297293) (xy 131.846412 -35.340786)
			(xy 131.836174 -35.386973) (xy 131.835839 -35.397458) (xy 138.812015 -35.397458) (xy 138.818115 -35.342021)
			(xy 138.832221 -35.288064) (xy 138.854033 -35.236735) (xy 138.883087 -35.189129) (xy 138.918762 -35.146261)
			(xy 138.960299 -35.109044) (xy 139.006812 -35.078271) (xy 139.057309 -35.054599) (xy 139.110716 -35.038531)
			(xy 139.165892 -35.030411) (xy 139.193778 -35.029902) (xy 139.221664 -35.030411) (xy 139.27684 -35.038531)
			(xy 139.330247 -35.054599) (xy 139.380744 -35.078271) (xy 139.427257 -35.109044) (xy 139.468794 -35.146261)
			(xy 139.490347 -35.17216) (xy 139.870179 -35.17216) (xy 139.876279 -35.116723) (xy 139.890385 -35.062766)
			(xy 139.912197 -35.011437) (xy 139.941251 -34.963831) (xy 139.976926 -34.920963) (xy 140.018463 -34.883746)
			(xy 140.064976 -34.852973) (xy 140.115473 -34.829301) (xy 140.16888 -34.813233) (xy 140.224056 -34.805113)
			(xy 140.251942 -34.804604) (xy 140.279828 -34.805113) (xy 140.335004 -34.813233) (xy 140.388411 -34.829301)
			(xy 140.438908 -34.852973) (xy 140.485421 -34.883746) (xy 140.526958 -34.920963) (xy 140.562633 -34.963831)
			(xy 140.591687 -35.011437) (xy 140.613499 -35.062766) (xy 140.627605 -35.116723) (xy 140.633705 -35.17216)
			(xy 140.631668 -35.227894) (xy 140.630843 -35.232358) (xy 148.962109 -35.232358) (xy 148.968209 -35.176921)
			(xy 148.982315 -35.122964) (xy 149.004127 -35.071635) (xy 149.033181 -35.024029) (xy 149.068856 -34.981161)
			(xy 149.110393 -34.943944) (xy 149.156906 -34.913171) (xy 149.207403 -34.889499) (xy 149.26081 -34.873431)
			(xy 149.315986 -34.865311) (xy 149.343872 -34.864802) (xy 149.371758 -34.865311) (xy 149.426934 -34.873431)
			(xy 149.480341 -34.889499) (xy 149.530838 -34.913171) (xy 149.577351 -34.943944) (xy 149.618888 -34.981161)
			(xy 149.654563 -35.024029) (xy 149.683617 -35.071635) (xy 149.705429 -35.122964) (xy 149.719535 -35.176921)
			(xy 149.725635 -35.232358) (xy 149.723598 -35.288092) (xy 149.713468 -35.342935) (xy 149.695461 -35.395719)
			(xy 149.66996 -35.445319) (xy 149.637509 -35.490677) (xy 149.5988 -35.530826) (xy 149.554657 -35.564912)
			(xy 149.506022 -35.592208) (xy 149.453931 -35.612131) (xy 149.399494 -35.624257) (xy 149.343872 -35.628328)
			(xy 149.28825 -35.624257) (xy 149.233813 -35.612131) (xy 149.181722 -35.592208) (xy 149.133087 -35.564912)
			(xy 149.088944 -35.530826) (xy 149.050235 -35.490677) (xy 149.017784 -35.445319) (xy 148.992283 -35.395719)
			(xy 148.974276 -35.342935) (xy 148.964146 -35.288092) (xy 148.962109 -35.232358) (xy 140.630843 -35.232358)
			(xy 140.621538 -35.282737) (xy 140.603531 -35.335521) (xy 140.57803 -35.385121) (xy 140.545579 -35.430479)
			(xy 140.50687 -35.470628) (xy 140.462727 -35.504714) (xy 140.414092 -35.53201) (xy 140.362001 -35.551933)
			(xy 140.307564 -35.564059) (xy 140.251942 -35.56813) (xy 140.19632 -35.564059) (xy 140.141883 -35.551933)
			(xy 140.089792 -35.53201) (xy 140.041157 -35.504714) (xy 139.997014 -35.470628) (xy 139.958305 -35.430479)
			(xy 139.925854 -35.385121) (xy 139.900353 -35.335521) (xy 139.882346 -35.282737) (xy 139.872216 -35.227894)
			(xy 139.870179 -35.17216) (xy 139.490347 -35.17216) (xy 139.504469 -35.189129) (xy 139.533523 -35.236735)
			(xy 139.555335 -35.288064) (xy 139.569441 -35.342021) (xy 139.575541 -35.397458) (xy 139.573504 -35.453192)
			(xy 139.563374 -35.508035) (xy 139.545367 -35.560819) (xy 139.519866 -35.610419) (xy 139.487415 -35.655777)
			(xy 139.448706 -35.695926) (xy 139.429578 -35.710696) (xy 150.225062 -35.710696) (xy 150.232453 -35.656441)
			(xy 150.247525 -35.603799) (xy 150.269968 -35.553853) (xy 150.299322 -35.507629) (xy 150.334983 -35.466076)
			(xy 150.376218 -35.430048) (xy 150.42218 -35.400286) (xy 150.471926 -35.377401) (xy 150.524432 -35.361863)
			(xy 150.57862 -35.353992) (xy 150.605998 -35.353498) (xy 150.628491 -35.352919) (xy 150.672771 -35.344979)
			(xy 150.714961 -35.329364) (xy 150.75374 -35.306563) (xy 150.787898 -35.277288) (xy 150.816366 -35.242454)
			(xy 150.838253 -35.203151) (xy 150.852877 -35.160608) (xy 150.859779 -35.116154) (xy 150.859744 -35.093656)
			(xy 150.859621 -35.066271) (xy 150.866218 -35.011909) (xy 150.880521 -34.959048) (xy 150.902234 -34.908775)
			(xy 150.930911 -34.862123) (xy 150.965964 -34.82005) (xy 151.006671 -34.783421) (xy 151.052198 -34.752988)
			(xy 151.101608 -34.729377) (xy 151.153885 -34.713073) (xy 151.207957 -34.70441) (xy 151.262712 -34.703568)
			(xy 151.317025 -34.710562) (xy 151.36978 -34.725249) (xy 151.419893 -34.747328) (xy 151.466335 -34.776345)
			(xy 151.508151 -34.811704) (xy 151.544482 -34.852678) (xy 151.574582 -34.898425) (xy 151.597832 -34.948006)
			(xy 151.613754 -35.000401) (xy 151.622022 -35.054535) (xy 151.622465 -35.109294) (xy 151.615075 -35.163555)
			(xy 151.600003 -35.216201) (xy 151.577559 -35.266152) (xy 151.548204 -35.312381) (xy 151.512541 -35.353937)
			(xy 151.471304 -35.389969) (xy 151.425338 -35.419734) (xy 151.375589 -35.442621) (xy 151.323079 -35.458161)
			(xy 151.268886 -35.466034) (xy 151.241506 -35.466528) (xy 151.219012 -35.467084) (xy 151.174729 -35.475025)
			(xy 151.132537 -35.490641) (xy 151.093755 -35.513445) (xy 151.059597 -35.542723) (xy 151.031129 -35.57756)
			(xy 151.009243 -35.616866) (xy 150.994622 -35.659413) (xy 150.987723 -35.70387) (xy 150.98776 -35.72637)
			(xy 150.987852 -35.753753) (xy 150.981251 -35.808111) (xy 150.966946 -35.860966) (xy 150.945232 -35.911234)
			(xy 150.916554 -35.95788) (xy 150.881502 -35.999948) (xy 150.840795 -36.036571) (xy 150.795271 -36.066999)
			(xy 150.745864 -36.090605) (xy 150.693589 -36.106906) (xy 150.639521 -36.115565) (xy 150.584771 -36.116405)
			(xy 150.530463 -36.109409) (xy 150.477713 -36.09472) (xy 150.427605 -36.072641) (xy 150.381168 -36.043624)
			(xy 150.339357 -36.008267) (xy 150.303031 -35.967295) (xy 150.272935 -35.92155) (xy 150.249689 -35.871973)
			(xy 150.233769 -35.819581) (xy 150.225504 -35.765452) (xy 150.225062 -35.710696) (xy 139.429578 -35.710696)
			(xy 139.404563 -35.730012) (xy 139.355928 -35.757308) (xy 139.303837 -35.777231) (xy 139.2494 -35.789357)
			(xy 139.193778 -35.793428) (xy 139.138156 -35.789357) (xy 139.083719 -35.777231) (xy 139.031628 -35.757308)
			(xy 138.982993 -35.730012) (xy 138.93885 -35.695926) (xy 138.900141 -35.655777) (xy 138.86769 -35.610419)
			(xy 138.842189 -35.560819) (xy 138.824182 -35.508035) (xy 138.814052 -35.453192) (xy 138.812015 -35.397458)
			(xy 131.835839 -35.397458) (xy 131.834664 -35.434256) (xy 131.841934 -35.481002) (xy 131.857733 -35.525594)
			(xy 131.881515 -35.566489) (xy 131.912458 -35.602274) (xy 131.930648 -35.617404) (xy 131.952128 -35.635132)
			(xy 131.9902 -35.67578) (xy 132.021957 -35.721532) (xy 132.046724 -35.771415) (xy 132.063975 -35.82437)
			(xy 132.073342 -35.879269) (xy 132.074627 -35.934948) (xy 132.067803 -35.990221) (xy 132.053014 -36.043915)
			(xy 132.030575 -36.094888) (xy 132.000962 -36.142056) (xy 131.964806 -36.184417) (xy 131.922875 -36.221071)
			(xy 131.876059 -36.251238) (xy 131.825355 -36.274278) (xy 131.77184 -36.289699) (xy 131.71665 -36.297176)
			(xy 131.660961 -36.296548) (xy 131.605954 -36.287829) (xy 131.5528 -36.271205) (xy 131.502628 -36.247029)
			(xy 131.456504 -36.215814) (xy 131.41541 -36.178224) (xy 131.380218 -36.135059) (xy 131.351676 -36.087235)
			(xy 131.330392 -36.035769) (xy 131.316817 -35.981756) (xy 131.31124 -35.926343) (xy 131.31378 -35.870707)
			(xy 131.324383 -35.816032) (xy 131.342823 -35.763481) (xy 131.368708 -35.714168) (xy 131.401488 -35.669144)
			(xy 131.420616 -35.6489) (xy 131.436859 -35.631693) (xy 131.463194 -35.592383) (xy 131.481797 -35.548877)
			(xy 131.492025 -35.50268) (xy 131.493525 -35.455388) (xy 131.486245 -35.408635) (xy 131.470437 -35.364039)
			(xy 131.446646 -35.323139) (xy 131.415696 -35.287349) (xy 131.397502 -35.272218) (xy 131.376067 -35.254435)
			(xy 131.337999 -35.213786) (xy 131.306246 -35.168034) (xy 131.281484 -35.118151) (xy 131.264238 -35.065198)
			(xy 131.254875 -35.010299) (xy 131.253594 -34.954623) (xy 127.293845 -34.954623) (xy 127.275926 -34.969446)
			(xy 127.228054 -34.998437) (xy 127.17646 -35.020124) (xy 127.122251 -35.034041) (xy 127.066591 -35.03989)
			(xy 127.038608 -35.0393) (xy 127.016397 -35.039713) (xy 126.972637 -35.047349) (xy 126.930871 -35.062477)
			(xy 126.892372 -35.084636) (xy 126.858311 -35.113152) (xy 126.829728 -35.147155) (xy 126.807492 -35.18561)
			(xy 126.79228 -35.227345) (xy 126.784557 -35.271089) (xy 126.7841 -35.2933) (xy 126.7841 -36.411765)
			(xy 138.694136 -36.411765) (xy 138.700462 -36.356447) (xy 138.71476 -36.302636) (xy 138.736728 -36.251474)
			(xy 138.765897 -36.204048) (xy 138.80165 -36.161365) (xy 138.843226 -36.124331) (xy 138.889743 -36.093733)
			(xy 138.940213 -36.070221) (xy 138.993565 -36.054293) (xy 139.048665 -36.046288) (xy 139.104343 -36.046377)
			(xy 139.159418 -36.054556) (xy 139.212718 -36.070653) (xy 139.263114 -36.094325) (xy 139.309534 -36.125071)
			(xy 139.350992 -36.162236) (xy 139.386609 -36.205032) (xy 139.40155 -36.228528) (xy 139.414047 -36.247951)
			(xy 139.444878 -36.282334) (xy 139.481414 -36.31058) (xy 139.522451 -36.331761) (xy 139.56664 -36.345178)
			(xy 139.612526 -36.350391) (xy 139.658599 -36.347229) (xy 139.703342 -36.335794) (xy 139.745283 -36.316463)
			(xy 139.783041 -36.289873) (xy 139.799568 -36.27374) (xy 139.819425 -36.254221) (xy 139.863786 -36.220572)
			(xy 139.912566 -36.193728) (xy 139.96473 -36.174258) (xy 140.01917 -36.162576) (xy 140.074729 -36.15893)
			(xy 140.130228 -36.163398) (xy 140.184489 -36.175885) (xy 140.204881 -36.183842) (xy 141.438629 -36.183842)
			(xy 141.444729 -36.128405) (xy 141.458835 -36.074448) (xy 141.480647 -36.023119) (xy 141.509701 -35.975513)
			(xy 141.545376 -35.932645) (xy 141.586913 -35.895428) (xy 141.633426 -35.864655) (xy 141.683923 -35.840983)
			(xy 141.73733 -35.824915) (xy 141.792506 -35.816795) (xy 141.820392 -35.816286) (xy 141.848278 -35.816795)
			(xy 141.903454 -35.824915) (xy 141.956861 -35.840983) (xy 142.007358 -35.864655) (xy 142.053871 -35.895428)
			(xy 142.095408 -35.932645) (xy 142.131083 -35.975513) (xy 142.160137 -36.023119) (xy 142.181949 -36.074448)
			(xy 142.196055 -36.128405) (xy 142.202155 -36.183842) (xy 142.200118 -36.239576) (xy 142.189988 -36.294419)
			(xy 142.171981 -36.347203) (xy 142.14648 -36.396803) (xy 142.114029 -36.442161) (xy 142.07532 -36.48231)
			(xy 142.031177 -36.516396) (xy 141.982542 -36.543692) (xy 141.930451 -36.563615) (xy 141.876014 -36.575741)
			(xy 141.820392 -36.579812) (xy 141.76477 -36.575741) (xy 141.710333 -36.563615) (xy 141.658242 -36.543692)
			(xy 141.609607 -36.516396) (xy 141.565464 -36.48231) (xy 141.526755 -36.442161) (xy 141.494304 -36.396803)
			(xy 141.468803 -36.347203) (xy 141.450796 -36.294419) (xy 141.440666 -36.239576) (xy 141.438629 -36.183842)
			(xy 140.204881 -36.183842) (xy 140.236359 -36.196125) (xy 140.284736 -36.223689) (xy 140.328594 -36.257991)
			(xy 140.367 -36.298304) (xy 140.39914 -36.34377) (xy 140.42433 -36.393425) (xy 140.442036 -36.446213)
			(xy 140.451882 -36.501015) (xy 140.453659 -36.556665) (xy 140.447329 -36.611983) (xy 140.433026 -36.665794)
			(xy 140.411054 -36.716954) (xy 140.38188 -36.764378) (xy 140.346124 -36.807058) (xy 140.304543 -36.844088)
			(xy 140.258023 -36.874682) (xy 140.20755 -36.89819) (xy 140.166179 -36.910536) (xy 142.893541 -36.910536)
			(xy 142.899641 -36.855099) (xy 142.913747 -36.801142) (xy 142.935559 -36.749813) (xy 142.964613 -36.702207)
			(xy 143.000288 -36.659339) (xy 143.041825 -36.622122) (xy 143.088338 -36.591349) (xy 143.138835 -36.567677)
			(xy 143.192242 -36.551609) (xy 143.247418 -36.543489) (xy 143.275304 -36.54298) (xy 143.30319 -36.543489)
			(xy 143.358366 -36.551609) (xy 143.411773 -36.567677) (xy 143.46227 -36.591349) (xy 143.508783 -36.622122)
			(xy 143.55032 -36.659339) (xy 143.585995 -36.702207) (xy 143.615049 -36.749813) (xy 143.636861 -36.801142)
			(xy 143.650967 -36.855099) (xy 143.657067 -36.910536) (xy 143.65503 -36.96627) (xy 143.6449 -37.021113)
			(xy 143.626893 -37.073897) (xy 143.601392 -37.123497) (xy 143.568941 -37.168855) (xy 143.530232 -37.209004)
			(xy 143.486089 -37.24309) (xy 143.437454 -37.270386) (xy 143.385363 -37.290309) (xy 143.330926 -37.302435)
			(xy 143.275304 -37.306506) (xy 143.219682 -37.302435) (xy 143.165245 -37.290309) (xy 143.113154 -37.270386)
			(xy 143.064519 -37.24309) (xy 143.020376 -37.209004) (xy 142.981667 -37.168855) (xy 142.949216 -37.123497)
			(xy 142.923715 -37.073897) (xy 142.905708 -37.021113) (xy 142.895578 -36.96627) (xy 142.893541 -36.910536)
			(xy 140.166179 -36.910536) (xy 140.154196 -36.914112) (xy 140.099095 -36.922111) (xy 140.043416 -36.922017)
			(xy 139.988342 -36.913832) (xy 139.935043 -36.897729) (xy 139.884649 -36.874051) (xy 139.838233 -36.843299)
			(xy 139.796778 -36.806129) (xy 139.761166 -36.763328) (xy 139.746228 -36.73983) (xy 139.733763 -36.720386)
			(xy 139.702925 -36.686007) (xy 139.666384 -36.657765) (xy 139.625342 -36.636588) (xy 139.58115 -36.623174)
			(xy 139.535262 -36.617963) (xy 139.489187 -36.621128) (xy 139.444442 -36.632564) (xy 139.402499 -36.651895)
			(xy 139.364739 -36.678485) (xy 139.34821 -36.694618) (xy 139.328388 -36.714171) (xy 139.284029 -36.747822)
			(xy 139.235251 -36.774668) (xy 139.183088 -36.79414) (xy 139.12865 -36.805825) (xy 139.073091 -36.809473)
			(xy 139.017592 -36.805008) (xy 138.963331 -36.792525) (xy 138.91146 -36.772288) (xy 138.863082 -36.744727)
			(xy 138.819223 -36.710427) (xy 138.780814 -36.670118) (xy 138.748671 -36.624654) (xy 138.723478 -36.575002)
			(xy 138.705768 -36.522215) (xy 138.695918 -36.467415) (xy 138.694136 -36.411765) (xy 126.7841 -36.411765)
			(xy 126.7841 -37.244292) (xy 127.159765 -37.244292) (xy 127.165865 -37.188855) (xy 127.179971 -37.134898)
			(xy 127.201783 -37.083569) (xy 127.230837 -37.035963) (xy 127.266512 -36.993095) (xy 127.308049 -36.955878)
			(xy 127.354562 -36.925105) (xy 127.405059 -36.901433) (xy 127.458466 -36.885365) (xy 127.513642 -36.877245)
			(xy 127.541528 -36.876736) (xy 127.569414 -36.877245) (xy 127.62459 -36.885365) (xy 127.677997 -36.901433)
			(xy 127.728494 -36.925105) (xy 127.775007 -36.955878) (xy 127.816544 -36.993095) (xy 127.852219 -37.035963)
			(xy 127.881273 -37.083569) (xy 127.903085 -37.134898) (xy 127.917191 -37.188855) (xy 127.923291 -37.244292)
			(xy 127.921254 -37.300026) (xy 127.911124 -37.354869) (xy 127.908987 -37.361132) (xy 133.704329 -37.361132)
			(xy 133.710429 -37.305695) (xy 133.724535 -37.251738) (xy 133.746347 -37.200409) (xy 133.775401 -37.152803)
			(xy 133.811076 -37.109935) (xy 133.852613 -37.072718) (xy 133.899126 -37.041945) (xy 133.949623 -37.018273)
			(xy 134.00303 -37.002205) (xy 134.058206 -36.994085) (xy 134.086092 -36.993576) (xy 134.113978 -36.994085)
			(xy 134.169154 -37.002205) (xy 134.222561 -37.018273) (xy 134.273058 -37.041945) (xy 134.319571 -37.072718)
			(xy 134.361108 -37.109935) (xy 134.396783 -37.152803) (xy 134.425837 -37.200409) (xy 134.447649 -37.251738)
			(xy 134.461755 -37.305695) (xy 134.467855 -37.361132) (xy 134.465818 -37.416866) (xy 134.455688 -37.471709)
			(xy 134.437681 -37.524493) (xy 134.41218 -37.574093) (xy 134.379729 -37.619451) (xy 134.34102 -37.6596)
			(xy 134.296877 -37.693686) (xy 134.248242 -37.720982) (xy 134.196151 -37.740905) (xy 134.141714 -37.753031)
			(xy 134.086092 -37.757102) (xy 134.03047 -37.753031) (xy 133.976033 -37.740905) (xy 133.923942 -37.720982)
			(xy 133.875307 -37.693686) (xy 133.831164 -37.6596) (xy 133.792455 -37.619451) (xy 133.760004 -37.574093)
			(xy 133.734503 -37.524493) (xy 133.716496 -37.471709) (xy 133.706366 -37.416866) (xy 133.704329 -37.361132)
			(xy 127.908987 -37.361132) (xy 127.893117 -37.407653) (xy 127.867616 -37.457253) (xy 127.835165 -37.502611)
			(xy 127.796456 -37.54276) (xy 127.752313 -37.576846) (xy 127.703678 -37.604142) (xy 127.651587 -37.624065)
			(xy 127.59715 -37.636191) (xy 127.541528 -37.640262) (xy 127.485906 -37.636191) (xy 127.431469 -37.624065)
			(xy 127.379378 -37.604142) (xy 127.330743 -37.576846) (xy 127.2866 -37.54276) (xy 127.247891 -37.502611)
			(xy 127.21544 -37.457253) (xy 127.189939 -37.407653) (xy 127.171932 -37.354869) (xy 127.161802 -37.300026)
			(xy 127.159765 -37.244292) (xy 126.7841 -37.244292) (xy 126.7841 -37.969952) (xy 126.09752 -38.656532)
			(xy 133.564883 -38.656532) (xy 133.570983 -38.601095) (xy 133.585089 -38.547138) (xy 133.606901 -38.495809)
			(xy 133.635955 -38.448203) (xy 133.67163 -38.405335) (xy 133.713167 -38.368118) (xy 133.75968 -38.337345)
			(xy 133.810177 -38.313673) (xy 133.863584 -38.297605) (xy 133.91876 -38.289485) (xy 133.946646 -38.288976)
			(xy 133.974532 -38.289485) (xy 134.029708 -38.297605) (xy 134.083115 -38.313673) (xy 134.133612 -38.337345)
			(xy 134.180125 -38.368118) (xy 134.221662 -38.405335) (xy 134.255053 -38.445458) (xy 136.436607 -38.445458)
			(xy 136.442707 -38.390021) (xy 136.456813 -38.336064) (xy 136.478625 -38.284735) (xy 136.507679 -38.237129)
			(xy 136.543354 -38.194261) (xy 136.584891 -38.157044) (xy 136.631404 -38.126271) (xy 136.681901 -38.102599)
			(xy 136.735308 -38.086531) (xy 136.790484 -38.078411) (xy 136.81837 -38.077902) (xy 136.846256 -38.078411)
			(xy 136.901432 -38.086531) (xy 136.954839 -38.102599) (xy 137.005336 -38.126271) (xy 137.051849 -38.157044)
			(xy 137.093386 -38.194261) (xy 137.129061 -38.237129) (xy 137.158115 -38.284735) (xy 137.179927 -38.336064)
			(xy 137.194033 -38.390021) (xy 137.200133 -38.445458) (xy 137.198096 -38.501192) (xy 137.195864 -38.513276)
			(xy 139.457937 -38.513276) (xy 139.464037 -38.457839) (xy 139.478143 -38.403882) (xy 139.499955 -38.352553)
			(xy 139.529009 -38.304947) (xy 139.564684 -38.262079) (xy 139.606221 -38.224862) (xy 139.652734 -38.194089)
			(xy 139.703231 -38.170417) (xy 139.756638 -38.154349) (xy 139.811814 -38.146229) (xy 139.8397 -38.14572)
			(xy 139.867586 -38.146229) (xy 139.922762 -38.154349) (xy 139.976169 -38.170417) (xy 140.026666 -38.194089)
			(xy 140.073179 -38.224862) (xy 140.114716 -38.262079) (xy 140.150391 -38.304947) (xy 140.179445 -38.352553)
			(xy 140.201257 -38.403882) (xy 140.215363 -38.457839) (xy 140.221463 -38.513276) (xy 140.219426 -38.56901)
			(xy 140.209296 -38.623853) (xy 140.191289 -38.676637) (xy 140.165788 -38.726237) (xy 140.133337 -38.771595)
			(xy 140.094628 -38.811744) (xy 140.050485 -38.84583) (xy 140.00185 -38.873126) (xy 139.949759 -38.893049)
			(xy 139.895322 -38.905175) (xy 139.8397 -38.909246) (xy 139.784078 -38.905175) (xy 139.729641 -38.893049)
			(xy 139.67755 -38.873126) (xy 139.628915 -38.84583) (xy 139.584772 -38.811744) (xy 139.546063 -38.771595)
			(xy 139.513612 -38.726237) (xy 139.488111 -38.676637) (xy 139.470104 -38.623853) (xy 139.459974 -38.56901)
			(xy 139.457937 -38.513276) (xy 137.195864 -38.513276) (xy 137.187966 -38.556035) (xy 137.169959 -38.608819)
			(xy 137.144458 -38.658419) (xy 137.112007 -38.703777) (xy 137.073298 -38.743926) (xy 137.029155 -38.778012)
			(xy 136.98052 -38.805308) (xy 136.928429 -38.825231) (xy 136.873992 -38.837357) (xy 136.81837 -38.841428)
			(xy 136.762748 -38.837357) (xy 136.708311 -38.825231) (xy 136.65622 -38.805308) (xy 136.607585 -38.778012)
			(xy 136.563442 -38.743926) (xy 136.524733 -38.703777) (xy 136.492282 -38.658419) (xy 136.466781 -38.608819)
			(xy 136.448774 -38.556035) (xy 136.438644 -38.501192) (xy 136.436607 -38.445458) (xy 134.255053 -38.445458)
			(xy 134.257337 -38.448203) (xy 134.286391 -38.495809) (xy 134.308203 -38.547138) (xy 134.322309 -38.601095)
			(xy 134.328409 -38.656532) (xy 134.326372 -38.712266) (xy 134.316242 -38.767109) (xy 134.298235 -38.819893)
			(xy 134.272734 -38.869493) (xy 134.240283 -38.914851) (xy 134.201574 -38.955) (xy 134.157431 -38.989086)
			(xy 134.108796 -39.016382) (xy 134.056705 -39.036305) (xy 134.002268 -39.048431) (xy 133.946646 -39.052502)
			(xy 133.891024 -39.048431) (xy 133.836587 -39.036305) (xy 133.784496 -39.016382) (xy 133.735861 -38.989086)
			(xy 133.691718 -38.955) (xy 133.653009 -38.914851) (xy 133.620558 -38.869493) (xy 133.595057 -38.819893)
			(xy 133.57705 -38.767109) (xy 133.56692 -38.712266) (xy 133.564883 -38.656532) (xy 126.09752 -38.656532)
			(xy 125.587488 -39.166564) (xy 141.365223 -39.166564) (xy 141.371323 -39.111127) (xy 141.385429 -39.05717)
			(xy 141.407241 -39.005841) (xy 141.436295 -38.958235) (xy 141.47197 -38.915367) (xy 141.513507 -38.87815)
			(xy 141.56002 -38.847377) (xy 141.610517 -38.823705) (xy 141.663924 -38.807637) (xy 141.7191 -38.799517)
			(xy 141.746986 -38.799008) (xy 141.774872 -38.799517) (xy 141.830048 -38.807637) (xy 141.883455 -38.823705)
			(xy 141.933952 -38.847377) (xy 141.980465 -38.87815) (xy 142.022002 -38.915367) (xy 142.057677 -38.958235)
			(xy 142.086731 -39.005841) (xy 142.108543 -39.05717) (xy 142.122649 -39.111127) (xy 142.128749 -39.166564)
			(xy 142.126712 -39.222298) (xy 142.116582 -39.277141) (xy 142.098575 -39.329925) (xy 142.089193 -39.348174)
			(xy 147.335747 -39.348174) (xy 147.341847 -39.292737) (xy 147.355953 -39.23878) (xy 147.377765 -39.187451)
			(xy 147.406819 -39.139845) (xy 147.442494 -39.096977) (xy 147.484031 -39.05976) (xy 147.530544 -39.028987)
			(xy 147.581041 -39.005315) (xy 147.634448 -38.989247) (xy 147.689624 -38.981127) (xy 147.71751 -38.980618)
			(xy 147.745396 -38.981127) (xy 147.752415 -38.98216) (xy 155.429965 -38.98216) (xy 155.436065 -38.926723)
			(xy 155.450171 -38.872766) (xy 155.471983 -38.821437) (xy 155.501037 -38.773831) (xy 155.536712 -38.730963)
			(xy 155.578249 -38.693746) (xy 155.624762 -38.662973) (xy 155.675259 -38.639301) (xy 155.728666 -38.623233)
			(xy 155.783842 -38.615113) (xy 155.811728 -38.614604) (xy 155.839614 -38.615113) (xy 155.89479 -38.623233)
			(xy 155.948197 -38.639301) (xy 155.998694 -38.662973) (xy 156.045207 -38.693746) (xy 156.086744 -38.730963)
			(xy 156.122419 -38.773831) (xy 156.151473 -38.821437) (xy 156.173285 -38.872766) (xy 156.187391 -38.926723)
			(xy 156.193491 -38.98216) (xy 156.191454 -39.037894) (xy 156.181324 -39.092737) (xy 156.163317 -39.145521)
			(xy 156.137816 -39.195121) (xy 156.105365 -39.240479) (xy 156.066656 -39.280628) (xy 156.022513 -39.314714)
			(xy 155.973878 -39.34201) (xy 155.921787 -39.361933) (xy 155.86735 -39.374059) (xy 155.811728 -39.37813)
			(xy 155.756106 -39.374059) (xy 155.701669 -39.361933) (xy 155.649578 -39.34201) (xy 155.600943 -39.314714)
			(xy 155.5568 -39.280628) (xy 155.518091 -39.240479) (xy 155.48564 -39.195121) (xy 155.460139 -39.145521)
			(xy 155.442132 -39.092737) (xy 155.432002 -39.037894) (xy 155.429965 -38.98216) (xy 147.752415 -38.98216)
			(xy 147.800572 -38.989247) (xy 147.853979 -39.005315) (xy 147.904476 -39.028987) (xy 147.950989 -39.05976)
			(xy 147.992526 -39.096977) (xy 148.028201 -39.139845) (xy 148.057255 -39.187451) (xy 148.079067 -39.23878)
			(xy 148.093173 -39.292737) (xy 148.099273 -39.348174) (xy 148.097236 -39.403908) (xy 148.087106 -39.458751)
			(xy 148.069099 -39.511535) (xy 148.043598 -39.561135) (xy 148.011147 -39.606493) (xy 147.972438 -39.646642)
			(xy 147.928295 -39.680728) (xy 147.87966 -39.708024) (xy 147.827569 -39.727947) (xy 147.773132 -39.740073)
			(xy 147.71751 -39.744144) (xy 147.661888 -39.740073) (xy 147.607451 -39.727947) (xy 147.55536 -39.708024)
			(xy 147.506725 -39.680728) (xy 147.462582 -39.646642) (xy 147.423873 -39.606493) (xy 147.391422 -39.561135)
			(xy 147.365921 -39.511535) (xy 147.347914 -39.458751) (xy 147.337784 -39.403908) (xy 147.335747 -39.348174)
			(xy 142.089193 -39.348174) (xy 142.073074 -39.379525) (xy 142.040623 -39.424883) (xy 142.001914 -39.465032)
			(xy 141.957771 -39.499118) (xy 141.909136 -39.526414) (xy 141.857045 -39.546337) (xy 141.802608 -39.558463)
			(xy 141.746986 -39.562534) (xy 141.691364 -39.558463) (xy 141.636927 -39.546337) (xy 141.584836 -39.526414)
			(xy 141.536201 -39.499118) (xy 141.492058 -39.465032) (xy 141.453349 -39.424883) (xy 141.420898 -39.379525)
			(xy 141.395397 -39.329925) (xy 141.37739 -39.277141) (xy 141.36726 -39.222298) (xy 141.365223 -39.166564)
			(xy 125.587488 -39.166564) (xy 124.77291 -39.981142) (xy 139.412217 -39.981142) (xy 139.418317 -39.925705)
			(xy 139.432423 -39.871748) (xy 139.454235 -39.820419) (xy 139.483289 -39.772813) (xy 139.518964 -39.729945)
			(xy 139.560501 -39.692728) (xy 139.607014 -39.661955) (xy 139.657511 -39.638283) (xy 139.710918 -39.622215)
			(xy 139.766094 -39.614095) (xy 139.79398 -39.613586) (xy 139.821866 -39.614095) (xy 139.877042 -39.622215)
			(xy 139.930449 -39.638283) (xy 139.980946 -39.661955) (xy 140.027459 -39.692728) (xy 140.068996 -39.729945)
			(xy 140.104671 -39.772813) (xy 140.133725 -39.820419) (xy 140.155537 -39.871748) (xy 140.169643 -39.925705)
			(xy 140.175743 -39.981142) (xy 140.173706 -40.036876) (xy 140.163576 -40.091719) (xy 140.145569 -40.144503)
			(xy 140.120068 -40.194103) (xy 140.087617 -40.239461) (xy 140.048908 -40.27961) (xy 140.022348 -40.300119)
			(xy 141.564717 -40.300119) (xy 141.569947 -40.245303) (xy 141.583005 -40.191809) (xy 141.603618 -40.140748)
			(xy 141.631358 -40.093181) (xy 141.66565 -40.050097) (xy 141.70578 -40.012391) (xy 141.750914 -39.980847)
			(xy 141.800114 -39.95612) (xy 141.852359 -39.938723) (xy 141.906562 -39.92902) (xy 141.961597 -39.92721)
			(xy 142.01632 -39.933332) (xy 142.069595 -39.947259) (xy 142.120314 -39.968701) (xy 142.167422 -39.997212)
			(xy 142.209942 -40.0322) (xy 142.228824 -40.052244) (xy 142.244991 -40.069225) (xy 142.282359 -40.097532)
			(xy 142.324288 -40.1185) (xy 142.369352 -40.131416) (xy 142.416022 -40.135842) (xy 142.462712 -40.131628)
			(xy 142.507835 -40.118917) (xy 142.549858 -40.098139) (xy 142.56893 -40.084502) (xy 142.59137 -40.068251)
			(xy 142.640055 -40.0418) (xy 142.692054 -40.02267) (xy 142.746273 -40.011264) (xy 142.801572 -40.00782)
			(xy 142.856788 -40.012413) (xy 142.910758 -40.024945) (xy 142.962348 -40.045152) (xy 143.010472 -40.07261)
			(xy 143.054118 -40.10674) (xy 143.092367 -40.146825) (xy 143.124415 -40.192022) (xy 143.149588 -40.24138)
			(xy 143.167356 -40.29386) (xy 143.177346 -40.348358) (xy 143.179346 -40.403728) (xy 143.173316 -40.458805)
			(xy 143.159382 -40.51243) (xy 143.149066 -40.538146) (xy 143.140489 -40.559682) (xy 143.130464 -40.604935)
			(xy 143.128816 -40.651257) (xy 143.135601 -40.697109) (xy 143.150594 -40.740968) (xy 143.173296 -40.781378)
			(xy 143.202954 -40.816999) (xy 143.238583 -40.846646) (xy 143.25854 -40.85844) (xy 143.281727 -40.871989)
			(xy 143.324377 -40.904625) (xy 143.362027 -40.94292) (xy 143.38219 -40.970218) (xy 146.912075 -40.970218)
			(xy 146.918175 -40.914781) (xy 146.932281 -40.860824) (xy 146.954093 -40.809495) (xy 146.983147 -40.761889)
			(xy 147.018822 -40.719021) (xy 147.060359 -40.681804) (xy 147.106872 -40.651031) (xy 147.157369 -40.627359)
			(xy 147.210776 -40.611291) (xy 147.265952 -40.603171) (xy 147.293838 -40.602662) (xy 147.321724 -40.603171)
			(xy 147.3769 -40.611291) (xy 147.430307 -40.627359) (xy 147.480804 -40.651031) (xy 147.527317 -40.681804)
			(xy 147.568854 -40.719021) (xy 147.604529 -40.761889) (xy 147.633583 -40.809495) (xy 147.655395 -40.860824)
			(xy 147.655972 -40.86303) (xy 148.065489 -40.86303) (xy 148.071589 -40.807593) (xy 148.085695 -40.753636)
			(xy 148.107507 -40.702307) (xy 148.136561 -40.654701) (xy 148.172236 -40.611833) (xy 148.213773 -40.574616)
			(xy 148.260286 -40.543843) (xy 148.310783 -40.520171) (xy 148.36419 -40.504103) (xy 148.419366 -40.495983)
			(xy 148.447252 -40.495474) (xy 148.475138 -40.495983) (xy 148.530314 -40.504103) (xy 148.583721 -40.520171)
			(xy 148.634218 -40.543843) (xy 148.680731 -40.574616) (xy 148.722268 -40.611833) (xy 148.757943 -40.654701)
			(xy 148.786997 -40.702307) (xy 148.808809 -40.753636) (xy 148.822915 -40.807593) (xy 148.829015 -40.86303)
			(xy 148.828179 -40.88589) (xy 150.376635 -40.88589) (xy 150.382735 -40.830453) (xy 150.396841 -40.776496)
			(xy 150.418653 -40.725167) (xy 150.447707 -40.677561) (xy 150.483382 -40.634693) (xy 150.524919 -40.597476)
			(xy 150.571432 -40.566703) (xy 150.621929 -40.543031) (xy 150.675336 -40.526963) (xy 150.730512 -40.518843)
			(xy 150.758398 -40.518334) (xy 150.786284 -40.518843) (xy 150.84146 -40.526963) (xy 150.894867 -40.543031)
			(xy 150.945364 -40.566703) (xy 150.991877 -40.597476) (xy 151.033414 -40.634693) (xy 151.069089 -40.677561)
			(xy 151.098143 -40.725167) (xy 151.119955 -40.776496) (xy 151.134061 -40.830453) (xy 151.140161 -40.88589)
			(xy 151.138124 -40.941624) (xy 151.127994 -40.996467) (xy 151.109987 -41.049251) (xy 151.084486 -41.098851)
			(xy 151.052035 -41.144209) (xy 151.013326 -41.184358) (xy 150.969183 -41.218444) (xy 150.920548 -41.24574)
			(xy 150.868457 -41.265663) (xy 150.81402 -41.277789) (xy 150.758398 -41.28186) (xy 150.702776 -41.277789)
			(xy 150.648339 -41.265663) (xy 150.596248 -41.24574) (xy 150.547613 -41.218444) (xy 150.50347 -41.184358)
			(xy 150.464761 -41.144209) (xy 150.43231 -41.098851) (xy 150.406809 -41.049251) (xy 150.388802 -40.996467)
			(xy 150.378672 -40.941624) (xy 150.376635 -40.88589) (xy 148.828179 -40.88589) (xy 148.826978 -40.918764)
			(xy 148.816848 -40.973607) (xy 148.798841 -41.026391) (xy 148.77334 -41.075991) (xy 148.740889 -41.121349)
			(xy 148.70218 -41.161498) (xy 148.658037 -41.195584) (xy 148.609402 -41.22288) (xy 148.557311 -41.242803)
			(xy 148.502874 -41.254929) (xy 148.447252 -41.259) (xy 148.39163 -41.254929) (xy 148.337193 -41.242803)
			(xy 148.285102 -41.22288) (xy 148.236467 -41.195584) (xy 148.192324 -41.161498) (xy 148.153615 -41.121349)
			(xy 148.121164 -41.075991) (xy 148.095663 -41.026391) (xy 148.077656 -40.973607) (xy 148.067526 -40.918764)
			(xy 148.065489 -40.86303) (xy 147.655972 -40.86303) (xy 147.669501 -40.914781) (xy 147.675601 -40.970218)
			(xy 147.673564 -41.025952) (xy 147.663434 -41.080795) (xy 147.645427 -41.133579) (xy 147.619926 -41.183179)
			(xy 147.587475 -41.228537) (xy 147.548766 -41.268686) (xy 147.504623 -41.302772) (xy 147.455988 -41.330068)
			(xy 147.403897 -41.349991) (xy 147.34946 -41.362117) (xy 147.293838 -41.366188) (xy 147.238216 -41.362117)
			(xy 147.183779 -41.349991) (xy 147.131688 -41.330068) (xy 147.083053 -41.302772) (xy 147.03891 -41.268686)
			(xy 147.000201 -41.228537) (xy 146.96775 -41.183179) (xy 146.942249 -41.133579) (xy 146.924242 -41.080795)
			(xy 146.914112 -41.025952) (xy 146.912075 -40.970218) (xy 143.38219 -40.970218) (xy 143.393934 -40.986117)
			(xy 143.419468 -41.033362) (xy 143.438124 -41.083722) (xy 143.449532 -41.1362) (xy 143.453467 -41.189759)
			(xy 143.449852 -41.243341) (xy 143.438757 -41.295886) (xy 143.420403 -41.346356) (xy 143.395152 -41.393753)
			(xy 143.379698 -41.415716) (xy 143.367399 -41.433252) (xy 143.348332 -41.471604) (xy 143.335968 -41.512611)
			(xy 143.330657 -41.555111) (xy 143.332549 -41.597899) (xy 143.341592 -41.639764) (xy 143.357529 -41.679519)
			(xy 143.379908 -41.716038) (xy 143.393668 -41.732454) (xy 143.41148 -41.753602) (xy 143.441466 -41.800056)
			(xy 143.464433 -41.850351) (xy 143.479901 -41.903434) (xy 143.487545 -41.958194) (xy 143.487447 -41.974162)
			(xy 152.779223 -41.974162) (xy 152.781246 -41.880118) (xy 152.791347 -41.786597) (xy 152.80945 -41.694291)
			(xy 152.835421 -41.603882) (xy 152.869068 -41.51604) (xy 152.910142 -41.431417) (xy 152.958338 -41.350637)
			(xy 153.0133 -41.274299) (xy 153.074621 -41.202969) (xy 153.141847 -41.137175) (xy 153.21448 -41.077403)
			(xy 153.291982 -41.024096) (xy 153.37378 -40.977649) (xy 153.459268 -40.938406) (xy 153.547813 -40.906656)
			(xy 153.63876 -40.882637) (xy 153.731435 -40.866524) (xy 153.825151 -40.858438) (xy 153.872184 -40.857932)
			(xy 153.919217 -40.858438) (xy 154.012933 -40.866524) (xy 154.105608 -40.882637) (xy 154.196555 -40.906656)
			(xy 154.2851 -40.938406) (xy 154.370588 -40.977649) (xy 154.452386 -41.024096) (xy 154.529888 -41.077403)
			(xy 154.602521 -41.137175) (xy 154.669747 -41.202969) (xy 154.731068 -41.274299) (xy 154.78603 -41.350637)
			(xy 154.834226 -41.431417) (xy 154.8753 -41.51604) (xy 154.908947 -41.603882) (xy 154.934918 -41.694291)
			(xy 154.953021 -41.786597) (xy 154.963122 -41.880118) (xy 154.965145 -41.974162) (xy 154.959077 -42.068031)
			(xy 154.944962 -42.161031) (xy 154.922905 -42.252473) (xy 154.893068 -42.341681) (xy 154.855674 -42.427993)
			(xy 154.810997 -42.510772) (xy 154.75937 -42.589403) (xy 154.701175 -42.663305) (xy 154.636842 -42.731931)
			(xy 154.566848 -42.794773) (xy 154.491711 -42.851365) (xy 154.411987 -42.901288) (xy 154.328266 -42.944173)
			(xy 154.241169 -42.979702) (xy 154.15134 -43.007612) (xy 154.059444 -43.027697) (xy 153.966162 -43.039808)
			(xy 153.872184 -43.043855) (xy 153.778206 -43.039808) (xy 153.684924 -43.027697) (xy 153.593028 -43.007612)
			(xy 153.503199 -42.979702) (xy 153.416102 -42.944173) (xy 153.332381 -42.901288) (xy 153.252657 -42.851365)
			(xy 153.17752 -42.794773) (xy 153.107526 -42.731931) (xy 153.043193 -42.663305) (xy 152.984998 -42.589403)
			(xy 152.933371 -42.510772) (xy 152.888694 -42.427993) (xy 152.8513 -42.341681) (xy 152.821463 -42.252473)
			(xy 152.799406 -42.161031) (xy 152.785291 -42.068031) (xy 152.779223 -41.974162) (xy 143.487447 -41.974162)
			(xy 143.487206 -42.013484) (xy 143.47889 -42.068146) (xy 143.462772 -42.121035) (xy 143.439189 -42.171045)
			(xy 143.408635 -42.217127) (xy 143.37175 -42.258317) (xy 143.329307 -42.293752) (xy 143.282193 -42.32269)
			(xy 143.231397 -42.344525) (xy 143.17798 -42.3588) (xy 143.123063 -42.365216) (xy 143.067795 -42.363639)
			(xy 143.013332 -42.354101) (xy 142.960817 -42.336803) (xy 142.911348 -42.312106) (xy 142.865962 -42.280528)
			(xy 142.825608 -42.24273) (xy 142.791133 -42.199504) (xy 142.763257 -42.151754) (xy 142.742565 -42.100482)
			(xy 142.729489 -42.046759) (xy 142.724304 -41.991712) (xy 142.727119 -41.936492) (xy 142.737874 -41.882257)
			(xy 142.756343 -41.830143) (xy 142.782142 -41.781239) (xy 142.798038 -41.758616) (xy 142.810312 -41.741063)
			(xy 142.829386 -41.702716) (xy 142.841757 -41.661712) (xy 142.847073 -41.619214) (xy 142.845184 -41.576427)
			(xy 142.836144 -41.534563) (xy 142.820208 -41.494809) (xy 142.797828 -41.458293) (xy 142.784068 -41.441878)
			(xy 142.766879 -41.421511) (xy 142.737788 -41.376856) (xy 142.71519 -41.32859) (xy 142.699523 -41.27765)
			(xy 142.691091 -41.225026) (xy 142.69006 -41.171742) (xy 142.696447 -41.118831) (xy 142.710131 -41.067323)
			(xy 142.72006 -41.04259) (xy 142.728586 -41.021036) (xy 142.738614 -40.975788) (xy 142.740267 -40.929472)
			(xy 142.733488 -40.883626) (xy 142.718502 -40.83977) (xy 142.695808 -40.799361) (xy 142.666159 -40.763741)
			(xy 142.630539 -40.734091) (xy 142.610586 -40.722296) (xy 142.584222 -40.706823) (xy 142.536371 -40.668786)
			(xy 142.515336 -40.646604) (xy 142.499203 -40.629589) (xy 142.46183 -40.601278) (xy 142.419895 -40.580309)
			(xy 142.374824 -40.567394) (xy 142.328147 -40.562972) (xy 142.281452 -40.567193) (xy 142.236326 -40.579914)
			(xy 142.194301 -40.600702) (xy 142.17523 -40.614346) (xy 142.152862 -40.630409) (xy 142.104493 -40.656725)
			(xy 142.052842 -40.675812) (xy 141.998984 -40.687275) (xy 141.944037 -40.690876) (xy 141.889143 -40.686538)
			(xy 141.835443 -40.674353) (xy 141.784053 -40.654574) (xy 141.736041 -40.627612) (xy 141.692405 -40.594026)
			(xy 141.654051 -40.554516) (xy 141.621776 -40.509901) (xy 141.596251 -40.461109) (xy 141.578007 -40.409155)
			(xy 141.567422 -40.355117) (xy 141.564717 -40.300119) (xy 140.022348 -40.300119) (xy 140.004765 -40.313696)
			(xy 139.95613 -40.340992) (xy 139.904039 -40.360915) (xy 139.849602 -40.373041) (xy 139.79398 -40.377112)
			(xy 139.738358 -40.373041) (xy 139.683921 -40.360915) (xy 139.63183 -40.340992) (xy 139.583195 -40.313696)
			(xy 139.539052 -40.27961) (xy 139.500343 -40.239461) (xy 139.467892 -40.194103) (xy 139.442391 -40.144503)
			(xy 139.424384 -40.091719) (xy 139.414254 -40.036876) (xy 139.412217 -39.981142) (xy 124.77291 -39.981142)
			(xy 124.305822 -40.44823) (xy 123.16968 -40.44823) (xy 123.13666 -40.48125) (xy 123.13666 -41.409892)
			(xy 124.111257 -41.409892) (xy 124.117357 -41.354455) (xy 124.131463 -41.300498) (xy 124.153275 -41.249169)
			(xy 124.182329 -41.201563) (xy 124.218004 -41.158695) (xy 124.259541 -41.121478) (xy 124.306054 -41.090705)
			(xy 124.356551 -41.067033) (xy 124.409958 -41.050965) (xy 124.465134 -41.042845) (xy 124.49302 -41.042336)
			(xy 124.520906 -41.042845) (xy 124.576082 -41.050965) (xy 124.629489 -41.067033) (xy 124.679986 -41.090705)
			(xy 124.683304 -41.0929) (xy 133.444487 -41.0929) (xy 133.450587 -41.037463) (xy 133.464693 -40.983506)
			(xy 133.486505 -40.932177) (xy 133.515559 -40.884571) (xy 133.551234 -40.841703) (xy 133.592771 -40.804486)
			(xy 133.639284 -40.773713) (xy 133.689781 -40.750041) (xy 133.743188 -40.733973) (xy 133.798364 -40.725853)
			(xy 133.82625 -40.725344) (xy 133.854136 -40.725853) (xy 133.909312 -40.733973) (xy 133.962719 -40.750041)
			(xy 134.013216 -40.773713) (xy 134.059729 -40.804486) (xy 134.101266 -40.841703) (xy 134.136941 -40.884571)
			(xy 134.165995 -40.932177) (xy 134.187807 -40.983506) (xy 134.201913 -41.037463) (xy 134.208013 -41.0929)
			(xy 134.205976 -41.148634) (xy 134.195846 -41.203477) (xy 134.177839 -41.256261) (xy 134.152338 -41.305861)
			(xy 134.119887 -41.351219) (xy 134.081178 -41.391368) (xy 134.037035 -41.425454) (xy 133.9884 -41.45275)
			(xy 133.936309 -41.472673) (xy 133.881872 -41.484799) (xy 133.82625 -41.48887) (xy 133.770628 -41.484799)
			(xy 133.716191 -41.472673) (xy 133.6641 -41.45275) (xy 133.615465 -41.425454) (xy 133.571322 -41.391368)
			(xy 133.532613 -41.351219) (xy 133.500162 -41.305861) (xy 133.474661 -41.256261) (xy 133.456654 -41.203477)
			(xy 133.446524 -41.148634) (xy 133.444487 -41.0929) (xy 124.683304 -41.0929) (xy 124.726499 -41.121478)
			(xy 124.768036 -41.158695) (xy 124.803711 -41.201563) (xy 124.832765 -41.249169) (xy 124.854577 -41.300498)
			(xy 124.868683 -41.354455) (xy 124.874783 -41.409892) (xy 124.872746 -41.465626) (xy 124.862616 -41.520469)
			(xy 124.844609 -41.573253) (xy 124.819108 -41.622853) (xy 124.786657 -41.668211) (xy 124.747948 -41.70836)
			(xy 124.703805 -41.742446) (xy 124.65517 -41.769742) (xy 124.603079 -41.789665) (xy 124.548642 -41.801791)
			(xy 124.49302 -41.805862) (xy 124.437398 -41.801791) (xy 124.382961 -41.789665) (xy 124.33087 -41.769742)
			(xy 124.282235 -41.742446) (xy 124.238092 -41.70836) (xy 124.199383 -41.668211) (xy 124.166932 -41.622853)
			(xy 124.141431 -41.573253) (xy 124.123424 -41.520469) (xy 124.113294 -41.465626) (xy 124.111257 -41.409892)
			(xy 123.13666 -41.409892) (xy 123.13666 -41.503854) (xy 123.734068 -42.101262) (xy 125.78461 -42.101262)
			(xy 125.808994 -42.125646) (xy 125.885956 -42.140378) (xy 125.923294 -42.124122) (xy 125.931422 -42.12082)
			(xy 125.957806 -42.110624) (xy 126.012764 -42.097249) (xy 126.069094 -42.092132) (xy 126.125562 -42.095387)
			(xy 126.180931 -42.106942) (xy 126.233988 -42.126543) (xy 126.283571 -42.153762) (xy 126.328592 -42.188001)
			(xy 126.368065 -42.228512) (xy 126.401127 -42.274405) (xy 126.427051 -42.324676) (xy 126.445271 -42.378224)
			(xy 126.455386 -42.433874) (xy 126.457176 -42.490407) (xy 126.450601 -42.546586) (xy 126.435806 -42.601179)
			(xy 126.424944 -42.627296) (xy 126.419231 -42.641421) (xy 126.413959 -42.671421) (xy 126.414283 -42.676336)
			(xy 139.471653 -42.676336) (xy 139.477753 -42.620899) (xy 139.491859 -42.566942) (xy 139.513671 -42.515613)
			(xy 139.542725 -42.468007) (xy 139.5784 -42.425139) (xy 139.619937 -42.387922) (xy 139.66645 -42.357149)
			(xy 139.716947 -42.333477) (xy 139.770354 -42.317409) (xy 139.82553 -42.309289) (xy 139.853416 -42.30878)
			(xy 139.881302 -42.309289) (xy 139.936478 -42.317409) (xy 139.989885 -42.333477) (xy 140.040382 -42.357149)
			(xy 140.086895 -42.387922) (xy 140.128432 -42.425139) (xy 140.164107 -42.468007) (xy 140.193161 -42.515613)
			(xy 140.213968 -42.564576) (xy 147.647405 -42.564576) (xy 147.653505 -42.509139) (xy 147.667611 -42.455182)
			(xy 147.689423 -42.403853) (xy 147.718477 -42.356247) (xy 147.754152 -42.313379) (xy 147.795689 -42.276162)
			(xy 147.842202 -42.245389) (xy 147.892699 -42.221717) (xy 147.946106 -42.205649) (xy 148.001282 -42.197529)
			(xy 148.029168 -42.19702) (xy 148.057054 -42.197529) (xy 148.11223 -42.205649) (xy 148.165637 -42.221717)
			(xy 148.216134 -42.245389) (xy 148.262647 -42.276162) (xy 148.304184 -42.313379) (xy 148.339859 -42.356247)
			(xy 148.368913 -42.403853) (xy 148.390725 -42.455182) (xy 148.404831 -42.509139) (xy 148.410931 -42.564576)
			(xy 148.408894 -42.62031) (xy 148.398764 -42.675153) (xy 148.380757 -42.727937) (xy 148.355256 -42.777537)
			(xy 148.322805 -42.822895) (xy 148.284096 -42.863044) (xy 148.239953 -42.89713) (xy 148.191318 -42.924426)
			(xy 148.139227 -42.944349) (xy 148.08479 -42.956475) (xy 148.029168 -42.960546) (xy 147.973546 -42.956475)
			(xy 147.919109 -42.944349) (xy 147.867018 -42.924426) (xy 147.818383 -42.89713) (xy 147.77424 -42.863044)
			(xy 147.735531 -42.822895) (xy 147.70308 -42.777537) (xy 147.677579 -42.727937) (xy 147.659572 -42.675153)
			(xy 147.649442 -42.62031) (xy 147.647405 -42.564576) (xy 140.213968 -42.564576) (xy 140.214973 -42.566942)
			(xy 140.229079 -42.620899) (xy 140.235179 -42.676336) (xy 140.233142 -42.73207) (xy 140.223012 -42.786913)
			(xy 140.205005 -42.839697) (xy 140.179504 -42.889297) (xy 140.147053 -42.934655) (xy 140.108344 -42.974804)
			(xy 140.064201 -43.00889) (xy 140.015566 -43.036186) (xy 139.963475 -43.056109) (xy 139.909038 -43.068235)
			(xy 139.853416 -43.072306) (xy 139.797794 -43.068235) (xy 139.743357 -43.056109) (xy 139.691266 -43.036186)
			(xy 139.642631 -43.00889) (xy 139.598488 -42.974804) (xy 139.559779 -42.934655) (xy 139.527328 -42.889297)
			(xy 139.501827 -42.839697) (xy 139.48382 -42.786913) (xy 139.47369 -42.73207) (xy 139.471653 -42.676336)
			(xy 126.414283 -42.676336) (xy 126.415964 -42.701815) (xy 126.425129 -42.730863) (xy 126.440931 -42.756902)
			(xy 126.45136 -42.768012) (xy 127.738387 -44.055039) (xy 129.157983 -44.055039) (xy 129.164086 -43.999565)
			(xy 129.178202 -43.945572) (xy 129.200029 -43.894209) (xy 129.229102 -43.846571) (xy 129.264801 -43.803675)
			(xy 129.306365 -43.766433) (xy 129.352909 -43.735639) (xy 129.40344 -43.711951) (xy 129.456882 -43.695873)
			(xy 129.512096 -43.687747) (xy 129.54 -43.687238) (xy 129.567904 -43.687747) (xy 129.623118 -43.695873)
			(xy 129.67656 -43.711951) (xy 129.727091 -43.735639) (xy 129.773635 -43.766433) (xy 129.815199 -43.803675)
			(xy 129.850898 -43.846571) (xy 129.869614 -43.877239) (xy 130.580383 -43.877239) (xy 130.586486 -43.821765)
			(xy 130.600602 -43.767772) (xy 130.622429 -43.716409) (xy 130.651502 -43.668771) (xy 130.687201 -43.625875)
			(xy 130.728765 -43.588633) (xy 130.775309 -43.557839) (xy 130.82584 -43.534151) (xy 130.879282 -43.518073)
			(xy 130.934496 -43.509947) (xy 130.9624 -43.509438) (xy 130.990304 -43.509947) (xy 131.045518 -43.518073)
			(xy 131.09896 -43.534151) (xy 131.149491 -43.557839) (xy 131.196035 -43.588633) (xy 131.237599 -43.625875)
			(xy 131.25782 -43.650172) (xy 150.219155 -43.650172) (xy 150.225255 -43.594735) (xy 150.239361 -43.540778)
			(xy 150.261173 -43.489449) (xy 150.290227 -43.441843) (xy 150.325902 -43.398975) (xy 150.367439 -43.361758)
			(xy 150.413952 -43.330985) (xy 150.464449 -43.307313) (xy 150.517856 -43.291245) (xy 150.573032 -43.283125)
			(xy 150.600918 -43.282616) (xy 150.628804 -43.283125) (xy 150.68398 -43.291245) (xy 150.737387 -43.307313)
			(xy 150.787884 -43.330985) (xy 150.834397 -43.361758) (xy 150.875934 -43.398975) (xy 150.911609 -43.441843)
			(xy 150.940663 -43.489449) (xy 150.962475 -43.540778) (xy 150.976581 -43.594735) (xy 150.982681 -43.650172)
			(xy 150.980644 -43.705906) (xy 150.970514 -43.760749) (xy 150.952507 -43.813533) (xy 150.927006 -43.863133)
			(xy 150.894555 -43.908491) (xy 150.855846 -43.94864) (xy 150.811703 -43.982726) (xy 150.763068 -44.010022)
			(xy 150.710977 -44.029945) (xy 150.65654 -44.042071) (xy 150.600918 -44.046142) (xy 150.545296 -44.042071)
			(xy 150.490859 -44.029945) (xy 150.438768 -44.010022) (xy 150.390133 -43.982726) (xy 150.34599 -43.94864)
			(xy 150.307281 -43.908491) (xy 150.27483 -43.863133) (xy 150.249329 -43.813533) (xy 150.231322 -43.760749)
			(xy 150.221192 -43.705906) (xy 150.219155 -43.650172) (xy 131.25782 -43.650172) (xy 131.273298 -43.668771)
			(xy 131.302371 -43.716409) (xy 131.324198 -43.767772) (xy 131.338314 -43.821765) (xy 131.344417 -43.877239)
			(xy 131.342379 -43.93301) (xy 131.332242 -43.987889) (xy 131.314223 -44.040709) (xy 131.288705 -44.090341)
			(xy 131.256233 -44.135729) (xy 131.217498 -44.175906) (xy 131.173326 -44.210014) (xy 131.145313 -44.225736)
			(xy 139.672567 -44.225736) (xy 139.678667 -44.170299) (xy 139.692773 -44.116342) (xy 139.714585 -44.065013)
			(xy 139.743639 -44.017407) (xy 139.779314 -43.974539) (xy 139.820851 -43.937322) (xy 139.867364 -43.906549)
			(xy 139.917861 -43.882877) (xy 139.971268 -43.866809) (xy 140.026444 -43.858689) (xy 140.05433 -43.85818)
			(xy 140.082216 -43.858689) (xy 140.137392 -43.866809) (xy 140.190799 -43.882877) (xy 140.241296 -43.906549)
			(xy 140.287809 -43.937322) (xy 140.329346 -43.974539) (xy 140.365021 -44.017407) (xy 140.394075 -44.065013)
			(xy 140.415887 -44.116342) (xy 140.429993 -44.170299) (xy 140.431758 -44.186341) (xy 140.718328 -44.186341)
			(xy 140.719008 -44.131084) (xy 140.727654 -44.076503) (xy 140.744086 -44.023741) (xy 140.76796 -43.973902)
			(xy 140.798775 -43.92803) (xy 140.835887 -43.887085) (xy 140.878519 -43.851923) (xy 140.925779 -43.823281)
			(xy 140.976677 -43.801759) (xy 141.030148 -43.787806) (xy 141.085073 -43.781715) (xy 141.140302 -43.783613)
			(xy 141.194679 -43.793461) (xy 141.247066 -43.811053) (xy 141.296366 -43.83602) (xy 141.341547 -43.867839)
			(xy 141.381664 -43.905845) (xy 141.415877 -43.949243) (xy 141.44347 -43.997122) (xy 141.463864 -44.048483)
			(xy 141.476635 -44.102249) (xy 141.481513 -44.157294) (xy 141.478397 -44.212468) (xy 141.467352 -44.266615)
			(xy 141.458442 -44.292774) (xy 141.453391 -44.308323) (xy 141.450442 -44.34087) (xy 141.455868 -44.373097)
			(xy 141.46931 -44.402885) (xy 141.489885 -44.428275) (xy 141.516241 -44.447598) (xy 141.546644 -44.459584)
			(xy 141.579095 -44.463444) (xy 141.595348 -44.461684) (xy 141.607291 -44.460126) (xy 141.631312 -44.458349)
			(xy 141.643354 -44.458128) (xy 141.66018 -44.457462) (xy 141.692571 -44.448285) (xy 141.721433 -44.430954)
			(xy 141.744757 -44.406677) (xy 141.760919 -44.377145) (xy 141.768793 -44.344413) (xy 141.76883 -44.327572)
			(xy 141.768519 -44.300217) (xy 141.774814 -44.245875) (xy 141.788807 -44.192989) (xy 141.810209 -44.142644)
			(xy 141.838582 -44.095872) (xy 141.873345 -44.053632) (xy 141.913784 -44.016789) (xy 141.959071 -43.9861)
			(xy 142.008276 -43.962194) (xy 142.060392 -43.94556) (xy 142.114349 -43.93654) (xy 142.169041 -43.935319)
			(xy 142.223346 -43.941922) (xy 142.276152 -43.956213) (xy 142.326375 -43.9779) (xy 142.372986 -44.006537)
			(xy 142.41503 -44.041538) (xy 142.451643 -44.082185) (xy 142.482075 -44.127644) (xy 142.505703 -44.176984)
			(xy 142.522042 -44.229193) (xy 142.530756 -44.2832) (xy 142.531668 -44.337898) (xy 142.524758 -44.392165)
			(xy 142.510169 -44.444889) (xy 142.488199 -44.494989) (xy 142.459298 -44.541438) (xy 142.42406 -44.583282)
			(xy 142.383207 -44.619665) (xy 142.337576 -44.64984) (xy 142.302971 -44.666172) (xy 150.110951 -44.666172)
			(xy 150.117051 -44.610735) (xy 150.131157 -44.556778) (xy 150.152969 -44.505449) (xy 150.182023 -44.457843)
			(xy 150.217698 -44.414975) (xy 150.259235 -44.377758) (xy 150.305748 -44.346985) (xy 150.356245 -44.323313)
			(xy 150.409652 -44.307245) (xy 150.464828 -44.299125) (xy 150.492714 -44.298616) (xy 150.5206 -44.299125)
			(xy 150.575776 -44.307245) (xy 150.629183 -44.323313) (xy 150.67968 -44.346985) (xy 150.726193 -44.377758)
			(xy 150.76773 -44.414975) (xy 150.779281 -44.428855) (xy 153.211025 -44.428855) (xy 153.213033 -44.356011)
			(xy 153.223042 -44.283831) (xy 153.240931 -44.213189) (xy 153.266482 -44.144944) (xy 153.299386 -44.079925)
			(xy 153.339242 -44.018919) (xy 153.385568 -43.962669) (xy 153.437801 -43.911856) (xy 153.495307 -43.867098)
			(xy 153.557387 -43.828937) (xy 153.623289 -43.797837) (xy 153.692212 -43.774176) (xy 153.763319 -43.75824)
			(xy 153.835748 -43.750224) (xy 153.872184 -43.749722) (xy 153.90862 -43.750224) (xy 153.981049 -43.75824)
			(xy 154.052156 -43.774176) (xy 154.121079 -43.797837) (xy 154.186981 -43.828937) (xy 154.249061 -43.867098)
			(xy 154.306567 -43.911856) (xy 154.3588 -43.962669) (xy 154.405126 -44.018919) (xy 154.444982 -44.079925)
			(xy 154.477886 -44.144944) (xy 154.503437 -44.213189) (xy 154.521326 -44.283831) (xy 154.531335 -44.356011)
			(xy 154.533343 -44.428855) (xy 154.527326 -44.501477) (xy 154.513356 -44.572997) (xy 154.491602 -44.642545)
			(xy 154.46233 -44.709279) (xy 154.425895 -44.772387) (xy 154.382738 -44.831104) (xy 154.333383 -44.884717)
			(xy 154.278431 -44.932576) (xy 154.218547 -44.974098) (xy 154.154458 -45.008781) (xy 154.086944 -45.036203)
			(xy 154.016822 -45.056032) (xy 153.944945 -45.068026) (xy 153.872184 -45.072041) (xy 153.799423 -45.068026)
			(xy 153.727546 -45.056032) (xy 153.657424 -45.036203) (xy 153.58991 -45.008781) (xy 153.525821 -44.974098)
			(xy 153.465937 -44.932576) (xy 153.410985 -44.884717) (xy 153.36163 -44.831104) (xy 153.318473 -44.772387)
			(xy 153.282038 -44.709279) (xy 153.252766 -44.642545) (xy 153.231012 -44.572997) (xy 153.217042 -44.501477)
			(xy 153.211025 -44.428855) (xy 150.779281 -44.428855) (xy 150.803405 -44.457843) (xy 150.832459 -44.505449)
			(xy 150.854271 -44.556778) (xy 150.868377 -44.610735) (xy 150.874477 -44.666172) (xy 150.87244 -44.721906)
			(xy 150.86231 -44.776749) (xy 150.844303 -44.829533) (xy 150.818802 -44.879133) (xy 150.786351 -44.924491)
			(xy 150.747642 -44.96464) (xy 150.703499 -44.998726) (xy 150.654864 -45.026022) (xy 150.602773 -45.045945)
			(xy 150.548336 -45.058071) (xy 150.492714 -45.062142) (xy 150.437092 -45.058071) (xy 150.382655 -45.045945)
			(xy 150.330564 -45.026022) (xy 150.281929 -44.998726) (xy 150.237786 -44.96464) (xy 150.199077 -44.924491)
			(xy 150.166626 -44.879133) (xy 150.141125 -44.829533) (xy 150.123118 -44.776749) (xy 150.112988 -44.721906)
			(xy 150.110951 -44.666172) (xy 142.302971 -44.666172) (xy 142.288103 -44.673189) (xy 142.235803 -44.689232)
			(xy 142.181748 -44.697641) (xy 142.154402 -44.698412) (xy 142.137579 -44.699101) (xy 142.105197 -44.708283)
			(xy 142.076341 -44.725613) (xy 142.053019 -44.749883) (xy 142.036855 -44.779407) (xy 142.028971 -44.81213)
			(xy 142.028926 -44.828968) (xy 142.029216 -44.857283) (xy 142.022423 -44.913498) (xy 142.007393 -44.968091)
			(xy 141.984457 -45.019862) (xy 141.954118 -45.067672) (xy 141.917044 -45.110472) (xy 141.874049 -45.147319)
			(xy 141.826079 -45.177405) (xy 141.774187 -45.200067) (xy 141.746986 -45.207936) (xy 141.725161 -45.214362)
			(xy 141.68403 -45.233796) (xy 141.647016 -45.26024) (xy 141.616348 -45.291774) (xy 142.653003 -45.291774)
			(xy 142.659103 -45.236337) (xy 142.673209 -45.18238) (xy 142.695021 -45.131051) (xy 142.724075 -45.083445)
			(xy 142.75975 -45.040577) (xy 142.801287 -45.00336) (xy 142.8478 -44.972587) (xy 142.898297 -44.948915)
			(xy 142.951704 -44.932847) (xy 143.00688 -44.924727) (xy 143.034766 -44.924218) (xy 143.062652 -44.924727)
			(xy 143.117828 -44.932847) (xy 143.171235 -44.948915) (xy 143.221732 -44.972587) (xy 143.268245 -45.00336)
			(xy 143.309782 -45.040577) (xy 143.345457 -45.083445) (xy 143.374511 -45.131051) (xy 143.396323 -45.18238)
			(xy 143.410429 -45.236337) (xy 143.416529 -45.291774) (xy 143.414492 -45.347508) (xy 143.404362 -45.402351)
			(xy 143.386355 -45.455135) (xy 143.360854 -45.504735) (xy 143.328403 -45.550093) (xy 143.289694 -45.590242)
			(xy 143.245551 -45.624328) (xy 143.196916 -45.651624) (xy 143.144825 -45.671547) (xy 143.090388 -45.683673)
			(xy 143.034766 -45.687744) (xy 142.979144 -45.683673) (xy 142.924707 -45.671547) (xy 142.872616 -45.651624)
			(xy 142.823981 -45.624328) (xy 142.779838 -45.590242) (xy 142.741129 -45.550093) (xy 142.708678 -45.504735)
			(xy 142.683177 -45.455135) (xy 142.66517 -45.402351) (xy 142.65504 -45.347508) (xy 142.653003 -45.291774)
			(xy 141.616348 -45.291774) (xy 141.6153 -45.292852) (xy 141.589895 -45.330588) (xy 141.571613 -45.372243)
			(xy 141.561038 -45.416487) (xy 141.558508 -45.461907) (xy 141.560804 -45.484542) (xy 141.563736 -45.511659)
			(xy 141.562716 -45.566193) (xy 141.553939 -45.620025) (xy 141.537584 -45.672058) (xy 141.526757 -45.694618)
			(xy 147.424647 -45.694618) (xy 147.430747 -45.639181) (xy 147.444853 -45.585224) (xy 147.466665 -45.533895)
			(xy 147.495719 -45.486289) (xy 147.531394 -45.443421) (xy 147.572931 -45.406204) (xy 147.619444 -45.375431)
			(xy 147.669941 -45.351759) (xy 147.723348 -45.335691) (xy 147.778524 -45.327571) (xy 147.80641 -45.327062)
			(xy 147.834296 -45.327571) (xy 147.889472 -45.335691) (xy 147.942879 -45.351759) (xy 147.993376 -45.375431)
			(xy 148.039889 -45.406204) (xy 148.081426 -45.443421) (xy 148.117101 -45.486289) (xy 148.146155 -45.533895)
			(xy 148.167967 -45.585224) (xy 148.182073 -45.639181) (xy 148.188173 -45.694618) (xy 148.186136 -45.750352)
			(xy 148.176006 -45.805195) (xy 148.157999 -45.857979) (xy 148.132498 -45.907579) (xy 148.100047 -45.952937)
			(xy 148.061338 -45.993086) (xy 148.017195 -46.027172) (xy 147.96856 -46.054468) (xy 147.916469 -46.074391)
			(xy 147.862032 -46.086517) (xy 147.80641 -46.090588) (xy 147.750788 -46.086517) (xy 147.696351 -46.074391)
			(xy 147.64426 -46.054468) (xy 147.595625 -46.027172) (xy 147.551482 -45.993086) (xy 147.512773 -45.952937)
			(xy 147.480322 -45.907579) (xy 147.454821 -45.857979) (xy 147.436814 -45.805195) (xy 147.426684 -45.750352)
			(xy 147.424647 -45.694618) (xy 141.526757 -45.694618) (xy 141.513985 -45.721232) (xy 141.483622 -45.766542)
			(xy 141.447116 -45.807067) (xy 141.40521 -45.841978) (xy 141.358758 -45.870565) (xy 141.308709 -45.892244)
			(xy 141.256082 -45.906574) (xy 141.20195 -45.913262) (xy 141.147418 -45.912171) (xy 141.093597 -45.903325)
			(xy 141.041585 -45.886903) (xy 140.992442 -45.863241) (xy 140.94717 -45.83282) (xy 140.906693 -45.796261)
			(xy 140.871835 -45.75431) (xy 140.843308 -45.707822) (xy 140.821694 -45.657745) (xy 140.807432 -45.605099)
			(xy 140.800813 -45.550959) (xy 140.801974 -45.496429) (xy 140.810889 -45.442619) (xy 140.827378 -45.390628)
			(xy 140.851104 -45.341516) (xy 140.881583 -45.296283) (xy 140.918193 -45.255853) (xy 140.960189 -45.22105)
			(xy 141.006714 -45.192582) (xy 141.056819 -45.171032) (xy 141.08303 -45.163486) (xy 141.104851 -45.157048)
			(xy 141.14598 -45.137614) (xy 141.182992 -45.11117) (xy 141.214708 -45.078561) (xy 141.240112 -45.040827)
			(xy 141.258395 -44.999174) (xy 141.268972 -44.954932) (xy 141.271506 -44.909514) (xy 141.269212 -44.88688)
			(xy 141.267067 -44.868163) (xy 141.266051 -44.830501) (xy 141.26718 -44.811696) (xy 141.268312 -44.79042)
			(xy 141.264328 -44.748003) (xy 141.253317 -44.706846) (xy 141.235588 -44.668107) (xy 141.211638 -44.632872)
			(xy 141.18214 -44.602132) (xy 141.147924 -44.576749) (xy 141.109949 -44.557436) (xy 141.069282 -44.544737)
			(xy 141.048232 -44.54144) (xy 141.020927 -44.537172) (xy 140.967816 -44.521907) (xy 140.917463 -44.499139)
			(xy 140.870922 -44.469343) (xy 140.829168 -44.433143) (xy 140.793075 -44.391296) (xy 140.763397 -44.34468)
			(xy 140.740758 -44.294269) (xy 140.725629 -44.241119) (xy 140.718328 -44.186341) (xy 140.431758 -44.186341)
			(xy 140.436093 -44.225736) (xy 140.434056 -44.28147) (xy 140.423926 -44.336313) (xy 140.405919 -44.389097)
			(xy 140.380418 -44.438697) (xy 140.347967 -44.484055) (xy 140.309258 -44.524204) (xy 140.265115 -44.55829)
			(xy 140.21648 -44.585586) (xy 140.164389 -44.605509) (xy 140.109952 -44.617635) (xy 140.05433 -44.621706)
			(xy 139.998708 -44.617635) (xy 139.944271 -44.605509) (xy 139.89218 -44.585586) (xy 139.843545 -44.55829)
			(xy 139.799402 -44.524204) (xy 139.760693 -44.484055) (xy 139.728242 -44.438697) (xy 139.702741 -44.389097)
			(xy 139.684734 -44.336313) (xy 139.674604 -44.28147) (xy 139.672567 -44.225736) (xy 131.145313 -44.225736)
			(xy 131.124658 -44.237328) (xy 131.072532 -44.257264) (xy 131.018059 -44.269399) (xy 130.9624 -44.273473)
			(xy 130.906741 -44.269399) (xy 130.852268 -44.257264) (xy 130.800142 -44.237328) (xy 130.751474 -44.210014)
			(xy 130.707302 -44.175906) (xy 130.668567 -44.135729) (xy 130.636095 -44.090341) (xy 130.610577 -44.040709)
			(xy 130.592558 -43.987889) (xy 130.582421 -43.93301) (xy 130.580383 -43.877239) (xy 129.869614 -43.877239)
			(xy 129.879971 -43.894209) (xy 129.901798 -43.945572) (xy 129.915914 -43.999565) (xy 129.922017 -44.055039)
			(xy 129.919979 -44.11081) (xy 129.909842 -44.165689) (xy 129.891823 -44.218509) (xy 129.866305 -44.268141)
			(xy 129.833833 -44.313529) (xy 129.795098 -44.353706) (xy 129.750926 -44.387814) (xy 129.702258 -44.415128)
			(xy 129.650132 -44.435064) (xy 129.595659 -44.447199) (xy 129.54 -44.451273) (xy 129.484341 -44.447199)
			(xy 129.429868 -44.435064) (xy 129.377742 -44.415128) (xy 129.329074 -44.387814) (xy 129.284902 -44.353706)
			(xy 129.246167 -44.313529) (xy 129.213695 -44.268141) (xy 129.188177 -44.218509) (xy 129.170158 -44.165689)
			(xy 129.160021 -44.11081) (xy 129.157983 -44.055039) (xy 127.738387 -44.055039) (xy 128.4478 -44.764452)
			(xy 128.4478 -45.426639) (xy 129.818383 -45.426639) (xy 129.824486 -45.371165) (xy 129.838602 -45.317172)
			(xy 129.860429 -45.265809) (xy 129.889502 -45.218171) (xy 129.925201 -45.175275) (xy 129.966765 -45.138033)
			(xy 130.013309 -45.107239) (xy 130.06384 -45.083551) (xy 130.117282 -45.067473) (xy 130.172496 -45.059347)
			(xy 130.2004 -45.058838) (xy 130.228304 -45.059347) (xy 130.283518 -45.067473) (xy 130.33696 -45.083551)
			(xy 130.387491 -45.107239) (xy 130.434035 -45.138033) (xy 130.475599 -45.175275) (xy 130.511298 -45.218171)
			(xy 130.514513 -45.223439) (xy 130.707383 -45.223439) (xy 130.713486 -45.167965) (xy 130.727602 -45.113972)
			(xy 130.749429 -45.062609) (xy 130.778502 -45.014971) (xy 130.814201 -44.972075) (xy 130.855765 -44.934833)
			(xy 130.902309 -44.904039) (xy 130.95284 -44.880351) (xy 131.006282 -44.864273) (xy 131.061496 -44.856147)
			(xy 131.0894 -44.855638) (xy 131.117304 -44.856147) (xy 131.172518 -44.864273) (xy 131.22596 -44.880351)
			(xy 131.276491 -44.904039) (xy 131.323035 -44.934833) (xy 131.364599 -44.972075) (xy 131.400298 -45.014971)
			(xy 131.429371 -45.062609) (xy 131.451198 -45.113972) (xy 131.465314 -45.167965) (xy 131.471417 -45.223439)
			(xy 131.470637 -45.244784) (xy 132.033517 -45.244784) (xy 132.039617 -45.189347) (xy 132.053723 -45.13539)
			(xy 132.075535 -45.084061) (xy 132.104589 -45.036455) (xy 132.140264 -44.993587) (xy 132.181801 -44.95637)
			(xy 132.228314 -44.925597) (xy 132.278811 -44.901925) (xy 132.332218 -44.885857) (xy 132.387394 -44.877737)
			(xy 132.41528 -44.877228) (xy 132.443166 -44.877737) (xy 132.498342 -44.885857) (xy 132.551749 -44.901925)
			(xy 132.602246 -44.925597) (xy 132.648759 -44.95637) (xy 132.690296 -44.993587) (xy 132.692358 -44.996065)
			(xy 133.379858 -44.996065) (xy 133.381317 -44.940516) (xy 133.390814 -44.885766) (xy 133.408149 -44.832971)
			(xy 133.420104 -44.807886) (xy 133.432668 -44.783798) (xy 133.46353 -44.739091) (xy 133.50042 -44.699212)
			(xy 133.542592 -44.664966) (xy 133.589193 -44.637046) (xy 133.639283 -44.616016) (xy 133.691848 -44.602302)
			(xy 133.745827 -44.596179) (xy 133.800129 -44.597772) (xy 133.853657 -44.607049) (xy 133.905328 -44.623822)
			(xy 133.954098 -44.647752) (xy 133.998983 -44.678356) (xy 134.039075 -44.715015) (xy 134.073563 -44.756988)
			(xy 134.101751 -44.803428) (xy 134.12307 -44.853395) (xy 134.130542 -44.879514) (xy 134.134823 -44.893809)
			(xy 134.150454 -44.919215) (xy 134.172752 -44.939029) (xy 134.19982 -44.951565) (xy 134.229353 -44.955756)
			(xy 134.25884 -44.951245) (xy 134.272528 -44.9453) (xy 134.297866 -44.933879) (xy 134.351052 -44.917752)
			(xy 134.406014 -44.909507) (xy 134.461591 -44.909318) (xy 134.516609 -44.917189) (xy 134.569903 -44.932954)
			(xy 134.620349 -44.956279) (xy 134.666879 -44.986673) (xy 134.708512 -45.023491) (xy 134.744365 -45.065957)
			(xy 134.755881 -45.084503) (xy 135.122646 -45.084503) (xy 135.124791 -45.029694) (xy 135.134762 -44.975757)
			(xy 135.152354 -44.923804) (xy 135.177204 -44.874905) (xy 135.208801 -44.830069) (xy 135.246491 -44.790219)
			(xy 135.2895 -44.756178) (xy 135.33694 -44.728645) (xy 135.387834 -44.70819) (xy 135.441133 -44.695233)
			(xy 135.495737 -44.690042) (xy 135.550522 -44.692723) (xy 135.604359 -44.703222) (xy 135.656137 -44.721322)
			(xy 135.70479 -44.74665) (xy 135.749315 -44.778684) (xy 135.788794 -44.816763) (xy 135.822413 -44.860103)
			(xy 135.849479 -44.907811) (xy 135.869435 -44.958902) (xy 135.881869 -45.012325) (xy 135.886526 -45.066978)
			(xy 135.883308 -45.121734) (xy 135.872282 -45.175465) (xy 135.853676 -45.227064) (xy 135.827873 -45.275466)
			(xy 135.812022 -45.297852) (xy 135.798768 -45.316821) (xy 135.778588 -45.358457) (xy 135.766279 -45.403058)
			(xy 135.762246 -45.44915) (xy 135.766623 -45.495211) (xy 135.779265 -45.539719) (xy 135.799754 -45.581203)
			(xy 135.827414 -45.618293) (xy 135.844026 -45.634402) (xy 135.863839 -45.653368) (xy 135.898297 -45.696041)
			(xy 135.926289 -45.743208) (xy 135.927195 -45.7454) (xy 137.286236 -45.7454) (xy 137.290309 -45.689741)
			(xy 137.302444 -45.635268) (xy 137.32238 -45.583142) (xy 137.349694 -45.534474) (xy 137.383802 -45.490302)
			(xy 137.423979 -45.451567) (xy 137.469367 -45.419095) (xy 137.518999 -45.393577) (xy 137.571819 -45.375558)
			(xy 137.626698 -45.365421) (xy 137.682469 -45.363383) (xy 137.737943 -45.369486) (xy 137.791936 -45.383602)
			(xy 137.843299 -45.405429) (xy 137.890937 -45.434502) (xy 137.933833 -45.470201) (xy 137.971075 -45.511765)
			(xy 138.001869 -45.558309) (xy 138.025557 -45.60884) (xy 138.041635 -45.662282) (xy 138.048075 -45.706039)
			(xy 138.301983 -45.706039) (xy 138.308086 -45.650565) (xy 138.322202 -45.596572) (xy 138.344029 -45.545209)
			(xy 138.373102 -45.497571) (xy 138.408801 -45.454675) (xy 138.450365 -45.417433) (xy 138.496909 -45.386639)
			(xy 138.54744 -45.362951) (xy 138.600882 -45.346873) (xy 138.656096 -45.338747) (xy 138.684 -45.338238)
			(xy 138.711904 -45.338747) (xy 138.767118 -45.346873) (xy 138.82056 -45.362951) (xy 138.871091 -45.386639)
			(xy 138.917635 -45.417433) (xy 138.959199 -45.454675) (xy 138.994898 -45.497571) (xy 139.023971 -45.545209)
			(xy 139.045798 -45.596572) (xy 139.059914 -45.650565) (xy 139.066017 -45.706039) (xy 139.063979 -45.76181)
			(xy 139.053842 -45.816689) (xy 139.035823 -45.869509) (xy 139.010305 -45.919141) (xy 138.977833 -45.964529)
			(xy 138.939098 -46.004706) (xy 138.894926 -46.038814) (xy 138.846258 -46.066128) (xy 138.794132 -46.086064)
			(xy 138.739659 -46.098199) (xy 138.684 -46.102273) (xy 138.628341 -46.098199) (xy 138.573868 -46.086064)
			(xy 138.521742 -46.066128) (xy 138.473074 -46.038814) (xy 138.428902 -46.004706) (xy 138.390167 -45.964529)
			(xy 138.357695 -45.919141) (xy 138.332177 -45.869509) (xy 138.314158 -45.816689) (xy 138.304021 -45.76181)
			(xy 138.301983 -45.706039) (xy 138.048075 -45.706039) (xy 138.049761 -45.717496) (xy 138.05027 -45.7454)
			(xy 138.049761 -45.773304) (xy 138.041635 -45.828518) (xy 138.025557 -45.88196) (xy 138.001869 -45.932491)
			(xy 137.971075 -45.979035) (xy 137.933833 -46.020599) (xy 137.890937 -46.056298) (xy 137.843299 -46.085371)
			(xy 137.791936 -46.107198) (xy 137.737943 -46.121314) (xy 137.682469 -46.127417) (xy 137.626698 -46.125379)
			(xy 137.571819 -46.115242) (xy 137.518999 -46.097223) (xy 137.469367 -46.071705) (xy 137.423979 -46.039233)
			(xy 137.383802 -46.000498) (xy 137.349694 -45.956326) (xy 137.32238 -45.907658) (xy 137.302444 -45.855532)
			(xy 137.290309 -45.801059) (xy 137.286236 -45.7454) (xy 135.927195 -45.7454) (xy 135.947239 -45.793897)
			(xy 135.960714 -45.847064) (xy 135.966437 -45.901613) (xy 135.96429 -45.956419) (xy 135.954317 -46.010353)
			(xy 135.936724 -46.062303) (xy 135.911873 -46.111198) (xy 135.880277 -46.156031) (xy 135.842587 -46.195877)
			(xy 135.799579 -46.229916) (xy 135.75214 -46.257445) (xy 135.701248 -46.277898) (xy 135.647951 -46.290852)
			(xy 135.593349 -46.296041) (xy 135.538567 -46.293358) (xy 135.484733 -46.282858) (xy 135.432958 -46.264757)
			(xy 135.384308 -46.239429) (xy 135.339787 -46.207395) (xy 135.300311 -46.169317) (xy 135.266695 -46.125978)
			(xy 135.239632 -46.078272) (xy 135.219678 -46.027182) (xy 135.207246 -45.973761) (xy 135.202592 -45.919111)
			(xy 135.205811 -45.864357) (xy 135.216837 -45.810629) (xy 135.235444 -45.759034) (xy 135.261247 -45.710634)
			(xy 135.277098 -45.68825) (xy 135.290347 -45.669278) (xy 135.310525 -45.627643) (xy 135.322833 -45.583043)
			(xy 135.326866 -45.536951) (xy 135.32249 -45.490891) (xy 135.30985 -45.446384) (xy 135.289362 -45.4049)
			(xy 135.261705 -45.367809) (xy 135.245094 -45.3517) (xy 135.225259 -45.332755) (xy 135.190798 -45.290082)
			(xy 135.162802 -45.242914) (xy 135.14185 -45.192223) (xy 135.128372 -45.139054) (xy 135.122646 -45.084503)
			(xy 134.755881 -45.084503) (xy 134.773683 -45.113173) (xy 134.795845 -45.164141) (xy 134.810383 -45.217783)
			(xy 134.81699 -45.272967) (xy 134.815526 -45.328525) (xy 134.806021 -45.383284) (xy 134.788678 -45.436086)
			(xy 134.776718 -45.461174) (xy 134.764107 -45.485234) (xy 134.733244 -45.529932) (xy 134.696356 -45.569803)
			(xy 134.654187 -45.604042) (xy 134.60759 -45.631956) (xy 134.557507 -45.652981) (xy 134.504948 -45.666693)
			(xy 134.450976 -45.672815) (xy 134.396681 -45.671223) (xy 134.343161 -45.66195) (xy 134.291496 -45.645182)
			(xy 134.24273 -45.621258) (xy 134.197848 -45.590662) (xy 134.157758 -45.554012) (xy 134.123269 -45.512048)
			(xy 134.095078 -45.465618) (xy 134.073755 -45.41566) (xy 134.06628 -45.389546) (xy 134.061991 -45.375255)
			(xy 134.046356 -45.349856) (xy 134.024059 -45.330047) (xy 133.996995 -45.317512) (xy 133.967466 -45.313318)
			(xy 133.937983 -45.31782) (xy 133.924294 -45.32376) (xy 133.898914 -45.335079) (xy 133.845737 -45.351203)
			(xy 133.790784 -45.359447) (xy 133.735217 -45.359636) (xy 133.680209 -45.351767) (xy 133.626923 -45.336006)
			(xy 133.576485 -45.312686) (xy 133.529962 -45.2823) (xy 133.488335 -45.24549) (xy 133.452485 -45.203033)
			(xy 133.42317 -45.155827) (xy 133.401008 -45.10487) (xy 133.386468 -45.051238) (xy 133.379858 -44.996065)
			(xy 132.692358 -44.996065) (xy 132.725971 -45.036455) (xy 132.755025 -45.084061) (xy 132.776837 -45.13539)
			(xy 132.790943 -45.189347) (xy 132.797043 -45.244784) (xy 132.795006 -45.300518) (xy 132.784876 -45.355361)
			(xy 132.766869 -45.408145) (xy 132.741368 -45.457745) (xy 132.708917 -45.503103) (xy 132.670208 -45.543252)
			(xy 132.626065 -45.577338) (xy 132.57743 -45.604634) (xy 132.525339 -45.624557) (xy 132.470902 -45.636683)
			(xy 132.41528 -45.640754) (xy 132.359658 -45.636683) (xy 132.305221 -45.624557) (xy 132.25313 -45.604634)
			(xy 132.204495 -45.577338) (xy 132.160352 -45.543252) (xy 132.121643 -45.503103) (xy 132.089192 -45.457745)
			(xy 132.063691 -45.408145) (xy 132.045684 -45.355361) (xy 132.035554 -45.300518) (xy 132.033517 -45.244784)
			(xy 131.470637 -45.244784) (xy 131.469379 -45.27921) (xy 131.459242 -45.334089) (xy 131.441223 -45.386909)
			(xy 131.415705 -45.436541) (xy 131.383233 -45.481929) (xy 131.344498 -45.522106) (xy 131.300326 -45.556214)
			(xy 131.251658 -45.583528) (xy 131.199532 -45.603464) (xy 131.145059 -45.615599) (xy 131.0894 -45.619673)
			(xy 131.033741 -45.615599) (xy 130.979268 -45.603464) (xy 130.927142 -45.583528) (xy 130.878474 -45.556214)
			(xy 130.834302 -45.522106) (xy 130.795567 -45.481929) (xy 130.763095 -45.436541) (xy 130.737577 -45.386909)
			(xy 130.719558 -45.334089) (xy 130.709421 -45.27921) (xy 130.707383 -45.223439) (xy 130.514513 -45.223439)
			(xy 130.540371 -45.265809) (xy 130.562198 -45.317172) (xy 130.576314 -45.371165) (xy 130.582417 -45.426639)
			(xy 130.580379 -45.48241) (xy 130.570242 -45.537289) (xy 130.552223 -45.590109) (xy 130.526705 -45.639741)
			(xy 130.494233 -45.685129) (xy 130.455498 -45.725306) (xy 130.411326 -45.759414) (xy 130.362658 -45.786728)
			(xy 130.310532 -45.806664) (xy 130.256059 -45.818799) (xy 130.2004 -45.822873) (xy 130.144741 -45.818799)
			(xy 130.090268 -45.806664) (xy 130.038142 -45.786728) (xy 129.989474 -45.759414) (xy 129.945302 -45.725306)
			(xy 129.906567 -45.685129) (xy 129.874095 -45.639741) (xy 129.848577 -45.590109) (xy 129.830558 -45.537289)
			(xy 129.820421 -45.48241) (xy 129.818383 -45.426639) (xy 128.4478 -45.426639) (xy 128.4478 -46.402498)
			(xy 127.62357 -47.226728) (xy 154.5209 -47.226728) (xy 154.5209 -45.410628) (xy 154.52852 -45.35297)
			(xy 154.534392 -45.312071) (xy 154.553142 -45.231595) (xy 154.579602 -45.153314) (xy 154.613522 -45.077965)
			(xy 154.654582 -45.006258) (xy 154.702398 -44.938866) (xy 154.756518 -44.876424) (xy 154.816434 -44.819519)
			(xy 154.881581 -44.768688) (xy 154.951347 -44.724408) (xy 155.025075 -44.687095) (xy 155.102071 -44.657102)
			(xy 155.181611 -44.634711) (xy 155.262946 -44.620131) (xy 155.345311 -44.6135) (xy 155.427932 -44.614882)
			(xy 155.510029 -44.624261) (xy 155.590832 -44.641552) (xy 155.669579 -44.66659) (xy 155.74553 -44.699139)
			(xy 155.802984 -44.730671) (xy 158.204786 -44.730671) (xy 158.208335 -44.67481) (xy 158.220009 -44.620067)
			(xy 158.239556 -44.567617) (xy 158.266558 -44.518587) (xy 158.300435 -44.474028) (xy 158.340458 -44.434898)
			(xy 158.38577 -44.402036) (xy 158.435398 -44.376149) (xy 158.488275 -44.35779) (xy 158.543268 -44.347355)
			(xy 158.599195 -44.345068) (xy 158.654856 -44.350978) (xy 158.709056 -44.364957) (xy 158.760632 -44.386706)
			(xy 158.808476 -44.415758) (xy 158.851561 -44.45149) (xy 158.888963 -44.493133) (xy 158.919878 -44.539795)
			(xy 158.943643 -44.590473) (xy 158.959748 -44.64408) (xy 158.967847 -44.699465) (xy 158.967766 -44.755439)
			(xy 158.959506 -44.8108) (xy 158.943246 -44.86436) (xy 158.919335 -44.914969) (xy 158.888284 -44.961541)
			(xy 158.869888 -44.982638) (xy 158.855605 -44.999185) (xy 158.832268 -45.03614) (xy 158.815595 -45.076541)
			(xy 158.806079 -45.119198) (xy 158.803998 -45.162855) (xy 158.809416 -45.206224) (xy 158.822171 -45.248028)
			(xy 158.841889 -45.287034) (xy 158.867987 -45.322092) (xy 158.899698 -45.35217) (xy 158.91764 -45.364654)
			(xy 158.942703 -45.38123) (xy 158.988105 -45.420589) (xy 159.027228 -45.466195) (xy 159.059223 -45.517056)
			(xy 159.083394 -45.572067) (xy 159.099215 -45.630034) (xy 159.103314 -45.659802) (xy 159.104076 -45.666406)
			(xy 159.106616 -45.692314) (xy 159.106616 -46.95063) (xy 159.106108 -46.951392) (xy 159.106108 -46.979332)
			(xy 159.106108 -46.979586) (xy 159.105696 -47.008094) (xy 159.098032 -47.064588) (xy 159.082557 -47.119458)
			(xy 159.059576 -47.171632) (xy 159.029537 -47.220087) (xy 158.993028 -47.263875) (xy 158.950766 -47.302139)
			(xy 158.903576 -47.33413) (xy 158.852383 -47.35922) (xy 158.798189 -47.376919) (xy 158.742055 -47.386881)
			(xy 158.68508 -47.38891) (xy 158.62838 -47.382967) (xy 158.573064 -47.369168) (xy 158.520215 -47.347784)
			(xy 158.470869 -47.319232) (xy 158.425991 -47.284072) (xy 158.38646 -47.242992) (xy 158.35305 -47.196796)
			(xy 158.326415 -47.14639) (xy 158.307076 -47.092759) (xy 158.295412 -47.036954) (xy 158.293054 -47.008542)
			(xy 158.292292 -46.997366) (xy 158.292292 -45.707554) (xy 158.292831 -45.677872) (xy 158.301504 -45.619145)
			(xy 158.318617 -45.5623) (xy 158.343806 -45.508544) (xy 158.376536 -45.459018) (xy 158.395924 -45.436536)
			(xy 158.406592 -45.425106) (xy 158.42159 -45.408994) (xy 158.446272 -45.372549) (xy 158.464305 -45.332396)
			(xy 158.475149 -45.289736) (xy 158.478481 -45.245846) (xy 158.4742 -45.202038) (xy 158.462435 -45.159623)
			(xy 158.443537 -45.11987) (xy 158.418073 -45.083968) (xy 158.386803 -45.05299) (xy 158.369 -45.040042)
			(xy 158.34627 -45.023708) (xy 158.305482 -44.985375) (xy 158.270733 -44.941494) (xy 158.242768 -44.893006)
			(xy 158.222189 -44.840953) (xy 158.209437 -44.786451) (xy 158.204786 -44.730671) (xy 155.802984 -44.730671)
			(xy 155.817969 -44.738895) (xy 155.886216 -44.785482) (xy 155.949628 -44.838463) (xy 156.007608 -44.897338)
			(xy 156.05961 -44.961555) (xy 156.105147 -45.030507) (xy 156.143788 -45.103547) (xy 156.17517 -45.179988)
			(xy 156.198998 -45.259109) (xy 156.215049 -45.340167) (xy 156.223169 -45.422399) (xy 156.223716 -45.463714)
			(xy 156.223716 -47.156624) (xy 156.223462 -47.16526) (xy 156.222843 -47.20614) (xy 156.214577 -47.287488)
			(xy 156.198548 -47.367667) (xy 156.174905 -47.44594) (xy 156.143865 -47.521586) (xy 156.105716 -47.593907)
			(xy 156.060807 -47.662236) (xy 156.009553 -47.725944) (xy 155.952427 -47.784445) (xy 155.889954 -47.837198)
			(xy 155.822711 -47.883717) (xy 155.751318 -47.923575) (xy 155.676431 -47.956403) (xy 155.598741 -47.981899)
			(xy 155.518965 -47.999829) (xy 155.437838 -48.010026) (xy 155.356106 -48.012397) (xy 155.274523 -48.00692)
			(xy 155.193842 -47.993646) (xy 155.114805 -47.972697) (xy 155.038141 -47.944265) (xy 154.964557 -47.908614)
			(xy 154.89473 -47.866071) (xy 154.829304 -47.817028) (xy 154.768882 -47.761938) (xy 154.714021 -47.701308)
			(xy 154.665227 -47.635697) (xy 154.622948 -47.56571) (xy 154.587576 -47.491991) (xy 154.559435 -47.41522)
			(xy 154.538785 -47.336105) (xy 154.531822 -47.295816) (xy 154.5209 -47.226728) (xy 127.62357 -47.226728)
			(xy 127.12954 -47.720758) (xy 125.949456 -47.720758) (xy 124.980446 -46.751748) (xy 123.008136 -46.751748)
			(xy 122.938032 -46.809406) (xy 122.929142 -46.853856) (xy 122.922496 -46.883998) (xy 122.900791 -46.941776)
			(xy 122.870078 -46.995312) (xy 122.831154 -47.043212) (xy 122.808492 -47.064168) (xy 122.787122 -47.082465)
			(xy 122.740019 -47.113228) (xy 122.688911 -47.136741) (xy 122.634904 -47.152495) (xy 122.579169 -47.160147)
			(xy 122.522914 -47.159533) (xy 122.495056 -47.155608) (xy 122.478886 -47.153552) (xy 122.446461 -47.156777)
			(xy 122.415909 -47.16811) (xy 122.389225 -47.186812) (xy 122.368147 -47.211662) (xy 122.35405 -47.24104)
			(xy 122.35053 -47.256954) (xy 122.345275 -47.281912) (xy 122.329013 -47.330255) (xy 122.306455 -47.375999)
			(xy 122.278001 -47.418329) (xy 122.244161 -47.456489) (xy 122.205536 -47.4898) (xy 122.184414 -47.504096)
			(xy 122.161174 -47.518695) (xy 122.11139 -47.541795) (xy 122.05881 -47.557523) (xy 122.004519 -47.565555)
			(xy 121.949637 -47.565724) (xy 121.895298 -47.558028) (xy 121.842621 -47.542626) (xy 121.792696 -47.519834)
			(xy 121.746551 -47.490124) (xy 121.70514 -47.454108) (xy 121.669316 -47.41253) (xy 121.63982 -47.366248)
			(xy 121.61726 -47.316217) (xy 121.602102 -47.26347) (xy 121.594658 -47.209096) (xy 121.595082 -47.154215)
			(xy 121.603365 -47.099962) (xy 121.610882 -47.073566) (xy 121.616621 -47.050868) (xy 121.620656 -47.00423)
			(xy 121.616082 -46.957642) (xy 121.603055 -46.912679) (xy 121.582015 -46.870862) (xy 121.553673 -46.833604)
			(xy 121.518988 -46.802167) (xy 121.479133 -46.777612) (xy 121.435455 -46.76077) (xy 121.389432 -46.752212)
			(xy 121.366026 -46.751748) (xy 121.013982 -46.751748) (xy 120.997331 -46.752245) (xy 120.965165 -46.76087)
			(xy 120.936329 -46.777527) (xy 120.912787 -46.801081) (xy 120.896145 -46.829927) (xy 120.887536 -46.862097)
			(xy 120.886982 -46.878748) (xy 120.887406 -46.894035) (xy 120.894632 -46.923742) (xy 120.908727 -46.950871)
			(xy 120.928881 -46.97386) (xy 120.953932 -46.991386) (xy 120.968008 -46.997366) (xy 120.994134 -47.006769)
			(xy 121.043563 -47.03206) (xy 121.088804 -47.064249) (xy 121.128901 -47.102656) (xy 121.163007 -47.14647)
			(xy 121.190401 -47.194765) (xy 121.210505 -47.246521) (xy 121.222895 -47.300645) (xy 121.227308 -47.355993)
			(xy 121.223651 -47.411396) (xy 121.212001 -47.465684) (xy 121.192605 -47.51771) (xy 121.165872 -47.566374)
			(xy 121.132367 -47.61065) (xy 121.092798 -47.6496) (xy 121.048001 -47.682404) (xy 120.998922 -47.708367)
			(xy 120.946597 -47.726942) (xy 120.892133 -47.737735) (xy 120.836679 -47.740519) (xy 120.809004 -47.738284)
			(xy 120.780305 -47.734984) (xy 120.724298 -47.720839) (xy 120.671063 -47.698413) (xy 120.621818 -47.668218)
			(xy 120.577686 -47.630945) (xy 120.539678 -47.587445) (xy 120.508662 -47.538712) (xy 120.485346 -47.485861)
			(xy 120.47728 -47.458122) (xy 120.470585 -47.431545) (xy 120.463996 -47.377135) (xy 120.465255 -47.322343)
			(xy 120.474337 -47.268294) (xy 120.491056 -47.216099) (xy 120.515066 -47.166832) (xy 120.530112 -47.143924)
			(xy 120.542059 -47.12458) (xy 120.559617 -47.082647) (xy 120.569435 -47.038259) (xy 120.571201 -46.992833)
			(xy 120.564857 -46.947817) (xy 120.550607 -46.904648) (xy 120.528904 -46.864702) (xy 120.500441 -46.829254)
			(xy 120.466127 -46.799436) (xy 120.427054 -46.776197) (xy 120.384472 -46.760279) (xy 120.339736 -46.752191)
			(xy 120.317006 -46.751748) (xy 117.945154 -46.751748) (xy 117.888258 -46.78299) (xy 117.870732 -46.810676)
			(xy 117.855645 -46.833556) (xy 117.819952 -46.875146) (xy 117.778675 -46.911199) (xy 117.732664 -46.940975)
			(xy 117.682865 -46.96386) (xy 117.630304 -46.979384) (xy 117.576063 -46.987227) (xy 117.521257 -46.987227)
			(xy 117.467016 -46.979384) (xy 117.414455 -46.96386) (xy 117.364656 -46.940975) (xy 117.318645 -46.911199)
			(xy 117.277368 -46.875146) (xy 117.241675 -46.833556) (xy 117.226588 -46.810676) (xy 117.209062 -46.78299)
			(xy 117.152166 -46.751748) (xy 117.052852 -46.751748) (xy 116.739416 -46.438312) (xy 114.282982 -46.438312)
			(xy 114.267331 -46.439501) (xy 114.237285 -46.448552) (xy 114.21035 -46.46465) (xy 114.198908 -46.475396)
			(xy 113.11636 -47.558198) (xy 113.11636 -48.062914) (xy 123.156217 -48.062914) (xy 123.162317 -48.007477)
			(xy 123.176423 -47.95352) (xy 123.198235 -47.902191) (xy 123.227289 -47.854585) (xy 123.262964 -47.811717)
			(xy 123.304501 -47.7745) (xy 123.351014 -47.743727) (xy 123.401511 -47.720055) (xy 123.454918 -47.703987)
			(xy 123.510094 -47.695867) (xy 123.53798 -47.695358) (xy 123.565866 -47.695867) (xy 123.621042 -47.703987)
			(xy 123.674449 -47.720055) (xy 123.724946 -47.743727) (xy 123.771459 -47.7745) (xy 123.812996 -47.811717)
			(xy 123.848671 -47.854585) (xy 123.877725 -47.902191) (xy 123.899537 -47.95352) (xy 123.913643 -48.007477)
			(xy 123.919743 -48.062914) (xy 123.917706 -48.118648) (xy 123.907576 -48.173491) (xy 123.889569 -48.226275)
			(xy 123.864068 -48.275875) (xy 123.831617 -48.321233) (xy 123.792908 -48.361382) (xy 123.748765 -48.395468)
			(xy 123.70013 -48.422764) (xy 123.648039 -48.442687) (xy 123.593602 -48.454813) (xy 123.53798 -48.458884)
			(xy 123.482358 -48.454813) (xy 123.427921 -48.442687) (xy 123.37583 -48.422764) (xy 123.327195 -48.395468)
			(xy 123.283052 -48.361382) (xy 123.244343 -48.321233) (xy 123.211892 -48.275875) (xy 123.186391 -48.226275)
			(xy 123.168384 -48.173491) (xy 123.158254 -48.118648) (xy 123.156217 -48.062914) (xy 113.11636 -48.062914)
			(xy 113.11636 -48.895018) (xy 128.035557 -48.895018) (xy 128.041657 -48.839581) (xy 128.055763 -48.785624)
			(xy 128.077575 -48.734295) (xy 128.106629 -48.686689) (xy 128.142304 -48.643821) (xy 128.183841 -48.606604)
			(xy 128.230354 -48.575831) (xy 128.280851 -48.552159) (xy 128.334258 -48.536091) (xy 128.389434 -48.527971)
			(xy 128.41732 -48.527462) (xy 128.445206 -48.527971) (xy 128.500382 -48.536091) (xy 128.553789 -48.552159)
			(xy 128.604286 -48.575831) (xy 128.650799 -48.606604) (xy 128.692336 -48.643821) (xy 128.728011 -48.686689)
			(xy 128.753613 -48.728639) (xy 128.929383 -48.728639) (xy 128.935486 -48.673165) (xy 128.949602 -48.619172)
			(xy 128.971429 -48.567809) (xy 129.000502 -48.520171) (xy 129.036201 -48.477275) (xy 129.077765 -48.440033)
			(xy 129.124309 -48.409239) (xy 129.17484 -48.385551) (xy 129.228282 -48.369473) (xy 129.283496 -48.361347)
			(xy 129.3114 -48.360838) (xy 129.339304 -48.361347) (xy 129.394518 -48.369473) (xy 129.44796 -48.385551)
			(xy 129.498491 -48.409239) (xy 129.545035 -48.440033) (xy 129.586599 -48.477275) (xy 129.622298 -48.520171)
			(xy 129.651371 -48.567809) (xy 129.673198 -48.619172) (xy 129.687314 -48.673165) (xy 129.693417 -48.728639)
			(xy 129.691379 -48.78441) (xy 129.681242 -48.839289) (xy 129.663223 -48.892109) (xy 129.637705 -48.941741)
			(xy 129.605233 -48.987129) (xy 129.566498 -49.027306) (xy 129.522326 -49.061414) (xy 129.473658 -49.088728)
			(xy 129.421532 -49.108664) (xy 129.367059 -49.120799) (xy 129.3114 -49.124873) (xy 129.255741 -49.120799)
			(xy 129.201268 -49.108664) (xy 129.149142 -49.088728) (xy 129.100474 -49.061414) (xy 129.056302 -49.027306)
			(xy 129.017567 -48.987129) (xy 128.985095 -48.941741) (xy 128.959577 -48.892109) (xy 128.941558 -48.839289)
			(xy 128.931421 -48.78441) (xy 128.929383 -48.728639) (xy 128.753613 -48.728639) (xy 128.757065 -48.734295)
			(xy 128.778877 -48.785624) (xy 128.792983 -48.839581) (xy 128.799083 -48.895018) (xy 128.797046 -48.950752)
			(xy 128.786916 -49.005595) (xy 128.768909 -49.058379) (xy 128.743408 -49.107979) (xy 128.710957 -49.153337)
			(xy 128.672248 -49.193486) (xy 128.628105 -49.227572) (xy 128.57947 -49.254868) (xy 128.527379 -49.274791)
			(xy 128.472942 -49.286917) (xy 128.41732 -49.290988) (xy 128.361698 -49.286917) (xy 128.307261 -49.274791)
			(xy 128.25517 -49.254868) (xy 128.206535 -49.227572) (xy 128.162392 -49.193486) (xy 128.123683 -49.153337)
			(xy 128.091232 -49.107979) (xy 128.065731 -49.058379) (xy 128.047724 -49.005595) (xy 128.037594 -48.950752)
			(xy 128.035557 -48.895018) (xy 113.11636 -48.895018) (xy 113.11636 -49.530526) (xy 114.455447 -49.530526)
			(xy 114.461547 -49.475089) (xy 114.475653 -49.421132) (xy 114.497465 -49.369803) (xy 114.526519 -49.322197)
			(xy 114.562194 -49.279329) (xy 114.603731 -49.242112) (xy 114.650244 -49.211339) (xy 114.700741 -49.187667)
			(xy 114.754148 -49.171599) (xy 114.809324 -49.163479) (xy 114.83721 -49.16297) (xy 114.865096 -49.163479)
			(xy 114.920272 -49.171599) (xy 114.973679 -49.187667) (xy 115.024176 -49.211339) (xy 115.070689 -49.242112)
			(xy 115.112226 -49.279329) (xy 115.127861 -49.298116) (xy 123.529343 -49.298116) (xy 123.535443 -49.242679)
			(xy 123.549549 -49.188722) (xy 123.571361 -49.137393) (xy 123.600415 -49.089787) (xy 123.63609 -49.046919)
			(xy 123.677627 -49.009702) (xy 123.72414 -48.978929) (xy 123.774637 -48.955257) (xy 123.828044 -48.939189)
			(xy 123.88322 -48.931069) (xy 123.911106 -48.93056) (xy 123.938992 -48.931069) (xy 123.994168 -48.939189)
			(xy 124.047575 -48.955257) (xy 124.098072 -48.978929) (xy 124.144585 -49.009702) (xy 124.186122 -49.046919)
			(xy 124.221797 -49.089787) (xy 124.250851 -49.137393) (xy 124.272663 -49.188722) (xy 124.286769 -49.242679)
			(xy 124.292869 -49.298116) (xy 124.292349 -49.31234) (xy 126.403353 -49.31234) (xy 126.409453 -49.256903)
			(xy 126.423559 -49.202946) (xy 126.445371 -49.151617) (xy 126.474425 -49.104011) (xy 126.5101 -49.061143)
			(xy 126.551637 -49.023926) (xy 126.59815 -48.993153) (xy 126.648647 -48.969481) (xy 126.702054 -48.953413)
			(xy 126.75723 -48.945293) (xy 126.785116 -48.944784) (xy 126.813002 -48.945293) (xy 126.868178 -48.953413)
			(xy 126.921585 -48.969481) (xy 126.972082 -48.993153) (xy 127.018595 -49.023926) (xy 127.060132 -49.061143)
			(xy 127.095807 -49.104011) (xy 127.124861 -49.151617) (xy 127.146673 -49.202946) (xy 127.160779 -49.256903)
			(xy 127.166879 -49.31234) (xy 127.164842 -49.368074) (xy 127.154712 -49.422917) (xy 127.136705 -49.475701)
			(xy 127.111204 -49.525301) (xy 127.078753 -49.570659) (xy 127.040044 -49.610808) (xy 126.995901 -49.644894)
			(xy 126.947266 -49.67219) (xy 126.895175 -49.692113) (xy 126.840738 -49.704239) (xy 126.785116 -49.70831)
			(xy 126.729494 -49.704239) (xy 126.675057 -49.692113) (xy 126.622966 -49.67219) (xy 126.574331 -49.644894)
			(xy 126.530188 -49.610808) (xy 126.491479 -49.570659) (xy 126.459028 -49.525301) (xy 126.433527 -49.475701)
			(xy 126.41552 -49.422917) (xy 126.40539 -49.368074) (xy 126.403353 -49.31234) (xy 124.292349 -49.31234)
			(xy 124.290832 -49.35385) (xy 124.280702 -49.408693) (xy 124.262695 -49.461477) (xy 124.237194 -49.511077)
			(xy 124.204743 -49.556435) (xy 124.166034 -49.596584) (xy 124.121891 -49.63067) (xy 124.073256 -49.657966)
			(xy 124.021165 -49.677889) (xy 123.966728 -49.690015) (xy 123.911106 -49.694086) (xy 123.855484 -49.690015)
			(xy 123.801047 -49.677889) (xy 123.748956 -49.657966) (xy 123.700321 -49.63067) (xy 123.656178 -49.596584)
			(xy 123.617469 -49.556435) (xy 123.585018 -49.511077) (xy 123.559517 -49.461477) (xy 123.54151 -49.408693)
			(xy 123.53138 -49.35385) (xy 123.529343 -49.298116) (xy 115.127861 -49.298116) (xy 115.147901 -49.322197)
			(xy 115.176955 -49.369803) (xy 115.198767 -49.421132) (xy 115.212873 -49.475089) (xy 115.218973 -49.530526)
			(xy 115.216936 -49.58626) (xy 115.206806 -49.641103) (xy 115.188799 -49.693887) (xy 115.163298 -49.743487)
			(xy 115.13553 -49.782299) (xy 129.716548 -49.782299) (xy 129.720656 -49.728082) (xy 129.732415 -49.674996)
			(xy 129.751588 -49.624115) (xy 129.777785 -49.576469) (xy 129.810478 -49.533022) (xy 129.849004 -49.494654)
			(xy 129.892584 -49.462139) (xy 129.940336 -49.436137) (xy 129.991295 -49.417173) (xy 130.044429 -49.405631)
			(xy 130.098663 -49.401744) (xy 130.152899 -49.405592) (xy 130.179572 -49.410874) (xy 130.193783 -49.413461)
			(xy 130.222584 -49.411388) (xy 130.249664 -49.401366) (xy 130.272875 -49.384189) (xy 130.290375 -49.361221)
			(xy 130.300775 -49.334284) (xy 130.302508 -49.319942) (xy 130.305162 -49.294112) (xy 130.316572 -49.243457)
			(xy 130.334733 -49.194813) (xy 130.359311 -49.149074) (xy 130.389854 -49.107083) (xy 130.425799 -49.069612)
			(xy 130.466485 -49.037352) (xy 130.511163 -49.010894) (xy 130.534918 -49.00041) (xy 130.547282 -48.994782)
			(xy 130.568665 -48.978038) (xy 130.584894 -48.956262) (xy 130.594828 -48.930986) (xy 130.597767 -48.903988)
			(xy 130.593507 -48.877166) (xy 130.582345 -48.852407) (xy 130.574034 -48.84166) (xy 130.557046 -48.820285)
			(xy 130.52867 -48.773641) (xy 130.507228 -48.723429) (xy 130.493159 -48.670675) (xy 130.486749 -48.616454)
			(xy 130.488129 -48.561874) (xy 130.497271 -48.508047) (xy 130.513987 -48.456071) (xy 130.537938 -48.407007)
			(xy 130.568635 -48.361855) (xy 130.605451 -48.321538) (xy 130.647635 -48.286876) (xy 130.694328 -48.258578)
			(xy 130.744575 -48.237221) (xy 130.797353 -48.22324) (xy 130.851584 -48.21692) (xy 130.906162 -48.218391)
			(xy 130.959974 -48.227623) (xy 131.011921 -48.244426) (xy 131.060945 -48.268459) (xy 131.106045 -48.299231)
			(xy 131.146302 -48.336115) (xy 131.180893 -48.378357) (xy 131.209113 -48.425096) (xy 131.230386 -48.475379)
			(xy 131.244279 -48.52818) (xy 131.250508 -48.582422) (xy 131.248946 -48.636997) (xy 131.240912 -48.683362)
			(xy 133.042347 -48.683362) (xy 133.047864 -48.627585) (xy 133.061478 -48.573214) (xy 133.082896 -48.521419)
			(xy 133.111657 -48.473312) (xy 133.147144 -48.429927) (xy 133.188594 -48.392198) (xy 133.235114 -48.360936)
			(xy 133.285706 -48.336812) (xy 133.339282 -48.320345) (xy 133.39469 -48.31189) (xy 133.450739 -48.311627)
			(xy 133.506223 -48.319563) (xy 133.559951 -48.335528) (xy 133.610767 -48.359176) (xy 133.657578 -48.390002)
			(xy 133.699379 -48.427341) (xy 133.735271 -48.470391) (xy 133.764482 -48.518226) (xy 133.786384 -48.569819)
			(xy 133.800506 -48.62406) (xy 133.806546 -48.679783) (xy 133.804372 -48.73579) (xy 133.794031 -48.790877)
			(xy 133.785356 -48.81753) (xy 133.781385 -48.830149) (xy 133.77944 -48.856526) (xy 133.784321 -48.882521)
			(xy 133.795701 -48.906396) (xy 133.812821 -48.926556) (xy 133.834537 -48.941654) (xy 133.846824 -48.946562)
			(xy 133.869518 -48.955226) (xy 133.912693 -48.977488) (xy 133.95269 -49.005055) (xy 133.97103 -49.020984)
			(xy 133.981515 -49.029748) (xy 134.00597 -49.041919) (xy 134.032774 -49.047183) (xy 134.060015 -49.045163)
			(xy 134.08575 -49.036004) (xy 134.108142 -49.020359) (xy 134.125594 -48.999345) (xy 134.136861 -48.974461)
			(xy 134.139432 -48.96104) (xy 134.14439 -48.933459) (xy 134.161288 -48.880031) (xy 134.185816 -48.829648)
			(xy 134.217447 -48.783392) (xy 134.255502 -48.742258) (xy 134.299161 -48.70713) (xy 134.347487 -48.678763)
			(xy 134.399441 -48.657767) (xy 134.453907 -48.644592) (xy 134.509714 -48.639522) (xy 134.565662 -48.642666)
			(xy 134.62055 -48.653956) (xy 134.673197 -48.67315) (xy 134.722471 -48.699835) (xy 134.767315 -48.733438)
			(xy 134.806764 -48.773236) (xy 134.808718 -48.775892) (xy 135.821165 -48.775892) (xy 135.827265 -48.720455)
			(xy 135.841371 -48.666498) (xy 135.863183 -48.615169) (xy 135.892237 -48.567563) (xy 135.927912 -48.524695)
			(xy 135.969449 -48.487478) (xy 136.015962 -48.456705) (xy 136.066459 -48.433033) (xy 136.119866 -48.416965)
			(xy 136.175042 -48.408845) (xy 136.202928 -48.408336) (xy 136.230814 -48.408845) (xy 136.28599 -48.416965)
			(xy 136.339397 -48.433033) (xy 136.389894 -48.456705) (xy 136.436407 -48.487478) (xy 136.477944 -48.524695)
			(xy 136.513619 -48.567563) (xy 136.542673 -48.615169) (xy 136.564485 -48.666498) (xy 136.578591 -48.720455)
			(xy 136.582286 -48.754039) (xy 138.301983 -48.754039) (xy 138.308086 -48.698565) (xy 138.322202 -48.644572)
			(xy 138.344029 -48.593209) (xy 138.373102 -48.545571) (xy 138.408801 -48.502675) (xy 138.450365 -48.465433)
			(xy 138.496909 -48.434639) (xy 138.54744 -48.410951) (xy 138.600882 -48.394873) (xy 138.656096 -48.386747)
			(xy 138.684 -48.386238) (xy 138.711904 -48.386747) (xy 138.767118 -48.394873) (xy 138.82056 -48.410951)
			(xy 138.871091 -48.434639) (xy 138.917635 -48.465433) (xy 138.959199 -48.502675) (xy 138.994898 -48.545571)
			(xy 139.001684 -48.55669) (xy 141.545309 -48.55669) (xy 141.551409 -48.501253) (xy 141.565515 -48.447296)
			(xy 141.587327 -48.395967) (xy 141.616381 -48.348361) (xy 141.652056 -48.305493) (xy 141.693593 -48.268276)
			(xy 141.740106 -48.237503) (xy 141.790603 -48.213831) (xy 141.84401 -48.197763) (xy 141.899186 -48.189643)
			(xy 141.927072 -48.189134) (xy 141.954958 -48.189643) (xy 142.010134 -48.197763) (xy 142.063541 -48.213831)
			(xy 142.114038 -48.237503) (xy 142.116082 -48.238855) (xy 153.211025 -48.238855) (xy 153.213033 -48.166011)
			(xy 153.223042 -48.093831) (xy 153.240931 -48.023189) (xy 153.266482 -47.954944) (xy 153.299386 -47.889925)
			(xy 153.339242 -47.828919) (xy 153.385568 -47.772669) (xy 153.437801 -47.721856) (xy 153.495307 -47.677098)
			(xy 153.557387 -47.638937) (xy 153.623289 -47.607837) (xy 153.692212 -47.584176) (xy 153.763319 -47.56824)
			(xy 153.835748 -47.560224) (xy 153.872184 -47.559722) (xy 153.90862 -47.560224) (xy 153.981049 -47.56824)
			(xy 154.052156 -47.584176) (xy 154.121079 -47.607837) (xy 154.186981 -47.638937) (xy 154.249061 -47.677098)
			(xy 154.306567 -47.721856) (xy 154.3588 -47.772669) (xy 154.405126 -47.828919) (xy 154.444982 -47.889925)
			(xy 154.477886 -47.954944) (xy 154.503437 -48.023189) (xy 154.521326 -48.093831) (xy 154.531335 -48.166011)
			(xy 154.532148 -48.195502) (xy 158.355537 -48.195502) (xy 158.361637 -48.140065) (xy 158.375743 -48.086108)
			(xy 158.397555 -48.034779) (xy 158.426609 -47.987173) (xy 158.462284 -47.944305) (xy 158.503821 -47.907088)
			(xy 158.550334 -47.876315) (xy 158.600831 -47.852643) (xy 158.654238 -47.836575) (xy 158.709414 -47.828455)
			(xy 158.7373 -47.827946) (xy 158.765186 -47.828455) (xy 158.820362 -47.836575) (xy 158.873769 -47.852643)
			(xy 158.924266 -47.876315) (xy 158.970779 -47.907088) (xy 159.012316 -47.944305) (xy 159.047991 -47.987173)
			(xy 159.077045 -48.034779) (xy 159.098857 -48.086108) (xy 159.112963 -48.140065) (xy 159.119063 -48.195502)
			(xy 159.117026 -48.251236) (xy 159.106896 -48.306079) (xy 159.088889 -48.358863) (xy 159.063388 -48.408463)
			(xy 159.030937 -48.453821) (xy 158.992228 -48.49397) (xy 158.948085 -48.528056) (xy 158.89945 -48.555352)
			(xy 158.847359 -48.575275) (xy 158.792922 -48.587401) (xy 158.7373 -48.591472) (xy 158.681678 -48.587401)
			(xy 158.627241 -48.575275) (xy 158.57515 -48.555352) (xy 158.526515 -48.528056) (xy 158.482372 -48.49397)
			(xy 158.443663 -48.453821) (xy 158.411212 -48.408463) (xy 158.385711 -48.358863) (xy 158.367704 -48.306079)
			(xy 158.357574 -48.251236) (xy 158.355537 -48.195502) (xy 154.532148 -48.195502) (xy 154.533343 -48.238855)
			(xy 154.527326 -48.311477) (xy 154.513356 -48.382997) (xy 154.491602 -48.452545) (xy 154.46233 -48.519279)
			(xy 154.425895 -48.582387) (xy 154.382738 -48.641104) (xy 154.333383 -48.694717) (xy 154.278431 -48.742576)
			(xy 154.218547 -48.784098) (xy 154.154458 -48.818781) (xy 154.086944 -48.846203) (xy 154.016822 -48.866032)
			(xy 153.944945 -48.878026) (xy 153.872184 -48.882041) (xy 153.799423 -48.878026) (xy 153.727546 -48.866032)
			(xy 153.657424 -48.846203) (xy 153.58991 -48.818781) (xy 153.525821 -48.784098) (xy 153.465937 -48.742576)
			(xy 153.410985 -48.694717) (xy 153.36163 -48.641104) (xy 153.318473 -48.582387) (xy 153.282038 -48.519279)
			(xy 153.252766 -48.452545) (xy 153.231012 -48.382997) (xy 153.217042 -48.311477) (xy 153.211025 -48.238855)
			(xy 142.116082 -48.238855) (xy 142.160551 -48.268276) (xy 142.202088 -48.305493) (xy 142.237763 -48.348361)
			(xy 142.266817 -48.395967) (xy 142.288629 -48.447296) (xy 142.302735 -48.501253) (xy 142.308835 -48.55669)
			(xy 142.306798 -48.612424) (xy 142.296668 -48.667267) (xy 142.278661 -48.720051) (xy 142.25316 -48.769651)
			(xy 142.220709 -48.815009) (xy 142.182 -48.855158) (xy 142.137857 -48.889244) (xy 142.089222 -48.91654)
			(xy 142.037131 -48.936463) (xy 141.982694 -48.948589) (xy 141.927072 -48.95266) (xy 141.87145 -48.948589)
			(xy 141.817013 -48.936463) (xy 141.764922 -48.91654) (xy 141.716287 -48.889244) (xy 141.672144 -48.855158)
			(xy 141.633435 -48.815009) (xy 141.600984 -48.769651) (xy 141.575483 -48.720051) (xy 141.557476 -48.667267)
			(xy 141.547346 -48.612424) (xy 141.545309 -48.55669) (xy 139.001684 -48.55669) (xy 139.023971 -48.593209)
			(xy 139.045798 -48.644572) (xy 139.059914 -48.698565) (xy 139.066017 -48.754039) (xy 139.063979 -48.80981)
			(xy 139.053842 -48.864689) (xy 139.035823 -48.917509) (xy 139.010305 -48.967141) (xy 138.977833 -49.012529)
			(xy 138.939098 -49.052706) (xy 138.894926 -49.086814) (xy 138.846258 -49.114128) (xy 138.794132 -49.134064)
			(xy 138.739659 -49.146199) (xy 138.684 -49.150273) (xy 138.628341 -49.146199) (xy 138.573868 -49.134064)
			(xy 138.521742 -49.114128) (xy 138.473074 -49.086814) (xy 138.428902 -49.052706) (xy 138.390167 -49.012529)
			(xy 138.357695 -48.967141) (xy 138.332177 -48.917509) (xy 138.314158 -48.864689) (xy 138.304021 -48.80981)
			(xy 138.301983 -48.754039) (xy 136.582286 -48.754039) (xy 136.584691 -48.775892) (xy 136.582654 -48.831626)
			(xy 136.572524 -48.886469) (xy 136.554517 -48.939253) (xy 136.529016 -48.988853) (xy 136.496565 -49.034211)
			(xy 136.457856 -49.07436) (xy 136.413713 -49.108446) (xy 136.365078 -49.135742) (xy 136.312987 -49.155665)
			(xy 136.25855 -49.167791) (xy 136.202928 -49.171862) (xy 136.147306 -49.167791) (xy 136.092869 -49.155665)
			(xy 136.040778 -49.135742) (xy 135.992143 -49.108446) (xy 135.948 -49.07436) (xy 135.909291 -49.034211)
			(xy 135.87684 -48.988853) (xy 135.851339 -48.939253) (xy 135.833332 -48.886469) (xy 135.823202 -48.831626)
			(xy 135.821165 -48.775892) (xy 134.808718 -48.775892) (xy 134.83997 -48.818375) (xy 134.86622 -48.867883)
			(xy 134.884949 -48.920697) (xy 134.895755 -48.975682) (xy 134.898405 -49.031656) (xy 134.892843 -49.087416)
			(xy 134.879189 -49.141763) (xy 134.857735 -49.19353) (xy 134.828943 -49.241605) (xy 134.793431 -49.284952)
			(xy 134.751963 -49.322642) (xy 134.705431 -49.353864) (xy 134.654833 -49.377947) (xy 134.601258 -49.394374)
			(xy 134.545857 -49.40279) (xy 134.489821 -49.403017) (xy 134.434354 -49.395047) (xy 134.380648 -49.379054)
			(xy 134.329857 -49.35538) (xy 134.283074 -49.324535) (xy 134.26186 -49.306226) (xy 134.25135 -49.297499)
			(xy 134.226902 -49.285345) (xy 134.200109 -49.280092) (xy 134.17288 -49.282114) (xy 134.147157 -49.291266)
			(xy 134.124771 -49.306897) (xy 134.107317 -49.327892) (xy 134.096039 -49.352757) (xy 134.093458 -49.36617)
			(xy 134.08829 -49.395092) (xy 134.070199 -49.450987) (xy 134.043755 -49.50345) (xy 134.009583 -49.551239)
			(xy 133.96849 -49.593227) (xy 133.921448 -49.62842) (xy 133.869567 -49.655988) (xy 133.841998 -49.666144)
			(xy 133.814904 -49.675021) (xy 133.758871 -49.685545) (xy 133.701895 -49.68762) (xy 133.645245 -49.681202)
			(xy 133.590178 -49.666432) (xy 133.537919 -49.643639) (xy 133.48963 -49.61333) (xy 133.446384 -49.576178)
			(xy 133.409142 -49.53301) (xy 133.378733 -49.484784) (xy 133.355831 -49.432573) (xy 133.340947 -49.377537)
			(xy 133.334411 -49.3209) (xy 133.336368 -49.26392) (xy 133.346775 -49.207865) (xy 133.355588 -49.18075)
			(xy 133.359505 -49.168114) (xy 133.361469 -49.141743) (xy 133.356603 -49.115751) (xy 133.345232 -49.091876)
			(xy 133.328118 -49.071717) (xy 133.306406 -49.056623) (xy 133.29412 -49.051718) (xy 133.267929 -49.041739)
			(xy 133.218617 -49.015096) (xy 133.173731 -48.981528) (xy 133.134236 -48.941758) (xy 133.100981 -48.89664)
			(xy 133.074681 -48.847144) (xy 133.055902 -48.794335) (xy 133.045046 -48.739347) (xy 133.042347 -48.683362)
			(xy 131.240912 -48.683362) (xy 131.239624 -48.690794) (xy 131.222734 -48.742713) (xy 131.198619 -48.791697)
			(xy 131.167772 -48.836746) (xy 131.130821 -48.87694) (xy 131.088521 -48.91146) (xy 131.041735 -48.939602)
			(xy 131.016756 -48.950626) (xy 131.004433 -48.956333) (xy 130.983061 -48.973066) (xy 130.966836 -48.994827)
			(xy 130.956901 -49.020086) (xy 130.953952 -49.047069) (xy 130.958198 -49.073878) (xy 130.96934 -49.09863)
			(xy 130.97764 -49.109376) (xy 130.990086 -49.125378) (xy 131.005849 -49.147534) (xy 131.031621 -49.195411)
			(xy 131.05034 -49.24646) (xy 131.061626 -49.299649) (xy 131.065252 -49.353901) (xy 131.061144 -49.408118)
			(xy 131.060642 -49.410384) (xy 131.702047 -49.410384) (xy 131.708147 -49.354947) (xy 131.722253 -49.30099)
			(xy 131.744065 -49.249661) (xy 131.773119 -49.202055) (xy 131.808794 -49.159187) (xy 131.850331 -49.12197)
			(xy 131.896844 -49.091197) (xy 131.947341 -49.067525) (xy 132.000748 -49.051457) (xy 132.055924 -49.043337)
			(xy 132.08381 -49.042828) (xy 132.111696 -49.043337) (xy 132.166872 -49.051457) (xy 132.220279 -49.067525)
			(xy 132.270776 -49.091197) (xy 132.317289 -49.12197) (xy 132.358826 -49.159187) (xy 132.394501 -49.202055)
			(xy 132.423555 -49.249661) (xy 132.445367 -49.30099) (xy 132.459473 -49.354947) (xy 132.465573 -49.410384)
			(xy 132.463536 -49.466118) (xy 132.453406 -49.520961) (xy 132.435399 -49.573745) (xy 132.409898 -49.623345)
			(xy 132.377447 -49.668703) (xy 132.338738 -49.708852) (xy 132.294595 -49.742938) (xy 132.24596 -49.770234)
			(xy 132.193869 -49.790157) (xy 132.139432 -49.802283) (xy 132.08381 -49.806354) (xy 132.028188 -49.802283)
			(xy 131.973751 -49.790157) (xy 131.92166 -49.770234) (xy 131.873025 -49.742938) (xy 131.828882 -49.708852)
			(xy 131.790173 -49.668703) (xy 131.757722 -49.623345) (xy 131.732221 -49.573745) (xy 131.714214 -49.520961)
			(xy 131.704084 -49.466118) (xy 131.702047 -49.410384) (xy 131.060642 -49.410384) (xy 131.049385 -49.461204)
			(xy 131.030212 -49.512085) (xy 131.004015 -49.559731) (xy 130.971322 -49.603178) (xy 130.932796 -49.641546)
			(xy 130.889216 -49.674061) (xy 130.841464 -49.700063) (xy 130.790505 -49.719027) (xy 130.737371 -49.730569)
			(xy 130.683137 -49.734456) (xy 130.628901 -49.730608) (xy 130.602228 -49.725326) (xy 130.588017 -49.722739)
			(xy 130.559216 -49.724812) (xy 130.532136 -49.734834) (xy 130.508925 -49.752011) (xy 130.491425 -49.774979)
			(xy 130.481025 -49.801916) (xy 130.479292 -49.816258) (xy 130.476475 -49.84331) (xy 130.464224 -49.896298)
			(xy 130.463937 -49.897039) (xy 135.120379 -49.897039) (xy 135.126482 -49.841565) (xy 135.140598 -49.787572)
			(xy 135.162425 -49.736209) (xy 135.191498 -49.688571) (xy 135.227197 -49.645675) (xy 135.268761 -49.608433)
			(xy 135.315305 -49.577639) (xy 135.365836 -49.553951) (xy 135.419278 -49.537873) (xy 135.474492 -49.529747)
			(xy 135.502396 -49.529238) (xy 135.5303 -49.529747) (xy 135.585514 -49.537873) (xy 135.638956 -49.553951)
			(xy 135.689487 -49.577639) (xy 135.736031 -49.608433) (xy 135.777595 -49.645675) (xy 135.813294 -49.688571)
			(xy 135.842367 -49.736209) (xy 135.864194 -49.787572) (xy 135.87831 -49.841565) (xy 135.884413 -49.897039)
			(xy 136.650983 -49.897039) (xy 136.657086 -49.841565) (xy 136.671202 -49.787572) (xy 136.693029 -49.736209)
			(xy 136.722102 -49.688571) (xy 136.757801 -49.645675) (xy 136.799365 -49.608433) (xy 136.845909 -49.577639)
			(xy 136.89644 -49.553951) (xy 136.949882 -49.537873) (xy 137.005096 -49.529747) (xy 137.033 -49.529238)
			(xy 137.060904 -49.529747) (xy 137.116118 -49.537873) (xy 137.16956 -49.553951) (xy 137.220091 -49.577639)
			(xy 137.224371 -49.580471) (xy 144.317291 -49.580471) (xy 144.321271 -49.525503) (xy 144.333123 -49.471679)
			(xy 144.352597 -49.420122) (xy 144.37929 -49.371904) (xy 144.412645 -49.328031) (xy 144.451967 -49.289415)
			(xy 144.496438 -49.256861) (xy 144.545131 -49.231047) (xy 144.597033 -49.21251) (xy 144.651063 -49.201636)
			(xy 144.706095 -49.198653) (xy 144.760983 -49.203621) (xy 144.814585 -49.216438) (xy 144.865784 -49.236837)
			(xy 144.913514 -49.264392) (xy 144.935448 -49.28108) (xy 144.952386 -49.293911) (xy 144.989646 -49.314333)
			(xy 145.029785 -49.328272) (xy 145.071683 -49.33534) (xy 145.114173 -49.33534) (xy 145.156071 -49.328272)
			(xy 145.19621 -49.314333) (xy 145.23347 -49.293911) (xy 145.250408 -49.28108) (xy 145.2723 -49.264337)
			(xy 145.320035 -49.236786) (xy 145.371239 -49.216391) (xy 145.424844 -49.203579) (xy 145.479736 -49.198615)
			(xy 145.53477 -49.201603) (xy 145.588801 -49.212481) (xy 145.640705 -49.231021) (xy 145.689399 -49.25684)
			(xy 145.73387 -49.289397) (xy 145.762921 -49.317928) (xy 147.679917 -49.317928) (xy 147.686017 -49.262491)
			(xy 147.700123 -49.208534) (xy 147.721935 -49.157205) (xy 147.750989 -49.109599) (xy 147.786664 -49.066731)
			(xy 147.828201 -49.029514) (xy 147.874714 -48.998741) (xy 147.925211 -48.975069) (xy 147.978618 -48.959001)
			(xy 148.033794 -48.950881) (xy 148.06168 -48.950372) (xy 148.089566 -48.950881) (xy 148.144742 -48.959001)
			(xy 148.146514 -48.959534) (xy 149.146005 -48.959534) (xy 149.152105 -48.904097) (xy 149.166211 -48.85014)
			(xy 149.188023 -48.798811) (xy 149.217077 -48.751205) (xy 149.252752 -48.708337) (xy 149.294289 -48.67112)
			(xy 149.340802 -48.640347) (xy 149.391299 -48.616675) (xy 149.444706 -48.600607) (xy 149.499882 -48.592487)
			(xy 149.527768 -48.591978) (xy 149.555654 -48.592487) (xy 149.61083 -48.600607) (xy 149.664237 -48.616675)
			(xy 149.714734 -48.640347) (xy 149.761247 -48.67112) (xy 149.802784 -48.708337) (xy 149.838459 -48.751205)
			(xy 149.867513 -48.798811) (xy 149.889325 -48.85014) (xy 149.903431 -48.904097) (xy 149.909531 -48.959534)
			(xy 149.907494 -49.015268) (xy 149.897364 -49.070111) (xy 149.879357 -49.122895) (xy 149.853856 -49.172495)
			(xy 149.821405 -49.217853) (xy 149.782696 -49.258002) (xy 149.738553 -49.292088) (xy 149.689918 -49.319384)
			(xy 149.637827 -49.339307) (xy 149.58339 -49.351433) (xy 149.527768 -49.355504) (xy 149.472146 -49.351433)
			(xy 149.417709 -49.339307) (xy 149.365618 -49.319384) (xy 149.316983 -49.292088) (xy 149.27284 -49.258002)
			(xy 149.234131 -49.217853) (xy 149.20168 -49.172495) (xy 149.176179 -49.122895) (xy 149.158172 -49.070111)
			(xy 149.148042 -49.015268) (xy 149.146005 -48.959534) (xy 148.146514 -48.959534) (xy 148.198149 -48.975069)
			(xy 148.248646 -48.998741) (xy 148.295159 -49.029514) (xy 148.336696 -49.066731) (xy 148.372371 -49.109599)
			(xy 148.401425 -49.157205) (xy 148.423237 -49.208534) (xy 148.437343 -49.262491) (xy 148.443443 -49.317928)
			(xy 148.441406 -49.373662) (xy 148.431276 -49.428505) (xy 148.413269 -49.481289) (xy 148.387768 -49.530889)
			(xy 148.355317 -49.576247) (xy 148.316608 -49.616396) (xy 148.272465 -49.650482) (xy 148.22383 -49.677778)
			(xy 148.171739 -49.697701) (xy 148.117302 -49.709827) (xy 148.06168 -49.713898) (xy 148.006058 -49.709827)
			(xy 147.951621 -49.697701) (xy 147.89953 -49.677778) (xy 147.850895 -49.650482) (xy 147.806752 -49.616396)
			(xy 147.768043 -49.576247) (xy 147.735592 -49.530889) (xy 147.710091 -49.481289) (xy 147.692084 -49.428505)
			(xy 147.681954 -49.373662) (xy 147.679917 -49.317928) (xy 145.762921 -49.317928) (xy 145.773193 -49.328016)
			(xy 145.806548 -49.371893) (xy 145.83324 -49.420114) (xy 145.852715 -49.471674) (xy 145.864566 -49.5255)
			(xy 145.868547 -49.580471) (xy 145.864574 -49.635444) (xy 145.852731 -49.689272) (xy 145.833264 -49.740835)
			(xy 145.806579 -49.789059) (xy 145.773231 -49.832941) (xy 145.733914 -49.871566) (xy 145.689447 -49.90413)
			(xy 145.640757 -49.929955) (xy 145.588856 -49.948504) (xy 145.534827 -49.95939) (xy 145.479793 -49.962386)
			(xy 145.4249 -49.95743) (xy 145.371293 -49.944626) (xy 145.320087 -49.924239) (xy 145.272347 -49.896695)
			(xy 145.250408 -49.880012) (xy 145.23347 -49.867181) (xy 145.19621 -49.846759) (xy 145.156071 -49.83282)
			(xy 145.114173 -49.825752) (xy 145.071683 -49.825752) (xy 145.029785 -49.83282) (xy 144.989646 -49.846759)
			(xy 144.952386 -49.867181) (xy 144.935448 -49.880012) (xy 144.913467 -49.89664) (xy 144.865733 -49.924188)
			(xy 144.814531 -49.944579) (xy 144.760927 -49.957388) (xy 144.706038 -49.962348) (xy 144.651006 -49.959356)
			(xy 144.596978 -49.948475) (xy 144.545079 -49.92993) (xy 144.49639 -49.904109) (xy 144.451924 -49.871548)
			(xy 144.412607 -49.832927) (xy 144.379259 -49.789048) (xy 144.352573 -49.740827) (xy 144.333106 -49.689266)
			(xy 144.321263 -49.635441) (xy 144.317291 -49.580471) (xy 137.224371 -49.580471) (xy 137.266635 -49.608433)
			(xy 137.308199 -49.645675) (xy 137.343898 -49.688571) (xy 137.372971 -49.736209) (xy 137.394798 -49.787572)
			(xy 137.408914 -49.841565) (xy 137.415017 -49.897039) (xy 137.412979 -49.95281) (xy 137.402842 -50.007689)
			(xy 137.384823 -50.060509) (xy 137.359305 -50.110141) (xy 137.326833 -50.155529) (xy 137.317702 -50.165)
			(xy 137.920728 -50.165) (xy 137.924801 -50.109341) (xy 137.936936 -50.054868) (xy 137.956872 -50.002742)
			(xy 137.984186 -49.954074) (xy 138.018294 -49.909902) (xy 138.058471 -49.871167) (xy 138.103859 -49.838695)
			(xy 138.153491 -49.813177) (xy 138.206311 -49.795158) (xy 138.26119 -49.785021) (xy 138.316961 -49.782983)
			(xy 138.372435 -49.789086) (xy 138.426428 -49.803202) (xy 138.477791 -49.825029) (xy 138.525429 -49.854102)
			(xy 138.568325 -49.889801) (xy 138.605567 -49.931365) (xy 138.636361 -49.977909) (xy 138.660049 -50.02844)
			(xy 138.676127 -50.081882) (xy 138.684253 -50.137096) (xy 138.684762 -50.165) (xy 138.684253 -50.192904)
			(xy 138.676127 -50.248118) (xy 138.660049 -50.30156) (xy 138.636361 -50.352091) (xy 138.605567 -50.398635)
			(xy 138.568325 -50.440199) (xy 138.525429 -50.475898) (xy 138.477791 -50.504971) (xy 138.426428 -50.526798)
			(xy 138.372435 -50.540914) (xy 138.316961 -50.547017) (xy 138.26119 -50.544979) (xy 138.206311 -50.534842)
			(xy 138.153491 -50.516823) (xy 138.103859 -50.491305) (xy 138.058471 -50.458833) (xy 138.018294 -50.420098)
			(xy 137.984186 -50.375926) (xy 137.956872 -50.327258) (xy 137.936936 -50.275132) (xy 137.924801 -50.220659)
			(xy 137.920728 -50.165) (xy 137.317702 -50.165) (xy 137.288098 -50.195706) (xy 137.243926 -50.229814)
			(xy 137.195258 -50.257128) (xy 137.143132 -50.277064) (xy 137.088659 -50.289199) (xy 137.033 -50.293273)
			(xy 136.977341 -50.289199) (xy 136.922868 -50.277064) (xy 136.870742 -50.257128) (xy 136.822074 -50.229814)
			(xy 136.777902 -50.195706) (xy 136.739167 -50.155529) (xy 136.706695 -50.110141) (xy 136.681177 -50.060509)
			(xy 136.663158 -50.007689) (xy 136.653021 -49.95281) (xy 136.650983 -49.897039) (xy 135.884413 -49.897039)
			(xy 135.882375 -49.95281) (xy 135.872238 -50.007689) (xy 135.854219 -50.060509) (xy 135.828701 -50.110141)
			(xy 135.796229 -50.155529) (xy 135.757494 -50.195706) (xy 135.713322 -50.229814) (xy 135.664654 -50.257128)
			(xy 135.612528 -50.277064) (xy 135.558055 -50.289199) (xy 135.502396 -50.293273) (xy 135.446737 -50.289199)
			(xy 135.392264 -50.277064) (xy 135.340138 -50.257128) (xy 135.29147 -50.229814) (xy 135.247298 -50.195706)
			(xy 135.208563 -50.155529) (xy 135.176091 -50.110141) (xy 135.150573 -50.060509) (xy 135.132554 -50.007689)
			(xy 135.122417 -49.95281) (xy 135.120379 -49.897039) (xy 130.463937 -49.897039) (xy 130.444578 -49.947012)
			(xy 130.417935 -49.994426) (xy 130.384833 -50.037579) (xy 130.345944 -50.075598) (xy 130.302053 -50.107715)
			(xy 130.254049 -50.133279) (xy 130.202904 -50.151773) (xy 130.149651 -50.162822) (xy 130.09537 -50.166204)
			(xy 130.041158 -50.161849) (xy 129.988113 -50.149846) (xy 129.937308 -50.130437) (xy 129.88977 -50.104016)
			(xy 129.846463 -50.071117) (xy 129.808262 -50.032406) (xy 129.791714 -50.010822) (xy 129.775951 -49.988666)
			(xy 129.750179 -49.940789) (xy 129.73146 -49.88974) (xy 129.720174 -49.836551) (xy 129.716548 -49.782299)
			(xy 115.13553 -49.782299) (xy 115.130847 -49.788845) (xy 115.092138 -49.828994) (xy 115.047995 -49.86308)
			(xy 114.99936 -49.890376) (xy 114.947269 -49.910299) (xy 114.892832 -49.922425) (xy 114.83721 -49.926496)
			(xy 114.781588 -49.922425) (xy 114.727151 -49.910299) (xy 114.67506 -49.890376) (xy 114.626425 -49.86308)
			(xy 114.582282 -49.828994) (xy 114.543573 -49.788845) (xy 114.511122 -49.743487) (xy 114.485621 -49.693887)
			(xy 114.467614 -49.641103) (xy 114.457484 -49.58626) (xy 114.455447 -49.530526) (xy 113.11636 -49.530526)
			(xy 113.11636 -50.261284) (xy 118.605045 -50.261284) (xy 118.611145 -50.205847) (xy 118.625251 -50.15189)
			(xy 118.647063 -50.100561) (xy 118.676117 -50.052955) (xy 118.711792 -50.010087) (xy 118.753329 -49.97287)
			(xy 118.799842 -49.942097) (xy 118.850339 -49.918425) (xy 118.903746 -49.902357) (xy 118.958922 -49.894237)
			(xy 118.986808 -49.893728) (xy 119.014694 -49.894237) (xy 119.06987 -49.902357) (xy 119.123277 -49.918425)
			(xy 119.173774 -49.942097) (xy 119.220287 -49.97287) (xy 119.261824 -50.010087) (xy 119.297499 -50.052955)
			(xy 119.326553 -50.100561) (xy 119.348365 -50.15189) (xy 119.362471 -50.205847) (xy 119.368571 -50.261284)
			(xy 119.366534 -50.317018) (xy 119.365709 -50.321482) (xy 132.610859 -50.321482) (xy 132.616959 -50.266045)
			(xy 132.631065 -50.212088) (xy 132.652877 -50.160759) (xy 132.681931 -50.113153) (xy 132.717606 -50.070285)
			(xy 132.759143 -50.033068) (xy 132.805656 -50.002295) (xy 132.856153 -49.978623) (xy 132.90956 -49.962555)
			(xy 132.964736 -49.954435) (xy 132.992622 -49.953926) (xy 133.020508 -49.954435) (xy 133.075684 -49.962555)
			(xy 133.129091 -49.978623) (xy 133.179588 -50.002295) (xy 133.226101 -50.033068) (xy 133.267638 -50.070285)
			(xy 133.303313 -50.113153) (xy 133.332367 -50.160759) (xy 133.354179 -50.212088) (xy 133.368285 -50.266045)
			(xy 133.374385 -50.321482) (xy 133.372348 -50.377216) (xy 133.362218 -50.432059) (xy 133.344211 -50.484843)
			(xy 133.31871 -50.534443) (xy 133.286259 -50.579801) (xy 133.24755 -50.61995) (xy 133.203407 -50.654036)
			(xy 133.154772 -50.681332) (xy 133.102681 -50.701255) (xy 133.048244 -50.713381) (xy 132.992622 -50.717452)
			(xy 132.937 -50.713381) (xy 132.882563 -50.701255) (xy 132.830472 -50.681332) (xy 132.781837 -50.654036)
			(xy 132.737694 -50.61995) (xy 132.698985 -50.579801) (xy 132.666534 -50.534443) (xy 132.641033 -50.484843)
			(xy 132.623026 -50.432059) (xy 132.612896 -50.377216) (xy 132.610859 -50.321482) (xy 119.365709 -50.321482)
			(xy 119.356404 -50.371861) (xy 119.338397 -50.424645) (xy 119.312896 -50.474245) (xy 119.280445 -50.519603)
			(xy 119.241736 -50.559752) (xy 119.197593 -50.593838) (xy 119.148958 -50.621134) (xy 119.096867 -50.641057)
			(xy 119.04243 -50.653183) (xy 118.986808 -50.657254) (xy 118.931186 -50.653183) (xy 118.876749 -50.641057)
			(xy 118.824658 -50.621134) (xy 118.776023 -50.593838) (xy 118.73188 -50.559752) (xy 118.693171 -50.519603)
			(xy 118.66072 -50.474245) (xy 118.635219 -50.424645) (xy 118.617212 -50.371861) (xy 118.607082 -50.317018)
			(xy 118.605045 -50.261284) (xy 113.11636 -50.261284) (xy 113.11636 -51.268639) (xy 119.328183 -51.268639)
			(xy 119.334286 -51.213165) (xy 119.348402 -51.159172) (xy 119.370229 -51.107809) (xy 119.399302 -51.060171)
			(xy 119.435001 -51.017275) (xy 119.476565 -50.980033) (xy 119.523109 -50.949239) (xy 119.57364 -50.925551)
			(xy 119.627082 -50.909473) (xy 119.682296 -50.901347) (xy 119.7102 -50.900838) (xy 119.738104 -50.901347)
			(xy 119.793318 -50.909473) (xy 119.84676 -50.925551) (xy 119.897291 -50.949239) (xy 119.943835 -50.980033)
			(xy 119.985399 -51.017275) (xy 120.021098 -51.060171) (xy 120.050171 -51.107809) (xy 120.071998 -51.159172)
			(xy 120.086114 -51.213165) (xy 120.092217 -51.268639) (xy 120.090179 -51.32441) (xy 120.080042 -51.379289)
			(xy 120.062023 -51.432109) (xy 120.036505 -51.481741) (xy 120.004033 -51.527129) (xy 119.965298 -51.567306)
			(xy 119.957355 -51.573439) (xy 120.623583 -51.573439) (xy 120.629686 -51.517965) (xy 120.643802 -51.463972)
			(xy 120.665629 -51.412609) (xy 120.694702 -51.364971) (xy 120.730401 -51.322075) (xy 120.771965 -51.284833)
			(xy 120.818509 -51.254039) (xy 120.86904 -51.230351) (xy 120.922482 -51.214273) (xy 120.977696 -51.206147)
			(xy 121.0056 -51.205638) (xy 121.033504 -51.206147) (xy 121.035223 -51.2064) (xy 125.423928 -51.2064)
			(xy 125.428001 -51.150741) (xy 125.440136 -51.096268) (xy 125.460072 -51.044142) (xy 125.487386 -50.995474)
			(xy 125.521494 -50.951302) (xy 125.561671 -50.912567) (xy 125.607059 -50.880095) (xy 125.656691 -50.854577)
			(xy 125.709511 -50.836558) (xy 125.76439 -50.826421) (xy 125.820161 -50.824383) (xy 125.875635 -50.830486)
			(xy 125.929628 -50.844602) (xy 125.980991 -50.866429) (xy 126.028629 -50.895502) (xy 126.071525 -50.931201)
			(xy 126.108767 -50.972765) (xy 126.139561 -51.019309) (xy 126.147727 -51.036728) (xy 154.5209 -51.036728)
			(xy 154.5209 -49.220628) (xy 154.52852 -49.16297) (xy 154.534392 -49.122071) (xy 154.553142 -49.041595)
			(xy 154.579602 -48.963314) (xy 154.613522 -48.887965) (xy 154.654582 -48.816258) (xy 154.702398 -48.748866)
			(xy 154.756518 -48.686424) (xy 154.816434 -48.629519) (xy 154.881581 -48.578688) (xy 154.951347 -48.534408)
			(xy 155.025075 -48.497095) (xy 155.102071 -48.467102) (xy 155.181611 -48.444711) (xy 155.262946 -48.430131)
			(xy 155.345311 -48.4235) (xy 155.427932 -48.424882) (xy 155.510029 -48.434261) (xy 155.590832 -48.451552)
			(xy 155.669579 -48.47659) (xy 155.74553 -48.509139) (xy 155.817969 -48.548895) (xy 155.886216 -48.595482)
			(xy 155.949628 -48.648463) (xy 156.007608 -48.707338) (xy 156.05961 -48.771555) (xy 156.105147 -48.840507)
			(xy 156.143788 -48.913547) (xy 156.17517 -48.989988) (xy 156.198998 -49.069109) (xy 156.215049 -49.150167)
			(xy 156.223169 -49.232399) (xy 156.223716 -49.273714) (xy 156.223716 -50.966624) (xy 156.223462 -50.97526)
			(xy 156.222843 -51.01614) (xy 156.214577 -51.097488) (xy 156.198548 -51.177667) (xy 156.174905 -51.25594)
			(xy 156.143865 -51.331586) (xy 156.105716 -51.403907) (xy 156.060807 -51.472236) (xy 156.009553 -51.535944)
			(xy 155.952427 -51.594445) (xy 155.889954 -51.647198) (xy 155.822711 -51.693717) (xy 155.751318 -51.733575)
			(xy 155.676431 -51.766403) (xy 155.598741 -51.791899) (xy 155.518965 -51.809829) (xy 155.437838 -51.820026)
			(xy 155.356106 -51.822397) (xy 155.274523 -51.81692) (xy 155.193842 -51.803646) (xy 155.114805 -51.782697)
			(xy 155.038141 -51.754265) (xy 154.964557 -51.718614) (xy 154.89473 -51.676071) (xy 154.829304 -51.627028)
			(xy 154.768882 -51.571938) (xy 154.714021 -51.511308) (xy 154.665227 -51.445697) (xy 154.622948 -51.37571)
			(xy 154.587576 -51.301991) (xy 154.559435 -51.22522) (xy 154.538785 -51.146105) (xy 154.531822 -51.105816)
			(xy 154.5209 -51.036728) (xy 126.147727 -51.036728) (xy 126.163249 -51.06984) (xy 126.179327 -51.123282)
			(xy 126.187453 -51.178496) (xy 126.187962 -51.2064) (xy 126.187453 -51.234304) (xy 126.179327 -51.289518)
			(xy 126.163249 -51.34296) (xy 126.139561 -51.393491) (xy 126.108767 -51.440035) (xy 126.071525 -51.481599)
			(xy 126.028629 -51.517298) (xy 125.980991 -51.546371) (xy 125.929628 -51.568198) (xy 125.875635 -51.582314)
			(xy 125.820161 -51.588417) (xy 125.76439 -51.586379) (xy 125.709511 -51.576242) (xy 125.656691 -51.558223)
			(xy 125.607059 -51.532705) (xy 125.561671 -51.500233) (xy 125.521494 -51.461498) (xy 125.487386 -51.417326)
			(xy 125.460072 -51.368658) (xy 125.440136 -51.316532) (xy 125.428001 -51.262059) (xy 125.423928 -51.2064)
			(xy 121.035223 -51.2064) (xy 121.088718 -51.214273) (xy 121.14216 -51.230351) (xy 121.192691 -51.254039)
			(xy 121.239235 -51.284833) (xy 121.280799 -51.322075) (xy 121.316498 -51.364971) (xy 121.345571 -51.412609)
			(xy 121.367398 -51.463972) (xy 121.381514 -51.517965) (xy 121.387617 -51.573439) (xy 121.385579 -51.62921)
			(xy 121.375442 -51.684089) (xy 121.35981 -51.729912) (xy 123.574555 -51.729912) (xy 123.580655 -51.674475)
			(xy 123.594761 -51.620518) (xy 123.616573 -51.569189) (xy 123.645627 -51.521583) (xy 123.681302 -51.478715)
			(xy 123.722839 -51.441498) (xy 123.769352 -51.410725) (xy 123.819849 -51.387053) (xy 123.873256 -51.370985)
			(xy 123.928432 -51.362865) (xy 123.956318 -51.362356) (xy 123.984204 -51.362865) (xy 124.03938 -51.370985)
			(xy 124.092787 -51.387053) (xy 124.143284 -51.410725) (xy 124.189797 -51.441498) (xy 124.231334 -51.478715)
			(xy 124.267009 -51.521583) (xy 124.296063 -51.569189) (xy 124.317875 -51.620518) (xy 124.331981 -51.674475)
			(xy 124.338081 -51.729912) (xy 124.336044 -51.785646) (xy 124.325914 -51.840489) (xy 124.321701 -51.852839)
			(xy 129.716783 -51.852839) (xy 129.722886 -51.797365) (xy 129.737002 -51.743372) (xy 129.758829 -51.692009)
			(xy 129.787902 -51.644371) (xy 129.823601 -51.601475) (xy 129.865165 -51.564233) (xy 129.911709 -51.533439)
			(xy 129.96224 -51.509751) (xy 130.015682 -51.493673) (xy 130.070896 -51.485547) (xy 130.0988 -51.485038)
			(xy 130.126704 -51.485547) (xy 130.181918 -51.493673) (xy 130.23536 -51.509751) (xy 130.285891 -51.533439)
			(xy 130.332435 -51.564233) (xy 130.373999 -51.601475) (xy 130.409698 -51.644371) (xy 130.438771 -51.692009)
			(xy 130.460598 -51.743372) (xy 130.474714 -51.797365) (xy 130.480817 -51.852839) (xy 130.478779 -51.90861)
			(xy 130.468642 -51.963489) (xy 130.450623 -52.016309) (xy 130.43389 -52.048855) (xy 153.211025 -52.048855)
			(xy 153.213033 -51.976011) (xy 153.223042 -51.903831) (xy 153.240931 -51.833189) (xy 153.266482 -51.764944)
			(xy 153.299386 -51.699925) (xy 153.339242 -51.638919) (xy 153.385568 -51.582669) (xy 153.437801 -51.531856)
			(xy 153.495307 -51.487098) (xy 153.557387 -51.448937) (xy 153.623289 -51.417837) (xy 153.692212 -51.394176)
			(xy 153.763319 -51.37824) (xy 153.835748 -51.370224) (xy 153.872184 -51.369722) (xy 153.90862 -51.370224)
			(xy 153.981049 -51.37824) (xy 154.052156 -51.394176) (xy 154.121079 -51.417837) (xy 154.186981 -51.448937)
			(xy 154.249061 -51.487098) (xy 154.306567 -51.531856) (xy 154.3588 -51.582669) (xy 154.405126 -51.638919)
			(xy 154.444982 -51.699925) (xy 154.477886 -51.764944) (xy 154.503437 -51.833189) (xy 154.521326 -51.903831)
			(xy 154.531335 -51.976011) (xy 154.533343 -52.048855) (xy 154.527326 -52.121477) (xy 154.513356 -52.192997)
			(xy 154.491602 -52.262545) (xy 154.46233 -52.329279) (xy 154.425895 -52.392387) (xy 154.382738 -52.451104)
			(xy 154.333383 -52.504717) (xy 154.278431 -52.552576) (xy 154.218547 -52.594098) (xy 154.154458 -52.628781)
			(xy 154.086944 -52.656203) (xy 154.016822 -52.676032) (xy 153.944945 -52.688026) (xy 153.872184 -52.692041)
			(xy 153.799423 -52.688026) (xy 153.727546 -52.676032) (xy 153.657424 -52.656203) (xy 153.58991 -52.628781)
			(xy 153.525821 -52.594098) (xy 153.465937 -52.552576) (xy 153.410985 -52.504717) (xy 153.36163 -52.451104)
			(xy 153.318473 -52.392387) (xy 153.282038 -52.329279) (xy 153.252766 -52.262545) (xy 153.231012 -52.192997)
			(xy 153.217042 -52.121477) (xy 153.211025 -52.048855) (xy 130.43389 -52.048855) (xy 130.425105 -52.065941)
			(xy 130.392633 -52.111329) (xy 130.353898 -52.151506) (xy 130.309726 -52.185614) (xy 130.261058 -52.212928)
			(xy 130.208932 -52.232864) (xy 130.154459 -52.244999) (xy 130.0988 -52.249073) (xy 130.043141 -52.244999)
			(xy 129.988668 -52.232864) (xy 129.936542 -52.212928) (xy 129.887874 -52.185614) (xy 129.843702 -52.151506)
			(xy 129.804967 -52.111329) (xy 129.772495 -52.065941) (xy 129.746977 -52.016309) (xy 129.728958 -51.963489)
			(xy 129.718821 -51.90861) (xy 129.716783 -51.852839) (xy 124.321701 -51.852839) (xy 124.307907 -51.893273)
			(xy 124.282406 -51.942873) (xy 124.249955 -51.988231) (xy 124.211246 -52.02838) (xy 124.167103 -52.062466)
			(xy 124.118468 -52.089762) (xy 124.066377 -52.109685) (xy 124.01194 -52.121811) (xy 123.956318 -52.125882)
			(xy 123.900696 -52.121811) (xy 123.846259 -52.109685) (xy 123.794168 -52.089762) (xy 123.745533 -52.062466)
			(xy 123.70139 -52.02838) (xy 123.662681 -51.988231) (xy 123.63023 -51.942873) (xy 123.604729 -51.893273)
			(xy 123.586722 -51.840489) (xy 123.576592 -51.785646) (xy 123.574555 -51.729912) (xy 121.35981 -51.729912)
			(xy 121.357423 -51.736909) (xy 121.331905 -51.786541) (xy 121.299433 -51.831929) (xy 121.260698 -51.872106)
			(xy 121.216526 -51.906214) (xy 121.167858 -51.933528) (xy 121.115732 -51.953464) (xy 121.061259 -51.965599)
			(xy 121.0056 -51.969673) (xy 120.949941 -51.965599) (xy 120.895468 -51.953464) (xy 120.843342 -51.933528)
			(xy 120.794674 -51.906214) (xy 120.750502 -51.872106) (xy 120.711767 -51.831929) (xy 120.679295 -51.786541)
			(xy 120.653777 -51.736909) (xy 120.635758 -51.684089) (xy 120.625621 -51.62921) (xy 120.623583 -51.573439)
			(xy 119.957355 -51.573439) (xy 119.921126 -51.601414) (xy 119.872458 -51.628728) (xy 119.820332 -51.648664)
			(xy 119.765859 -51.660799) (xy 119.7102 -51.664873) (xy 119.654541 -51.660799) (xy 119.600068 -51.648664)
			(xy 119.547942 -51.628728) (xy 119.499274 -51.601414) (xy 119.455102 -51.567306) (xy 119.416367 -51.527129)
			(xy 119.383895 -51.481741) (xy 119.358377 -51.432109) (xy 119.340358 -51.379289) (xy 119.330221 -51.32441)
			(xy 119.328183 -51.268639) (xy 113.11636 -51.268639) (xy 113.11636 -51.747438) (xy 114.083337 -51.747438)
			(xy 114.089437 -51.692001) (xy 114.103543 -51.638044) (xy 114.125355 -51.586715) (xy 114.154409 -51.539109)
			(xy 114.190084 -51.496241) (xy 114.231621 -51.459024) (xy 114.278134 -51.428251) (xy 114.328631 -51.404579)
			(xy 114.382038 -51.388511) (xy 114.437214 -51.380391) (xy 114.4651 -51.379882) (xy 114.492986 -51.380391)
			(xy 114.548162 -51.388511) (xy 114.601569 -51.404579) (xy 114.652066 -51.428251) (xy 114.698579 -51.459024)
			(xy 114.740116 -51.496241) (xy 114.775791 -51.539109) (xy 114.804845 -51.586715) (xy 114.826657 -51.638044)
			(xy 114.840763 -51.692001) (xy 114.846863 -51.747438) (xy 114.844826 -51.803172) (xy 114.834696 -51.858015)
			(xy 114.816689 -51.910799) (xy 114.791188 -51.960399) (xy 114.758737 -52.005757) (xy 114.720028 -52.045906)
			(xy 114.675885 -52.079992) (xy 114.62725 -52.107288) (xy 114.575159 -52.127211) (xy 114.520722 -52.139337)
			(xy 114.4651 -52.143408) (xy 114.409478 -52.139337) (xy 114.355041 -52.127211) (xy 114.30295 -52.107288)
			(xy 114.254315 -52.079992) (xy 114.210172 -52.045906) (xy 114.171463 -52.005757) (xy 114.139012 -51.960399)
			(xy 114.113511 -51.910799) (xy 114.095504 -51.858015) (xy 114.085374 -51.803172) (xy 114.083337 -51.747438)
			(xy 113.11636 -51.747438) (xy 113.11636 -52.640239) (xy 118.032783 -52.640239) (xy 118.038886 -52.584765)
			(xy 118.053002 -52.530772) (xy 118.074829 -52.479409) (xy 118.103902 -52.431771) (xy 118.139601 -52.388875)
			(xy 118.181165 -52.351633) (xy 118.227709 -52.320839) (xy 118.27824 -52.297151) (xy 118.331682 -52.281073)
			(xy 118.386896 -52.272947) (xy 118.4148 -52.272438) (xy 118.442704 -52.272947) (xy 118.497918 -52.281073)
			(xy 118.55136 -52.297151) (xy 118.601891 -52.320839) (xy 118.648435 -52.351633) (xy 118.689999 -52.388875)
			(xy 118.725698 -52.431771) (xy 118.754771 -52.479409) (xy 118.776598 -52.530772) (xy 118.790714 -52.584765)
			(xy 118.796817 -52.640239) (xy 118.794905 -52.692572) (xy 124.343921 -52.692572) (xy 124.350021 -52.637135)
			(xy 124.364127 -52.583178) (xy 124.385939 -52.531849) (xy 124.414993 -52.484243) (xy 124.450668 -52.441375)
			(xy 124.492205 -52.404158) (xy 124.538718 -52.373385) (xy 124.589215 -52.349713) (xy 124.642622 -52.333645)
			(xy 124.697798 -52.325525) (xy 124.725684 -52.325016) (xy 124.75357 -52.325525) (xy 124.808746 -52.333645)
			(xy 124.862153 -52.349713) (xy 124.91265 -52.373385) (xy 124.959163 -52.404158) (xy 125.0007 -52.441375)
			(xy 125.036375 -52.484243) (xy 125.065429 -52.531849) (xy 125.087241 -52.583178) (xy 125.101347 -52.637135)
			(xy 125.10359 -52.65752) (xy 128.201673 -52.65752) (xy 128.207773 -52.602083) (xy 128.221879 -52.548126)
			(xy 128.243691 -52.496797) (xy 128.272745 -52.449191) (xy 128.30842 -52.406323) (xy 128.349957 -52.369106)
			(xy 128.39647 -52.338333) (xy 128.446967 -52.314661) (xy 128.500374 -52.298593) (xy 128.55555 -52.290473)
			(xy 128.583436 -52.289964) (xy 128.611322 -52.290473) (xy 128.666498 -52.298593) (xy 128.719905 -52.314661)
			(xy 128.770402 -52.338333) (xy 128.816915 -52.369106) (xy 128.858452 -52.406323) (xy 128.894127 -52.449191)
			(xy 128.923181 -52.496797) (xy 128.944993 -52.548126) (xy 128.959099 -52.602083) (xy 128.965199 -52.65752)
			(xy 128.963162 -52.713254) (xy 128.953032 -52.768097) (xy 128.948838 -52.78039) (xy 129.665474 -52.78039)
			(xy 129.667097 -52.724347) (xy 129.676903 -52.669145) (xy 129.694682 -52.615972) (xy 129.720051 -52.565973)
			(xy 129.752463 -52.520225) (xy 129.791221 -52.479712) (xy 129.835491 -52.445307) (xy 129.884318 -52.417751)
			(xy 129.936652 -52.397636) (xy 129.991366 -52.385397) (xy 130.047283 -52.381296) (xy 130.103197 -52.385421)
			(xy 130.157906 -52.397684) (xy 130.210232 -52.417822) (xy 130.259047 -52.445399) (xy 130.303301 -52.479823)
			(xy 130.342042 -52.520353) (xy 130.358642 -52.542948) (xy 130.368653 -52.556062) (xy 130.39398 -52.577181)
			(xy 130.423875 -52.591099) (xy 130.456339 -52.596886) (xy 130.489202 -52.594156) (xy 130.520266 -52.58309)
			(xy 130.534156 -52.57419) (xy 130.557507 -52.558671) (xy 130.607836 -52.533964) (xy 130.66124 -52.516889)
			(xy 130.716567 -52.507811) (xy 130.772627 -52.506928) (xy 130.828212 -52.514258) (xy 130.882127 -52.529643)
			(xy 130.93321 -52.552752) (xy 130.980361 -52.583087) (xy 130.999833 -52.600116) (xy 131.715509 -52.600116)
			(xy 131.721609 -52.544679) (xy 131.735715 -52.490722) (xy 131.757527 -52.439393) (xy 131.786581 -52.391787)
			(xy 131.822256 -52.348919) (xy 131.863793 -52.311702) (xy 131.910306 -52.280929) (xy 131.960803 -52.257257)
			(xy 132.01421 -52.241189) (xy 132.069386 -52.233069) (xy 132.097272 -52.23256) (xy 132.125158 -52.233069)
			(xy 132.180334 -52.241189) (xy 132.233741 -52.257257) (xy 132.284238 -52.280929) (xy 132.330751 -52.311702)
			(xy 132.372288 -52.348919) (xy 132.407963 -52.391787) (xy 132.437017 -52.439393) (xy 132.458829 -52.490722)
			(xy 132.472935 -52.544679) (xy 132.479035 -52.600116) (xy 132.476998 -52.65585) (xy 132.476926 -52.656241)
			(xy 133.388861 -52.656241) (xy 133.394964 -52.600767) (xy 133.40908 -52.546774) (xy 133.430907 -52.495411)
			(xy 133.45998 -52.447773) (xy 133.495679 -52.404877) (xy 133.537243 -52.367635) (xy 133.583787 -52.336841)
			(xy 133.634318 -52.313153) (xy 133.68776 -52.297075) (xy 133.742974 -52.288949) (xy 133.770878 -52.28844)
			(xy 133.798782 -52.288949) (xy 133.853996 -52.297075) (xy 133.907438 -52.313153) (xy 133.957969 -52.336841)
			(xy 134.004513 -52.367635) (xy 134.046077 -52.404877) (xy 134.081776 -52.447773) (xy 134.110849 -52.495411)
			(xy 134.132676 -52.546774) (xy 134.146792 -52.600767) (xy 134.152895 -52.656241) (xy 134.150857 -52.712012)
			(xy 134.14072 -52.766891) (xy 134.122701 -52.819711) (xy 134.097183 -52.869343) (xy 134.064711 -52.914731)
			(xy 134.025976 -52.954908) (xy 133.981804 -52.989016) (xy 133.933136 -53.01633) (xy 133.88101 -53.036266)
			(xy 133.826537 -53.048401) (xy 133.770878 -53.052475) (xy 133.715219 -53.048401) (xy 133.660746 -53.036266)
			(xy 133.60862 -53.01633) (xy 133.559952 -52.989016) (xy 133.51578 -52.954908) (xy 133.477045 -52.914731)
			(xy 133.444573 -52.869343) (xy 133.419055 -52.819711) (xy 133.401036 -52.766891) (xy 133.390899 -52.712012)
			(xy 133.388861 -52.656241) (xy 132.476926 -52.656241) (xy 132.466868 -52.710693) (xy 132.448861 -52.763477)
			(xy 132.42336 -52.813077) (xy 132.390909 -52.858435) (xy 132.3522 -52.898584) (xy 132.308057 -52.93267)
			(xy 132.259422 -52.959966) (xy 132.207331 -52.979889) (xy 132.152894 -52.992015) (xy 132.097272 -52.996086)
			(xy 132.04165 -52.992015) (xy 131.987213 -52.979889) (xy 131.935122 -52.959966) (xy 131.886487 -52.93267)
			(xy 131.842344 -52.898584) (xy 131.803635 -52.858435) (xy 131.771184 -52.813077) (xy 131.745683 -52.763477)
			(xy 131.727676 -52.710693) (xy 131.717546 -52.65585) (xy 131.715509 -52.600116) (xy 130.999833 -52.600116)
			(xy 131.022566 -52.619996) (xy 131.058915 -52.662684) (xy 131.088626 -52.710231) (xy 131.11106 -52.761614)
			(xy 131.125733 -52.815727) (xy 131.132329 -52.871404) (xy 131.130707 -52.927448) (xy 131.120901 -52.982651)
			(xy 131.103123 -53.035824) (xy 131.077754 -53.085823) (xy 131.045343 -53.131572) (xy 131.006585 -53.172086)
			(xy 130.962316 -53.206492) (xy 130.961701 -53.206839) (xy 134.826818 -53.206839) (xy 134.830777 -53.1505)
			(xy 134.842991 -53.095358) (xy 134.863195 -53.042616) (xy 134.890946 -52.993426) (xy 134.925641 -52.94886)
			(xy 134.966522 -52.909891) (xy 134.989316 -52.893214) (xy 135.001461 -52.883999) (xy 135.020076 -52.859874)
			(xy 135.030779 -52.831342) (xy 135.032622 -52.800926) (xy 135.025445 -52.771311) (xy 135.009879 -52.745113)
			(xy 134.998968 -52.734464) (xy 134.97861 -52.715464) (xy 134.943136 -52.672538) (xy 134.914274 -52.624915)
			(xy 134.892637 -52.573604) (xy 134.878683 -52.519694) (xy 134.872708 -52.464329) (xy 134.874839 -52.408683)
			(xy 134.885031 -52.353937) (xy 134.903068 -52.301253) (xy 134.928567 -52.251747) (xy 134.960987 -52.206471)
			(xy 134.99964 -52.166384) (xy 135.043707 -52.132338) (xy 135.092252 -52.105054) (xy 135.144245 -52.085112)
			(xy 135.198584 -52.072934) (xy 135.254115 -52.068779) (xy 135.281924 -52.070254) (xy 135.309652 -52.072723)
			(xy 135.364026 -52.084643) (xy 135.416093 -52.104333) (xy 135.464748 -52.131376) (xy 135.50896 -52.165198)
			(xy 135.547791 -52.205083) (xy 135.580418 -52.250184) (xy 135.606149 -52.299546) (xy 135.624439 -52.352121)
			(xy 135.634899 -52.406795) (xy 135.637307 -52.462408) (xy 135.631614 -52.517782) (xy 135.617939 -52.571741)
			(xy 135.596573 -52.623143) (xy 135.567968 -52.670896) (xy 135.532731 -52.713989) (xy 135.491609 -52.751508)
			(xy 135.486607 -52.754885) (xy 137.199148 -52.754885) (xy 137.201308 -52.699433) (xy 137.211474 -52.644878)
			(xy 137.229432 -52.592369) (xy 137.254804 -52.543014) (xy 137.287054 -52.497853) (xy 137.325503 -52.457837)
			(xy 137.36934 -52.423809) (xy 137.417643 -52.396488) (xy 137.469392 -52.376447) (xy 137.523498 -52.364111)
			(xy 137.57882 -52.359738) (xy 137.634192 -52.363421) (xy 137.688447 -52.375083) (xy 137.740442 -52.394477)
			(xy 137.789081 -52.421196) (xy 137.81151 -52.437538) (xy 137.823662 -52.446005) (xy 137.851404 -52.456326)
			(xy 137.880939 -52.458289) (xy 137.909803 -52.451732) (xy 137.935591 -52.4372) (xy 137.95615 -52.415905)
			(xy 137.963402 -52.402994) (xy 137.976352 -52.378729) (xy 138.008266 -52.333933) (xy 138.046277 -52.294179)
			(xy 138.089599 -52.26029) (xy 138.137335 -52.232968) (xy 138.188497 -52.212778) (xy 138.242027 -52.200138)
			(xy 138.296817 -52.195309) (xy 138.351732 -52.198392) (xy 138.405637 -52.209323) (xy 138.457416 -52.227874)
			(xy 138.505997 -52.253664) (xy 138.550375 -52.286157) (xy 138.589632 -52.324681) (xy 138.622955 -52.36844)
			(xy 138.649654 -52.416527) (xy 138.669178 -52.467947) (xy 138.675618 -52.494688) (xy 138.681136 -52.521537)
			(xy 138.685324 -52.57619) (xy 138.685116 -52.579288) (xy 139.295123 -52.579288) (xy 139.301223 -52.523851)
			(xy 139.315329 -52.469894) (xy 139.337141 -52.418565) (xy 139.366195 -52.370959) (xy 139.40187 -52.328091)
			(xy 139.443407 -52.290874) (xy 139.48992 -52.260101) (xy 139.540417 -52.236429) (xy 139.593824 -52.220361)
			(xy 139.649 -52.212241) (xy 139.676886 -52.211732) (xy 139.704772 -52.212241) (xy 139.759948 -52.220361)
			(xy 139.813355 -52.236429) (xy 139.863852 -52.260101) (xy 139.910365 -52.290874) (xy 139.951902 -52.328091)
			(xy 139.987577 -52.370959) (xy 140.016631 -52.418565) (xy 140.038443 -52.469894) (xy 140.052549 -52.523851)
			(xy 140.058649 -52.579288) (xy 140.056612 -52.635022) (xy 140.046482 -52.689865) (xy 140.044732 -52.694994)
			(xy 140.311229 -52.694994) (xy 140.313131 -52.638956) (xy 140.323217 -52.5838) (xy 140.341269 -52.530714)
			(xy 140.366898 -52.480844) (xy 140.399552 -52.435262) (xy 140.438527 -52.394953) (xy 140.482983 -52.360783)
			(xy 140.531963 -52.33349) (xy 140.58441 -52.313661) (xy 140.639196 -52.301725) (xy 140.695138 -52.297937)
			(xy 140.751033 -52.30238) (xy 140.805675 -52.314958) (xy 140.857886 -52.3354) (xy 140.906543 -52.363265)
			(xy 140.950595 -52.397953) (xy 140.989095 -52.438717) (xy 141.00556 -52.461414) (xy 141.01951 -52.480413)
			(xy 141.053181 -52.513388) (xy 141.092351 -52.539595) (xy 141.135678 -52.558137) (xy 141.18168 -52.56838)
			(xy 141.228782 -52.569972) (xy 141.275371 -52.56286) (xy 141.319851 -52.547286) (xy 141.360702 -52.523784)
			(xy 141.396523 -52.493158) (xy 141.411706 -52.47513) (xy 141.429866 -52.453327) (xy 141.471617 -52.414901)
			(xy 141.518599 -52.383081) (xy 141.569774 -52.358569) (xy 141.624015 -52.341905) (xy 141.680126 -52.333458)
			(xy 141.736869 -52.333413) (xy 141.792993 -52.341771) (xy 141.84726 -52.358348) (xy 141.898474 -52.382779)
			(xy 141.945506 -52.414524) (xy 141.987318 -52.452884) (xy 142.005558 -52.474622) (xy 142.02079 -52.492613)
			(xy 142.05669 -52.523156) (xy 142.097603 -52.546563) (xy 142.142128 -52.56203) (xy 142.188741 -52.56903)
			(xy 142.235845 -52.567322) (xy 142.281828 -52.556964) (xy 142.325115 -52.538312) (xy 142.364225 -52.512003)
			(xy 142.397818 -52.47894) (xy 142.411704 -52.45989) (xy 142.427755 -52.437599) (xy 142.465262 -52.397465)
			(xy 142.508136 -52.363126) (xy 142.555492 -52.335291) (xy 142.60635 -52.314534) (xy 142.659659 -52.301287)
			(xy 142.714317 -52.295821) (xy 142.769194 -52.298251) (xy 142.823155 -52.308526) (xy 142.875085 -52.326434)
			(xy 142.92391 -52.351604) (xy 142.96862 -52.383516) (xy 143.008291 -52.421511) (xy 143.042103 -52.464802)
			(xy 143.069357 -52.512495) (xy 143.089489 -52.563603) (xy 143.102084 -52.617071) (xy 143.10688 -52.671792)
			(xy 143.103778 -52.726635) (xy 143.092844 -52.780466) (xy 143.074302 -52.832173) (xy 143.048536 -52.880686)
			(xy 143.016079 -52.925002) (xy 142.977602 -52.964206) (xy 142.9339 -52.997485) (xy 142.885877 -53.024153)
			(xy 142.834526 -53.043659) (xy 142.780908 -53.055598) (xy 142.726133 -53.059724) (xy 142.671332 -53.055951)
			(xy 142.617638 -53.044358) (xy 142.566162 -53.025185) (xy 142.517968 -52.998827) (xy 142.474052 -52.96583)
			(xy 142.435323 -52.926876) (xy 142.402581 -52.88277) (xy 142.376502 -52.834425) (xy 142.357627 -52.782839)
			(xy 142.346345 -52.729079) (xy 142.34414 -52.701698) (xy 142.342641 -52.685386) (xy 142.332349 -52.654299)
			(xy 142.314483 -52.626856) (xy 142.290218 -52.604866) (xy 142.261154 -52.589779) (xy 142.229207 -52.582587)
			(xy 142.196481 -52.583767) (xy 142.165134 -52.593239) (xy 142.137232 -52.61038) (xy 142.114613 -52.634059)
			(xy 142.098768 -52.662717) (xy 142.090741 -52.694465) (xy 142.090394 -52.710842) (xy 142.090217 -52.736596)
			(xy 142.083775 -52.787693) (xy 142.070528 -52.837463) (xy 142.050716 -52.885002) (xy 142.03807 -52.907438)
			(xy 142.02739 -52.926588) (xy 142.012023 -52.96765) (xy 142.003931 -53.01074) (xy 142.003353 -53.054579)
			(xy 142.010307 -53.097867) (xy 142.024588 -53.13932) (xy 142.04577 -53.177706) (xy 142.073225 -53.211888)
			(xy 142.089378 -53.226716) (xy 142.10965 -53.245286) (xy 142.145326 -53.287108) (xy 142.174628 -53.333618)
			(xy 142.196948 -53.383853) (xy 142.211826 -53.436773) (xy 142.214485 -53.457112) (xy 148.355557 -53.457112)
			(xy 148.361657 -53.401675) (xy 148.375763 -53.347718) (xy 148.397575 -53.296389) (xy 148.426629 -53.248783)
			(xy 148.462304 -53.205915) (xy 148.503841 -53.168698) (xy 148.550354 -53.137925) (xy 148.600851 -53.114253)
			(xy 148.654258 -53.098185) (xy 148.709434 -53.090065) (xy 148.73732 -53.089556) (xy 148.765206 -53.090065)
			(xy 148.820382 -53.098185) (xy 148.873789 -53.114253) (xy 148.924286 -53.137925) (xy 148.970799 -53.168698)
			(xy 149.012336 -53.205915) (xy 149.048011 -53.248783) (xy 149.077065 -53.296389) (xy 149.098877 -53.347718)
			(xy 149.112983 -53.401675) (xy 149.119083 -53.457112) (xy 149.117046 -53.512846) (xy 149.106916 -53.567689)
			(xy 149.088909 -53.620473) (xy 149.063408 -53.670073) (xy 149.030957 -53.715431) (xy 148.992248 -53.75558)
			(xy 148.948105 -53.789666) (xy 148.89947 -53.816962) (xy 148.847379 -53.836885) (xy 148.792942 -53.849011)
			(xy 148.73732 -53.853082) (xy 148.681698 -53.849011) (xy 148.627261 -53.836885) (xy 148.57517 -53.816962)
			(xy 148.526535 -53.789666) (xy 148.482392 -53.75558) (xy 148.443683 -53.715431) (xy 148.411232 -53.670073)
			(xy 148.385731 -53.620473) (xy 148.367724 -53.567689) (xy 148.357594 -53.512846) (xy 148.355557 -53.457112)
			(xy 142.214485 -53.457112) (xy 142.218951 -53.49128) (xy 142.218177 -53.546246) (xy 142.20952 -53.600531)
			(xy 142.193158 -53.653011) (xy 142.169432 -53.702598) (xy 142.138832 -53.748264) (xy 142.101993 -53.789065)
			(xy 142.059677 -53.824154) (xy 142.012763 -53.852804) (xy 141.962221 -53.874421) (xy 141.909099 -53.888559)
			(xy 141.854497 -53.894923) (xy 141.799548 -53.893382) (xy 141.772386 -53.889148) (xy 141.749434 -53.885631)
			(xy 141.703005 -53.886158) (xy 141.657444 -53.89511) (xy 141.614267 -53.912187) (xy 141.574909 -53.936823)
			(xy 141.540681 -53.968197) (xy 141.51272 -54.005266) (xy 141.501876 -54.0258) (xy 141.489319 -54.049958)
			(xy 141.458326 -54.094721) (xy 141.421285 -54.134624) (xy 141.378948 -54.168857) (xy 141.332175 -54.196725)
			(xy 141.281915 -54.217661) (xy 141.229191 -54.231241) (xy 141.175071 -54.237189) (xy 141.120655 -54.235383)
			(xy 141.067049 -54.225862) (xy 141.01534 -54.208817) (xy 140.966579 -54.184595) (xy 140.921756 -54.153689)
			(xy 140.881781 -54.116725) (xy 140.847466 -54.074454) (xy 140.819508 -54.027735) (xy 140.798474 -53.977516)
			(xy 140.784793 -53.924818) (xy 140.77874 -53.87071) (xy 140.78044 -53.816291) (xy 140.789858 -53.762666)
			(xy 140.806803 -53.710924) (xy 140.83093 -53.662116) (xy 140.86175 -53.617233) (xy 140.898636 -53.577187)
			(xy 140.940841 -53.542791) (xy 140.987505 -53.514742) (xy 141.037683 -53.493611) (xy 141.090355 -53.479828)
			(xy 141.144452 -53.473671) (xy 141.198874 -53.475265) (xy 141.225778 -53.479446) (xy 141.248734 -53.482932)
			(xy 141.295161 -53.48241) (xy 141.34072 -53.473465) (xy 141.383896 -53.456392) (xy 141.423254 -53.431762)
			(xy 141.457483 -53.400392) (xy 141.485444 -53.363327) (xy 141.496288 -53.342794) (xy 141.50848 -53.320188)
			(xy 141.519122 -53.301018) (xy 141.534488 -53.259961) (xy 141.542581 -53.216877) (xy 141.543162 -53.173042)
			(xy 141.536213 -53.129758) (xy 141.52194 -53.088309) (xy 141.500766 -53.049923) (xy 141.47332 -53.015739)
			(xy 141.457172 -53.00091) (xy 141.440179 -52.985546) (xy 141.409618 -52.951415) (xy 141.396212 -52.932838)
			(xy 141.382296 -52.913811) (xy 141.348623 -52.880829) (xy 141.309449 -52.854617) (xy 141.266115 -52.836072)
			(xy 141.220107 -52.825829) (xy 141.172999 -52.82424) (xy 141.126404 -52.831358) (xy 141.08192 -52.84694)
			(xy 141.041068 -52.870451) (xy 141.005248 -52.901088) (xy 140.990066 -52.919122) (xy 140.972057 -52.940615)
			(xy 140.930881 -52.978674) (xy 140.884577 -53.010295) (xy 140.834143 -53.034796) (xy 140.780665 -53.05165)
			(xy 140.725296 -53.060493) (xy 140.669229 -53.061136) (xy 140.613672 -53.053563) (xy 140.559822 -53.037938)
			(xy 140.50884 -53.014598) (xy 140.461824 -52.984046) (xy 140.419788 -52.94694) (xy 140.383636 -52.90408)
			(xy 140.354149 -52.856389) (xy 140.331961 -52.804895) (xy 140.317551 -52.750708) (xy 140.311229 -52.694994)
			(xy 140.044732 -52.694994) (xy 140.028475 -52.742649) (xy 140.002974 -52.792249) (xy 139.970523 -52.837607)
			(xy 139.931814 -52.877756) (xy 139.887671 -52.911842) (xy 139.839036 -52.939138) (xy 139.786945 -52.959061)
			(xy 139.732508 -52.971187) (xy 139.676886 -52.975258) (xy 139.621264 -52.971187) (xy 139.566827 -52.959061)
			(xy 139.514736 -52.939138) (xy 139.466101 -52.911842) (xy 139.421958 -52.877756) (xy 139.383249 -52.837607)
			(xy 139.350798 -52.792249) (xy 139.325297 -52.742649) (xy 139.30729 -52.689865) (xy 139.29716 -52.635022)
			(xy 139.295123 -52.579288) (xy 138.685116 -52.579288) (xy 138.681654 -52.63088) (xy 138.6702 -52.684483)
			(xy 138.6512 -52.735898) (xy 138.625042 -52.784067) (xy 138.592266 -52.828) (xy 138.553544 -52.866795)
			(xy 138.509672 -52.899655) (xy 138.461552 -52.925903) (xy 138.410173 -52.945) (xy 138.356592 -52.956554)
			(xy 138.301909 -52.960327) (xy 138.247248 -52.956241) (xy 138.193733 -52.944382) (xy 138.142465 -52.924992)
			(xy 138.094496 -52.89847) (xy 138.072368 -52.882292) (xy 138.060247 -52.873729) (xy 138.03248 -52.863293)
			(xy 138.002888 -52.861249) (xy 137.973951 -52.867769) (xy 137.948094 -52.882306) (xy 137.927486 -52.903641)
			(xy 137.920222 -52.916582) (xy 137.912786 -52.930773) (xy 137.895876 -52.957989) (xy 137.88644 -52.970938)
			(xy 137.86852 -52.99396) (xy 137.826867 -53.034803) (xy 137.779478 -53.068826) (xy 137.72746 -53.095234)
			(xy 137.672027 -53.113411) (xy 137.614472 -53.122932) (xy 137.556138 -53.123577) (xy 137.498387 -53.115328)
			(xy 137.442566 -53.09838) (xy 137.416032 -53.086254) (xy 137.39126 -53.073742) (xy 137.345229 -53.042745)
			(xy 137.304171 -53.00541) (xy 137.268952 -52.962524) (xy 137.240313 -52.914991) (xy 137.218858 -52.863812)
			(xy 137.205039 -52.810066) (xy 137.199148 -52.754885) (xy 135.486607 -52.754885) (xy 135.445474 -52.782657)
			(xy 135.420608 -52.79517) (xy 135.411018 -52.80034) (xy 135.397054 -52.817041) (xy 135.391206 -52.83801)
			(xy 135.39451 -52.859527) (xy 135.40638 -52.877775) (xy 135.415274 -52.88407) (xy 135.425309 -52.890579)
			(xy 135.444627 -52.904687) (xy 135.453882 -52.912264) (xy 135.474661 -52.930246) (xy 135.511405 -52.971102)
			(xy 135.541905 -53.016808) (xy 135.565531 -53.066418) (xy 135.581794 -53.118904) (xy 135.590356 -53.173182)
			(xy 135.591041 -53.228126) (xy 135.583834 -53.282599) (xy 135.568884 -53.335475) (xy 135.546501 -53.385658)
			(xy 135.517149 -53.43211) (xy 135.481435 -53.473869) (xy 135.440097 -53.51007) (xy 135.417306 -53.52542)
			(xy 135.393418 -53.540485) (xy 135.342051 -53.563965) (xy 135.287786 -53.579623) (xy 135.231807 -53.587116)
			(xy 135.175335 -53.586282) (xy 135.119601 -53.57714) (xy 135.065822 -53.559887) (xy 135.015171 -53.534901)
			(xy 134.968753 -53.502727) (xy 134.92758 -53.464067) (xy 134.892551 -53.419763) (xy 134.86443 -53.370784)
			(xy 134.84383 -53.318196) (xy 134.831201 -53.263147) (xy 134.826818 -53.206839) (xy 130.961701 -53.206839)
			(xy 130.913489 -53.234049) (xy 130.861155 -53.254165) (xy 130.806441 -53.266405) (xy 130.750524 -53.270507)
			(xy 130.694609 -53.266383) (xy 130.6399 -53.25412) (xy 130.587573 -53.233984) (xy 130.538757 -53.206407)
			(xy 130.494502 -53.171984) (xy 130.455761 -53.131455) (xy 130.43916 -53.10886) (xy 130.429146 -53.095748)
			(xy 130.40382 -53.074629) (xy 130.373926 -53.06071) (xy 130.341462 -53.054922) (xy 130.308599 -53.057652)
			(xy 130.277535 -53.068718) (xy 130.263646 -53.077618) (xy 130.240289 -53.093128) (xy 130.18996 -53.117834)
			(xy 130.136557 -53.134909) (xy 130.08123 -53.143986) (xy 130.02517 -53.144869) (xy 129.969585 -53.137539)
			(xy 129.91567 -53.122153) (xy 129.864588 -53.099044) (xy 129.817437 -53.068708) (xy 129.775233 -53.031799)
			(xy 129.738885 -52.989111) (xy 129.709174 -52.941564) (xy 129.686741 -52.89018) (xy 129.672069 -52.836068)
			(xy 129.665474 -52.78039) (xy 128.948838 -52.78039) (xy 128.935025 -52.820881) (xy 128.909524 -52.870481)
			(xy 128.877073 -52.915839) (xy 128.838364 -52.955988) (xy 128.794221 -52.990074) (xy 128.745586 -53.01737)
			(xy 128.693495 -53.037293) (xy 128.639058 -53.049419) (xy 128.583436 -53.05349) (xy 128.527814 -53.049419)
			(xy 128.473377 -53.037293) (xy 128.421286 -53.01737) (xy 128.372651 -52.990074) (xy 128.328508 -52.955988)
			(xy 128.289799 -52.915839) (xy 128.257348 -52.870481) (xy 128.231847 -52.820881) (xy 128.21384 -52.768097)
			(xy 128.20371 -52.713254) (xy 128.201673 -52.65752) (xy 125.10359 -52.65752) (xy 125.107447 -52.692572)
			(xy 125.10541 -52.748306) (xy 125.09528 -52.803149) (xy 125.077273 -52.855933) (xy 125.051772 -52.905533)
			(xy 125.019321 -52.950891) (xy 124.980612 -52.99104) (xy 124.936469 -53.025126) (xy 124.887834 -53.052422)
			(xy 124.835743 -53.072345) (xy 124.781306 -53.084471) (xy 124.725684 -53.088542) (xy 124.670062 -53.084471)
			(xy 124.615625 -53.072345) (xy 124.563534 -53.052422) (xy 124.514899 -53.025126) (xy 124.470756 -52.99104)
			(xy 124.432047 -52.950891) (xy 124.399596 -52.905533) (xy 124.374095 -52.855933) (xy 124.356088 -52.803149)
			(xy 124.345958 -52.748306) (xy 124.343921 -52.692572) (xy 118.794905 -52.692572) (xy 118.794779 -52.69601)
			(xy 118.784642 -52.750889) (xy 118.766623 -52.803709) (xy 118.741105 -52.853341) (xy 118.708633 -52.898729)
			(xy 118.669898 -52.938906) (xy 118.625726 -52.973014) (xy 118.577058 -53.000328) (xy 118.524932 -53.020264)
			(xy 118.470459 -53.032399) (xy 118.4148 -53.036473) (xy 118.359141 -53.032399) (xy 118.304668 -53.020264)
			(xy 118.252542 -53.000328) (xy 118.203874 -52.973014) (xy 118.159702 -52.938906) (xy 118.120967 -52.898729)
			(xy 118.088495 -52.853341) (xy 118.062977 -52.803709) (xy 118.044958 -52.750889) (xy 118.034821 -52.69601)
			(xy 118.032783 -52.640239) (xy 113.11636 -52.640239) (xy 113.11636 -53.436284) (xy 123.249689 -53.436284)
			(xy 123.255789 -53.380847) (xy 123.269895 -53.32689) (xy 123.291707 -53.275561) (xy 123.320761 -53.227955)
			(xy 123.356436 -53.185087) (xy 123.397973 -53.14787) (xy 123.444486 -53.117097) (xy 123.494983 -53.093425)
			(xy 123.54839 -53.077357) (xy 123.603566 -53.069237) (xy 123.631452 -53.068728) (xy 123.659338 -53.069237)
			(xy 123.714514 -53.077357) (xy 123.767921 -53.093425) (xy 123.818418 -53.117097) (xy 123.864931 -53.14787)
			(xy 123.906468 -53.185087) (xy 123.942143 -53.227955) (xy 123.971197 -53.275561) (xy 123.993009 -53.32689)
			(xy 124.007115 -53.380847) (xy 124.013215 -53.436284) (xy 124.011178 -53.492018) (xy 124.001048 -53.546861)
			(xy 123.983041 -53.599645) (xy 123.95754 -53.649245) (xy 123.925089 -53.694603) (xy 123.88638 -53.734752)
			(xy 123.842237 -53.768838) (xy 123.793602 -53.796134) (xy 123.741511 -53.816057) (xy 123.687074 -53.828183)
			(xy 123.631452 -53.832254) (xy 123.57583 -53.828183) (xy 123.521393 -53.816057) (xy 123.469302 -53.796134)
			(xy 123.420667 -53.768838) (xy 123.376524 -53.734752) (xy 123.337815 -53.694603) (xy 123.305364 -53.649245)
			(xy 123.279863 -53.599645) (xy 123.261856 -53.546861) (xy 123.251726 -53.492018) (xy 123.249689 -53.436284)
			(xy 113.11636 -53.436284) (xy 113.11636 -53.968922) (xy 132.817107 -53.968922) (xy 132.823207 -53.913485)
			(xy 132.837313 -53.859528) (xy 132.859125 -53.808199) (xy 132.888179 -53.760593) (xy 132.923854 -53.717725)
			(xy 132.965391 -53.680508) (xy 133.011904 -53.649735) (xy 133.062401 -53.626063) (xy 133.115808 -53.609995)
			(xy 133.170984 -53.601875) (xy 133.19887 -53.601366) (xy 133.226756 -53.601875) (xy 133.281932 -53.609995)
			(xy 133.335339 -53.626063) (xy 133.385836 -53.649735) (xy 133.432349 -53.680508) (xy 133.473886 -53.717725)
			(xy 133.509561 -53.760593) (xy 133.538615 -53.808199) (xy 133.560427 -53.859528) (xy 133.566382 -53.882308)
			(xy 138.791695 -53.882308) (xy 138.797795 -53.826871) (xy 138.811901 -53.772914) (xy 138.833713 -53.721585)
			(xy 138.862767 -53.673979) (xy 138.898442 -53.631111) (xy 138.939979 -53.593894) (xy 138.986492 -53.563121)
			(xy 139.036989 -53.539449) (xy 139.090396 -53.523381) (xy 139.145572 -53.515261) (xy 139.173458 -53.514752)
			(xy 139.201344 -53.515261) (xy 139.25652 -53.523381) (xy 139.309927 -53.539449) (xy 139.360424 -53.563121)
			(xy 139.406937 -53.593894) (xy 139.448474 -53.631111) (xy 139.484149 -53.673979) (xy 139.513203 -53.721585)
			(xy 139.535015 -53.772914) (xy 139.549121 -53.826871) (xy 139.555221 -53.882308) (xy 139.553184 -53.938042)
			(xy 139.543054 -53.992885) (xy 139.525047 -54.045669) (xy 139.499546 -54.095269) (xy 139.467095 -54.140627)
			(xy 139.428386 -54.180776) (xy 139.384243 -54.214862) (xy 139.335608 -54.242158) (xy 139.283517 -54.262081)
			(xy 139.22908 -54.274207) (xy 139.173458 -54.278278) (xy 139.117836 -54.274207) (xy 139.063399 -54.262081)
			(xy 139.011308 -54.242158) (xy 138.962673 -54.214862) (xy 138.91853 -54.180776) (xy 138.879821 -54.140627)
			(xy 138.84737 -54.095269) (xy 138.821869 -54.045669) (xy 138.803862 -53.992885) (xy 138.793732 -53.938042)
			(xy 138.791695 -53.882308) (xy 133.566382 -53.882308) (xy 133.574533 -53.913485) (xy 133.580633 -53.968922)
			(xy 133.578596 -54.024656) (xy 133.568466 -54.079499) (xy 133.550459 -54.132283) (xy 133.524958 -54.181883)
			(xy 133.492507 -54.227241) (xy 133.453798 -54.26739) (xy 133.409655 -54.301476) (xy 133.36102 -54.328772)
			(xy 133.308929 -54.348695) (xy 133.254492 -54.360821) (xy 133.19887 -54.364892) (xy 133.143248 -54.360821)
			(xy 133.088811 -54.348695) (xy 133.03672 -54.328772) (xy 132.988085 -54.301476) (xy 132.943942 -54.26739)
			(xy 132.905233 -54.227241) (xy 132.872782 -54.181883) (xy 132.847281 -54.132283) (xy 132.829274 -54.079499)
			(xy 132.819144 -54.024656) (xy 132.817107 -53.968922) (xy 113.11636 -53.968922) (xy 113.11636 -54.48632)
			(xy 123.358909 -54.48632) (xy 123.365009 -54.430883) (xy 123.379115 -54.376926) (xy 123.400927 -54.325597)
			(xy 123.429981 -54.277991) (xy 123.465656 -54.235123) (xy 123.507193 -54.197906) (xy 123.553706 -54.167133)
			(xy 123.604203 -54.143461) (xy 123.65761 -54.127393) (xy 123.712786 -54.119273) (xy 123.740672 -54.118764)
			(xy 123.768558 -54.119273) (xy 123.823734 -54.127393) (xy 123.877141 -54.143461) (xy 123.927638 -54.167133)
			(xy 123.974151 -54.197906) (xy 124.015688 -54.235123) (xy 124.051363 -54.277991) (xy 124.080417 -54.325597)
			(xy 124.102229 -54.376926) (xy 124.116335 -54.430883) (xy 124.122435 -54.48632) (xy 124.120398 -54.542054)
			(xy 124.111035 -54.592746) (xy 130.822191 -54.592746) (xy 130.828291 -54.537309) (xy 130.842397 -54.483352)
			(xy 130.864209 -54.432023) (xy 130.893263 -54.384417) (xy 130.928938 -54.341549) (xy 130.970475 -54.304332)
			(xy 131.016988 -54.273559) (xy 131.067485 -54.249887) (xy 131.120892 -54.233819) (xy 131.176068 -54.225699)
			(xy 131.203954 -54.22519) (xy 131.23184 -54.225699) (xy 131.287016 -54.233819) (xy 131.340423 -54.249887)
			(xy 131.39092 -54.273559) (xy 131.437433 -54.304332) (xy 131.47897 -54.341549) (xy 131.514645 -54.384417)
			(xy 131.543699 -54.432023) (xy 131.565511 -54.483352) (xy 131.579617 -54.537309) (xy 131.585717 -54.592746)
			(xy 131.58368 -54.64848) (xy 131.57355 -54.703323) (xy 131.555543 -54.756107) (xy 131.530042 -54.805707)
			(xy 131.497591 -54.851065) (xy 131.474091 -54.875439) (xy 137.971783 -54.875439) (xy 137.977886 -54.819965)
			(xy 137.992002 -54.765972) (xy 138.013829 -54.714609) (xy 138.042902 -54.666971) (xy 138.078601 -54.624075)
			(xy 138.120165 -54.586833) (xy 138.166709 -54.556039) (xy 138.21724 -54.532351) (xy 138.270682 -54.516273)
			(xy 138.325896 -54.508147) (xy 138.3538 -54.507638) (xy 138.381704 -54.508147) (xy 138.436918 -54.516273)
			(xy 138.49036 -54.532351) (xy 138.540891 -54.556039) (xy 138.587435 -54.586833) (xy 138.628999 -54.624075)
			(xy 138.664698 -54.666971) (xy 138.693771 -54.714609) (xy 138.715598 -54.765972) (xy 138.725595 -54.80421)
			(xy 153.779221 -54.80421) (xy 153.781244 -54.710166) (xy 153.791345 -54.616645) (xy 153.809448 -54.524339)
			(xy 153.835419 -54.43393) (xy 153.869066 -54.346088) (xy 153.91014 -54.261465) (xy 153.958336 -54.180685)
			(xy 154.013298 -54.104347) (xy 154.074619 -54.033017) (xy 154.141845 -53.967223) (xy 154.214478 -53.907451)
			(xy 154.29198 -53.854144) (xy 154.373778 -53.807697) (xy 154.459266 -53.768454) (xy 154.547811 -53.736704)
			(xy 154.638758 -53.712685) (xy 154.731433 -53.696572) (xy 154.825149 -53.688486) (xy 154.872182 -53.68798)
			(xy 154.919215 -53.688486) (xy 155.012931 -53.696572) (xy 155.105606 -53.712685) (xy 155.196553 -53.736704)
			(xy 155.285098 -53.768454) (xy 155.370586 -53.807697) (xy 155.452384 -53.854144) (xy 155.529886 -53.907451)
			(xy 155.602519 -53.967223) (xy 155.669745 -54.033017) (xy 155.731066 -54.104347) (xy 155.786028 -54.180685)
			(xy 155.834224 -54.261465) (xy 155.875298 -54.346088) (xy 155.908945 -54.43393) (xy 155.934916 -54.524339)
			(xy 155.953019 -54.616645) (xy 155.96312 -54.710166) (xy 155.965143 -54.80421) (xy 155.959075 -54.898079)
			(xy 155.94496 -54.991079) (xy 155.922903 -55.082521) (xy 155.893066 -55.171729) (xy 155.855672 -55.258041)
			(xy 155.810995 -55.34082) (xy 155.759368 -55.419451) (xy 155.701173 -55.493353) (xy 155.63684 -55.561979)
			(xy 155.566846 -55.624821) (xy 155.491709 -55.681413) (xy 155.411985 -55.731336) (xy 155.328264 -55.774221)
			(xy 155.241167 -55.80975) (xy 155.151338 -55.83766) (xy 155.059442 -55.857745) (xy 154.96616 -55.869856)
			(xy 154.872182 -55.873903) (xy 154.778204 -55.869856) (xy 154.684922 -55.857745) (xy 154.593026 -55.83766)
			(xy 154.503197 -55.80975) (xy 154.4161 -55.774221) (xy 154.332379 -55.731336) (xy 154.252655 -55.681413)
			(xy 154.177518 -55.624821) (xy 154.107524 -55.561979) (xy 154.043191 -55.493353) (xy 153.984996 -55.419451)
			(xy 153.933369 -55.34082) (xy 153.888692 -55.258041) (xy 153.851298 -55.171729) (xy 153.821461 -55.082521)
			(xy 153.799404 -54.991079) (xy 153.785289 -54.898079) (xy 153.779221 -54.80421) (xy 138.725595 -54.80421)
			(xy 138.729714 -54.819965) (xy 138.735817 -54.875439) (xy 138.733779 -54.93121) (xy 138.723642 -54.986089)
			(xy 138.705623 -55.038909) (xy 138.680105 -55.088541) (xy 138.647633 -55.133929) (xy 138.608898 -55.174106)
			(xy 138.564726 -55.208214) (xy 138.516058 -55.235528) (xy 138.463932 -55.255464) (xy 138.409459 -55.267599)
			(xy 138.3538 -55.271673) (xy 138.298141 -55.267599) (xy 138.243668 -55.255464) (xy 138.191542 -55.235528)
			(xy 138.142874 -55.208214) (xy 138.098702 -55.174106) (xy 138.059967 -55.133929) (xy 138.027495 -55.088541)
			(xy 138.001977 -55.038909) (xy 137.983958 -54.986089) (xy 137.973821 -54.93121) (xy 137.971783 -54.875439)
			(xy 131.474091 -54.875439) (xy 131.458882 -54.891214) (xy 131.414739 -54.9253) (xy 131.366104 -54.952596)
			(xy 131.314013 -54.972519) (xy 131.259576 -54.984645) (xy 131.203954 -54.988716) (xy 131.148332 -54.984645)
			(xy 131.093895 -54.972519) (xy 131.041804 -54.952596) (xy 130.993169 -54.9253) (xy 130.949026 -54.891214)
			(xy 130.910317 -54.851065) (xy 130.877866 -54.805707) (xy 130.852365 -54.756107) (xy 130.834358 -54.703323)
			(xy 130.824228 -54.64848) (xy 130.822191 -54.592746) (xy 124.111035 -54.592746) (xy 124.110268 -54.596897)
			(xy 124.092261 -54.649681) (xy 124.06676 -54.699281) (xy 124.034309 -54.744639) (xy 123.9956 -54.784788)
			(xy 123.951457 -54.818874) (xy 123.902822 -54.84617) (xy 123.850731 -54.866093) (xy 123.796294 -54.878219)
			(xy 123.740672 -54.88229) (xy 123.68505 -54.878219) (xy 123.630613 -54.866093) (xy 123.578522 -54.84617)
			(xy 123.529887 -54.818874) (xy 123.485744 -54.784788) (xy 123.447035 -54.744639) (xy 123.414584 -54.699281)
			(xy 123.389083 -54.649681) (xy 123.371076 -54.596897) (xy 123.360946 -54.542054) (xy 123.358909 -54.48632)
			(xy 113.11636 -54.48632) (xy 113.11636 -55.147736) (xy 126.332487 -55.147736) (xy 126.338587 -55.092299)
			(xy 126.352693 -55.038342) (xy 126.374505 -54.987013) (xy 126.403559 -54.939407) (xy 126.439234 -54.896539)
			(xy 126.480771 -54.859322) (xy 126.527284 -54.828549) (xy 126.577781 -54.804877) (xy 126.631188 -54.788809)
			(xy 126.686364 -54.780689) (xy 126.71425 -54.78018) (xy 126.742136 -54.780689) (xy 126.797312 -54.788809)
			(xy 126.850719 -54.804877) (xy 126.901216 -54.828549) (xy 126.947729 -54.859322) (xy 126.989266 -54.896539)
			(xy 127.024941 -54.939407) (xy 127.053995 -54.987013) (xy 127.075807 -55.038342) (xy 127.089913 -55.092299)
			(xy 127.096013 -55.147736) (xy 127.093976 -55.20347) (xy 127.083846 -55.258313) (xy 127.065839 -55.311097)
			(xy 127.040338 -55.360697) (xy 127.007887 -55.406055) (xy 126.969178 -55.446204) (xy 126.925035 -55.48029)
			(xy 126.8764 -55.507586) (xy 126.824309 -55.527509) (xy 126.769872 -55.539635) (xy 126.71425 -55.543706)
			(xy 126.658628 -55.539635) (xy 126.604191 -55.527509) (xy 126.5521 -55.507586) (xy 126.503465 -55.48029)
			(xy 126.459322 -55.446204) (xy 126.420613 -55.406055) (xy 126.388162 -55.360697) (xy 126.362661 -55.311097)
			(xy 126.344654 -55.258313) (xy 126.334524 -55.20347) (xy 126.332487 -55.147736) (xy 113.11636 -55.147736)
			(xy 113.11636 -55.993039) (xy 131.520183 -55.993039) (xy 131.526286 -55.937565) (xy 131.540402 -55.883572)
			(xy 131.562229 -55.832209) (xy 131.591302 -55.784571) (xy 131.627001 -55.741675) (xy 131.668565 -55.704433)
			(xy 131.715109 -55.673639) (xy 131.76564 -55.649951) (xy 131.819082 -55.633873) (xy 131.874296 -55.625747)
			(xy 131.9022 -55.625238) (xy 131.930104 -55.625747) (xy 131.985318 -55.633873) (xy 132.03876 -55.649951)
			(xy 132.089291 -55.673639) (xy 132.135835 -55.704433) (xy 132.177399 -55.741675) (xy 132.213098 -55.784571)
			(xy 132.242171 -55.832209) (xy 132.263998 -55.883572) (xy 132.274026 -55.921928) (xy 138.593829 -55.921928)
			(xy 138.599929 -55.866491) (xy 138.614035 -55.812534) (xy 138.635847 -55.761205) (xy 138.664901 -55.713599)
			(xy 138.700576 -55.670731) (xy 138.742113 -55.633514) (xy 138.788626 -55.602741) (xy 138.839123 -55.579069)
			(xy 138.89253 -55.563001) (xy 138.947706 -55.554881) (xy 138.975592 -55.554372) (xy 139.003478 -55.554881)
			(xy 139.058654 -55.563001) (xy 139.112061 -55.579069) (xy 139.162558 -55.602741) (xy 139.209071 -55.633514)
			(xy 139.250608 -55.670731) (xy 139.286283 -55.713599) (xy 139.315337 -55.761205) (xy 139.337149 -55.812534)
			(xy 139.351255 -55.866491) (xy 139.357355 -55.921928) (xy 139.355318 -55.977662) (xy 139.345188 -56.032505)
			(xy 139.344611 -56.034196) (xy 146.863815 -56.034196) (xy 146.869915 -55.978759) (xy 146.884021 -55.924802)
			(xy 146.905833 -55.873473) (xy 146.934887 -55.825867) (xy 146.970562 -55.782999) (xy 147.012099 -55.745782)
			(xy 147.058612 -55.715009) (xy 147.109109 -55.691337) (xy 147.162516 -55.675269) (xy 147.217692 -55.667149)
			(xy 147.245578 -55.66664) (xy 147.273464 -55.667149) (xy 147.32864 -55.675269) (xy 147.382047 -55.691337)
			(xy 147.432544 -55.715009) (xy 147.479057 -55.745782) (xy 147.520594 -55.782999) (xy 147.556269 -55.825867)
			(xy 147.585323 -55.873473) (xy 147.607135 -55.924802) (xy 147.621241 -55.978759) (xy 147.627341 -56.034196)
			(xy 147.625304 -56.08993) (xy 147.619976 -56.118778) (xy 150.927815 -56.118778) (xy 150.933915 -56.063341)
			(xy 150.948021 -56.009384) (xy 150.969833 -55.958055) (xy 150.998887 -55.910449) (xy 151.034562 -55.867581)
			(xy 151.076099 -55.830364) (xy 151.122612 -55.799591) (xy 151.173109 -55.775919) (xy 151.226516 -55.759851)
			(xy 151.281692 -55.751731) (xy 151.309578 -55.751222) (xy 151.337464 -55.751731) (xy 151.39264 -55.759851)
			(xy 151.446047 -55.775919) (xy 151.496544 -55.799591) (xy 151.543057 -55.830364) (xy 151.584594 -55.867581)
			(xy 151.620269 -55.910449) (xy 151.649323 -55.958055) (xy 151.671135 -56.009384) (xy 151.685241 -56.063341)
			(xy 151.691341 -56.118778) (xy 151.689304 -56.174512) (xy 151.679174 -56.229355) (xy 151.661167 -56.282139)
			(xy 151.635666 -56.331739) (xy 151.603215 -56.377097) (xy 151.564506 -56.417246) (xy 151.520363 -56.451332)
			(xy 151.471728 -56.478628) (xy 151.419637 -56.498551) (xy 151.3652 -56.510677) (xy 151.309578 -56.514748)
			(xy 151.253956 -56.510677) (xy 151.199519 -56.498551) (xy 151.147428 -56.478628) (xy 151.098793 -56.451332)
			(xy 151.05465 -56.417246) (xy 151.015941 -56.377097) (xy 150.98349 -56.331739) (xy 150.957989 -56.282139)
			(xy 150.939982 -56.229355) (xy 150.929852 -56.174512) (xy 150.927815 -56.118778) (xy 147.619976 -56.118778)
			(xy 147.615174 -56.144773) (xy 147.597167 -56.197557) (xy 147.571666 -56.247157) (xy 147.539215 -56.292515)
			(xy 147.500506 -56.332664) (xy 147.456363 -56.36675) (xy 147.407728 -56.394046) (xy 147.355637 -56.413969)
			(xy 147.3012 -56.426095) (xy 147.245578 -56.430166) (xy 147.189956 -56.426095) (xy 147.135519 -56.413969)
			(xy 147.083428 -56.394046) (xy 147.034793 -56.36675) (xy 146.99065 -56.332664) (xy 146.951941 -56.292515)
			(xy 146.91949 -56.247157) (xy 146.893989 -56.197557) (xy 146.875982 -56.144773) (xy 146.865852 -56.08993)
			(xy 146.863815 -56.034196) (xy 139.344611 -56.034196) (xy 139.327181 -56.085289) (xy 139.30168 -56.134889)
			(xy 139.269229 -56.180247) (xy 139.23052 -56.220396) (xy 139.186377 -56.254482) (xy 139.137742 -56.281778)
			(xy 139.085651 -56.301701) (xy 139.031214 -56.313827) (xy 138.975592 -56.317898) (xy 138.91997 -56.313827)
			(xy 138.865533 -56.301701) (xy 138.813442 -56.281778) (xy 138.764807 -56.254482) (xy 138.720664 -56.220396)
			(xy 138.681955 -56.180247) (xy 138.649504 -56.134889) (xy 138.624003 -56.085289) (xy 138.605996 -56.032505)
			(xy 138.595866 -55.977662) (xy 138.593829 -55.921928) (xy 132.274026 -55.921928) (xy 132.278114 -55.937565)
			(xy 132.284217 -55.993039) (xy 132.282179 -56.04881) (xy 132.272042 -56.103689) (xy 132.254023 -56.156509)
			(xy 132.228505 -56.206141) (xy 132.196033 -56.251529) (xy 132.157298 -56.291706) (xy 132.113126 -56.325814)
			(xy 132.064458 -56.353128) (xy 132.012332 -56.373064) (xy 131.957859 -56.385199) (xy 131.9022 -56.389273)
			(xy 131.846541 -56.385199) (xy 131.792068 -56.373064) (xy 131.739942 -56.353128) (xy 131.691274 -56.325814)
			(xy 131.647102 -56.291706) (xy 131.608367 -56.251529) (xy 131.575895 -56.206141) (xy 131.550377 -56.156509)
			(xy 131.532358 -56.103689) (xy 131.522221 -56.04881) (xy 131.520183 -55.993039) (xy 113.11636 -55.993039)
			(xy 113.11636 -56.656478) (xy 113.305082 -56.8452) (xy 124.763528 -56.8452) (xy 124.767601 -56.789541)
			(xy 124.779736 -56.735068) (xy 124.799672 -56.682942) (xy 124.826986 -56.634274) (xy 124.861094 -56.590102)
			(xy 124.901271 -56.551367) (xy 124.946659 -56.518895) (xy 124.996291 -56.493377) (xy 125.049111 -56.475358)
			(xy 125.10399 -56.465221) (xy 125.159761 -56.463183) (xy 125.164551 -56.46371) (xy 143.885157 -56.46371)
			(xy 143.891257 -56.408273) (xy 143.905363 -56.354316) (xy 143.927175 -56.302987) (xy 143.956229 -56.255381)
			(xy 143.991904 -56.212513) (xy 144.033441 -56.175296) (xy 144.079954 -56.144523) (xy 144.130451 -56.120851)
			(xy 144.183858 -56.104783) (xy 144.239034 -56.096663) (xy 144.26692 -56.096154) (xy 144.294806 -56.096663)
			(xy 144.349982 -56.104783) (xy 144.403389 -56.120851) (xy 144.453886 -56.144523) (xy 144.500399 -56.175296)
			(xy 144.541936 -56.212513) (xy 144.577611 -56.255381) (xy 144.606665 -56.302987) (xy 144.628477 -56.354316)
			(xy 144.642583 -56.408273) (xy 144.648683 -56.46371) (xy 144.648312 -56.47387) (xy 144.911317 -56.47387)
			(xy 144.917417 -56.418433) (xy 144.931523 -56.364476) (xy 144.953335 -56.313147) (xy 144.982389 -56.265541)
			(xy 145.018064 -56.222673) (xy 145.059601 -56.185456) (xy 145.106114 -56.154683) (xy 145.156611 -56.131011)
			(xy 145.210018 -56.114943) (xy 145.265194 -56.106823) (xy 145.29308 -56.106314) (xy 145.320966 -56.106823)
			(xy 145.376142 -56.114943) (xy 145.429549 -56.131011) (xy 145.480046 -56.154683) (xy 145.526559 -56.185456)
			(xy 145.568096 -56.222673) (xy 145.603771 -56.265541) (xy 145.632825 -56.313147) (xy 145.654637 -56.364476)
			(xy 145.668743 -56.418433) (xy 145.674843 -56.47387) (xy 145.672806 -56.529604) (xy 145.662676 -56.584447)
			(xy 145.644669 -56.637231) (xy 145.619168 -56.686831) (xy 145.586717 -56.732189) (xy 145.548008 -56.772338)
			(xy 145.503865 -56.806424) (xy 145.45523 -56.83372) (xy 145.403139 -56.853643) (xy 145.348702 -56.865769)
			(xy 145.29308 -56.86984) (xy 145.237458 -56.865769) (xy 145.183021 -56.853643) (xy 145.13093 -56.83372)
			(xy 145.082295 -56.806424) (xy 145.038152 -56.772338) (xy 144.999443 -56.732189) (xy 144.966992 -56.686831)
			(xy 144.941491 -56.637231) (xy 144.923484 -56.584447) (xy 144.913354 -56.529604) (xy 144.911317 -56.47387)
			(xy 144.648312 -56.47387) (xy 144.646646 -56.519444) (xy 144.636516 -56.574287) (xy 144.618509 -56.627071)
			(xy 144.593008 -56.676671) (xy 144.560557 -56.722029) (xy 144.521848 -56.762178) (xy 144.477705 -56.796264)
			(xy 144.42907 -56.82356) (xy 144.376979 -56.843483) (xy 144.322542 -56.855609) (xy 144.26692 -56.85968)
			(xy 144.211298 -56.855609) (xy 144.156861 -56.843483) (xy 144.10477 -56.82356) (xy 144.056135 -56.796264)
			(xy 144.011992 -56.762178) (xy 143.973283 -56.722029) (xy 143.940832 -56.676671) (xy 143.915331 -56.627071)
			(xy 143.897324 -56.574287) (xy 143.887194 -56.519444) (xy 143.885157 -56.46371) (xy 125.164551 -56.46371)
			(xy 125.215235 -56.469286) (xy 125.269228 -56.483402) (xy 125.320591 -56.505229) (xy 125.368229 -56.534302)
			(xy 125.411125 -56.570001) (xy 125.448367 -56.611565) (xy 125.479161 -56.658109) (xy 125.502849 -56.70864)
			(xy 125.518927 -56.762082) (xy 125.527053 -56.817296) (xy 125.527562 -56.8452) (xy 125.527053 -56.873104)
			(xy 125.51927 -56.92599) (xy 131.490719 -56.92599) (xy 131.496819 -56.870553) (xy 131.510925 -56.816596)
			(xy 131.532737 -56.765267) (xy 131.561791 -56.717661) (xy 131.597466 -56.674793) (xy 131.639003 -56.637576)
			(xy 131.685516 -56.606803) (xy 131.736013 -56.583131) (xy 131.78942 -56.567063) (xy 131.844596 -56.558943)
			(xy 131.872482 -56.558434) (xy 131.900368 -56.558943) (xy 131.955544 -56.567063) (xy 132.008951 -56.583131)
			(xy 132.059448 -56.606803) (xy 132.105961 -56.637576) (xy 132.147498 -56.674793) (xy 132.183173 -56.717661)
			(xy 132.212227 -56.765267) (xy 132.234039 -56.816596) (xy 132.248145 -56.870553) (xy 132.254245 -56.92599)
			(xy 132.252208 -56.981724) (xy 132.242078 -57.036567) (xy 132.224071 -57.089351) (xy 132.19857 -57.138951)
			(xy 132.166119 -57.184309) (xy 132.12741 -57.224458) (xy 132.083267 -57.258544) (xy 132.034632 -57.28584)
			(xy 131.982541 -57.305763) (xy 131.928104 -57.317889) (xy 131.872482 -57.32196) (xy 131.81686 -57.317889)
			(xy 131.762423 -57.305763) (xy 131.710332 -57.28584) (xy 131.661697 -57.258544) (xy 131.617554 -57.224458)
			(xy 131.578845 -57.184309) (xy 131.546394 -57.138951) (xy 131.520893 -57.089351) (xy 131.502886 -57.036567)
			(xy 131.492756 -56.981724) (xy 131.490719 -56.92599) (xy 125.51927 -56.92599) (xy 125.518927 -56.928318)
			(xy 125.502849 -56.98176) (xy 125.479161 -57.032291) (xy 125.448367 -57.078835) (xy 125.411125 -57.120399)
			(xy 125.368229 -57.156098) (xy 125.320591 -57.185171) (xy 125.269228 -57.206998) (xy 125.215235 -57.221114)
			(xy 125.159761 -57.227217) (xy 125.10399 -57.225179) (xy 125.049111 -57.215042) (xy 124.996291 -57.197023)
			(xy 124.946659 -57.171505) (xy 124.901271 -57.139033) (xy 124.861094 -57.100298) (xy 124.826986 -57.056126)
			(xy 124.799672 -57.007458) (xy 124.779736 -56.955332) (xy 124.767601 -56.900859) (xy 124.763528 -56.8452)
			(xy 113.305082 -56.8452) (xy 114.300272 -57.84039) (xy 126.330455 -57.84039) (xy 126.336555 -57.784953)
			(xy 126.350661 -57.730996) (xy 126.372473 -57.679667) (xy 126.401527 -57.632061) (xy 126.437202 -57.589193)
			(xy 126.478739 -57.551976) (xy 126.525252 -57.521203) (xy 126.575749 -57.497531) (xy 126.629156 -57.481463)
			(xy 126.684332 -57.473343) (xy 126.712218 -57.472834) (xy 126.740104 -57.473343) (xy 126.79528 -57.481463)
			(xy 126.848687 -57.497531) (xy 126.899184 -57.521203) (xy 126.945697 -57.551976) (xy 126.987234 -57.589193)
			(xy 127.022909 -57.632061) (xy 127.051963 -57.679667) (xy 127.073775 -57.730996) (xy 127.087881 -57.784953)
			(xy 127.093981 -57.84039) (xy 127.093183 -57.862225) (xy 127.872997 -57.862225) (xy 127.8791 -57.806751)
			(xy 127.893216 -57.752758) (xy 127.915043 -57.701395) (xy 127.944116 -57.653757) (xy 127.979815 -57.610861)
			(xy 128.021379 -57.573619) (xy 128.067923 -57.542825) (xy 128.118454 -57.519137) (xy 128.171896 -57.503059)
			(xy 128.22711 -57.494933) (xy 128.255014 -57.494424) (xy 128.282918 -57.494933) (xy 128.338132 -57.503059)
			(xy 128.391574 -57.519137) (xy 128.442105 -57.542825) (xy 128.488649 -57.573619) (xy 128.530213 -57.610861)
			(xy 128.565912 -57.653757) (xy 128.594985 -57.701395) (xy 128.616812 -57.752758) (xy 128.630928 -57.806751)
			(xy 128.636278 -57.855376) (xy 135.307069 -57.855376) (xy 135.313169 -57.799939) (xy 135.327275 -57.745982)
			(xy 135.349087 -57.694653) (xy 135.378141 -57.647047) (xy 135.413816 -57.604179) (xy 135.455353 -57.566962)
			(xy 135.501866 -57.536189) (xy 135.552363 -57.512517) (xy 135.60577 -57.496449) (xy 135.660946 -57.488329)
			(xy 135.688832 -57.48782) (xy 135.716718 -57.488329) (xy 135.771894 -57.496449) (xy 135.825301 -57.512517)
			(xy 135.875798 -57.536189) (xy 135.922311 -57.566962) (xy 135.929536 -57.573436) (xy 138.155933 -57.573436)
			(xy 138.162033 -57.517999) (xy 138.176139 -57.464042) (xy 138.197951 -57.412713) (xy 138.227005 -57.365107)
			(xy 138.26268 -57.322239) (xy 138.304217 -57.285022) (xy 138.35073 -57.254249) (xy 138.401227 -57.230577)
			(xy 138.454634 -57.214509) (xy 138.50981 -57.206389) (xy 138.537696 -57.20588) (xy 138.565582 -57.206389)
			(xy 138.620758 -57.214509) (xy 138.674165 -57.230577) (xy 138.724662 -57.254249) (xy 138.771175 -57.285022)
			(xy 138.812712 -57.322239) (xy 138.848387 -57.365107) (xy 138.877441 -57.412713) (xy 138.899253 -57.464042)
			(xy 138.913359 -57.517999) (xy 138.917363 -57.554386) (xy 143.994377 -57.554386) (xy 144.000477 -57.498949)
			(xy 144.014583 -57.444992) (xy 144.036395 -57.393663) (xy 144.065449 -57.346057) (xy 144.101124 -57.303189)
			(xy 144.142661 -57.265972) (xy 144.189174 -57.235199) (xy 144.239671 -57.211527) (xy 144.293078 -57.195459)
			(xy 144.348254 -57.187339) (xy 144.37614 -57.18683) (xy 144.404026 -57.187339) (xy 144.459202 -57.195459)
			(xy 144.512609 -57.211527) (xy 144.563106 -57.235199) (xy 144.609619 -57.265972) (xy 144.651156 -57.303189)
			(xy 144.686831 -57.346057) (xy 144.715885 -57.393663) (xy 144.737697 -57.444992) (xy 144.751803 -57.498949)
			(xy 144.755723 -57.534574) (xy 145.081497 -57.534574) (xy 145.087597 -57.479137) (xy 145.101703 -57.42518)
			(xy 145.123515 -57.373851) (xy 145.152569 -57.326245) (xy 145.188244 -57.283377) (xy 145.229781 -57.24616)
			(xy 145.276294 -57.215387) (xy 145.326791 -57.191715) (xy 145.380198 -57.175647) (xy 145.435374 -57.167527)
			(xy 145.46326 -57.167018) (xy 145.491146 -57.167527) (xy 145.546322 -57.175647) (xy 145.599729 -57.191715)
			(xy 145.650226 -57.215387) (xy 145.696739 -57.24616) (xy 145.738276 -57.283377) (xy 145.773951 -57.326245)
			(xy 145.803005 -57.373851) (xy 145.824817 -57.42518) (xy 145.838923 -57.479137) (xy 145.845023 -57.534574)
			(xy 145.842986 -57.590308) (xy 145.832856 -57.645151) (xy 145.814849 -57.697935) (xy 145.789348 -57.747535)
			(xy 145.756897 -57.792893) (xy 145.718188 -57.833042) (xy 145.674045 -57.867128) (xy 145.62541 -57.894424)
			(xy 145.573319 -57.914347) (xy 145.518882 -57.926473) (xy 145.46326 -57.930544) (xy 145.407638 -57.926473)
			(xy 145.353201 -57.914347) (xy 145.30111 -57.894424) (xy 145.252475 -57.867128) (xy 145.208332 -57.833042)
			(xy 145.169623 -57.792893) (xy 145.137172 -57.747535) (xy 145.111671 -57.697935) (xy 145.093664 -57.645151)
			(xy 145.083534 -57.590308) (xy 145.081497 -57.534574) (xy 144.755723 -57.534574) (xy 144.757903 -57.554386)
			(xy 144.755866 -57.61012) (xy 144.745736 -57.664963) (xy 144.727729 -57.717747) (xy 144.702228 -57.767347)
			(xy 144.669777 -57.812705) (xy 144.631068 -57.852854) (xy 144.586925 -57.88694) (xy 144.53829 -57.914236)
			(xy 144.486199 -57.934159) (xy 144.431762 -57.946285) (xy 144.37614 -57.950356) (xy 144.320518 -57.946285)
			(xy 144.266081 -57.934159) (xy 144.21399 -57.914236) (xy 144.165355 -57.88694) (xy 144.121212 -57.852854)
			(xy 144.082503 -57.812705) (xy 144.050052 -57.767347) (xy 144.024551 -57.717747) (xy 144.006544 -57.664963)
			(xy 143.996414 -57.61012) (xy 143.994377 -57.554386) (xy 138.917363 -57.554386) (xy 138.919459 -57.573436)
			(xy 138.917422 -57.62917) (xy 138.907292 -57.684013) (xy 138.889285 -57.736797) (xy 138.863784 -57.786397)
			(xy 138.831333 -57.831755) (xy 138.792624 -57.871904) (xy 138.748481 -57.90599) (xy 138.699846 -57.933286)
			(xy 138.647755 -57.953209) (xy 138.593318 -57.965335) (xy 138.537696 -57.969406) (xy 138.482074 -57.965335)
			(xy 138.427637 -57.953209) (xy 138.375546 -57.933286) (xy 138.326911 -57.90599) (xy 138.282768 -57.871904)
			(xy 138.244059 -57.831755) (xy 138.211608 -57.786397) (xy 138.186107 -57.736797) (xy 138.1681 -57.684013)
			(xy 138.15797 -57.62917) (xy 138.155933 -57.573436) (xy 135.929536 -57.573436) (xy 135.963848 -57.604179)
			(xy 135.999523 -57.647047) (xy 136.028577 -57.694653) (xy 136.050389 -57.745982) (xy 136.064495 -57.799939)
			(xy 136.070595 -57.855376) (xy 136.068558 -57.91111) (xy 136.058428 -57.965953) (xy 136.040421 -58.018737)
			(xy 136.01492 -58.068337) (xy 135.982469 -58.113695) (xy 135.94376 -58.153844) (xy 135.899617 -58.18793)
			(xy 135.850982 -58.215226) (xy 135.798891 -58.235149) (xy 135.744454 -58.247275) (xy 135.688832 -58.251346)
			(xy 135.63321 -58.247275) (xy 135.578773 -58.235149) (xy 135.526682 -58.215226) (xy 135.478047 -58.18793)
			(xy 135.433904 -58.153844) (xy 135.395195 -58.113695) (xy 135.362744 -58.068337) (xy 135.337243 -58.018737)
			(xy 135.319236 -57.965953) (xy 135.309106 -57.91111) (xy 135.307069 -57.855376) (xy 128.636278 -57.855376)
			(xy 128.637031 -57.862225) (xy 128.634993 -57.917996) (xy 128.624856 -57.972875) (xy 128.606837 -58.025695)
			(xy 128.581319 -58.075327) (xy 128.548847 -58.120715) (xy 128.510112 -58.160892) (xy 128.46594 -58.195)
			(xy 128.417272 -58.222314) (xy 128.365146 -58.24225) (xy 128.310673 -58.254385) (xy 128.255014 -58.258459)
			(xy 128.199355 -58.254385) (xy 128.144882 -58.24225) (xy 128.092756 -58.222314) (xy 128.044088 -58.195)
			(xy 127.999916 -58.160892) (xy 127.961181 -58.120715) (xy 127.928709 -58.075327) (xy 127.903191 -58.025695)
			(xy 127.885172 -57.972875) (xy 127.875035 -57.917996) (xy 127.872997 -57.862225) (xy 127.093183 -57.862225)
			(xy 127.091944 -57.896124) (xy 127.081814 -57.950967) (xy 127.063807 -58.003751) (xy 127.038306 -58.053351)
			(xy 127.005855 -58.098709) (xy 126.967146 -58.138858) (xy 126.923003 -58.172944) (xy 126.874368 -58.20024)
			(xy 126.822277 -58.220163) (xy 126.76784 -58.232289) (xy 126.712218 -58.23636) (xy 126.656596 -58.232289)
			(xy 126.602159 -58.220163) (xy 126.550068 -58.20024) (xy 126.501433 -58.172944) (xy 126.45729 -58.138858)
			(xy 126.418581 -58.098709) (xy 126.38613 -58.053351) (xy 126.360629 -58.003751) (xy 126.342622 -57.950967)
			(xy 126.332492 -57.896124) (xy 126.330455 -57.84039) (xy 114.300272 -57.84039) (xy 114.898932 -58.43905)
			(xy 130.840478 -58.43905) (xy 130.844551 -58.383391) (xy 130.856686 -58.328918) (xy 130.876622 -58.276792)
			(xy 130.903936 -58.228124) (xy 130.938044 -58.183952) (xy 130.978221 -58.145217) (xy 131.023609 -58.112745)
			(xy 131.073241 -58.087227) (xy 131.126061 -58.069208) (xy 131.18094 -58.059071) (xy 131.236711 -58.057033)
			(xy 131.292185 -58.063136) (xy 131.346178 -58.077252) (xy 131.397541 -58.099079) (xy 131.445179 -58.128152)
			(xy 131.488075 -58.163851) (xy 131.525317 -58.205415) (xy 131.556111 -58.251959) (xy 131.579799 -58.30249)
			(xy 131.595877 -58.355932) (xy 131.604003 -58.411146) (xy 131.604512 -58.43905) (xy 131.604003 -58.466954)
			(xy 131.595877 -58.522168) (xy 131.585421 -58.556924) (xy 133.756907 -58.556924) (xy 133.763007 -58.501487)
			(xy 133.777113 -58.44753) (xy 133.798925 -58.396201) (xy 133.827979 -58.348595) (xy 133.863654 -58.305727)
			(xy 133.905191 -58.26851) (xy 133.951704 -58.237737) (xy 134.002201 -58.214065) (xy 134.055608 -58.197997)
			(xy 134.110784 -58.189877) (xy 134.13867 -58.189368) (xy 134.166556 -58.189877) (xy 134.221732 -58.197997)
			(xy 134.275139 -58.214065) (xy 134.325636 -58.237737) (xy 134.372149 -58.26851) (xy 134.413686 -58.305727)
			(xy 134.449361 -58.348595) (xy 134.478415 -58.396201) (xy 134.500227 -58.44753) (xy 134.514333 -58.501487)
			(xy 134.520433 -58.556924) (xy 134.518396 -58.612658) (xy 134.508266 -58.667501) (xy 134.495788 -58.704079)
			(xy 138.045385 -58.704079) (xy 138.048313 -58.647984) (xy 138.059435 -58.592923) (xy 138.078508 -58.540089)
			(xy 138.105122 -58.490621) (xy 138.1387 -58.44559) (xy 138.178517 -58.405969) (xy 138.223714 -58.372613)
			(xy 138.273312 -58.346244) (xy 138.32624 -58.327431) (xy 138.381354 -58.316581) (xy 138.437464 -58.313929)
			(xy 138.493356 -58.319532) (xy 138.547822 -58.333269) (xy 138.599686 -58.354843) (xy 138.647827 -58.383787)
			(xy 138.691204 -58.419476) (xy 138.72888 -58.46114) (xy 138.760041 -58.507876) (xy 138.784012 -58.558677)
			(xy 138.800277 -58.612442) (xy 138.808484 -58.668012) (xy 138.808968 -58.696098) (xy 138.809417 -58.711138)
			(xy 138.816504 -58.740371) (xy 138.830238 -58.767133) (xy 138.849856 -58.789936) (xy 138.874267 -58.807513)
			(xy 138.902114 -58.818887) (xy 138.916918 -58.821574) (xy 138.943618 -58.826121) (xy 138.995464 -58.841785)
			(xy 139.044581 -58.864609) (xy 139.06754 -58.878978) (xy 139.081374 -58.887522) (xy 139.112224 -58.897776)
			(xy 139.144665 -58.899897) (xy 139.176588 -58.893749) (xy 139.20592 -58.879729) (xy 139.230755 -58.85875)
			(xy 139.249479 -58.832173) (xy 139.260876 -58.801727) (xy 139.264206 -58.769388) (xy 139.259252 -58.737257)
			(xy 139.246336 -58.707423) (xy 139.236704 -58.69432) (xy 139.21989 -58.67205) (xy 139.19221 -58.623601)
			(xy 139.171881 -58.571636) (xy 139.159339 -58.517265) (xy 139.154849 -58.461647) (xy 139.158509 -58.405968)
			(xy 139.17024 -58.351416) (xy 139.189792 -58.299154) (xy 139.216748 -58.250298) (xy 139.250532 -58.205889)
			(xy 139.290425 -58.166874) (xy 139.335574 -58.134087) (xy 139.385019 -58.108225) (xy 139.437702 -58.089841)
			(xy 139.492502 -58.079327) (xy 139.548249 -58.076907) (xy 139.603753 -58.082633) (xy 139.630912 -58.089038)
			(xy 139.652634 -58.094051) (xy 139.697085 -58.097348) (xy 139.741429 -58.092834) (xy 139.784303 -58.080645)
			(xy 139.82439 -58.061156) (xy 139.860458 -58.034967) (xy 139.891398 -58.002882) (xy 139.904216 -57.984644)
			(xy 139.920273 -57.96159) (xy 139.958127 -57.920074) (xy 140.00166 -57.88456) (xy 140.049932 -57.855816)
			(xy 140.101899 -57.834463) (xy 140.156435 -57.820963) (xy 140.212362 -57.81561) (xy 140.268469 -57.818517)
			(xy 140.323542 -57.829623) (xy 140.376391 -57.848688) (xy 140.425872 -57.875298) (xy 140.470914 -57.908878)
			(xy 140.510543 -57.948702) (xy 140.543903 -57.993908) (xy 140.57027 -58.043518) (xy 140.589076 -58.09646)
			(xy 140.599912 -58.151587) (xy 140.602545 -58.207708) (xy 140.596918 -58.263607) (xy 140.583151 -58.318077)
			(xy 140.561544 -58.369938) (xy 140.532564 -58.418069) (xy 140.515086 -58.440066) (xy 140.511225 -58.444975)
			(xy 142.177679 -58.444975) (xy 142.18378 -58.389427) (xy 142.197918 -58.335363) (xy 142.219791 -58.28394)
			(xy 142.248931 -58.236257) (xy 142.284715 -58.193335) (xy 142.326377 -58.156092) (xy 142.373026 -58.125324)
			(xy 142.423664 -58.101691) (xy 142.477208 -58.085696) (xy 142.532513 -58.077683) (xy 142.588394 -58.077823)
			(xy 142.643658 -58.086113) (xy 142.697121 -58.102375) (xy 142.747641 -58.126262) (xy 142.794135 -58.157263)
			(xy 142.83561 -58.194714) (xy 142.871179 -58.237814) (xy 142.90008 -58.285642) (xy 142.921696 -58.337174)
			(xy 142.929102 -58.36412) (xy 142.935211 -58.385962) (xy 142.954107 -58.427187) (xy 142.980018 -58.464407)
			(xy 143.01212 -58.496439) (xy 143.049396 -58.522268) (xy 143.090663 -58.541075) (xy 143.134611 -58.552262)
			(xy 143.157194 -58.554366) (xy 143.183864 -58.55716) (xy 143.206165 -58.559865) (xy 143.251056 -58.558233)
			(xy 143.29496 -58.548734) (xy 143.336511 -58.531665) (xy 143.374413 -58.507556) (xy 143.407487 -58.477159)
			(xy 143.434701 -58.441422) (xy 143.455209 -58.401456) (xy 143.462248 -58.380122) (xy 143.471 -58.353478)
			(xy 143.495104 -58.302845) (xy 143.526362 -58.256287) (xy 143.564101 -58.214807) (xy 143.607505 -58.1793)
			(xy 143.655641 -58.150531) (xy 143.707471 -58.12912) (xy 143.761877 -58.115528) (xy 143.817686 -58.110049)
			(xy 143.873697 -58.112801) (xy 143.928701 -58.123724) (xy 143.981512 -58.142583) (xy 144.030994 -58.168971)
			(xy 144.076078 -58.20232) (xy 144.115793 -58.24191) (xy 144.123587 -58.252378) (xy 146.863815 -58.252378)
			(xy 146.869915 -58.196941) (xy 146.884021 -58.142984) (xy 146.905833 -58.091655) (xy 146.934887 -58.044049)
			(xy 146.970562 -58.001181) (xy 147.012099 -57.963964) (xy 147.058612 -57.933191) (xy 147.109109 -57.909519)
			(xy 147.162516 -57.893451) (xy 147.217692 -57.885331) (xy 147.245578 -57.884822) (xy 147.273464 -57.885331)
			(xy 147.32864 -57.893451) (xy 147.382047 -57.909519) (xy 147.432544 -57.933191) (xy 147.479057 -57.963964)
			(xy 147.520594 -58.001181) (xy 147.556269 -58.044049) (xy 147.585323 -58.091655) (xy 147.607135 -58.142984)
			(xy 147.621241 -58.196941) (xy 147.627341 -58.252378) (xy 147.625304 -58.308112) (xy 147.615174 -58.362955)
			(xy 147.597167 -58.415739) (xy 147.589743 -58.430178) (xy 148.355303 -58.430178) (xy 148.361403 -58.374741)
			(xy 148.375509 -58.320784) (xy 148.397321 -58.269455) (xy 148.426375 -58.221849) (xy 148.46205 -58.178981)
			(xy 148.503587 -58.141764) (xy 148.5501 -58.110991) (xy 148.600597 -58.087319) (xy 148.654004 -58.071251)
			(xy 148.70918 -58.063131) (xy 148.737066 -58.062622) (xy 148.764952 -58.063131) (xy 148.820128 -58.071251)
			(xy 148.873535 -58.087319) (xy 148.924032 -58.110991) (xy 148.970545 -58.141764) (xy 149.012082 -58.178981)
			(xy 149.047757 -58.221849) (xy 149.076811 -58.269455) (xy 149.098623 -58.320784) (xy 149.112729 -58.374741)
			(xy 149.118829 -58.430178) (xy 149.118207 -58.447196) (xy 149.911815 -58.447196) (xy 149.917915 -58.391759)
			(xy 149.932021 -58.337802) (xy 149.953833 -58.286473) (xy 149.982887 -58.238867) (xy 150.018562 -58.195999)
			(xy 150.060099 -58.158782) (xy 150.106612 -58.128009) (xy 150.157109 -58.104337) (xy 150.210516 -58.088269)
			(xy 150.265692 -58.080149) (xy 150.293578 -58.07964) (xy 150.321464 -58.080149) (xy 150.37664 -58.088269)
			(xy 150.430047 -58.104337) (xy 150.480544 -58.128009) (xy 150.527057 -58.158782) (xy 150.568594 -58.195999)
			(xy 150.604269 -58.238867) (xy 150.633323 -58.286473) (xy 150.655135 -58.337802) (xy 150.669241 -58.391759)
			(xy 150.675341 -58.447196) (xy 150.673304 -58.50293) (xy 150.663174 -58.557773) (xy 150.645167 -58.610557)
			(xy 150.619666 -58.660157) (xy 150.587215 -58.705515) (xy 150.548506 -58.745664) (xy 150.504363 -58.77975)
			(xy 150.455728 -58.807046) (xy 150.403637 -58.826969) (xy 150.3492 -58.839095) (xy 150.293578 -58.843166)
			(xy 150.237956 -58.839095) (xy 150.183519 -58.826969) (xy 150.131428 -58.807046) (xy 150.082793 -58.77975)
			(xy 150.03865 -58.745664) (xy 149.999941 -58.705515) (xy 149.96749 -58.660157) (xy 149.941989 -58.610557)
			(xy 149.923982 -58.557773) (xy 149.913852 -58.50293) (xy 149.911815 -58.447196) (xy 149.118207 -58.447196)
			(xy 149.116792 -58.485912) (xy 149.106662 -58.540755) (xy 149.088655 -58.593539) (xy 149.063154 -58.643139)
			(xy 149.030703 -58.688497) (xy 148.991994 -58.728646) (xy 148.947851 -58.762732) (xy 148.899216 -58.790028)
			(xy 148.847125 -58.809951) (xy 148.792688 -58.822077) (xy 148.737066 -58.826148) (xy 148.681444 -58.822077)
			(xy 148.627007 -58.809951) (xy 148.574916 -58.790028) (xy 148.526281 -58.762732) (xy 148.482138 -58.728646)
			(xy 148.443429 -58.688497) (xy 148.410978 -58.643139) (xy 148.385477 -58.593539) (xy 148.36747 -58.540755)
			(xy 148.35734 -58.485912) (xy 148.355303 -58.430178) (xy 147.589743 -58.430178) (xy 147.571666 -58.465339)
			(xy 147.539215 -58.510697) (xy 147.500506 -58.550846) (xy 147.456363 -58.584932) (xy 147.407728 -58.612228)
			(xy 147.355637 -58.632151) (xy 147.3012 -58.644277) (xy 147.245578 -58.648348) (xy 147.189956 -58.644277)
			(xy 147.135519 -58.632151) (xy 147.083428 -58.612228) (xy 147.034793 -58.584932) (xy 146.99065 -58.550846)
			(xy 146.951941 -58.510697) (xy 146.91949 -58.465339) (xy 146.893989 -58.415739) (xy 146.875982 -58.362955)
			(xy 146.865852 -58.308112) (xy 146.863815 -58.252378) (xy 144.123587 -58.252378) (xy 144.149284 -58.286889)
			(xy 144.175828 -58.336287) (xy 144.194853 -58.389039) (xy 144.20595 -58.444008) (xy 144.208878 -58.500009)
			(xy 144.203575 -58.555836) (xy 144.190155 -58.610284) (xy 144.168908 -58.662181) (xy 144.140291 -58.710408)
			(xy 144.104921 -58.753924) (xy 144.06356 -58.791793) (xy 144.023234 -58.819052) (xy 145.948907 -58.819052)
			(xy 145.955007 -58.763615) (xy 145.969113 -58.709658) (xy 145.990925 -58.658329) (xy 146.019979 -58.610723)
			(xy 146.055654 -58.567855) (xy 146.097191 -58.530638) (xy 146.143704 -58.499865) (xy 146.194201 -58.476193)
			(xy 146.247608 -58.460125) (xy 146.302784 -58.452005) (xy 146.33067 -58.451496) (xy 146.358556 -58.452005)
			(xy 146.413732 -58.460125) (xy 146.467139 -58.476193) (xy 146.517636 -58.499865) (xy 146.564149 -58.530638)
			(xy 146.605686 -58.567855) (xy 146.641361 -58.610723) (xy 146.670415 -58.658329) (xy 146.692227 -58.709658)
			(xy 146.706333 -58.763615) (xy 146.712433 -58.819052) (xy 146.710396 -58.874786) (xy 146.700266 -58.929629)
			(xy 146.682259 -58.982413) (xy 146.656758 -59.032013) (xy 146.624307 -59.077371) (xy 146.585598 -59.11752)
			(xy 146.541455 -59.151606) (xy 146.49282 -59.178902) (xy 146.440729 -59.198825) (xy 146.386292 -59.210951)
			(xy 146.33067 -59.215022) (xy 146.275048 -59.210951) (xy 146.220611 -59.198825) (xy 146.16852 -59.178902)
			(xy 146.119885 -59.151606) (xy 146.075742 -59.11752) (xy 146.037033 -59.077371) (xy 146.004582 -59.032013)
			(xy 145.979081 -58.982413) (xy 145.961074 -58.929629) (xy 145.950944 -58.874786) (xy 145.948907 -58.819052)
			(xy 144.023234 -58.819052) (xy 144.017101 -58.823198) (xy 143.966544 -58.847462) (xy 143.912979 -58.864061)
			(xy 143.857561 -58.87264) (xy 143.801485 -58.873011) (xy 143.773652 -58.86958) (xy 143.751352 -58.866863)
			(xy 143.706459 -58.868493) (xy 143.662552 -58.87799) (xy 143.621 -58.895061) (xy 143.583096 -58.919171)
			(xy 143.550022 -58.949571) (xy 143.522809 -58.985313) (xy 143.502305 -59.025282) (xy 143.495268 -59.046618)
			(xy 143.486751 -59.072766) (xy 143.463263 -59.122491) (xy 143.43288 -59.168327) (xy 143.396229 -59.209326)
			(xy 143.354072 -59.244638) (xy 143.30728 -59.27353) (xy 143.256826 -59.295405) (xy 143.203753 -59.309808)
			(xy 143.149162 -59.316441) (xy 143.094184 -59.315167) (xy 143.039959 -59.306012) (xy 142.987611 -59.289166)
			(xy 142.938223 -59.264978) (xy 142.892821 -59.233949) (xy 142.852344 -59.196723) (xy 142.817632 -59.15407)
			(xy 142.789404 -59.106875) (xy 142.768245 -59.056116) (xy 142.760954 -59.0296) (xy 142.754786 -59.007776)
			(xy 142.735898 -58.966554) (xy 142.709997 -58.929336) (xy 142.677904 -58.897302) (xy 142.640638 -58.87147)
			(xy 142.599381 -58.852658) (xy 142.555441 -58.841462) (xy 142.532862 -58.839354) (xy 142.50502 -58.836967)
			(xy 142.45044 -58.824975) (xy 142.398193 -58.80515) (xy 142.349396 -58.777916) (xy 142.305095 -58.743855)
			(xy 142.266235 -58.703696) (xy 142.233649 -58.658299) (xy 142.208034 -58.608634) (xy 142.189937 -58.555763)
			(xy 142.179746 -58.500818) (xy 142.177679 -58.444975) (xy 140.511225 -58.444975) (xy 140.501115 -58.457827)
			(xy 140.478978 -58.497216) (xy 140.464156 -58.539899) (xy 140.457117 -58.584531) (xy 140.458083 -58.629704)
			(xy 140.467023 -58.673994) (xy 140.483655 -58.716004) (xy 140.507455 -58.754411) (xy 140.522198 -58.771536)
			(xy 140.54072 -58.792899) (xy 140.571902 -58.840064) (xy 140.595782 -58.891313) (xy 140.611837 -58.945527)
			(xy 140.619714 -59.001516) (xy 140.619241 -59.058054) (xy 140.610429 -59.113903) (xy 140.593471 -59.16784)
			(xy 140.568738 -59.218684) (xy 140.536771 -59.26532) (xy 140.498272 -59.306728) (xy 140.454083 -59.342)
			(xy 140.405171 -59.370364) (xy 140.35261 -59.391198) (xy 140.297549 -59.404047) (xy 140.241194 -59.408629)
			(xy 140.184781 -59.404842) (xy 140.129544 -59.392772) (xy 140.076694 -59.372681) (xy 140.05179 -59.359292)
			(xy 140.037865 -59.351972) (xy 140.007526 -59.34369) (xy 139.976083 -59.343092) (xy 139.945451 -59.350214)
			(xy 139.917496 -59.364623) (xy 139.893923 -59.38544) (xy 139.884658 -59.398154) (xy 139.868858 -59.420521)
			(xy 139.831805 -59.460845) (xy 139.789365 -59.495454) (xy 139.74241 -59.523635) (xy 139.691907 -59.54481)
			(xy 139.638894 -59.558542) (xy 139.584462 -59.56455) (xy 139.529731 -59.562709) (xy 139.475825 -59.553057)
			(xy 139.423855 -59.535793) (xy 139.374889 -59.511273) (xy 139.329934 -59.48) (xy 139.309602 -59.461654)
			(xy 139.297284 -59.4508) (xy 139.268387 -59.435238) (xy 139.236477 -59.427557) (xy 139.203663 -59.428264)
			(xy 139.172114 -59.437314) (xy 139.143914 -59.454108) (xy 139.132056 -59.465464) (xy 139.121115 -59.476449)
			(xy 139.097719 -59.496796) (xy 139.08532 -59.506104) (xy 139.067228 -59.52008) (xy 139.035862 -59.553333)
			(xy 139.010952 -59.591661) (xy 138.993301 -59.633828) (xy 138.98348 -59.678472) (xy 138.981805 -59.724154)
			(xy 138.98833 -59.769397) (xy 139.002845 -59.812744) (xy 139.013438 -59.833002) (xy 139.026246 -59.857142)
			(xy 139.045489 -59.90829) (xy 139.057238 -59.961661) (xy 139.061251 -60.016161) (xy 139.057448 -60.070677)
			(xy 139.045906 -60.124093) (xy 139.026861 -60.175315) (xy 139.000703 -60.223296) (xy 138.967967 -60.267054)
			(xy 138.929323 -60.305694) (xy 138.885561 -60.338426) (xy 138.837577 -60.364579) (xy 138.786353 -60.383618)
			(xy 138.732936 -60.395154) (xy 138.67842 -60.398951) (xy 138.62392 -60.394932) (xy 138.57055 -60.383177)
			(xy 138.519404 -60.363929) (xy 138.471527 -60.33758) (xy 138.4279 -60.304671) (xy 138.389414 -60.265873)
			(xy 138.356856 -60.221981) (xy 138.330895 -60.173894) (xy 138.312059 -60.122594) (xy 138.300735 -60.069132)
			(xy 138.297155 -60.014601) (xy 138.301391 -59.960117) (xy 138.313357 -59.906795) (xy 138.332809 -59.855726)
			(xy 138.359348 -59.807954) (xy 138.392431 -59.764458) (xy 138.431381 -59.726126) (xy 138.453114 -59.709558)
			(xy 138.47124 -59.695624) (xy 138.502603 -59.662362) (xy 138.527509 -59.624026) (xy 138.545155 -59.581852)
			(xy 138.554972 -59.537202) (xy 138.556642 -59.491517) (xy 138.550112 -59.446269) (xy 138.535592 -59.40292)
			(xy 138.524996 -59.38266) (xy 138.510111 -59.354276) (xy 138.489043 -59.29375) (xy 138.478383 -59.230555)
			(xy 138.477752 -59.19851) (xy 138.477364 -59.183466) (xy 138.470272 -59.154223) (xy 138.45653 -59.127455)
			(xy 138.4369 -59.10465) (xy 138.412474 -59.087077) (xy 138.384613 -59.075713) (xy 138.369802 -59.073034)
			(xy 138.342104 -59.068361) (xy 138.288419 -59.051831) (xy 138.237738 -59.027609) (xy 138.191155 -58.996218)
			(xy 138.149678 -58.958337) (xy 138.114203 -58.914785) (xy 138.085497 -58.866502) (xy 138.064179 -58.814532)
			(xy 138.050712 -58.759998) (xy 138.045385 -58.704079) (xy 134.495788 -58.704079) (xy 134.490259 -58.720285)
			(xy 134.464758 -58.769885) (xy 134.432307 -58.815243) (xy 134.393598 -58.855392) (xy 134.349455 -58.889478)
			(xy 134.30082 -58.916774) (xy 134.248729 -58.936697) (xy 134.194292 -58.948823) (xy 134.13867 -58.952894)
			(xy 134.083048 -58.948823) (xy 134.028611 -58.936697) (xy 133.97652 -58.916774) (xy 133.927885 -58.889478)
			(xy 133.883742 -58.855392) (xy 133.845033 -58.815243) (xy 133.812582 -58.769885) (xy 133.787081 -58.720285)
			(xy 133.769074 -58.667501) (xy 133.758944 -58.612658) (xy 133.756907 -58.556924) (xy 131.585421 -58.556924)
			(xy 131.579799 -58.57561) (xy 131.556111 -58.626141) (xy 131.525317 -58.672685) (xy 131.488075 -58.714249)
			(xy 131.445179 -58.749948) (xy 131.397541 -58.779021) (xy 131.346178 -58.800848) (xy 131.292185 -58.814964)
			(xy 131.236711 -58.821067) (xy 131.18094 -58.819029) (xy 131.126061 -58.808892) (xy 131.073241 -58.790873)
			(xy 131.023609 -58.765355) (xy 130.978221 -58.732883) (xy 130.938044 -58.694148) (xy 130.903936 -58.649976)
			(xy 130.876622 -58.601308) (xy 130.856686 -58.549182) (xy 130.844551 -58.494709) (xy 130.840478 -58.43905)
			(xy 114.898932 -58.43905) (xy 114.903504 -58.443622) (xy 121.41962 -58.443622) (xy 122.271037 -59.295039)
			(xy 125.633225 -59.295039) (xy 125.639328 -59.239565) (xy 125.653444 -59.185572) (xy 125.675271 -59.134209)
			(xy 125.704344 -59.086571) (xy 125.740043 -59.043675) (xy 125.781607 -59.006433) (xy 125.828151 -58.975639)
			(xy 125.878682 -58.951951) (xy 125.932124 -58.935873) (xy 125.987338 -58.927747) (xy 126.015242 -58.927238)
			(xy 126.043146 -58.927747) (xy 126.09836 -58.935873) (xy 126.151802 -58.951951) (xy 126.202333 -58.975639)
			(xy 126.248877 -59.006433) (xy 126.290441 -59.043675) (xy 126.32614 -59.086571) (xy 126.355213 -59.134209)
			(xy 126.37704 -59.185572) (xy 126.391156 -59.239565) (xy 126.397259 -59.295039) (xy 126.395221 -59.35081)
			(xy 126.385084 -59.405689) (xy 126.367065 -59.458509) (xy 126.341547 -59.508141) (xy 126.309075 -59.553529)
			(xy 126.27034 -59.593706) (xy 126.226168 -59.627814) (xy 126.1775 -59.655128) (xy 126.125374 -59.675064)
			(xy 126.070901 -59.687199) (xy 126.015242 -59.691273) (xy 125.959583 -59.687199) (xy 125.90511 -59.675064)
			(xy 125.852984 -59.655128) (xy 125.804316 -59.627814) (xy 125.760144 -59.593706) (xy 125.721409 -59.553529)
			(xy 125.688937 -59.508141) (xy 125.663419 -59.458509) (xy 125.6454 -59.405689) (xy 125.635263 -59.35081)
			(xy 125.633225 -59.295039) (xy 122.271037 -59.295039) (xy 122.798087 -59.822089) (xy 126.383033 -59.822089)
			(xy 126.389136 -59.766615) (xy 126.403252 -59.712622) (xy 126.425079 -59.661259) (xy 126.454152 -59.613621)
			(xy 126.489851 -59.570725) (xy 126.531415 -59.533483) (xy 126.577959 -59.502689) (xy 126.62849 -59.479001)
			(xy 126.681932 -59.462923) (xy 126.737146 -59.454797) (xy 126.76505 -59.454288) (xy 126.792954 -59.454797)
			(xy 126.848168 -59.462923) (xy 126.90161 -59.479001) (xy 126.952141 -59.502689) (xy 126.998685 -59.533483)
			(xy 127.040249 -59.570725) (xy 127.075948 -59.613621) (xy 127.105021 -59.661259) (xy 127.11055 -59.67427)
			(xy 135.933941 -59.67427) (xy 135.940041 -59.618833) (xy 135.954147 -59.564876) (xy 135.975959 -59.513547)
			(xy 136.005013 -59.465941) (xy 136.040688 -59.423073) (xy 136.082225 -59.385856) (xy 136.128738 -59.355083)
			(xy 136.179235 -59.331411) (xy 136.232642 -59.315343) (xy 136.287818 -59.307223) (xy 136.315704 -59.306714)
			(xy 136.34359 -59.307223) (xy 136.398766 -59.315343) (xy 136.452173 -59.331411) (xy 136.50267 -59.355083)
			(xy 136.549183 -59.385856) (xy 136.59072 -59.423073) (xy 136.626395 -59.465941) (xy 136.655449 -59.513547)
			(xy 136.677261 -59.564876) (xy 136.691367 -59.618833) (xy 136.697467 -59.67427) (xy 136.69543 -59.730004)
			(xy 136.6853 -59.784847) (xy 136.667293 -59.837631) (xy 136.641792 -59.887231) (xy 136.609341 -59.932589)
			(xy 136.570632 -59.972738) (xy 136.526489 -60.006824) (xy 136.477854 -60.03412) (xy 136.425763 -60.054043)
			(xy 136.371326 -60.066169) (xy 136.315704 -60.07024) (xy 136.260082 -60.066169) (xy 136.205645 -60.054043)
			(xy 136.153554 -60.03412) (xy 136.104919 -60.006824) (xy 136.060776 -59.972738) (xy 136.022067 -59.932589)
			(xy 135.989616 -59.887231) (xy 135.964115 -59.837631) (xy 135.946108 -59.784847) (xy 135.935978 -59.730004)
			(xy 135.933941 -59.67427) (xy 127.11055 -59.67427) (xy 127.126848 -59.712622) (xy 127.140964 -59.766615)
			(xy 127.147067 -59.822089) (xy 127.145029 -59.87786) (xy 127.134892 -59.932739) (xy 127.116873 -59.985559)
			(xy 127.091355 -60.035191) (xy 127.058883 -60.080579) (xy 127.020148 -60.120756) (xy 126.975976 -60.154864)
			(xy 126.927308 -60.182178) (xy 126.875182 -60.202114) (xy 126.820709 -60.214249) (xy 126.76505 -60.218323)
			(xy 126.709391 -60.214249) (xy 126.654918 -60.202114) (xy 126.602792 -60.182178) (xy 126.554124 -60.154864)
			(xy 126.509952 -60.120756) (xy 126.471217 -60.080579) (xy 126.438745 -60.035191) (xy 126.413227 -59.985559)
			(xy 126.395208 -59.932739) (xy 126.385071 -59.87786) (xy 126.383033 -59.822089) (xy 122.798087 -59.822089)
			(xy 122.90552 -59.929522) (xy 122.90552 -61.146497) (xy 150.356771 -61.146497) (xy 150.362343 -61.092162)
			(xy 150.375606 -61.039177) (xy 150.396291 -60.988626) (xy 150.423974 -60.941541) (xy 150.458088 -60.898886)
			(xy 150.497938 -60.861531) (xy 150.542707 -60.830242) (xy 150.591481 -60.805657) (xy 150.643262 -60.788279)
			(xy 150.696993 -60.778464) (xy 150.751574 -60.776412) (xy 150.80589 -60.782164) (xy 150.85883 -60.795604)
			(xy 150.909312 -60.816457) (xy 150.956304 -60.844296) (xy 150.998846 -60.878553) (xy 151.036068 -60.918526)
			(xy 151.052022 -60.940696) (xy 151.061933 -60.954092) (xy 151.087357 -60.975619) (xy 151.117486 -60.989832)
			(xy 151.150266 -60.995763) (xy 151.183465 -60.993007) (xy 151.214819 -60.981753) (xy 151.242192 -60.962767)
			(xy 151.263719 -60.937343) (xy 151.277932 -60.907214) (xy 151.281384 -60.890912) (xy 151.283911 -60.877504)
			(xy 151.290651 -60.851063) (xy 151.294846 -60.83808) (xy 151.301552 -60.816206) (xy 151.307985 -60.770917)
			(xy 151.30621 -60.725207) (xy 151.296285 -60.680552) (xy 151.27853 -60.638394) (xy 151.253518 -60.600094)
			(xy 151.222057 -60.566887) (xy 151.185161 -60.539845) (xy 151.144022 -60.519841) (xy 151.122126 -60.513214)
			(xy 151.09576 -60.505284) (xy 151.045434 -60.482954) (xy 150.998842 -60.453622) (xy 150.95695 -60.417895)
			(xy 150.920631 -60.376517) (xy 150.890638 -60.330347) (xy 150.867594 -60.280344) (xy 150.851979 -60.227548)
			(xy 150.844117 -60.173056) (xy 150.844171 -60.117999) (xy 150.85214 -60.063522) (xy 150.867858 -60.010757)
			(xy 150.890999 -59.960799) (xy 150.921083 -59.914688) (xy 150.957483 -59.873381) (xy 150.999444 -59.837736)
			(xy 151.046094 -59.808495) (xy 151.096463 -59.786264) (xy 151.149505 -59.771506) (xy 151.204117 -59.764527)
			(xy 151.259166 -59.765473) (xy 151.313507 -59.774323) (xy 151.366011 -59.790893) (xy 151.415587 -59.814841)
			(xy 151.461205 -59.845667) (xy 151.501917 -59.882731) (xy 151.536878 -59.925264) (xy 151.56536 -59.972381)
			(xy 151.586772 -60.023104) (xy 151.600669 -60.076378) (xy 151.606763 -60.131096) (xy 151.604926 -60.186122)
			(xy 151.595197 -60.240313) (xy 151.586946 -60.26658) (xy 151.580176 -60.288435) (xy 151.573752 -60.333731)
			(xy 151.575536 -60.379446) (xy 151.58547 -60.424104) (xy 151.603233 -60.466264) (xy 151.628252 -60.504566)
			(xy 151.65972 -60.537774) (xy 151.696622 -60.564816) (xy 151.737767 -60.584819) (xy 151.759666 -60.591446)
			(xy 151.784275 -60.598769) (xy 151.831413 -60.619118) (xy 151.875395 -60.64561) (xy 151.915423 -60.677765)
			(xy 151.933402 -60.696094) (xy 151.948897 -60.711673) (xy 151.98415 -60.73789) (xy 152.02339 -60.757648)
			(xy 152.065444 -60.770356) (xy 152.109058 -60.775637) (xy 152.152931 -60.773331) (xy 152.195751 -60.763509)
			(xy 152.236242 -60.746462) (xy 152.273195 -60.7227) (xy 152.305505 -60.692933) (xy 152.319228 -60.675774)
			(xy 152.335971 -60.654697) (xy 152.374404 -60.617008) (xy 152.417752 -60.585096) (xy 152.465156 -60.559593)
			(xy 152.515673 -60.541007) (xy 152.568302 -60.529705) (xy 152.621996 -60.525912) (xy 152.67569 -60.529705)
			(xy 152.728319 -60.541007) (xy 152.778836 -60.559593) (xy 152.82624 -60.585096) (xy 152.869588 -60.617008)
			(xy 152.908021 -60.654697) (xy 152.924764 -60.675774) (xy 152.938547 -60.692876) (xy 152.970869 -60.722609)
			(xy 153.00782 -60.746343) (xy 153.048301 -60.763373) (xy 153.091107 -60.773191) (xy 153.134963 -60.775506)
			(xy 153.178565 -60.770247) (xy 153.220613 -60.757573) (xy 153.259857 -60.737859) (xy 153.295129 -60.711694)
			(xy 153.31059 -60.696094) (xy 153.327379 -60.678958) (xy 153.364475 -60.648539) (xy 153.405084 -60.622998)
			(xy 153.426668 -60.612528) (xy 153.446536 -60.602699) (xy 153.482896 -60.577358) (xy 153.514306 -60.546092)
			(xy 153.539814 -60.509849) (xy 153.558645 -60.46973) (xy 153.570228 -60.426951) (xy 153.574212 -60.382811)
			(xy 153.570475 -60.33865) (xy 153.559131 -60.295808) (xy 153.540525 -60.255584) (xy 153.528268 -60.237116)
			(xy 153.512962 -60.214338) (xy 153.488351 -60.165289) (xy 153.471022 -60.113219) (xy 153.461329 -60.059205)
			(xy 153.459474 -60.004359) (xy 153.465495 -59.949813) (xy 153.479268 -59.896691) (xy 153.500508 -59.846091)
			(xy 153.528777 -59.799055) (xy 153.563493 -59.756554) (xy 153.603939 -59.719464) (xy 153.64928 -59.68855)
			(xy 153.698583 -59.664451) (xy 153.750829 -59.647662) (xy 153.804942 -59.638531) (xy 153.859804 -59.637246)
			(xy 153.914285 -59.643833) (xy 153.96726 -59.658156) (xy 154.017637 -59.67992) (xy 154.064377 -59.708676)
			(xy 154.106516 -59.743831) (xy 154.143184 -59.78466) (xy 154.173625 -59.83032) (xy 154.197212 -59.87987)
			(xy 154.213457 -59.932288) (xy 154.222026 -59.986492) (xy 154.222742 -60.041365) (xy 154.21559 -60.095774)
			(xy 154.200717 -60.148598) (xy 154.178431 -60.198747) (xy 154.149192 -60.245185) (xy 154.113601 -60.286957)
			(xy 154.072394 -60.323199) (xy 154.02642 -60.353165) (xy 154.001724 -60.365132) (xy 153.981815 -60.374882)
			(xy 153.945452 -60.400233) (xy 153.91404 -60.431509) (xy 153.888533 -60.467762) (xy 153.869704 -60.507892)
			(xy 153.858125 -60.55068) (xy 153.854147 -60.594829) (xy 153.857892 -60.638998) (xy 153.869245 -60.681847)
			(xy 153.887862 -60.722075) (xy 153.900124 -60.740544) (xy 153.915786 -60.76393) (xy 153.940851 -60.814322)
			(xy 153.958241 -60.86785) (xy 153.967577 -60.923352) (xy 153.968225 -60.957138) (xy 154.246622 -60.957138)
			(xy 154.250765 -60.90257) (xy 154.262664 -60.849154) (xy 154.282073 -60.797986) (xy 154.308595 -60.750117)
			(xy 154.341685 -60.70653) (xy 154.380665 -60.668118) (xy 154.424733 -60.635671) (xy 154.472985 -60.609854)
			(xy 154.498548 -60.600082) (xy 154.520635 -60.591523) (xy 154.561413 -60.567435) (xy 154.59702 -60.536204)
			(xy 154.62622 -60.498915) (xy 154.648002 -60.456859) (xy 154.66161 -60.411494) (xy 154.666573 -60.364393)
			(xy 154.665172 -60.340748) (xy 154.663391 -60.313436) (xy 154.66682 -60.258811) (xy 154.678021 -60.205236)
			(xy 154.696763 -60.153812) (xy 154.72266 -60.105593) (xy 154.755183 -60.061571) (xy 154.793663 -60.022648)
			(xy 154.83731 -59.989623) (xy 154.885229 -59.963174) (xy 154.936435 -59.943845) (xy 154.989878 -59.932031)
			(xy 155.04446 -59.927976) (xy 155.099062 -59.931763) (xy 155.152563 -59.943313) (xy 155.203864 -59.962391)
			(xy 155.251912 -59.988603) (xy 155.295721 -60.021413) (xy 155.334391 -60.060146) (xy 155.36713 -60.104008)
			(xy 155.393265 -60.152099) (xy 155.412259 -60.20343) (xy 155.423723 -60.256949) (xy 155.427422 -60.311557)
			(xy 155.423278 -60.366133) (xy 155.411378 -60.419557) (xy 155.391966 -60.470732) (xy 155.36544 -60.518608)
			(xy 155.332345 -60.562201) (xy 155.29336 -60.600618) (xy 155.249285 -60.63307) (xy 155.201025 -60.65889)
			(xy 155.19867 -60.65979) (xy 156.533849 -60.65979) (xy 156.539949 -60.604353) (xy 156.554055 -60.550396)
			(xy 156.575867 -60.499067) (xy 156.604921 -60.451461) (xy 156.640596 -60.408593) (xy 156.682133 -60.371376)
			(xy 156.728646 -60.340603) (xy 156.779143 -60.316931) (xy 156.83255 -60.300863) (xy 156.887726 -60.292743)
			(xy 156.915612 -60.292234) (xy 156.943498 -60.292743) (xy 156.998674 -60.300863) (xy 157.052081 -60.316931)
			(xy 157.102578 -60.340603) (xy 157.149091 -60.371376) (xy 157.190628 -60.408593) (xy 157.226303 -60.451461)
			(xy 157.255357 -60.499067) (xy 157.277169 -60.550396) (xy 157.291275 -60.604353) (xy 157.297375 -60.65979)
			(xy 157.295338 -60.715524) (xy 157.285208 -60.770367) (xy 157.267201 -60.823151) (xy 157.2417 -60.872751)
			(xy 157.209249 -60.918109) (xy 157.17054 -60.958258) (xy 157.126397 -60.992344) (xy 157.077762 -61.01964)
			(xy 157.025671 -61.039563) (xy 156.971234 -61.051689) (xy 156.915612 -61.05576) (xy 156.85999 -61.051689)
			(xy 156.805553 -61.039563) (xy 156.753462 -61.01964) (xy 156.704827 -60.992344) (xy 156.660684 -60.958258)
			(xy 156.621975 -60.918109) (xy 156.589524 -60.872751) (xy 156.564023 -60.823151) (xy 156.546016 -60.770367)
			(xy 156.535886 -60.715524) (xy 156.533849 -60.65979) (xy 155.19867 -60.65979) (xy 155.175458 -60.668662)
			(xy 155.153373 -60.677222) (xy 155.112601 -60.701317) (xy 155.077001 -60.73255) (xy 155.047804 -60.769839)
			(xy 155.026022 -60.811893) (xy 155.012409 -60.857254) (xy 155.007438 -60.904352) (xy 155.008834 -60.927996)
			(xy 155.010566 -60.955308) (xy 155.007131 -61.009925) (xy 154.995926 -61.063491) (xy 154.977182 -61.114906)
			(xy 154.951283 -61.163114) (xy 154.918761 -61.207127) (xy 154.880284 -61.246042) (xy 154.83664 -61.279058)
			(xy 154.788726 -61.305499) (xy 154.737526 -61.324821) (xy 154.68409 -61.336629) (xy 154.629515 -61.34068)
			(xy 154.574921 -61.336891) (xy 154.521429 -61.325339) (xy 154.470137 -61.306262) (xy 154.422097 -61.280051)
			(xy 154.378296 -61.247244) (xy 154.339632 -61.208515) (xy 154.3069 -61.164658) (xy 154.28077 -61.116574)
			(xy 154.26178 -61.065249) (xy 154.250319 -61.011738) (xy 154.246622 -60.957138) (xy 153.968225 -60.957138)
			(xy 153.968657 -60.979623) (xy 153.961458 -61.035442) (xy 153.946136 -61.089598) (xy 153.923023 -61.140915)
			(xy 153.892622 -61.188279) (xy 153.855591 -61.230663) (xy 153.812735 -61.267146) (xy 153.764984 -61.296936)
			(xy 153.713375 -61.319387) (xy 153.659026 -61.334012) (xy 153.603119 -61.340493) (xy 153.546866 -61.33869)
			(xy 153.491489 -61.328641) (xy 153.438189 -61.310566) (xy 153.388123 -61.284855) (xy 153.342378 -61.252067)
			(xy 153.301947 -61.212914) (xy 153.284428 -61.190886) (xy 153.270652 -61.173776) (xy 153.238332 -61.144037)
			(xy 153.201381 -61.120298) (xy 153.160898 -61.103264) (xy 153.118089 -61.093444) (xy 153.07423 -61.09113)
			(xy 153.030626 -61.096391) (xy 152.988576 -61.10907) (xy 152.949331 -61.128789) (xy 152.914061 -61.154962)
			(xy 152.898602 -61.170566) (xy 152.878857 -61.19063) (xy 152.834518 -61.225312) (xy 152.785563 -61.253101)
			(xy 152.733055 -61.273393) (xy 152.678135 -61.285747) (xy 152.621996 -61.289895) (xy 152.565857 -61.285747)
			(xy 152.510937 -61.273393) (xy 152.458429 -61.253101) (xy 152.409474 -61.225312) (xy 152.365135 -61.19063)
			(xy 152.34539 -61.170566) (xy 152.329908 -61.154972) (xy 152.294655 -61.128749) (xy 152.255414 -61.108986)
			(xy 152.213356 -61.096274) (xy 152.169738 -61.090993) (xy 152.125862 -61.0933) (xy 152.083038 -61.103126)
			(xy 152.042545 -61.120179) (xy 152.005593 -61.143947) (xy 151.973284 -61.173723) (xy 151.959564 -61.190886)
			(xy 151.942954 -61.211689) (xy 151.904989 -61.249002) (xy 151.862206 -61.280676) (xy 151.815437 -61.306097)
			(xy 151.765588 -61.324771) (xy 151.713628 -61.336336) (xy 151.660565 -61.340567) (xy 151.607429 -61.337382)
			(xy 151.555251 -61.326844) (xy 151.505044 -61.309156) (xy 151.457783 -61.284662) (xy 151.435816 -61.269626)
			(xy 151.416361 -61.25644) (xy 151.373695 -61.236742) (xy 151.328136 -61.225216) (xy 151.281235 -61.222254)
			(xy 151.234589 -61.227958) (xy 151.189783 -61.242133) (xy 151.148344 -61.264296) (xy 151.111681 -61.293694)
			(xy 151.081041 -61.329327) (xy 151.068786 -61.349382) (xy 151.054661 -61.372761) (xy 151.020831 -61.415642)
			(xy 150.981231 -61.453261) (xy 150.936671 -61.484848) (xy 150.888062 -61.509756) (xy 150.836397 -61.527478)
			(xy 150.782733 -61.537651) (xy 150.728167 -61.540066) (xy 150.673814 -61.534675) (xy 150.620786 -61.521588)
			(xy 150.570166 -61.501071) (xy 150.522989 -61.473545) (xy 150.48022 -61.439573) (xy 150.442733 -61.399848)
			(xy 150.411295 -61.355183) (xy 150.386548 -61.306491) (xy 150.368998 -61.254768) (xy 150.359004 -61.20107)
			(xy 150.356771 -61.146497) (xy 122.90552 -61.146497) (xy 122.90552 -61.676806) (xy 123.777501 -61.676806)
			(xy 123.783601 -61.621369) (xy 123.797707 -61.567412) (xy 123.819519 -61.516083) (xy 123.848573 -61.468477)
			(xy 123.884248 -61.425609) (xy 123.925785 -61.388392) (xy 123.972298 -61.357619) (xy 124.022795 -61.333947)
			(xy 124.076202 -61.317879) (xy 124.131378 -61.309759) (xy 124.159264 -61.30925) (xy 124.18715 -61.309759)
			(xy 124.242326 -61.317879) (xy 124.295733 -61.333947) (xy 124.34623 -61.357619) (xy 124.392743 -61.388392)
			(xy 124.43428 -61.425609) (xy 124.469955 -61.468477) (xy 124.499009 -61.516083) (xy 124.520821 -61.567412)
			(xy 124.534927 -61.621369) (xy 124.541027 -61.676806) (xy 124.53899 -61.73254) (xy 124.52886 -61.787383)
			(xy 124.510853 -61.840167) (xy 124.485352 -61.889767) (xy 124.452901 -61.935125) (xy 124.414192 -61.975274)
			(xy 124.370049 -62.00936) (xy 124.321414 -62.036656) (xy 124.269323 -62.056579) (xy 124.214886 -62.068705)
			(xy 124.159264 -62.072776) (xy 124.103642 -62.068705) (xy 124.049205 -62.056579) (xy 123.997114 -62.036656)
			(xy 123.948479 -62.00936) (xy 123.904336 -61.975274) (xy 123.865627 -61.935125) (xy 123.833176 -61.889767)
			(xy 123.807675 -61.840167) (xy 123.789668 -61.787383) (xy 123.779538 -61.73254) (xy 123.777501 -61.676806)
			(xy 122.90552 -61.676806) (xy 122.90552 -62.857906) (xy 131.106417 -62.857906) (xy 131.112517 -62.802469)
			(xy 131.126623 -62.748512) (xy 131.148435 -62.697183) (xy 131.177489 -62.649577) (xy 131.213164 -62.606709)
			(xy 131.254701 -62.569492) (xy 131.301214 -62.538719) (xy 131.351711 -62.515047) (xy 131.405118 -62.498979)
			(xy 131.460294 -62.490859) (xy 131.48818 -62.49035) (xy 131.516066 -62.490859) (xy 131.571242 -62.498979)
			(xy 131.624649 -62.515047) (xy 131.675146 -62.538719) (xy 131.721659 -62.569492) (xy 131.763196 -62.606709)
			(xy 131.798871 -62.649577) (xy 131.827925 -62.697183) (xy 131.849737 -62.748512) (xy 131.863843 -62.802469)
			(xy 131.869943 -62.857906) (xy 131.867906 -62.91364) (xy 131.857776 -62.968483) (xy 131.839769 -63.021267)
			(xy 131.814268 -63.070867) (xy 131.781817 -63.116225) (xy 131.743108 -63.156374) (xy 131.698965 -63.19046)
			(xy 131.65033 -63.217756) (xy 131.598239 -63.237679) (xy 131.543802 -63.249805) (xy 131.48818 -63.253876)
			(xy 131.432558 -63.249805) (xy 131.378121 -63.237679) (xy 131.32603 -63.217756) (xy 131.277395 -63.19046)
			(xy 131.233252 -63.156374) (xy 131.194543 -63.116225) (xy 131.162092 -63.070867) (xy 131.136591 -63.021267)
			(xy 131.118584 -62.968483) (xy 131.108454 -62.91364) (xy 131.106417 -62.857906) (xy 122.90552 -62.857906)
			(xy 122.90552 -63.511481) (xy 135.704126 -63.511481) (xy 135.709099 -63.457378) (xy 135.721698 -63.404528)
			(xy 135.741668 -63.353999) (xy 135.768605 -63.306816) (xy 135.801965 -63.263932) (xy 135.841072 -63.226215)
			(xy 135.862822 -63.209932) (xy 135.880369 -63.196772) (xy 135.91099 -63.165371) (xy 135.935759 -63.129175)
			(xy 135.95394 -63.089261) (xy 135.964993 -63.046817) (xy 135.968587 -63.003105) (xy 135.964616 -62.959425)
			(xy 135.953199 -62.917077) (xy 135.944356 -62.897004) (xy 135.933032 -62.871564) (xy 135.917149 -62.818191)
			(xy 135.909194 -62.763076) (xy 135.909335 -62.707391) (xy 135.91757 -62.652317) (xy 135.933723 -62.599025)
			(xy 135.957452 -62.548648) (xy 135.988251 -62.502255) (xy 136.025467 -62.460832) (xy 136.06831 -62.425259)
			(xy 136.115869 -62.396292) (xy 136.167133 -62.374546) (xy 136.221014 -62.360483) (xy 136.276367 -62.354402)
			(xy 136.332016 -62.356432) (xy 136.386778 -62.36653) (xy 136.439491 -62.384482) (xy 136.470118 -62.400198)
			(xy 138.226799 -62.400198) (xy 138.232899 -62.344761) (xy 138.247005 -62.290804) (xy 138.268817 -62.239475)
			(xy 138.297871 -62.191869) (xy 138.333546 -62.149001) (xy 138.375083 -62.111784) (xy 138.421596 -62.081011)
			(xy 138.472093 -62.057339) (xy 138.5255 -62.041271) (xy 138.580676 -62.033151) (xy 138.608562 -62.032642)
			(xy 138.636448 -62.033151) (xy 138.691624 -62.041271) (xy 138.745031 -62.057339) (xy 138.795528 -62.081011)
			(xy 138.842041 -62.111784) (xy 138.883578 -62.149001) (xy 138.919253 -62.191869) (xy 138.948307 -62.239475)
			(xy 138.970119 -62.290804) (xy 138.984225 -62.344761) (xy 138.990325 -62.400198) (xy 138.988288 -62.455932)
			(xy 138.978158 -62.510775) (xy 138.960151 -62.563559) (xy 138.93465 -62.613159) (xy 138.902199 -62.658517)
			(xy 138.86349 -62.698666) (xy 138.819347 -62.732752) (xy 138.799103 -62.744114) (xy 139.341097 -62.744114)
			(xy 139.347197 -62.688677) (xy 139.361303 -62.63472) (xy 139.383115 -62.583391) (xy 139.412169 -62.535785)
			(xy 139.447844 -62.492917) (xy 139.489381 -62.4557) (xy 139.535894 -62.424927) (xy 139.586391 -62.401255)
			(xy 139.639798 -62.385187) (xy 139.694974 -62.377067) (xy 139.72286 -62.376558) (xy 139.750746 -62.377067)
			(xy 139.805922 -62.385187) (xy 139.859329 -62.401255) (xy 139.909826 -62.424927) (xy 139.956339 -62.4557)
			(xy 139.997876 -62.492917) (xy 140.033551 -62.535785) (xy 140.062605 -62.583391) (xy 140.084417 -62.63472)
			(xy 140.087384 -62.64607) (xy 143.045941 -62.64607) (xy 143.052041 -62.590633) (xy 143.066147 -62.536676)
			(xy 143.087959 -62.485347) (xy 143.117013 -62.437741) (xy 143.152688 -62.394873) (xy 143.194225 -62.357656)
			(xy 143.240738 -62.326883) (xy 143.291235 -62.303211) (xy 143.344642 -62.287143) (xy 143.399818 -62.279023)
			(xy 143.427704 -62.278514) (xy 143.45559 -62.279023) (xy 143.510766 -62.287143) (xy 143.564173 -62.303211)
			(xy 143.61467 -62.326883) (xy 143.661183 -62.357656) (xy 143.70272 -62.394873) (xy 143.738395 -62.437741)
			(xy 143.767449 -62.485347) (xy 143.789261 -62.536676) (xy 143.803367 -62.590633) (xy 143.809467 -62.64607)
			(xy 144.798541 -62.64607) (xy 144.804641 -62.590633) (xy 144.818747 -62.536676) (xy 144.840559 -62.485347)
			(xy 144.869613 -62.437741) (xy 144.905288 -62.394873) (xy 144.946825 -62.357656) (xy 144.993338 -62.326883)
			(xy 145.043835 -62.303211) (xy 145.097242 -62.287143) (xy 145.152418 -62.279023) (xy 145.180304 -62.278514)
			(xy 145.20819 -62.279023) (xy 145.263366 -62.287143) (xy 145.316773 -62.303211) (xy 145.36727 -62.326883)
			(xy 145.413783 -62.357656) (xy 145.45532 -62.394873) (xy 145.490995 -62.437741) (xy 145.520049 -62.485347)
			(xy 145.541861 -62.536676) (xy 145.555967 -62.590633) (xy 145.562067 -62.64607) (xy 146.449541 -62.64607)
			(xy 146.455641 -62.590633) (xy 146.469747 -62.536676) (xy 146.491559 -62.485347) (xy 146.520613 -62.437741)
			(xy 146.556288 -62.394873) (xy 146.597825 -62.357656) (xy 146.644338 -62.326883) (xy 146.694835 -62.303211)
			(xy 146.748242 -62.287143) (xy 146.803418 -62.279023) (xy 146.831304 -62.278514) (xy 146.85919 -62.279023)
			(xy 146.914366 -62.287143) (xy 146.967773 -62.303211) (xy 147.01827 -62.326883) (xy 147.064783 -62.357656)
			(xy 147.10632 -62.394873) (xy 147.141995 -62.437741) (xy 147.171049 -62.485347) (xy 147.192861 -62.536676)
			(xy 147.206967 -62.590633) (xy 147.213067 -62.64607) (xy 147.21103 -62.701804) (xy 147.203576 -62.74216)
			(xy 150.204447 -62.74216) (xy 150.210774 -62.68708) (xy 150.225008 -62.633495) (xy 150.24685 -62.582536)
			(xy 150.275838 -62.535275) (xy 150.311362 -62.492709) (xy 150.352674 -62.455733) (xy 150.398904 -62.425127)
			(xy 150.449077 -62.401536) (xy 150.502136 -62.385456) (xy 150.556965 -62.377227) (xy 150.612407 -62.377021)
			(xy 150.667295 -62.384843) (xy 150.720473 -62.400529) (xy 150.77082 -62.423747) (xy 150.817275 -62.454009)
			(xy 150.85886 -62.490677) (xy 150.8947 -62.532978) (xy 150.924038 -62.580023) (xy 150.946257 -62.630818)
			(xy 150.960888 -62.684296) (xy 150.967625 -62.739327) (xy 150.966323 -62.794755) (xy 150.957012 -62.84941)
			(xy 150.939887 -62.902142) (xy 150.915309 -62.951839) (xy 150.883796 -62.997455) (xy 150.846011 -63.038028)
			(xy 150.824692 -63.055754) (xy 150.80717 -63.07042) (xy 150.777211 -63.104917) (xy 150.753902 -63.144213)
			(xy 150.737993 -63.187044) (xy 150.729998 -63.232029) (xy 150.730173 -63.277718) (xy 150.738514 -63.32264)
			(xy 150.754751 -63.365348) (xy 150.778361 -63.404464) (xy 150.804393 -63.433978) (xy 151.198833 -63.433978)
			(xy 151.204933 -63.378541) (xy 151.219039 -63.324584) (xy 151.240851 -63.273255) (xy 151.269905 -63.225649)
			(xy 151.30558 -63.182781) (xy 151.347117 -63.145564) (xy 151.39363 -63.114791) (xy 151.444127 -63.091119)
			(xy 151.497534 -63.075051) (xy 151.55271 -63.066931) (xy 151.580596 -63.066422) (xy 151.608482 -63.066931)
			(xy 151.663658 -63.075051) (xy 151.717065 -63.091119) (xy 151.767562 -63.114791) (xy 151.814075 -63.145564)
			(xy 151.855612 -63.182781) (xy 151.891287 -63.225649) (xy 151.920341 -63.273255) (xy 151.942153 -63.324584)
			(xy 151.956259 -63.378541) (xy 151.962359 -63.433978) (xy 151.96084 -63.475548) (xy 152.240944 -63.475548)
			(xy 152.240948 -63.420206) (xy 152.248947 -63.365444) (xy 152.264773 -63.312413) (xy 152.288095 -63.262225)
			(xy 152.318423 -63.215933) (xy 152.355121 -63.174508) (xy 152.397418 -63.138819) (xy 152.444428 -63.109616)
			(xy 152.495164 -63.087511) (xy 152.548561 -63.072967) (xy 152.603499 -63.066291) (xy 152.658825 -63.067622)
			(xy 152.713379 -63.076931) (xy 152.766015 -63.094025) (xy 152.815629 -63.118544) (xy 152.861181 -63.149973)
			(xy 152.901714 -63.187654) (xy 152.91943 -63.208916) (xy 152.934053 -63.226285) (xy 152.96835 -63.256032)
			(xy 153.007386 -63.279211) (xy 153.049919 -63.295087) (xy 153.094596 -63.303153) (xy 153.139996 -63.303153)
			(xy 153.184673 -63.295087) (xy 153.227206 -63.279211) (xy 153.266242 -63.256032) (xy 153.300539 -63.226285)
			(xy 153.315162 -63.208916) (xy 153.332197 -63.188559) (xy 153.370863 -63.152198) (xy 153.414197 -63.121547)
			(xy 153.46136 -63.097198) (xy 153.511443 -63.079622) (xy 153.563479 -63.069156) (xy 153.616463 -63.066005)
			(xy 153.669372 -63.070227) (xy 153.721186 -63.081742) (xy 153.770903 -63.100328) (xy 153.817564 -63.125626)
			(xy 153.860269 -63.157147) (xy 153.87955 -63.175388) (xy 153.895499 -63.190343) (xy 153.93153 -63.215103)
			(xy 153.971268 -63.23333) (xy 154.013539 -63.244485) (xy 154.057096 -63.248241) (xy 154.100653 -63.244485)
			(xy 154.142924 -63.23333) (xy 154.182662 -63.215103) (xy 154.218693 -63.190343) (xy 154.234642 -63.175388)
			(xy 154.254945 -63.156126) (xy 154.300217 -63.123223) (xy 154.34981 -63.097286) (xy 154.40266 -63.078872)
			(xy 154.457633 -63.068377) (xy 154.513549 -63.066026) (xy 154.569209 -63.071869) (xy 154.623419 -63.08578)
			(xy 154.675014 -63.107462) (xy 154.722888 -63.136448) (xy 154.766014 -63.172118) (xy 154.803466 -63.213705)
			(xy 154.834441 -63.260318) (xy 154.858275 -63.310955) (xy 154.874454 -63.364531) (xy 154.882633 -63.419896)
			(xy 154.882636 -63.475862) (xy 154.874463 -63.531228) (xy 154.85829 -63.584806) (xy 154.834462 -63.635446)
			(xy 154.803492 -63.682062) (xy 154.766045 -63.723653) (xy 154.722922 -63.759327) (xy 154.675051 -63.788319)
			(xy 154.623458 -63.810007) (xy 154.569251 -63.823924) (xy 154.513591 -63.829773) (xy 154.457675 -63.827428)
			(xy 154.4027 -63.816939) (xy 154.349848 -63.798531) (xy 154.300253 -63.7726) (xy 154.254977 -63.739701)
			(xy 154.234642 -63.720472) (xy 154.218693 -63.705517) (xy 154.182662 -63.680757) (xy 154.142924 -63.66253)
			(xy 154.100653 -63.651375) (xy 154.057096 -63.647619) (xy 154.013539 -63.651375) (xy 153.971268 -63.66253)
			(xy 153.93153 -63.680757) (xy 153.895499 -63.705517) (xy 153.87955 -63.720472) (xy 153.860226 -63.738674)
			(xy 153.817531 -63.770214) (xy 153.770875 -63.79553) (xy 153.721159 -63.814132) (xy 153.669345 -63.825661)
			(xy 153.616432 -63.829895) (xy 153.563443 -63.826752) (xy 153.511402 -63.816292) (xy 153.461314 -63.798717)
			(xy 153.414147 -63.774367) (xy 153.370811 -63.743713) (xy 153.332144 -63.707346) (xy 153.315162 -63.686944)
			(xy 153.300539 -63.669575) (xy 153.266242 -63.639828) (xy 153.227206 -63.616649) (xy 153.184673 -63.600773)
			(xy 153.139996 -63.592707) (xy 153.094596 -63.592707) (xy 153.049919 -63.600773) (xy 153.007386 -63.616649)
			(xy 152.96835 -63.639828) (xy 152.934053 -63.669575) (xy 152.91943 -63.686944) (xy 152.901682 -63.70818)
			(xy 152.861144 -63.745856) (xy 152.815589 -63.77728) (xy 152.765971 -63.801793) (xy 152.713333 -63.81888)
			(xy 152.658779 -63.828183) (xy 152.603452 -63.829507) (xy 152.548515 -63.822824) (xy 152.49512 -63.808274)
			(xy 152.444387 -63.786162) (xy 152.39738 -63.756953) (xy 152.355087 -63.721259) (xy 152.318394 -63.67983)
			(xy 152.288072 -63.633534) (xy 152.264756 -63.583343) (xy 152.248936 -63.53031) (xy 152.240944 -63.475548)
			(xy 151.96084 -63.475548) (xy 151.960322 -63.489712) (xy 151.950192 -63.544555) (xy 151.932185 -63.597339)
			(xy 151.906684 -63.646939) (xy 151.874233 -63.692297) (xy 151.835524 -63.732446) (xy 151.791381 -63.766532)
			(xy 151.742746 -63.793828) (xy 151.690655 -63.813751) (xy 151.636218 -63.825877) (xy 151.580596 -63.829948)
			(xy 151.524974 -63.825877) (xy 151.470537 -63.813751) (xy 151.418446 -63.793828) (xy 151.369811 -63.766532)
			(xy 151.325668 -63.732446) (xy 151.286959 -63.692297) (xy 151.254508 -63.646939) (xy 151.229007 -63.597339)
			(xy 151.211 -63.544555) (xy 151.20087 -63.489712) (xy 151.198833 -63.433978) (xy 150.804393 -63.433978)
			(xy 150.808584 -63.43873) (xy 150.826216 -63.453264) (xy 150.847631 -63.470874) (xy 150.885712 -63.511167)
			(xy 150.91756 -63.556547) (xy 150.942503 -63.60606) (xy 150.960015 -63.658662) (xy 150.969729 -63.713246)
			(xy 150.971438 -63.76866) (xy 150.965108 -63.823738) (xy 150.950871 -63.87732) (xy 150.929028 -63.928276)
			(xy 150.900038 -63.975533) (xy 150.864513 -64.018096) (xy 150.8232 -64.055069) (xy 150.776971 -64.085671)
			(xy 150.726798 -64.109259) (xy 150.673739 -64.125335) (xy 150.618912 -64.133561) (xy 150.563472 -64.133763)
			(xy 150.508586 -64.125938) (xy 150.455411 -64.11025) (xy 150.405068 -64.08703) (xy 150.358616 -64.056766)
			(xy 150.317034 -64.020097) (xy 150.281199 -63.977795) (xy 150.251864 -63.93075) (xy 150.229649 -63.879955)
			(xy 150.215021 -63.826479) (xy 150.208289 -63.771448) (xy 150.209593 -63.716023) (xy 150.218907 -63.66137)
			(xy 150.236035 -63.608642) (xy 150.260615 -63.558948) (xy 150.29213 -63.513336) (xy 150.329916 -63.472766)
			(xy 150.351236 -63.455042) (xy 150.36876 -63.440379) (xy 150.398716 -63.405881) (xy 150.422022 -63.366583)
			(xy 150.437929 -63.323752) (xy 150.445923 -63.278768) (xy 150.445747 -63.23308) (xy 150.437407 -63.188158)
			(xy 150.421171 -63.145451) (xy 150.397563 -63.106334) (xy 150.367342 -63.072068) (xy 150.349712 -63.057532)
			(xy 150.328274 -63.039949) (xy 150.290189 -62.999658) (xy 150.258338 -62.954277) (xy 150.233392 -62.904764)
			(xy 150.215876 -62.852161) (xy 150.206159 -62.797576) (xy 150.204447 -62.74216) (xy 147.203576 -62.74216)
			(xy 147.2009 -62.756647) (xy 147.182893 -62.809431) (xy 147.157392 -62.859031) (xy 147.124941 -62.904389)
			(xy 147.086232 -62.944538) (xy 147.042089 -62.978624) (xy 146.993454 -63.00592) (xy 146.941363 -63.025843)
			(xy 146.886926 -63.037969) (xy 146.831304 -63.04204) (xy 146.775682 -63.037969) (xy 146.721245 -63.025843)
			(xy 146.669154 -63.00592) (xy 146.620519 -62.978624) (xy 146.576376 -62.944538) (xy 146.537667 -62.904389)
			(xy 146.505216 -62.859031) (xy 146.479715 -62.809431) (xy 146.461708 -62.756647) (xy 146.451578 -62.701804)
			(xy 146.449541 -62.64607) (xy 145.562067 -62.64607) (xy 145.56003 -62.701804) (xy 145.5499 -62.756647)
			(xy 145.531893 -62.809431) (xy 145.506392 -62.859031) (xy 145.473941 -62.904389) (xy 145.435232 -62.944538)
			(xy 145.391089 -62.978624) (xy 145.342454 -63.00592) (xy 145.290363 -63.025843) (xy 145.235926 -63.037969)
			(xy 145.180304 -63.04204) (xy 145.124682 -63.037969) (xy 145.070245 -63.025843) (xy 145.018154 -63.00592)
			(xy 144.969519 -62.978624) (xy 144.925376 -62.944538) (xy 144.886667 -62.904389) (xy 144.854216 -62.859031)
			(xy 144.828715 -62.809431) (xy 144.810708 -62.756647) (xy 144.800578 -62.701804) (xy 144.798541 -62.64607)
			(xy 143.809467 -62.64607) (xy 143.80743 -62.701804) (xy 143.7973 -62.756647) (xy 143.779293 -62.809431)
			(xy 143.753792 -62.859031) (xy 143.721341 -62.904389) (xy 143.682632 -62.944538) (xy 143.638489 -62.978624)
			(xy 143.589854 -63.00592) (xy 143.537763 -63.025843) (xy 143.483326 -63.037969) (xy 143.427704 -63.04204)
			(xy 143.372082 -63.037969) (xy 143.317645 -63.025843) (xy 143.265554 -63.00592) (xy 143.216919 -62.978624)
			(xy 143.172776 -62.944538) (xy 143.134067 -62.904389) (xy 143.101616 -62.859031) (xy 143.076115 -62.809431)
			(xy 143.058108 -62.756647) (xy 143.047978 -62.701804) (xy 143.045941 -62.64607) (xy 140.087384 -62.64607)
			(xy 140.098523 -62.688677) (xy 140.104623 -62.744114) (xy 140.102586 -62.799848) (xy 140.092456 -62.854691)
			(xy 140.074449 -62.907475) (xy 140.048948 -62.957075) (xy 140.016497 -63.002433) (xy 139.977788 -63.042582)
			(xy 139.933645 -63.076668) (xy 139.88501 -63.103964) (xy 139.832919 -63.123887) (xy 139.778482 -63.136013)
			(xy 139.72286 -63.140084) (xy 139.667238 -63.136013) (xy 139.612801 -63.123887) (xy 139.56071 -63.103964)
			(xy 139.512075 -63.076668) (xy 139.467932 -63.042582) (xy 139.429223 -63.002433) (xy 139.396772 -62.957075)
			(xy 139.371271 -62.907475) (xy 139.353264 -62.854691) (xy 139.343134 -62.799848) (xy 139.341097 -62.744114)
			(xy 138.799103 -62.744114) (xy 138.770712 -62.760048) (xy 138.718621 -62.779971) (xy 138.664184 -62.792097)
			(xy 138.608562 -62.796168) (xy 138.55294 -62.792097) (xy 138.498503 -62.779971) (xy 138.446412 -62.760048)
			(xy 138.397777 -62.732752) (xy 138.353634 -62.698666) (xy 138.314925 -62.658517) (xy 138.282474 -62.613159)
			(xy 138.256973 -62.563559) (xy 138.238966 -62.510775) (xy 138.228836 -62.455932) (xy 138.226799 -62.400198)
			(xy 136.470118 -62.400198) (xy 136.489035 -62.409905) (xy 136.534356 -62.442261) (xy 136.574493 -62.480861)
			(xy 136.608592 -62.524885) (xy 136.63593 -62.573399) (xy 136.655924 -62.625372) (xy 136.668151 -62.679699)
			(xy 136.672351 -62.735226) (xy 136.668434 -62.790774) (xy 136.656485 -62.845162) (xy 136.636755 -62.897236)
			(xy 136.609666 -62.945889) (xy 136.575792 -62.990087) (xy 136.535852 -63.028891) (xy 136.51357 -63.045594)
			(xy 136.496076 -63.058821) (xy 136.465456 -63.090211) (xy 136.440685 -63.126396) (xy 136.422499 -63.166298)
			(xy 136.411441 -63.208732) (xy 136.407837 -63.252435) (xy 136.411796 -63.296108) (xy 136.4232 -63.33845)
			(xy 136.432036 -63.358522) (xy 136.445498 -63.391542) (xy 136.451421 -63.406894) (xy 136.469939 -63.434082)
			(xy 136.494795 -63.455629) (xy 136.524337 -63.470101) (xy 136.556597 -63.476535) (xy 136.58943 -63.474502)
			(xy 136.62065 -63.464139) (xy 136.648181 -63.446134) (xy 136.67019 -63.421686) (xy 136.678162 -63.40729)
			(xy 136.691453 -63.382679) (xy 136.724062 -63.33724) (xy 136.762956 -63.297049) (xy 136.807302 -63.262967)
			(xy 136.856149 -63.235725) (xy 136.90845 -63.215908) (xy 136.963084 -63.203939) (xy 137.01888 -63.200076)
			(xy 137.074642 -63.2044) (xy 137.129175 -63.216821) (xy 137.18131 -63.23707) (xy 137.22993 -63.264714)
			(xy 137.273992 -63.299162) (xy 137.312553 -63.339673) (xy 137.344785 -63.385381) (xy 137.369999 -63.435305)
			(xy 137.387652 -63.488375) (xy 137.397368 -63.543454) (xy 137.398937 -63.599362) (xy 137.392327 -63.6549)
			(xy 137.377679 -63.708877) (xy 137.355306 -63.760137) (xy 137.325689 -63.807581) (xy 137.289462 -63.850192)
			(xy 137.247401 -63.887057) (xy 137.200409 -63.917385) (xy 137.149492 -63.940528) (xy 137.095741 -63.955988)
			(xy 137.04031 -63.963434) (xy 136.984385 -63.962707) (xy 136.929165 -63.953822) (xy 136.875835 -63.93697)
			(xy 136.825537 -63.912512) (xy 136.779349 -63.880972) (xy 136.738261 -63.843026) (xy 136.720326 -63.821564)
			(xy 136.705352 -63.803719) (xy 136.669994 -63.773392) (xy 136.6297 -63.750019) (xy 136.58582 -63.734383)
			(xy 136.539826 -63.727007) (xy 136.493258 -63.728139) (xy 136.447676 -63.737741) (xy 136.404608 -63.755491)
			(xy 136.365498 -63.780794) (xy 136.348216 -63.796418) (xy 136.328122 -63.814707) (xy 136.283759 -63.846072)
			(xy 136.235394 -63.870826) (xy 136.184006 -63.888466) (xy 136.130635 -63.898637) (xy 136.076361 -63.901132)
			(xy 136.022282 -63.895902) (xy 135.969492 -63.883051) (xy 135.91906 -63.86284) (xy 135.872005 -63.835678)
			(xy 135.829281 -63.802114) (xy 135.79175 -63.762828) (xy 135.760174 -63.718615) (xy 135.735191 -63.670368)
			(xy 135.717305 -63.619065) (xy 135.70688 -63.565743) (xy 135.704126 -63.511481) (xy 122.90552 -63.511481)
			(xy 122.90552 -64.52694) (xy 130.599687 -64.52694) (xy 130.605787 -64.471503) (xy 130.619893 -64.417546)
			(xy 130.641705 -64.366217) (xy 130.670759 -64.318611) (xy 130.706434 -64.275743) (xy 130.747971 -64.238526)
			(xy 130.794484 -64.207753) (xy 130.844981 -64.184081) (xy 130.898388 -64.168013) (xy 130.953564 -64.159893)
			(xy 130.98145 -64.159384) (xy 131.009336 -64.159893) (xy 131.064512 -64.168013) (xy 131.117919 -64.184081)
			(xy 131.168416 -64.207753) (xy 131.214929 -64.238526) (xy 131.256466 -64.275743) (xy 131.292141 -64.318611)
			(xy 131.321195 -64.366217) (xy 131.343007 -64.417546) (xy 131.344713 -64.42407) (xy 143.045941 -64.42407)
			(xy 143.052041 -64.368633) (xy 143.066147 -64.314676) (xy 143.087959 -64.263347) (xy 143.117013 -64.215741)
			(xy 143.152688 -64.172873) (xy 143.194225 -64.135656) (xy 143.240738 -64.104883) (xy 143.291235 -64.081211)
			(xy 143.344642 -64.065143) (xy 143.399818 -64.057023) (xy 143.427704 -64.056514) (xy 143.45559 -64.057023)
			(xy 143.510766 -64.065143) (xy 143.564173 -64.081211) (xy 143.61467 -64.104883) (xy 143.661183 -64.135656)
			(xy 143.70272 -64.172873) (xy 143.738395 -64.215741) (xy 143.767449 -64.263347) (xy 143.789261 -64.314676)
			(xy 143.797939 -64.34787) (xy 146.449541 -64.34787) (xy 146.455641 -64.292433) (xy 146.469747 -64.238476)
			(xy 146.491559 -64.187147) (xy 146.520613 -64.139541) (xy 146.556288 -64.096673) (xy 146.597825 -64.059456)
			(xy 146.644338 -64.028683) (xy 146.694835 -64.005011) (xy 146.748242 -63.988943) (xy 146.803418 -63.980823)
			(xy 146.831304 -63.980314) (xy 146.85919 -63.980823) (xy 146.914366 -63.988943) (xy 146.967773 -64.005011)
			(xy 147.01827 -64.028683) (xy 147.064783 -64.059456) (xy 147.10632 -64.096673) (xy 147.141995 -64.139541)
			(xy 147.171049 -64.187147) (xy 147.192861 -64.238476) (xy 147.206967 -64.292433) (xy 147.213067 -64.34787)
			(xy 147.21103 -64.403604) (xy 147.2009 -64.458447) (xy 147.182893 -64.511231) (xy 147.157392 -64.560831)
			(xy 147.124941 -64.606189) (xy 147.086232 -64.646338) (xy 147.042089 -64.680424) (xy 146.993454 -64.70772)
			(xy 146.941363 -64.727643) (xy 146.886926 -64.739769) (xy 146.831304 -64.74384) (xy 146.775682 -64.739769)
			(xy 146.721245 -64.727643) (xy 146.669154 -64.70772) (xy 146.620519 -64.680424) (xy 146.576376 -64.646338)
			(xy 146.537667 -64.606189) (xy 146.505216 -64.560831) (xy 146.479715 -64.511231) (xy 146.461708 -64.458447)
			(xy 146.451578 -64.403604) (xy 146.449541 -64.34787) (xy 143.797939 -64.34787) (xy 143.803367 -64.368633)
			(xy 143.809467 -64.42407) (xy 143.80743 -64.479804) (xy 143.7973 -64.534647) (xy 143.779293 -64.587431)
			(xy 143.753792 -64.637031) (xy 143.721341 -64.682389) (xy 143.682632 -64.722538) (xy 143.638489 -64.756624)
			(xy 143.589854 -64.78392) (xy 143.537763 -64.803843) (xy 143.483326 -64.815969) (xy 143.427704 -64.82004)
			(xy 143.372082 -64.815969) (xy 143.317645 -64.803843) (xy 143.265554 -64.78392) (xy 143.216919 -64.756624)
			(xy 143.172776 -64.722538) (xy 143.134067 -64.682389) (xy 143.101616 -64.637031) (xy 143.076115 -64.587431)
			(xy 143.058108 -64.534647) (xy 143.047978 -64.479804) (xy 143.045941 -64.42407) (xy 131.344713 -64.42407)
			(xy 131.357113 -64.471503) (xy 131.363213 -64.52694) (xy 131.361176 -64.582674) (xy 131.351046 -64.637517)
			(xy 131.333039 -64.690301) (xy 131.307538 -64.739901) (xy 131.275087 -64.785259) (xy 131.236378 -64.825408)
			(xy 131.192235 -64.859494) (xy 131.1436 -64.88679) (xy 131.091509 -64.906713) (xy 131.037072 -64.918839)
			(xy 130.98145 -64.92291) (xy 130.925828 -64.918839) (xy 130.871391 -64.906713) (xy 130.8193 -64.88679)
			(xy 130.770665 -64.859494) (xy 130.726522 -64.825408) (xy 130.687813 -64.785259) (xy 130.655362 -64.739901)
			(xy 130.629861 -64.690301) (xy 130.611854 -64.637517) (xy 130.601724 -64.582674) (xy 130.599687 -64.52694)
			(xy 122.90552 -64.52694) (xy 122.90552 -64.904384) (xy 127.674877 -64.904384) (xy 127.680977 -64.848947)
			(xy 127.695083 -64.79499) (xy 127.716895 -64.743661) (xy 127.745949 -64.696055) (xy 127.781624 -64.653187)
			(xy 127.823161 -64.61597) (xy 127.869674 -64.585197) (xy 127.920171 -64.561525) (xy 127.973578 -64.545457)
			(xy 128.028754 -64.537337) (xy 128.05664 -64.536828) (xy 128.084526 -64.537337) (xy 128.139702 -64.545457)
			(xy 128.193109 -64.561525) (xy 128.243606 -64.585197) (xy 128.290119 -64.61597) (xy 128.331656 -64.653187)
			(xy 128.367331 -64.696055) (xy 128.396385 -64.743661) (xy 128.418197 -64.79499) (xy 128.432303 -64.848947)
			(xy 128.438403 -64.904384) (xy 128.436366 -64.960118) (xy 128.426236 -65.014961) (xy 128.408229 -65.067745)
			(xy 128.382728 -65.117345) (xy 128.350277 -65.162703) (xy 128.311568 -65.202852) (xy 128.267425 -65.236938)
			(xy 128.21879 -65.264234) (xy 128.166699 -65.284157) (xy 128.112262 -65.296283) (xy 128.05664 -65.300354)
			(xy 128.001018 -65.296283) (xy 127.946581 -65.284157) (xy 127.89449 -65.264234) (xy 127.845855 -65.236938)
			(xy 127.801712 -65.202852) (xy 127.763003 -65.162703) (xy 127.730552 -65.117345) (xy 127.705051 -65.067745)
			(xy 127.687044 -65.014961) (xy 127.676914 -64.960118) (xy 127.674877 -64.904384) (xy 122.90552 -64.904384)
			(xy 122.90552 -65.543956) (xy 138.792203 -65.543956) (xy 138.798303 -65.488519) (xy 138.812409 -65.434562)
			(xy 138.834221 -65.383233) (xy 138.863275 -65.335627) (xy 138.89895 -65.292759) (xy 138.940487 -65.255542)
			(xy 138.987 -65.224769) (xy 139.037497 -65.201097) (xy 139.090904 -65.185029) (xy 139.14608 -65.176909)
			(xy 139.173966 -65.1764) (xy 139.201852 -65.176909) (xy 139.257028 -65.185029) (xy 139.262177 -65.186578)
			(xy 150.538433 -65.186578) (xy 150.544533 -65.131141) (xy 150.558639 -65.077184) (xy 150.580451 -65.025855)
			(xy 150.609505 -64.978249) (xy 150.64518 -64.935381) (xy 150.686717 -64.898164) (xy 150.73323 -64.867391)
			(xy 150.783727 -64.843719) (xy 150.837134 -64.827651) (xy 150.89231 -64.819531) (xy 150.920196 -64.819022)
			(xy 150.948082 -64.819531) (xy 151.003258 -64.827651) (xy 151.056665 -64.843719) (xy 151.107162 -64.867391)
			(xy 151.153675 -64.898164) (xy 151.195212 -64.935381) (xy 151.230887 -64.978249) (xy 151.259941 -65.025855)
			(xy 151.281753 -65.077184) (xy 151.295859 -65.131141) (xy 151.301959 -65.186578) (xy 151.299922 -65.242312)
			(xy 151.289792 -65.297155) (xy 151.271785 -65.349939) (xy 151.246284 -65.399539) (xy 151.213833 -65.444897)
			(xy 151.175124 -65.485046) (xy 151.130981 -65.519132) (xy 151.082346 -65.546428) (xy 151.030255 -65.566351)
			(xy 150.975818 -65.578477) (xy 150.920196 -65.582548) (xy 150.864574 -65.578477) (xy 150.810137 -65.566351)
			(xy 150.758046 -65.546428) (xy 150.709411 -65.519132) (xy 150.665268 -65.485046) (xy 150.626559 -65.444897)
			(xy 150.594108 -65.399539) (xy 150.568607 -65.349939) (xy 150.5506 -65.297155) (xy 150.54047 -65.242312)
			(xy 150.538433 -65.186578) (xy 139.262177 -65.186578) (xy 139.310435 -65.201097) (xy 139.360932 -65.224769)
			(xy 139.407445 -65.255542) (xy 139.448982 -65.292759) (xy 139.484657 -65.335627) (xy 139.513711 -65.383233)
			(xy 139.535523 -65.434562) (xy 139.549629 -65.488519) (xy 139.555729 -65.543956) (xy 139.553692 -65.59969)
			(xy 139.543562 -65.654533) (xy 139.525555 -65.707317) (xy 139.500054 -65.756917) (xy 139.467603 -65.802275)
			(xy 139.428894 -65.842424) (xy 139.384751 -65.87651) (xy 139.336116 -65.903806) (xy 139.284025 -65.923729)
			(xy 139.229588 -65.935855) (xy 139.173966 -65.939926) (xy 139.118344 -65.935855) (xy 139.063907 -65.923729)
			(xy 139.011816 -65.903806) (xy 138.963181 -65.87651) (xy 138.919038 -65.842424) (xy 138.880329 -65.802275)
			(xy 138.847878 -65.756917) (xy 138.822377 -65.707317) (xy 138.80437 -65.654533) (xy 138.79424 -65.59969)
			(xy 138.792203 -65.543956) (xy 122.90552 -65.543956) (xy 122.90552 -66.04967) (xy 143.045941 -66.04967)
			(xy 143.052041 -65.994233) (xy 143.066147 -65.940276) (xy 143.087959 -65.888947) (xy 143.117013 -65.841341)
			(xy 143.152688 -65.798473) (xy 143.194225 -65.761256) (xy 143.240738 -65.730483) (xy 143.291235 -65.706811)
			(xy 143.344642 -65.690743) (xy 143.399818 -65.682623) (xy 143.427704 -65.682114) (xy 143.45559 -65.682623)
			(xy 143.510766 -65.690743) (xy 143.564173 -65.706811) (xy 143.61467 -65.730483) (xy 143.661183 -65.761256)
			(xy 143.70272 -65.798473) (xy 143.738395 -65.841341) (xy 143.767449 -65.888947) (xy 143.789261 -65.940276)
			(xy 143.803367 -65.994233) (xy 143.809467 -66.04967) (xy 144.773141 -66.04967) (xy 144.779241 -65.994233)
			(xy 144.793347 -65.940276) (xy 144.815159 -65.888947) (xy 144.844213 -65.841341) (xy 144.879888 -65.798473)
			(xy 144.921425 -65.761256) (xy 144.967938 -65.730483) (xy 145.018435 -65.706811) (xy 145.071842 -65.690743)
			(xy 145.127018 -65.682623) (xy 145.154904 -65.682114) (xy 145.18279 -65.682623) (xy 145.237966 -65.690743)
			(xy 145.291373 -65.706811) (xy 145.34187 -65.730483) (xy 145.388383 -65.761256) (xy 145.42992 -65.798473)
			(xy 145.465595 -65.841341) (xy 145.494649 -65.888947) (xy 145.516461 -65.940276) (xy 145.530567 -65.994233)
			(xy 145.536667 -66.04967) (xy 146.449541 -66.04967) (xy 146.455641 -65.994233) (xy 146.469747 -65.940276)
			(xy 146.491559 -65.888947) (xy 146.520613 -65.841341) (xy 146.556288 -65.798473) (xy 146.597825 -65.761256)
			(xy 146.644338 -65.730483) (xy 146.694835 -65.706811) (xy 146.748242 -65.690743) (xy 146.803418 -65.682623)
			(xy 146.831304 -65.682114) (xy 146.85919 -65.682623) (xy 146.914366 -65.690743) (xy 146.967773 -65.706811)
			(xy 147.01827 -65.730483) (xy 147.064783 -65.761256) (xy 147.10632 -65.798473) (xy 147.141995 -65.841341)
			(xy 147.171049 -65.888947) (xy 147.192861 -65.940276) (xy 147.206967 -65.994233) (xy 147.213067 -66.04967)
			(xy 147.21103 -66.105404) (xy 147.2009 -66.160247) (xy 147.182893 -66.213031) (xy 147.157392 -66.262631)
			(xy 147.124941 -66.307989) (xy 147.086232 -66.348138) (xy 147.042089 -66.382224) (xy 146.993454 -66.40952)
			(xy 146.941363 -66.429443) (xy 146.886926 -66.441569) (xy 146.831304 -66.44564) (xy 146.775682 -66.441569)
			(xy 146.721245 -66.429443) (xy 146.669154 -66.40952) (xy 146.620519 -66.382224) (xy 146.576376 -66.348138)
			(xy 146.537667 -66.307989) (xy 146.505216 -66.262631) (xy 146.479715 -66.213031) (xy 146.461708 -66.160247)
			(xy 146.451578 -66.105404) (xy 146.449541 -66.04967) (xy 145.536667 -66.04967) (xy 145.53463 -66.105404)
			(xy 145.5245 -66.160247) (xy 145.506493 -66.213031) (xy 145.480992 -66.262631) (xy 145.448541 -66.307989)
			(xy 145.409832 -66.348138) (xy 145.365689 -66.382224) (xy 145.317054 -66.40952) (xy 145.264963 -66.429443)
			(xy 145.210526 -66.441569) (xy 145.154904 -66.44564) (xy 145.099282 -66.441569) (xy 145.044845 -66.429443)
			(xy 144.992754 -66.40952) (xy 144.944119 -66.382224) (xy 144.899976 -66.348138) (xy 144.861267 -66.307989)
			(xy 144.828816 -66.262631) (xy 144.803315 -66.213031) (xy 144.785308 -66.160247) (xy 144.775178 -66.105404)
			(xy 144.773141 -66.04967) (xy 143.809467 -66.04967) (xy 143.80743 -66.105404) (xy 143.7973 -66.160247)
			(xy 143.779293 -66.213031) (xy 143.753792 -66.262631) (xy 143.721341 -66.307989) (xy 143.682632 -66.348138)
			(xy 143.638489 -66.382224) (xy 143.589854 -66.40952) (xy 143.537763 -66.429443) (xy 143.483326 -66.441569)
			(xy 143.427704 -66.44564) (xy 143.372082 -66.441569) (xy 143.317645 -66.429443) (xy 143.265554 -66.40952)
			(xy 143.216919 -66.382224) (xy 143.172776 -66.348138) (xy 143.134067 -66.307989) (xy 143.101616 -66.262631)
			(xy 143.076115 -66.213031) (xy 143.058108 -66.160247) (xy 143.047978 -66.105404) (xy 143.045941 -66.04967)
			(xy 122.90552 -66.04967) (xy 122.90552 -66.211196) (xy 122.90606 -66.227813) (xy 122.914653 -66.259917)
			(xy 122.931255 -66.288708) (xy 122.942604 -66.300858) (xy 123.302698 -66.660933) (xy 150.462148 -66.660933)
			(xy 150.464378 -66.605197) (xy 150.4747 -66.550379) (xy 150.492895 -66.497649) (xy 150.518573 -66.44813)
			(xy 150.551189 -66.402878) (xy 150.590046 -66.362857) (xy 150.634316 -66.328921) (xy 150.683056 -66.301792)
			(xy 150.735226 -66.28205) (xy 150.789716 -66.270115) (xy 150.845362 -66.266241) (xy 150.900979 -66.270512)
			(xy 150.955382 -66.282835) (xy 151.007411 -66.302949) (xy 151.055956 -66.330424) (xy 151.099983 -66.364675)
			(xy 151.138554 -66.404972) (xy 151.163111 -66.43956) (xy 157.725617 -66.43956) (xy 157.731717 -66.384123)
			(xy 157.745823 -66.330166) (xy 157.767635 -66.278837) (xy 157.796689 -66.231231) (xy 157.832364 -66.188363)
			(xy 157.873901 -66.151146) (xy 157.920414 -66.120373) (xy 157.970911 -66.096701) (xy 158.024318 -66.080633)
			(xy 158.079494 -66.072513) (xy 158.10738 -66.072004) (xy 158.135266 -66.072513) (xy 158.190442 -66.080633)
			(xy 158.243849 -66.096701) (xy 158.294346 -66.120373) (xy 158.340859 -66.151146) (xy 158.382396 -66.188363)
			(xy 158.418071 -66.231231) (xy 158.447125 -66.278837) (xy 158.468937 -66.330166) (xy 158.483043 -66.384123)
			(xy 158.489143 -66.43956) (xy 158.487106 -66.495294) (xy 158.476976 -66.550137) (xy 158.458969 -66.602921)
			(xy 158.433468 -66.652521) (xy 158.401017 -66.697879) (xy 158.362308 -66.738028) (xy 158.318165 -66.772114)
			(xy 158.26953 -66.79941) (xy 158.217439 -66.819333) (xy 158.163002 -66.831459) (xy 158.10738 -66.83553)
			(xy 158.051758 -66.831459) (xy 157.997321 -66.819333) (xy 157.94523 -66.79941) (xy 157.896595 -66.772114)
			(xy 157.852452 -66.738028) (xy 157.813743 -66.697879) (xy 157.781292 -66.652521) (xy 157.755791 -66.602921)
			(xy 157.737784 -66.550137) (xy 157.727654 -66.495294) (xy 157.725617 -66.43956) (xy 151.163111 -66.43956)
			(xy 151.170846 -66.450455) (xy 151.19617 -66.500156) (xy 151.213988 -66.553015) (xy 151.22392 -66.607905)
			(xy 151.225752 -66.663656) (xy 151.219448 -66.719079) (xy 151.20514 -66.772994) (xy 151.183134 -66.824251)
			(xy 151.153899 -66.871757) (xy 151.13635 -66.89344) (xy 151.126263 -66.90622) (xy 151.112353 -66.935647)
			(xy 151.106329 -66.967634) (xy 151.108581 -67.000106) (xy 151.118963 -67.030955) (xy 151.136802 -67.05818)
			(xy 151.148542 -67.069462) (xy 151.168949 -67.088477) (xy 151.204482 -67.131474) (xy 151.233375 -67.179187)
			(xy 151.255012 -67.230599) (xy 151.268933 -67.284613) (xy 151.274841 -67.340078) (xy 151.272609 -67.395813)
			(xy 151.272265 -67.397639) (xy 160.907983 -67.397639) (xy 160.914086 -67.342165) (xy 160.928202 -67.288172)
			(xy 160.950029 -67.236809) (xy 160.979102 -67.189171) (xy 161.014801 -67.146275) (xy 161.056365 -67.109033)
			(xy 161.102909 -67.078239) (xy 161.15344 -67.054551) (xy 161.206882 -67.038473) (xy 161.262096 -67.030347)
			(xy 161.29 -67.029838) (xy 161.317904 -67.030347) (xy 161.373118 -67.038473) (xy 161.42656 -67.054551)
			(xy 161.477091 -67.078239) (xy 161.523635 -67.109033) (xy 161.565199 -67.146275) (xy 161.600898 -67.189171)
			(xy 161.629971 -67.236809) (xy 161.651798 -67.288172) (xy 161.665914 -67.342165) (xy 161.672017 -67.397639)
			(xy 161.669979 -67.45341) (xy 161.659842 -67.508289) (xy 161.641823 -67.561109) (xy 161.616305 -67.610741)
			(xy 161.583833 -67.656129) (xy 161.545098 -67.696306) (xy 161.500926 -67.730414) (xy 161.452258 -67.757728)
			(xy 161.400132 -67.777664) (xy 161.345659 -67.789799) (xy 161.29 -67.793873) (xy 161.234341 -67.789799)
			(xy 161.179868 -67.777664) (xy 161.127742 -67.757728) (xy 161.079074 -67.730414) (xy 161.034902 -67.696306)
			(xy 160.996167 -67.656129) (xy 160.963695 -67.610741) (xy 160.938177 -67.561109) (xy 160.920158 -67.508289)
			(xy 160.910021 -67.45341) (xy 160.907983 -67.397639) (xy 151.272265 -67.397639) (xy 151.262285 -67.450628)
			(xy 151.24409 -67.503356) (xy 151.218411 -67.552873) (xy 151.185795 -67.598123) (xy 151.146939 -67.638141)
			(xy 151.102669 -67.672075) (xy 151.05393 -67.699201) (xy 151.001761 -67.718941) (xy 150.947273 -67.730874)
			(xy 150.891628 -67.734747) (xy 150.836013 -67.730475) (xy 150.781612 -67.718151) (xy 150.729586 -67.698037)
			(xy 150.681043 -67.670561) (xy 150.637018 -67.63631) (xy 150.59845 -67.596014) (xy 150.56616 -67.550531)
			(xy 150.540837 -67.500831) (xy 150.523021 -67.447974) (xy 150.513092 -67.393086) (xy 150.51126 -67.337337)
			(xy 150.517566 -67.281915) (xy 150.531874 -67.228002) (xy 150.55388 -67.176748) (xy 150.583115 -67.129244)
			(xy 150.600664 -67.107562) (xy 150.610762 -67.094787) (xy 150.624682 -67.06536) (xy 150.630711 -67.033369)
			(xy 150.628458 -67.000894) (xy 150.618069 -66.970042) (xy 150.600218 -66.942819) (xy 150.588472 -66.93154)
			(xy 150.56805 -66.912539) (xy 150.532515 -66.869542) (xy 150.50362 -66.821828) (xy 150.48198 -66.770416)
			(xy 150.468057 -66.7164) (xy 150.462148 -66.660933) (xy 123.302698 -66.660933) (xy 124.086191 -67.444384)
			(xy 134.118095 -67.444384) (xy 134.124195 -67.388947) (xy 134.138301 -67.33499) (xy 134.160113 -67.283661)
			(xy 134.189167 -67.236055) (xy 134.224842 -67.193187) (xy 134.266379 -67.15597) (xy 134.312892 -67.125197)
			(xy 134.363389 -67.101525) (xy 134.416796 -67.085457) (xy 134.471972 -67.077337) (xy 134.499858 -67.076828)
			(xy 134.527744 -67.077337) (xy 134.58292 -67.085457) (xy 134.636327 -67.101525) (xy 134.686824 -67.125197)
			(xy 134.733337 -67.15597) (xy 134.774874 -67.193187) (xy 134.810549 -67.236055) (xy 134.839603 -67.283661)
			(xy 134.861415 -67.33499) (xy 134.875521 -67.388947) (xy 134.881621 -67.444384) (xy 134.879584 -67.500118)
			(xy 134.869454 -67.554961) (xy 134.851447 -67.607745) (xy 134.825946 -67.657345) (xy 134.793495 -67.702703)
			(xy 134.754786 -67.742852) (xy 134.710643 -67.776938) (xy 134.662008 -67.804234) (xy 134.609917 -67.824157)
			(xy 134.583884 -67.829956) (xy 136.592055 -67.829956) (xy 136.598155 -67.774519) (xy 136.612261 -67.720562)
			(xy 136.634073 -67.669233) (xy 136.663127 -67.621627) (xy 136.698802 -67.578759) (xy 136.740339 -67.541542)
			(xy 136.786852 -67.510769) (xy 136.837349 -67.487097) (xy 136.890756 -67.471029) (xy 136.945932 -67.462909)
			(xy 136.973818 -67.4624) (xy 137.001704 -67.462909) (xy 137.05688 -67.471029) (xy 137.110287 -67.487097)
			(xy 137.160784 -67.510769) (xy 137.207297 -67.541542) (xy 137.248834 -67.578759) (xy 137.284509 -67.621627)
			(xy 137.313563 -67.669233) (xy 137.335375 -67.720562) (xy 137.347041 -67.765186) (xy 138.077701 -67.765186)
			(xy 138.083801 -67.709749) (xy 138.097907 -67.655792) (xy 138.119719 -67.604463) (xy 138.148773 -67.556857)
			(xy 138.184448 -67.513989) (xy 138.225985 -67.476772) (xy 138.272498 -67.445999) (xy 138.322995 -67.422327)
			(xy 138.376402 -67.406259) (xy 138.431578 -67.398139) (xy 138.459464 -67.39763) (xy 138.48735 -67.398139)
			(xy 138.542526 -67.406259) (xy 138.595933 -67.422327) (xy 138.64643 -67.445999) (xy 138.692943 -67.476772)
			(xy 138.73448 -67.513989) (xy 138.770155 -67.556857) (xy 138.799209 -67.604463) (xy 138.821021 -67.655792)
			(xy 138.835127 -67.709749) (xy 138.841227 -67.765186) (xy 138.83919 -67.82092) (xy 138.82906 -67.875763)
			(xy 138.811053 -67.928547) (xy 138.785552 -67.978147) (xy 138.753101 -68.023505) (xy 138.714392 -68.063654)
			(xy 138.670249 -68.09774) (xy 138.621614 -68.125036) (xy 138.569523 -68.144959) (xy 138.515086 -68.157085)
			(xy 138.459464 -68.161156) (xy 138.403842 -68.157085) (xy 138.349405 -68.144959) (xy 138.297314 -68.125036)
			(xy 138.248679 -68.09774) (xy 138.204536 -68.063654) (xy 138.165827 -68.023505) (xy 138.133376 -67.978147)
			(xy 138.107875 -67.928547) (xy 138.089868 -67.875763) (xy 138.079738 -67.82092) (xy 138.077701 -67.765186)
			(xy 137.347041 -67.765186) (xy 137.349481 -67.774519) (xy 137.355581 -67.829956) (xy 137.353544 -67.88569)
			(xy 137.343414 -67.940533) (xy 137.325407 -67.993317) (xy 137.299906 -68.042917) (xy 137.267455 -68.088275)
			(xy 137.228746 -68.128424) (xy 137.184603 -68.16251) (xy 137.135968 -68.189806) (xy 137.083877 -68.209729)
			(xy 137.02944 -68.221855) (xy 136.973818 -68.225926) (xy 136.918196 -68.221855) (xy 136.863759 -68.209729)
			(xy 136.811668 -68.189806) (xy 136.763033 -68.16251) (xy 136.71889 -68.128424) (xy 136.680181 -68.088275)
			(xy 136.64773 -68.042917) (xy 136.622229 -67.993317) (xy 136.604222 -67.940533) (xy 136.594092 -67.88569)
			(xy 136.592055 -67.829956) (xy 134.583884 -67.829956) (xy 134.55548 -67.836283) (xy 134.499858 -67.840354)
			(xy 134.444236 -67.836283) (xy 134.389799 -67.824157) (xy 134.337708 -67.804234) (xy 134.289073 -67.776938)
			(xy 134.24493 -67.742852) (xy 134.206221 -67.702703) (xy 134.17377 -67.657345) (xy 134.148269 -67.607745)
			(xy 134.130262 -67.554961) (xy 134.120132 -67.500118) (xy 134.118095 -67.444384) (xy 124.086191 -67.444384)
			(xy 124.943487 -68.301634) (xy 133.090157 -68.301634) (xy 133.096257 -68.246197) (xy 133.110363 -68.19224)
			(xy 133.132175 -68.140911) (xy 133.161229 -68.093305) (xy 133.196904 -68.050437) (xy 133.238441 -68.01322)
			(xy 133.284954 -67.982447) (xy 133.335451 -67.958775) (xy 133.388858 -67.942707) (xy 133.444034 -67.934587)
			(xy 133.47192 -67.934078) (xy 133.499806 -67.934587) (xy 133.554982 -67.942707) (xy 133.608389 -67.958775)
			(xy 133.658886 -67.982447) (xy 133.705399 -68.01322) (xy 133.746936 -68.050437) (xy 133.782611 -68.093305)
			(xy 133.811665 -68.140911) (xy 133.833477 -68.19224) (xy 133.847583 -68.246197) (xy 133.853683 -68.301634)
			(xy 133.851646 -68.357368) (xy 133.841516 -68.412211) (xy 133.823509 -68.464995) (xy 133.798008 -68.514595)
			(xy 133.765557 -68.559953) (xy 133.726848 -68.600102) (xy 133.682705 -68.634188) (xy 133.63407 -68.661484)
			(xy 133.581979 -68.681407) (xy 133.527542 -68.693533) (xy 133.47192 -68.697604) (xy 133.416298 -68.693533)
			(xy 133.361861 -68.681407) (xy 133.30977 -68.661484) (xy 133.261135 -68.634188) (xy 133.216992 -68.600102)
			(xy 133.178283 -68.559953) (xy 133.145832 -68.514595) (xy 133.120331 -68.464995) (xy 133.102324 -68.412211)
			(xy 133.092194 -68.357368) (xy 133.090157 -68.301634) (xy 124.943487 -68.301634) (xy 125.551712 -68.909827)
			(xy 150.589507 -68.909827) (xy 150.597147 -68.854506) (xy 150.61277 -68.800891) (xy 150.636042 -68.750125)
			(xy 150.666465 -68.703294) (xy 150.70339 -68.661399) (xy 150.746027 -68.625333) (xy 150.793467 -68.595868)
			(xy 150.844695 -68.573633) (xy 150.898617 -68.559103) (xy 150.926292 -68.555362) (xy 150.947837 -68.552364)
			(xy 150.989545 -68.540029) (xy 151.028544 -68.520771) (xy 151.063692 -68.495152) (xy 151.093964 -68.463921)
			(xy 151.118474 -68.427991) (xy 151.136506 -68.388411) (xy 151.147534 -68.346338) (xy 151.151235 -68.303001)
			(xy 151.149812 -68.281296) (xy 151.147882 -68.25344) (xy 151.151256 -68.197705) (xy 151.162719 -68.143057)
			(xy 151.182024 -68.090664) (xy 151.208761 -68.041644) (xy 151.242357 -67.997045) (xy 151.282094 -67.957819)
			(xy 151.327126 -67.924804) (xy 151.376488 -67.898705) (xy 151.429128 -67.880081) (xy 151.48392 -67.869328)
			(xy 151.539694 -67.866677) (xy 151.595259 -67.872183) (xy 151.649428 -67.88573) (xy 151.701043 -67.907028)
			(xy 151.749003 -67.935622) (xy 151.792283 -67.970902) (xy 151.829958 -68.012113) (xy 151.861224 -68.058375)
			(xy 151.885413 -68.108701) (xy 151.902008 -68.162015) (xy 151.910655 -68.217179) (xy 151.911168 -68.273014)
			(xy 151.907232 -68.301548) (xy 152.190144 -68.301548) (xy 152.190148 -68.246206) (xy 152.198147 -68.191444)
			(xy 152.213973 -68.138413) (xy 152.237295 -68.088225) (xy 152.267623 -68.041933) (xy 152.304321 -68.000508)
			(xy 152.346618 -67.964819) (xy 152.393628 -67.935616) (xy 152.444364 -67.913511) (xy 152.497761 -67.898967)
			(xy 152.552699 -67.892291) (xy 152.608025 -67.893622) (xy 152.662579 -67.902931) (xy 152.715215 -67.920025)
			(xy 152.764829 -67.944544) (xy 152.810381 -67.975973) (xy 152.850914 -68.013654) (xy 152.86863 -68.034916)
			(xy 152.883253 -68.052285) (xy 152.91755 -68.082032) (xy 152.956586 -68.105211) (xy 152.999119 -68.121087)
			(xy 153.043796 -68.129153) (xy 153.089196 -68.129153) (xy 153.133873 -68.121087) (xy 153.176406 -68.105211)
			(xy 153.215442 -68.082032) (xy 153.249739 -68.052285) (xy 153.264362 -68.034916) (xy 153.281957 -68.013831)
			(xy 153.32214 -67.976404) (xy 153.367274 -67.945123) (xy 153.416426 -67.920635) (xy 153.46858 -67.903446)
			(xy 153.52266 -67.89391) (xy 153.577548 -67.892225) (xy 153.63211 -67.898425) (xy 153.685221 -67.912382)
			(xy 153.735782 -67.933808) (xy 153.78275 -67.962261) (xy 153.825155 -67.997153) (xy 153.84399 -68.017136)
			(xy 153.860185 -68.034162) (xy 153.897669 -68.062492) (xy 153.939722 -68.083447) (xy 153.984911 -68.096313)
			(xy 154.031696 -68.10065) (xy 154.078481 -68.096313) (xy 154.12367 -68.083447) (xy 154.165723 -68.062492)
			(xy 154.203207 -68.034162) (xy 154.219402 -68.017136) (xy 154.238134 -67.997247) (xy 154.280291 -67.962495)
			(xy 154.326974 -67.934111) (xy 154.377229 -67.912676) (xy 154.430027 -67.898629) (xy 154.484289 -67.892257)
			(xy 154.538905 -67.893691) (xy 154.592758 -67.9029) (xy 154.644746 -67.919697) (xy 154.693807 -67.943738)
			(xy 154.738937 -67.974531) (xy 154.779213 -68.011447) (xy 154.813812 -68.053731) (xy 154.842025 -68.100517)
			(xy 154.863276 -68.15085) (xy 154.87713 -68.203699) (xy 154.883303 -68.257983) (xy 154.88167 -68.312594)
			(xy 154.877548 -68.336178) (xy 155.313633 -68.336178) (xy 155.319733 -68.280741) (xy 155.333839 -68.226784)
			(xy 155.355651 -68.175455) (xy 155.384705 -68.127849) (xy 155.42038 -68.084981) (xy 155.461917 -68.047764)
			(xy 155.50843 -68.016991) (xy 155.558927 -67.993319) (xy 155.612334 -67.977251) (xy 155.66751 -67.969131)
			(xy 155.695396 -67.968622) (xy 155.723282 -67.969131) (xy 155.778458 -67.977251) (xy 155.831865 -67.993319)
			(xy 155.882362 -68.016991) (xy 155.928875 -68.047764) (xy 155.970412 -68.084981) (xy 156.006087 -68.127849)
			(xy 156.035141 -68.175455) (xy 156.056953 -68.226784) (xy 156.071059 -68.280741) (xy 156.077159 -68.336178)
			(xy 156.075122 -68.391912) (xy 156.064992 -68.446755) (xy 156.046985 -68.499539) (xy 156.021484 -68.549139)
			(xy 155.989033 -68.594497) (xy 155.950324 -68.634646) (xy 155.906181 -68.668732) (xy 155.857546 -68.696028)
			(xy 155.805455 -68.715951) (xy 155.751018 -68.728077) (xy 155.695396 -68.732148) (xy 155.639774 -68.728077)
			(xy 155.585337 -68.715951) (xy 155.533246 -68.696028) (xy 155.484611 -68.668732) (xy 155.440468 -68.634646)
			(xy 155.401759 -68.594497) (xy 155.369308 -68.549139) (xy 155.343807 -68.499539) (xy 155.3258 -68.446755)
			(xy 155.31567 -68.391912) (xy 155.313633 -68.336178) (xy 154.877548 -68.336178) (xy 154.872264 -68.366413)
			(xy 154.855278 -68.41834) (xy 154.831058 -68.467312) (xy 154.8001 -68.51233) (xy 154.763037 -68.552471)
			(xy 154.720627 -68.586914) (xy 154.673738 -68.614956) (xy 154.623328 -68.636023) (xy 154.570429 -68.649684)
			(xy 154.516122 -68.655659) (xy 154.461518 -68.653827) (xy 154.407734 -68.644224) (xy 154.355869 -68.627048)
			(xy 154.306985 -68.602649) (xy 154.262081 -68.571527) (xy 154.222076 -68.534317) (xy 154.187788 -68.491782)
			(xy 154.159917 -68.444791) (xy 154.149044 -68.419726) (xy 154.14222 -68.404518) (xy 154.121948 -68.37807)
			(xy 154.095518 -68.357773) (xy 154.064734 -68.345014) (xy 154.031696 -68.340662) (xy 153.998658 -68.345014)
			(xy 153.967874 -68.357773) (xy 153.941444 -68.37807) (xy 153.921172 -68.404518) (xy 153.914348 -68.419726)
			(xy 153.906384 -68.438373) (xy 153.887038 -68.474009) (xy 153.87574 -68.490846) (xy 153.864029 -68.508598)
			(xy 153.845978 -68.547101) (xy 153.834603 -68.588075) (xy 153.830223 -68.630373) (xy 153.832959 -68.672808)
			(xy 153.842737 -68.714193) (xy 153.85928 -68.753367) (xy 153.882127 -68.789232) (xy 153.89606 -68.805298)
			(xy 153.914143 -68.826134) (xy 153.944793 -68.872004) (xy 153.968518 -68.921809) (xy 153.984824 -68.974512)
			(xy 153.99337 -69.029013) (xy 153.993979 -69.084177) (xy 153.986637 -69.138854) (xy 153.971498 -69.191904)
			(xy 153.948878 -69.24222) (xy 153.919248 -69.288755) (xy 153.883225 -69.330538) (xy 153.84156 -69.366698)
			(xy 153.795123 -69.396481) (xy 153.744881 -69.419266) (xy 153.691881 -69.434579) (xy 153.637229 -69.4421)
			(xy 153.582063 -69.441672) (xy 153.527534 -69.433305) (xy 153.474778 -69.417172) (xy 153.424895 -69.393611)
			(xy 153.378925 -69.363112) (xy 153.337827 -69.32631) (xy 153.302456 -69.283974) (xy 153.27355 -69.236986)
			(xy 153.251712 -69.186324) (xy 153.237398 -69.133047) (xy 153.230905 -69.078263) (xy 153.232368 -69.023115)
			(xy 153.241759 -68.968752) (xy 153.258879 -68.916308) (xy 153.283374 -68.866877) (xy 153.298652 -68.843906)
			(xy 153.310412 -68.826184) (xy 153.328459 -68.787674) (xy 153.339829 -68.746693) (xy 153.344204 -68.70439)
			(xy 153.341461 -68.66195) (xy 153.331676 -68.620562) (xy 153.315125 -68.581386) (xy 153.29227 -68.54552)
			(xy 153.278332 -68.529454) (xy 153.264362 -68.512944) (xy 153.249739 -68.495575) (xy 153.215442 -68.465828)
			(xy 153.176406 -68.442649) (xy 153.133873 -68.426773) (xy 153.089196 -68.418707) (xy 153.043796 -68.418707)
			(xy 152.999119 -68.426773) (xy 152.956586 -68.442649) (xy 152.91755 -68.465828) (xy 152.883253 -68.495575)
			(xy 152.86863 -68.512944) (xy 152.850882 -68.53418) (xy 152.810344 -68.571856) (xy 152.764789 -68.60328)
			(xy 152.715171 -68.627793) (xy 152.662533 -68.64488) (xy 152.607979 -68.654183) (xy 152.552652 -68.655507)
			(xy 152.497715 -68.648824) (xy 152.44432 -68.634274) (xy 152.393587 -68.612162) (xy 152.34658 -68.582953)
			(xy 152.304287 -68.547259) (xy 152.267594 -68.50583) (xy 152.237272 -68.459534) (xy 152.213956 -68.409343)
			(xy 152.198136 -68.35631) (xy 152.190144 -68.301548) (xy 151.907232 -68.301548) (xy 151.903538 -68.328327)
			(xy 151.887926 -68.381937) (xy 151.864667 -68.432699) (xy 151.834257 -68.479529) (xy 151.797346 -68.521426)
			(xy 151.754722 -68.557495) (xy 151.707296 -68.586967) (xy 151.656081 -68.60921) (xy 151.60217 -68.623751)
			(xy 151.5745 -68.627498) (xy 151.552944 -68.630427) (xy 151.511229 -68.642767) (xy 151.472226 -68.662032)
			(xy 151.437075 -68.687659) (xy 151.406802 -68.718899) (xy 151.382294 -68.754839) (xy 151.364266 -68.794429)
			(xy 151.353244 -68.836511) (xy 151.349552 -68.879856) (xy 151.35098 -68.901564) (xy 151.352847 -68.929429)
			(xy 151.349476 -68.985173) (xy 151.338015 -69.039829) (xy 151.31871 -69.092232) (xy 151.291971 -69.14126)
			(xy 151.258372 -69.185867) (xy 151.218629 -69.2251) (xy 151.173591 -69.25812) (xy 151.124222 -69.284222)
			(xy 151.071574 -69.302849) (xy 151.016774 -69.313602) (xy 150.960991 -69.316252) (xy 150.905419 -69.310742)
			(xy 150.851242 -69.29719) (xy 150.79962 -69.275886) (xy 150.751655 -69.247284) (xy 150.708372 -69.211996)
			(xy 150.670695 -69.170775) (xy 150.639429 -69.124503) (xy 150.615243 -69.074167) (xy 150.598652 -69.020843)
			(xy 150.590012 -68.96567) (xy 150.589507 -68.909827) (xy 125.551712 -68.909827) (xy 126.527515 -69.885578)
			(xy 143.578833 -69.885578) (xy 143.584933 -69.830141) (xy 143.599039 -69.776184) (xy 143.620851 -69.724855)
			(xy 143.649905 -69.677249) (xy 143.68558 -69.634381) (xy 143.727117 -69.597164) (xy 143.77363 -69.566391)
			(xy 143.824127 -69.542719) (xy 143.877534 -69.526651) (xy 143.93271 -69.518531) (xy 143.960596 -69.518022)
			(xy 143.988482 -69.518531) (xy 144.043658 -69.526651) (xy 144.097065 -69.542719) (xy 144.147562 -69.566391)
			(xy 144.194075 -69.597164) (xy 144.235612 -69.634381) (xy 144.271287 -69.677249) (xy 144.300341 -69.724855)
			(xy 144.322153 -69.776184) (xy 144.324191 -69.783978) (xy 147.312633 -69.783978) (xy 147.318733 -69.728541)
			(xy 147.332839 -69.674584) (xy 147.354651 -69.623255) (xy 147.383705 -69.575649) (xy 147.41938 -69.532781)
			(xy 147.460917 -69.495564) (xy 147.50743 -69.464791) (xy 147.557927 -69.441119) (xy 147.611334 -69.425051)
			(xy 147.66651 -69.416931) (xy 147.694396 -69.416422) (xy 147.722282 -69.416931) (xy 147.777458 -69.425051)
			(xy 147.830865 -69.441119) (xy 147.881362 -69.464791) (xy 147.927875 -69.495564) (xy 147.969412 -69.532781)
			(xy 148.005087 -69.575649) (xy 148.034141 -69.623255) (xy 148.055953 -69.674584) (xy 148.070059 -69.728541)
			(xy 148.076159 -69.783978) (xy 148.074122 -69.839712) (xy 148.06565 -69.885578) (xy 149.700233 -69.885578)
			(xy 149.706333 -69.830141) (xy 149.720439 -69.776184) (xy 149.742251 -69.724855) (xy 149.771305 -69.677249)
			(xy 149.80698 -69.634381) (xy 149.848517 -69.597164) (xy 149.89503 -69.566391) (xy 149.945527 -69.542719)
			(xy 149.998934 -69.526651) (xy 150.05411 -69.518531) (xy 150.081996 -69.518022) (xy 150.109882 -69.518531)
			(xy 150.165058 -69.526651) (xy 150.218465 -69.542719) (xy 150.268962 -69.566391) (xy 150.315475 -69.597164)
			(xy 150.357012 -69.634381) (xy 150.392687 -69.677249) (xy 150.421741 -69.724855) (xy 150.443553 -69.776184)
			(xy 150.457659 -69.830141) (xy 150.463759 -69.885578) (xy 150.461722 -69.941312) (xy 150.451592 -69.996155)
			(xy 150.433585 -70.048939) (xy 150.408084 -70.098539) (xy 150.375633 -70.143897) (xy 150.336924 -70.184046)
			(xy 150.329382 -70.18987) (xy 151.148033 -70.18987) (xy 151.154133 -70.134433) (xy 151.168239 -70.080476)
			(xy 151.190051 -70.029147) (xy 151.219105 -69.981541) (xy 151.25478 -69.938673) (xy 151.296317 -69.901456)
			(xy 151.34283 -69.870683) (xy 151.393327 -69.847011) (xy 151.446734 -69.830943) (xy 151.50191 -69.822823)
			(xy 151.529796 -69.822314) (xy 151.557682 -69.822823) (xy 151.612858 -69.830943) (xy 151.666265 -69.847011)
			(xy 151.716762 -69.870683) (xy 151.763275 -69.901456) (xy 151.804812 -69.938673) (xy 151.840487 -69.981541)
			(xy 151.869541 -70.029147) (xy 151.891353 -70.080476) (xy 151.905459 -70.134433) (xy 151.911559 -70.18987)
			(xy 151.909522 -70.245604) (xy 151.899392 -70.300447) (xy 151.881385 -70.353231) (xy 151.855884 -70.402831)
			(xy 151.823433 -70.448189) (xy 151.784724 -70.488338) (xy 151.740581 -70.522424) (xy 151.691946 -70.54972)
			(xy 151.639855 -70.569643) (xy 151.585418 -70.581769) (xy 151.529796 -70.58584) (xy 151.474174 -70.581769)
			(xy 151.419737 -70.569643) (xy 151.367646 -70.54972) (xy 151.319011 -70.522424) (xy 151.274868 -70.488338)
			(xy 151.236159 -70.448189) (xy 151.203708 -70.402831) (xy 151.178207 -70.353231) (xy 151.1602 -70.300447)
			(xy 151.15007 -70.245604) (xy 151.148033 -70.18987) (xy 150.329382 -70.18987) (xy 150.292781 -70.218132)
			(xy 150.244146 -70.245428) (xy 150.192055 -70.265351) (xy 150.137618 -70.277477) (xy 150.081996 -70.281548)
			(xy 150.026374 -70.277477) (xy 149.971937 -70.265351) (xy 149.919846 -70.245428) (xy 149.871211 -70.218132)
			(xy 149.827068 -70.184046) (xy 149.788359 -70.143897) (xy 149.755908 -70.098539) (xy 149.730407 -70.048939)
			(xy 149.7124 -69.996155) (xy 149.70227 -69.941312) (xy 149.700233 -69.885578) (xy 148.06565 -69.885578)
			(xy 148.063992 -69.894555) (xy 148.045985 -69.947339) (xy 148.020484 -69.996939) (xy 147.988033 -70.042297)
			(xy 147.949324 -70.082446) (xy 147.905181 -70.116532) (xy 147.856546 -70.143828) (xy 147.804455 -70.163751)
			(xy 147.750018 -70.175877) (xy 147.694396 -70.179948) (xy 147.638774 -70.175877) (xy 147.584337 -70.163751)
			(xy 147.532246 -70.143828) (xy 147.483611 -70.116532) (xy 147.439468 -70.082446) (xy 147.400759 -70.042297)
			(xy 147.368308 -69.996939) (xy 147.342807 -69.947339) (xy 147.3248 -69.894555) (xy 147.31467 -69.839712)
			(xy 147.312633 -69.783978) (xy 144.324191 -69.783978) (xy 144.336259 -69.830141) (xy 144.342359 -69.885578)
			(xy 144.340322 -69.941312) (xy 144.330192 -69.996155) (xy 144.312185 -70.048939) (xy 144.286684 -70.098539)
			(xy 144.254233 -70.143897) (xy 144.215524 -70.184046) (xy 144.171381 -70.218132) (xy 144.122746 -70.245428)
			(xy 144.070655 -70.265351) (xy 144.016218 -70.277477) (xy 143.960596 -70.281548) (xy 143.904974 -70.277477)
			(xy 143.850537 -70.265351) (xy 143.798446 -70.245428) (xy 143.749811 -70.218132) (xy 143.705668 -70.184046)
			(xy 143.666959 -70.143897) (xy 143.634508 -70.098539) (xy 143.609007 -70.048939) (xy 143.591 -69.996155)
			(xy 143.58087 -69.941312) (xy 143.578833 -69.885578) (xy 126.527515 -69.885578) (xy 126.959338 -70.317378)
			(xy 138.104879 -70.317378) (xy 138.110979 -70.261941) (xy 138.125085 -70.207984) (xy 138.146897 -70.156655)
			(xy 138.175951 -70.109049) (xy 138.211626 -70.066181) (xy 138.253163 -70.028964) (xy 138.299676 -69.998191)
			(xy 138.350173 -69.974519) (xy 138.40358 -69.958451) (xy 138.458756 -69.950331) (xy 138.486642 -69.949822)
			(xy 138.514528 -69.950331) (xy 138.569704 -69.958451) (xy 138.623111 -69.974519) (xy 138.673608 -69.998191)
			(xy 138.720121 -70.028964) (xy 138.761658 -70.066181) (xy 138.797333 -70.109049) (xy 138.826387 -70.156655)
			(xy 138.848199 -70.207984) (xy 138.862305 -70.261941) (xy 138.868405 -70.317378) (xy 138.866368 -70.373112)
			(xy 138.856238 -70.427955) (xy 138.838231 -70.480739) (xy 138.81273 -70.530339) (xy 138.780279 -70.575697)
			(xy 138.74157 -70.615846) (xy 138.697427 -70.649932) (xy 138.648792 -70.677228) (xy 138.596701 -70.697151)
			(xy 138.542264 -70.709277) (xy 138.486642 -70.713348) (xy 138.43102 -70.709277) (xy 138.376583 -70.697151)
			(xy 138.324492 -70.677228) (xy 138.275857 -70.649932) (xy 138.231714 -70.615846) (xy 138.193005 -70.575697)
			(xy 138.160554 -70.530339) (xy 138.135053 -70.480739) (xy 138.117046 -70.427955) (xy 138.106916 -70.373112)
			(xy 138.104879 -70.317378) (xy 126.959338 -70.317378) (xy 127.705866 -71.063866) (xy 127.722422 -71.079734)
			(xy 127.760135 -71.105818) (xy 127.801918 -71.124708) (xy 127.846413 -71.13579) (xy 127.892174 -71.138705)
			(xy 127.937716 -71.133358) (xy 127.981558 -71.119922) (xy 128.022275 -71.098834) (xy 128.058546 -71.07078)
			(xy 128.089191 -71.03667) (xy 128.101598 -71.017384) (xy 128.124837 -70.980601) (xy 128.177132 -70.911055)
			(xy 128.235627 -70.846638) (xy 128.299823 -70.7879) (xy 128.36917 -70.735344) (xy 128.443077 -70.689418)
			(xy 128.520909 -70.650517) (xy 128.602003 -70.618972) (xy 128.685664 -70.595053) (xy 128.771177 -70.578965)
			(xy 128.85781 -70.570845) (xy 128.944823 -70.570763) (xy 129.031471 -70.57872) (xy 129.117014 -70.594647)
			(xy 129.20072 -70.618409) (xy 129.281873 -70.649801) (xy 129.359779 -70.688557) (xy 129.433771 -70.734343)
			(xy 129.503217 -70.786769) (xy 129.567524 -70.845386) (xy 129.62614 -70.909693) (xy 129.678565 -70.97914)
			(xy 129.72435 -71.053133) (xy 129.763104 -71.13104) (xy 129.770462 -71.150062) (xy 134.268094 -71.150062)
			(xy 134.271384 -71.095364) (xy 134.282464 -71.041699) (xy 134.301106 -70.99017) (xy 134.326926 -70.941837)
			(xy 134.359394 -70.897695) (xy 134.397842 -70.85865) (xy 134.441478 -70.825505) (xy 134.489407 -70.798943)
			(xy 134.540643 -70.779509) (xy 134.594131 -70.767603) (xy 134.648772 -70.76347) (xy 134.703442 -70.767195)
			(xy 134.757018 -70.778701) (xy 134.808397 -70.797751) (xy 134.856523 -70.823954) (xy 134.900406 -70.856771)
			(xy 134.939145 -70.895528) (xy 134.971942 -70.939426) (xy 134.998123 -70.987565) (xy 135.017149 -71.038953)
			(xy 135.023352 -71.065644) (xy 135.028681 -71.088071) (xy 135.046338 -71.130649) (xy 135.07138 -71.169346)
			(xy 135.090234 -71.18936) (xy 141.148815 -71.18936) (xy 141.154915 -71.133923) (xy 141.169021 -71.079966)
			(xy 141.190833 -71.028637) (xy 141.219887 -70.981031) (xy 141.255562 -70.938163) (xy 141.297099 -70.900946)
			(xy 141.343612 -70.870173) (xy 141.394109 -70.846501) (xy 141.447516 -70.830433) (xy 141.502692 -70.822313)
			(xy 141.530578 -70.821804) (xy 141.558464 -70.822313) (xy 141.61364 -70.830433) (xy 141.667047 -70.846501)
			(xy 141.717544 -70.870173) (xy 141.764057 -70.900946) (xy 141.805594 -70.938163) (xy 141.817424 -70.952378)
			(xy 142.943833 -70.952378) (xy 142.949933 -70.896941) (xy 142.964039 -70.842984) (xy 142.985851 -70.791655)
			(xy 143.014905 -70.744049) (xy 143.05058 -70.701181) (xy 143.092117 -70.663964) (xy 143.13863 -70.633191)
			(xy 143.189127 -70.609519) (xy 143.242534 -70.593451) (xy 143.29771 -70.585331) (xy 143.325596 -70.584822)
			(xy 143.353482 -70.585331) (xy 143.408658 -70.593451) (xy 143.462065 -70.609519) (xy 143.512562 -70.633191)
			(xy 143.559075 -70.663964) (xy 143.600612 -70.701181) (xy 143.615401 -70.718952) (xy 153.269441 -70.718952)
			(xy 153.275541 -70.663515) (xy 153.289647 -70.609558) (xy 153.311459 -70.558229) (xy 153.340513 -70.510623)
			(xy 153.376188 -70.467755) (xy 153.417725 -70.430538) (xy 153.464238 -70.399765) (xy 153.514735 -70.376093)
			(xy 153.568142 -70.360025) (xy 153.623318 -70.351905) (xy 153.651204 -70.351396) (xy 153.67909 -70.351905)
			(xy 153.734266 -70.360025) (xy 153.787673 -70.376093) (xy 153.83817 -70.399765) (xy 153.884683 -70.430538)
			(xy 153.92622 -70.467755) (xy 153.961895 -70.510623) (xy 153.990949 -70.558229) (xy 154.012761 -70.609558)
			(xy 154.026867 -70.663515) (xy 154.032967 -70.718952) (xy 154.03093 -70.774686) (xy 154.0208 -70.829529)
			(xy 154.002793 -70.882313) (xy 153.977292 -70.931913) (xy 153.944841 -70.977271) (xy 153.906132 -71.01742)
			(xy 153.861989 -71.051506) (xy 153.813354 -71.078802) (xy 153.761263 -71.098725) (xy 153.706826 -71.110851)
			(xy 153.651204 -71.114922) (xy 153.595582 -71.110851) (xy 153.541145 -71.098725) (xy 153.489054 -71.078802)
			(xy 153.440419 -71.051506) (xy 153.396276 -71.01742) (xy 153.357567 -70.977271) (xy 153.325116 -70.931913)
			(xy 153.299615 -70.882313) (xy 153.281608 -70.829529) (xy 153.271478 -70.774686) (xy 153.269441 -70.718952)
			(xy 143.615401 -70.718952) (xy 143.636287 -70.744049) (xy 143.665341 -70.791655) (xy 143.687153 -70.842984)
			(xy 143.701259 -70.896941) (xy 143.707359 -70.952378) (xy 143.705322 -71.008112) (xy 143.695192 -71.062955)
			(xy 143.677185 -71.115739) (xy 143.651684 -71.165339) (xy 143.619233 -71.210697) (xy 143.580524 -71.250846)
			(xy 143.536381 -71.284932) (xy 143.487746 -71.312228) (xy 143.435655 -71.332151) (xy 143.381218 -71.344277)
			(xy 143.325596 -71.348348) (xy 143.269974 -71.344277) (xy 143.215537 -71.332151) (xy 143.163446 -71.312228)
			(xy 143.114811 -71.284932) (xy 143.070668 -71.250846) (xy 143.031959 -71.210697) (xy 142.999508 -71.165339)
			(xy 142.974007 -71.115739) (xy 142.956 -71.062955) (xy 142.94587 -71.008112) (xy 142.943833 -70.952378)
			(xy 141.817424 -70.952378) (xy 141.841269 -70.981031) (xy 141.870323 -71.028637) (xy 141.892135 -71.079966)
			(xy 141.906241 -71.133923) (xy 141.912341 -71.18936) (xy 141.910304 -71.245094) (xy 141.900174 -71.299937)
			(xy 141.882167 -71.352721) (xy 141.856666 -71.402321) (xy 141.824215 -71.447679) (xy 141.785506 -71.487828)
			(xy 141.741363 -71.521914) (xy 141.692728 -71.54921) (xy 141.640637 -71.569133) (xy 141.5862 -71.581259)
			(xy 141.530578 -71.58533) (xy 141.474956 -71.581259) (xy 141.420519 -71.569133) (xy 141.368428 -71.54921)
			(xy 141.319793 -71.521914) (xy 141.27565 -71.487828) (xy 141.236941 -71.447679) (xy 141.20449 -71.402321)
			(xy 141.178989 -71.352721) (xy 141.160982 -71.299937) (xy 141.150852 -71.245094) (xy 141.148815 -71.18936)
			(xy 135.090234 -71.18936) (xy 135.102986 -71.202896) (xy 135.140122 -71.2302) (xy 135.181571 -71.250364)
			(xy 135.225976 -71.262726) (xy 135.271881 -71.266883) (xy 135.294878 -71.265288) (xy 135.322203 -71.263238)
			(xy 135.376926 -71.266093) (xy 135.430677 -71.276747) (xy 135.482352 -71.294978) (xy 135.530888 -71.320413)
			(xy 135.575287 -71.352529) (xy 135.614637 -71.390665) (xy 135.648127 -71.434036) (xy 135.675069 -71.481752)
			(xy 135.69491 -71.532831) (xy 135.707242 -71.586222) (xy 135.71181 -71.640828) (xy 135.708521 -71.695526)
			(xy 135.700808 -71.732886) (xy 145.88997 -71.732886) (xy 145.893265 -71.678061) (xy 145.904386 -71.624275)
			(xy 145.923105 -71.57264) (xy 145.949034 -71.524222) (xy 145.981638 -71.480022) (xy 146.020243 -71.440954)
			(xy 146.064051 -71.407825) (xy 146.112156 -71.381321) (xy 146.163565 -71.361987) (xy 146.217214 -71.350225)
			(xy 146.271996 -71.346277) (xy 146.326778 -71.350225) (xy 146.380427 -71.361987) (xy 146.431836 -71.381321)
			(xy 146.479941 -71.407825) (xy 146.523749 -71.440954) (xy 146.562354 -71.480022) (xy 146.594958 -71.524222)
			(xy 146.598174 -71.530228) (xy 160.708085 -71.530228) (xy 160.714185 -71.474791) (xy 160.728291 -71.420834)
			(xy 160.750103 -71.369505) (xy 160.779157 -71.321899) (xy 160.814832 -71.279031) (xy 160.856369 -71.241814)
			(xy 160.902882 -71.211041) (xy 160.953379 -71.187369) (xy 161.006786 -71.171301) (xy 161.061962 -71.163181)
			(xy 161.089848 -71.162672) (xy 161.117734 -71.163181) (xy 161.17291 -71.171301) (xy 161.226317 -71.187369)
			(xy 161.276814 -71.211041) (xy 161.323327 -71.241814) (xy 161.364864 -71.279031) (xy 161.400539 -71.321899)
			(xy 161.429593 -71.369505) (xy 161.451405 -71.420834) (xy 161.465511 -71.474791) (xy 161.471611 -71.530228)
			(xy 161.469574 -71.585962) (xy 161.459444 -71.640805) (xy 161.441437 -71.693589) (xy 161.415936 -71.743189)
			(xy 161.383485 -71.788547) (xy 161.344776 -71.828696) (xy 161.300633 -71.862782) (xy 161.251998 -71.890078)
			(xy 161.199907 -71.910001) (xy 161.14547 -71.922127) (xy 161.089848 -71.926198) (xy 161.034226 -71.922127)
			(xy 160.979789 -71.910001) (xy 160.927698 -71.890078) (xy 160.879063 -71.862782) (xy 160.83492 -71.828696)
			(xy 160.796211 -71.788547) (xy 160.76376 -71.743189) (xy 160.738259 -71.693589) (xy 160.720252 -71.640805)
			(xy 160.710122 -71.585962) (xy 160.708085 -71.530228) (xy 146.598174 -71.530228) (xy 146.620887 -71.57264)
			(xy 146.639606 -71.624275) (xy 146.650727 -71.678061) (xy 146.654022 -71.732886) (xy 146.649421 -71.787617)
			(xy 146.63702 -71.841122) (xy 146.617075 -71.892297) (xy 146.589998 -71.940083) (xy 146.556349 -71.983492)
			(xy 146.536918 -72.002904) (xy 146.520938 -72.018981) (xy 146.494452 -72.055763) (xy 146.47491 -72.09666)
			(xy 146.462933 -72.140375) (xy 146.4589 -72.185521) (xy 146.46294 -72.230667) (xy 146.474924 -72.274379)
			(xy 146.494473 -72.315273) (xy 146.520965 -72.352051) (xy 146.536918 -72.368156) (xy 146.551962 -72.383104)
			(xy 162.206955 -72.383104) (xy 162.213344 -72.328975) (xy 162.227373 -72.276307) (xy 162.248756 -72.226172)
			(xy 162.277057 -72.17959) (xy 162.3117 -72.137512) (xy 162.35198 -72.100792) (xy 162.397077 -72.07018)
			(xy 162.446071 -72.046299) (xy 162.497966 -72.029634) (xy 162.551704 -72.020526) (xy 162.606192 -72.019159)
			(xy 162.660319 -72.025562) (xy 162.712984 -72.039604) (xy 162.763114 -72.061) (xy 162.809688 -72.089313)
			(xy 162.831018 -72.106282) (xy 162.844198 -72.116539) (xy 162.874587 -72.130369) (xy 162.907524 -72.135844)
			(xy 162.940753 -72.132588) (xy 162.972 -72.120824) (xy 162.999127 -72.101358) (xy 163.010088 -72.088756)
			(xy 163.027703 -72.067953) (xy 163.067965 -72.031203) (xy 163.113049 -72.000559) (xy 163.162036 -71.976644)
			(xy 163.213928 -71.959945) (xy 163.267668 -71.950802) (xy 163.322163 -71.949403) (xy 163.376302 -71.955774)
			(xy 163.428983 -71.969786) (xy 163.479133 -71.991155) (xy 163.52573 -72.019444) (xy 163.567827 -72.054078)
			(xy 163.604565 -72.094351) (xy 163.635196 -72.139444) (xy 163.659097 -72.188437) (xy 163.675781 -72.240334)
			(xy 163.684908 -72.294077) (xy 163.686292 -72.348572) (xy 163.679906 -72.40271) (xy 163.665878 -72.455386)
			(xy 163.644495 -72.50553) (xy 163.616193 -72.55212) (xy 163.581547 -72.594206) (xy 163.541263 -72.630933)
			(xy 163.496161 -72.661551) (xy 163.447161 -72.685438) (xy 163.395259 -72.702107) (xy 163.341514 -72.711219)
			(xy 163.287018 -72.712587) (xy 163.232883 -72.706185) (xy 163.18021 -72.692142) (xy 163.130073 -72.670745)
			(xy 163.083491 -72.642429) (xy 163.062158 -72.625458) (xy 163.049001 -72.615168) (xy 163.018605 -72.601335)
			(xy 162.985661 -72.595862) (xy 162.952425 -72.599124) (xy 162.921174 -72.610898) (xy 162.894047 -72.630376)
			(xy 162.883088 -72.642984) (xy 162.865432 -72.663749) (xy 162.825171 -72.700488) (xy 162.78009 -72.731123)
			(xy 162.731108 -72.755029) (xy 162.679221 -72.77172) (xy 162.625488 -72.780855) (xy 162.571001 -72.78225)
			(xy 162.51687 -72.775874) (xy 162.464198 -72.761858) (xy 162.414057 -72.740488) (xy 162.367469 -72.712199)
			(xy 162.325381 -72.677566) (xy 162.288652 -72.637295) (xy 162.258029 -72.592207) (xy 162.234135 -72.543218)
			(xy 162.217457 -72.491328) (xy 162.208335 -72.437592) (xy 162.206955 -72.383104) (xy 146.551962 -72.383104)
			(xy 146.55607 -72.387186) (xy 146.589251 -72.42978) (xy 146.616096 -72.476626) (xy 146.63607 -72.526788)
			(xy 146.648774 -72.579264) (xy 146.653954 -72.633008) (xy 146.651507 -72.686944) (xy 146.641481 -72.739998)
			(xy 146.624077 -72.791108) (xy 146.599642 -72.839255) (xy 146.568664 -72.883477) (xy 146.531762 -72.92289)
			(xy 146.51101 -72.940164) (xy 146.493613 -72.954755) (xy 146.46387 -72.989058) (xy 146.440694 -73.028099)
			(xy 146.424822 -73.070637) (xy 146.416759 -73.115318) (xy 146.416763 -73.16072) (xy 146.424832 -73.205399)
			(xy 146.44071 -73.247935) (xy 146.463892 -73.286973) (xy 146.49364 -73.321272) (xy 146.51101 -73.335896)
			(xy 146.531844 -73.353338) (xy 146.568952 -73.393023) (xy 146.600053 -73.437572) (xy 146.624519 -73.486082)
			(xy 146.641856 -73.537573) (xy 146.651711 -73.591003) (xy 146.653886 -73.645291) (xy 146.648337 -73.699338)
			(xy 146.635176 -73.752051) (xy 146.614669 -73.802364) (xy 146.587231 -73.849258) (xy 146.5707 -73.87082)
			(xy 146.557759 -73.887855) (xy 146.537114 -73.92532) (xy 146.52304 -73.965714) (xy 146.515935 -74.007896)
			(xy 146.516 -74.050672) (xy 146.523232 -74.092832) (xy 146.537429 -74.133183) (xy 146.558187 -74.170585)
			(xy 146.571208 -74.187558) (xy 146.588945 -74.21052) (xy 146.617963 -74.260761) (xy 146.639036 -74.314818)
			(xy 146.651677 -74.371443) (xy 146.655595 -74.42933) (xy 146.650699 -74.487142) (xy 146.637102 -74.543545)
			(xy 146.615118 -74.597238) (xy 146.585254 -74.646981) (xy 146.567144 -74.66965) (xy 146.557948 -74.681402)
			(xy 146.54473 -74.708147) (xy 146.538098 -74.737232) (xy 146.538416 -74.767063) (xy 146.545666 -74.796001)
			(xy 146.559451 -74.822457) (xy 146.568922 -74.833988) (xy 146.586945 -74.855426) (xy 146.617056 -74.902652)
			(xy 146.639939 -74.953772) (xy 146.655103 -75.007688) (xy 146.662222 -75.063242) (xy 146.661143 -75.11924)
			(xy 146.651889 -75.174478) (xy 146.634659 -75.22777) (xy 146.609824 -75.277971) (xy 146.590914 -75.305251)
			(xy 158.139968 -75.305251) (xy 158.14577 -75.249904) (xy 158.159552 -75.195987) (xy 158.18102 -75.144644)
			(xy 158.209721 -75.096965) (xy 158.245044 -75.053962) (xy 158.28624 -75.016547) (xy 158.309056 -75.000612)
			(xy 158.327868 -74.987257) (xy 158.360863 -74.955021) (xy 158.387498 -74.917362) (xy 158.406901 -74.875513)
			(xy 158.418433 -74.830851) (xy 158.421717 -74.784841) (xy 158.416643 -74.738993) (xy 158.40338 -74.694814)
			(xy 158.382362 -74.653753) (xy 158.354279 -74.61716) (xy 158.337504 -74.601324) (xy 158.317214 -74.582271)
			(xy 158.281761 -74.539369) (xy 158.252917 -74.491771) (xy 158.231294 -74.440487) (xy 158.217352 -74.386606)
			(xy 158.211387 -74.331271) (xy 158.213525 -74.275656) (xy 158.223721 -74.220942) (xy 158.241758 -74.16829)
			(xy 158.267254 -74.118818) (xy 158.299667 -74.073575) (xy 158.338309 -74.033521) (xy 158.382362 -73.999507)
			(xy 158.430888 -73.972254) (xy 158.48286 -73.952341) (xy 158.537173 -73.940191) (xy 158.592675 -73.936061)
			(xy 158.648189 -73.940038) (xy 158.702535 -73.95204) (xy 158.754561 -73.97181) (xy 158.803162 -73.998929)
			(xy 158.847308 -74.032822) (xy 158.88606 -74.072769) (xy 158.918598 -74.117923) (xy 158.944229 -74.167326)
			(xy 158.962411 -74.219928) (xy 158.972757 -74.274613) (xy 158.975047 -74.330222) (xy 158.969234 -74.385573)
			(xy 158.955441 -74.439492) (xy 158.933959 -74.490835) (xy 158.905246 -74.538513) (xy 158.86991 -74.581512)
			(xy 158.828702 -74.618921) (xy 158.80588 -74.634852) (xy 158.78701 -74.648131) (xy 158.75401 -74.680375)
			(xy 158.727371 -74.718046) (xy 158.707968 -74.759905) (xy 158.705365 -74.76999) (xy 162.292005 -74.76999)
			(xy 162.29786 -74.715292) (xy 162.311511 -74.662002) (xy 162.332674 -74.611225) (xy 162.36091 -74.564014)
			(xy 162.395635 -74.521348) (xy 162.436127 -74.484112) (xy 162.481547 -74.453077) (xy 162.530954 -74.428888)
			(xy 162.583322 -74.412045) (xy 162.637567 -74.402898) (xy 162.692563 -74.401637) (xy 162.74717 -74.408288)
			(xy 162.800256 -74.422713) (xy 162.850719 -74.444612) (xy 162.897515 -74.473532) (xy 162.918902 -74.490834)
			(xy 162.931367 -74.500619) (xy 162.959956 -74.514268) (xy 162.991025 -74.520466) (xy 163.022663 -74.518831)
			(xy 163.052927 -74.509464) (xy 163.079957 -74.492941) (xy 163.091368 -74.481944) (xy 163.111439 -74.461904)
			(xy 163.156524 -74.427489) (xy 163.206207 -74.400126) (xy 163.259393 -74.380419) (xy 163.314909 -74.368802)
			(xy 163.371534 -74.365531) (xy 163.428019 -74.370677) (xy 163.48312 -74.384128) (xy 163.535623 -74.405587)
			(xy 163.584372 -74.434581) (xy 163.628291 -74.470472) (xy 163.666414 -74.512469) (xy 163.697901 -74.559645)
			(xy 163.722058 -74.610963) (xy 163.738352 -74.665292) (xy 163.746425 -74.721433) (xy 163.746098 -74.778152)
			(xy 163.73738 -74.834197) (xy 163.729416 -74.86142) (xy 163.723076 -74.883371) (xy 163.717402 -74.928703)
			(xy 163.719929 -74.974318) (xy 163.730575 -75.018745) (xy 163.748996 -75.060551) (xy 163.7746 -75.098388)
			(xy 163.806558 -75.131034) (xy 163.82492 -75.14463) (xy 163.846868 -75.160791) (xy 163.886446 -75.198264)
			(xy 163.920287 -75.240987) (xy 163.943012 -75.28003) (xy 164.716967 -75.28003) (xy 164.723067 -75.224593)
			(xy 164.737173 -75.170636) (xy 164.758985 -75.119307) (xy 164.788039 -75.071701) (xy 164.823714 -75.028833)
			(xy 164.865251 -74.991616) (xy 164.911764 -74.960843) (xy 164.962261 -74.937171) (xy 165.015668 -74.921103)
			(xy 165.070844 -74.912983) (xy 165.09873 -74.912474) (xy 165.126616 -74.912983) (xy 165.181792 -74.921103)
			(xy 165.235199 -74.937171) (xy 165.285696 -74.960843) (xy 165.332209 -74.991616) (xy 165.373746 -75.028833)
			(xy 165.409421 -75.071701) (xy 165.438475 -75.119307) (xy 165.460287 -75.170636) (xy 165.474393 -75.224593)
			(xy 165.480493 -75.28003) (xy 165.478456 -75.335764) (xy 165.468326 -75.390607) (xy 165.450319 -75.443391)
			(xy 165.424818 -75.492991) (xy 165.392367 -75.538349) (xy 165.353658 -75.578498) (xy 165.309515 -75.612584)
			(xy 165.26088 -75.63988) (xy 165.208789 -75.659803) (xy 165.154352 -75.671929) (xy 165.09873 -75.676)
			(xy 165.043108 -75.671929) (xy 164.988671 -75.659803) (xy 164.93658 -75.63988) (xy 164.887945 -75.612584)
			(xy 164.843802 -75.578498) (xy 164.805093 -75.538349) (xy 164.772642 -75.492991) (xy 164.747141 -75.443391)
			(xy 164.729134 -75.390607) (xy 164.719004 -75.335764) (xy 164.716967 -75.28003) (xy 163.943012 -75.28003)
			(xy 163.947704 -75.288092) (xy 163.968137 -75.33862) (xy 163.981172 -75.391541) (xy 163.986542 -75.445778)
			(xy 163.984138 -75.500228) (xy 163.97401 -75.553782) (xy 163.956362 -75.605348) (xy 163.931556 -75.653879)
			(xy 163.900095 -75.698384) (xy 163.862621 -75.73796) (xy 163.819895 -75.771799) (xy 163.772789 -75.799213)
			(xy 163.72226 -75.819644) (xy 163.669338 -75.832675) (xy 163.615101 -75.838042) (xy 163.560651 -75.835636)
			(xy 163.507098 -75.825504) (xy 163.455532 -75.807854) (xy 163.407004 -75.783045) (xy 163.384484 -75.767692)
			(xy 163.366012 -75.755165) (xy 163.325632 -75.736163) (xy 163.282552 -75.724508) (xy 163.238099 -75.720559)
			(xy 163.193639 -75.724439) (xy 163.150541 -75.736026) (xy 163.110131 -75.754966) (xy 163.091622 -75.767438)
			(xy 163.068339 -75.783355) (xy 163.017973 -75.808736) (xy 162.964418 -75.826425) (xy 162.908843 -75.836036)
			(xy 162.852458 -75.837361) (xy 162.796493 -75.830371) (xy 162.742167 -75.815217) (xy 162.690664 -75.79223)
			(xy 162.643106 -75.761911) (xy 162.60053 -75.724921) (xy 162.563864 -75.682066) (xy 162.533906 -75.634279)
			(xy 162.511311 -75.582603) (xy 162.49657 -75.528163) (xy 162.490004 -75.472146) (xy 162.491756 -75.415773)
			(xy 162.501789 -75.360273) (xy 162.519884 -75.306854) (xy 162.532314 -75.281536) (xy 162.539236 -75.266947)
			(xy 162.546291 -75.235448) (xy 162.545225 -75.203185) (xy 162.536107 -75.17222) (xy 162.519518 -75.144529)
			(xy 162.496518 -75.121879) (xy 162.482784 -75.113388) (xy 162.459189 -75.099245) (xy 162.416023 -75.065145)
			(xy 162.378201 -75.025199) (xy 162.346509 -74.980235) (xy 162.321603 -74.931186) (xy 162.304 -74.879068)
			(xy 162.294066 -74.824962) (xy 162.292005 -74.76999) (xy 158.705365 -74.76999) (xy 158.696438 -74.804579)
			(xy 158.693161 -74.850601) (xy 158.698243 -74.896458) (xy 158.711518 -74.940645) (xy 158.73255 -74.98171)
			(xy 158.760649 -75.018305) (xy 158.777432 -75.03414) (xy 158.797769 -75.053137) (xy 158.83322 -75.096035)
			(xy 158.862063 -75.143628) (xy 158.883685 -75.194906) (xy 158.897627 -75.248782) (xy 158.903594 -75.304112)
			(xy 158.901459 -75.359721) (xy 158.891268 -75.414431) (xy 158.873236 -75.467079) (xy 158.847746 -75.516549)
			(xy 158.815339 -75.56179) (xy 158.776703 -75.601844) (xy 158.732658 -75.635859) (xy 158.684138 -75.663113)
			(xy 158.632174 -75.68303) (xy 158.577867 -75.695185) (xy 158.52237 -75.699321) (xy 158.466861 -75.695351)
			(xy 158.412519 -75.683358) (xy 158.360495 -75.663597) (xy 158.311894 -75.636487) (xy 158.267747 -75.602603)
			(xy 158.228992 -75.562666) (xy 158.196451 -75.517521) (xy 158.170813 -75.468127) (xy 158.152624 -75.415533)
			(xy 158.142269 -75.360855) (xy 158.139968 -75.305251) (xy 146.590914 -75.305251) (xy 146.577916 -75.324001)
			(xy 146.539622 -75.364873) (xy 146.495764 -75.399706) (xy 146.447284 -75.427754) (xy 146.395225 -75.448413)
			(xy 146.340706 -75.46124) (xy 146.284897 -75.465958) (xy 146.228997 -75.462467) (xy 146.174209 -75.450841)
			(xy 146.121709 -75.43133) (xy 146.072625 -75.404354) (xy 146.028013 -75.370492) (xy 145.98883 -75.330472)
			(xy 145.955919 -75.285154) (xy 145.929986 -75.235511) (xy 145.91159 -75.18261) (xy 145.901125 -75.127588)
			(xy 145.898816 -75.071628) (xy 145.904713 -75.015931) (xy 145.918689 -74.961694) (xy 145.940444 -74.910084)
			(xy 145.969511 -74.862208) (xy 145.987008 -74.840338) (xy 145.99622 -74.828596) (xy 146.009441 -74.80185)
			(xy 146.016074 -74.77276) (xy 146.015754 -74.742926) (xy 146.008498 -74.713986) (xy 145.994706 -74.687529)
			(xy 145.98523 -74.676) (xy 145.968253 -74.655706) (xy 145.939437 -74.611332) (xy 145.917029 -74.563402)
			(xy 145.901461 -74.512835) (xy 145.893029 -74.460602) (xy 145.891897 -74.407705) (xy 145.898086 -74.355159)
			(xy 145.911477 -74.303972) (xy 145.931813 -74.255127) (xy 145.958704 -74.209561) (xy 145.974816 -74.188574)
			(xy 145.987762 -74.171543) (xy 146.008405 -74.134077) (xy 146.022478 -74.093682) (xy 146.029582 -74.0515)
			(xy 146.029516 -74.008724) (xy 146.022283 -73.966563) (xy 146.008087 -73.926212) (xy 145.987329 -73.888809)
			(xy 145.974308 -73.871836) (xy 145.957675 -73.850273) (xy 145.92999 -73.80338) (xy 145.909257 -73.753026)
			(xy 145.895899 -73.700234) (xy 145.890186 -73.646079) (xy 145.892234 -73.591662) (xy 145.902003 -73.53809)
			(xy 145.919294 -73.486452) (xy 145.943754 -73.4378) (xy 145.974887 -73.393121) (xy 146.012058 -73.353326)
			(xy 146.032982 -73.335896) (xy 146.05032 -73.321238) (xy 146.080064 -73.286946) (xy 146.103242 -73.247915)
			(xy 146.119118 -73.205388) (xy 146.127186 -73.160716) (xy 146.127189 -73.115322) (xy 146.119128 -73.070649)
			(xy 146.103258 -73.028119) (xy 146.080086 -72.989085) (xy 146.050347 -72.954788) (xy 146.032982 -72.940164)
			(xy 146.012279 -72.922838) (xy 145.975385 -72.883432) (xy 145.944413 -72.839218) (xy 145.919983 -72.79108)
			(xy 145.902583 -72.739979) (xy 145.892559 -72.686936) (xy 145.890112 -72.633009) (xy 145.895291 -72.579276)
			(xy 145.907992 -72.52681) (xy 145.927962 -72.476657) (xy 145.954802 -72.42982) (xy 145.987976 -72.387235)
			(xy 146.007074 -72.368156) (xy 146.022989 -72.35202) (xy 146.049468 -72.315246) (xy 146.069005 -72.274359)
			(xy 146.080983 -72.230656) (xy 146.085021 -72.185521) (xy 146.08099 -72.140385) (xy 146.06902 -72.09668)
			(xy 146.049489 -72.05579) (xy 146.023016 -72.019012) (xy 146.007074 -72.002904) (xy 145.987643 -71.983492)
			(xy 145.953994 -71.940083) (xy 145.926917 -71.892297) (xy 145.906972 -71.841122) (xy 145.894571 -71.787617)
			(xy 145.88997 -71.732886) (xy 135.700808 -71.732886) (xy 135.697442 -71.749192) (xy 135.678802 -71.800721)
			(xy 135.652984 -71.849054) (xy 135.620518 -71.893197) (xy 135.582072 -71.932243) (xy 135.538436 -71.965389)
			(xy 135.490509 -71.991953) (xy 135.439274 -72.011389) (xy 135.385787 -72.023298) (xy 135.331147 -72.027433)
			(xy 135.276476 -72.023711) (xy 135.2229 -72.012208) (xy 135.171521 -71.993161) (xy 135.123393 -71.96696)
			(xy 135.079508 -71.934146) (xy 135.040768 -71.895392) (xy 135.007968 -71.851496) (xy 134.981784 -71.803359)
			(xy 134.962755 -71.751973) (xy 134.95655 -71.725282) (xy 134.951201 -71.70286) (xy 134.933549 -71.660282)
			(xy 134.908511 -71.621584) (xy 134.876907 -71.588033) (xy 134.839774 -71.560728) (xy 134.798327 -71.540563)
			(xy 134.753924 -71.5282) (xy 134.70802 -71.524044) (xy 134.685024 -71.525638) (xy 134.657696 -71.527659)
			(xy 134.602973 -71.524803) (xy 134.549222 -71.514149) (xy 134.497546 -71.495917) (xy 134.44901 -71.470482)
			(xy 134.404611 -71.438365) (xy 134.365262 -71.400229) (xy 134.331773 -71.356856) (xy 134.304831 -71.30914)
			(xy 134.284991 -71.258061) (xy 134.27266 -71.204669) (xy 134.268094 -71.150062) (xy 129.770462 -71.150062)
			(xy 129.794496 -71.212193) (xy 129.818256 -71.295899) (xy 129.834182 -71.381442) (xy 129.842137 -71.468091)
			(xy 129.842054 -71.555104) (xy 129.833933 -71.641737) (xy 129.817844 -71.72725) (xy 129.793924 -71.81091)
			(xy 129.762378 -71.892003) (xy 129.723475 -71.969835) (xy 129.677548 -72.043741) (xy 129.624991 -72.113088)
			(xy 129.566252 -72.177283) (xy 129.501834 -72.235777) (xy 129.432288 -72.28807) (xy 129.395474 -72.31126)
			(xy 129.376217 -72.3237) (xy 129.342135 -72.354355) (xy 129.314105 -72.390626) (xy 129.293034 -72.431337)
			(xy 129.290718 -72.438899) (xy 141.152958 -72.438899) (xy 141.153894 -72.383609) (xy 141.162802 -72.329033)
			(xy 141.179496 -72.276314) (xy 141.203625 -72.226558) (xy 141.234686 -72.180807) (xy 141.272025 -72.140019)
			(xy 141.314863 -72.105049) (xy 141.3623 -72.07663) (xy 141.413343 -72.055357) (xy 141.466922 -72.041676)
			(xy 141.521915 -72.035874) (xy 141.57717 -72.038071) (xy 141.631528 -72.048223) (xy 141.683852 -72.066116)
			(xy 141.733044 -72.091376) (xy 141.778074 -72.123472) (xy 141.817999 -72.161734) (xy 141.835378 -72.183244)
			(xy 141.850051 -72.201159) (xy 141.884661 -72.231914) (xy 141.924274 -72.255885) (xy 141.967575 -72.272277)
			(xy 142.013131 -72.280548) (xy 142.059431 -72.280424) (xy 142.104942 -72.271908) (xy 142.148155 -72.255283)
			(xy 142.187637 -72.231099) (xy 142.205202 -72.21601) (xy 142.226097 -72.197895) (xy 142.272187 -72.167337)
			(xy 142.322207 -72.143753) (xy 142.375107 -72.127638) (xy 142.42978 -72.119328) (xy 142.48508 -72.118999)
			(xy 142.539848 -72.126656) (xy 142.592936 -72.14214) (xy 142.643233 -72.165126) (xy 142.689685 -72.195133)
			(xy 142.731318 -72.231532) (xy 142.76726 -72.27356) (xy 142.796757 -72.320336) (xy 142.819193 -72.370881)
			(xy 142.834097 -72.424136) (xy 142.841156 -72.478984) (xy 142.840223 -72.534276) (xy 142.831317 -72.588855)
			(xy 142.814624 -72.641576) (xy 142.790496 -72.691336) (xy 142.759436 -72.73709) (xy 142.722097 -72.777881)
			(xy 142.679259 -72.812854) (xy 142.631821 -72.841276) (xy 142.580777 -72.862552) (xy 142.527197 -72.876236)
			(xy 142.472202 -72.882041) (xy 142.416944 -72.879845) (xy 142.362583 -72.869696) (xy 142.310257 -72.851804)
			(xy 142.261062 -72.826546) (xy 142.216028 -72.79445) (xy 142.176101 -72.756188) (xy 142.15872 -72.734678)
			(xy 142.144054 -72.716759) (xy 142.109439 -72.686012) (xy 142.069824 -72.662048) (xy 142.026523 -72.64566)
			(xy 141.980968 -72.637392) (xy 141.93467 -72.637516) (xy 141.88916 -72.646029) (xy 141.845947 -72.66265)
			(xy 141.806462 -72.686826) (xy 141.788896 -72.701912) (xy 141.767981 -72.720003) (xy 141.721891 -72.750558)
			(xy 141.671872 -72.774139) (xy 141.618974 -72.790251) (xy 141.564303 -72.798558) (xy 141.509005 -72.798885)
			(xy 141.45424 -72.791226) (xy 141.401154 -72.77574) (xy 141.35086 -72.752753) (xy 141.304411 -72.722745)
			(xy 141.262782 -72.686346) (xy 141.226843 -72.644318) (xy 141.197348 -72.597543) (xy 141.174916 -72.546999)
			(xy 141.160015 -72.493746) (xy 141.152958 -72.438899) (xy 129.290718 -72.438899) (xy 129.279608 -72.475167)
			(xy 129.274261 -72.520694) (xy 129.277167 -72.566442) (xy 129.288231 -72.610927) (xy 129.307095 -72.652706)
			(xy 129.333146 -72.690424) (xy 129.348992 -72.706992) (xy 130.17705 -73.53505) (xy 140.606525 -73.53505)
			(xy 140.612625 -73.479613) (xy 140.626731 -73.425656) (xy 140.648543 -73.374327) (xy 140.677597 -73.326721)
			(xy 140.713272 -73.283853) (xy 140.754809 -73.246636) (xy 140.801322 -73.215863) (xy 140.851819 -73.192191)
			(xy 140.905226 -73.176123) (xy 140.960402 -73.168003) (xy 140.988288 -73.167494) (xy 141.016174 -73.168003)
			(xy 141.07135 -73.176123) (xy 141.124757 -73.192191) (xy 141.175254 -73.215863) (xy 141.221767 -73.246636)
			(xy 141.263304 -73.283853) (xy 141.298979 -73.326721) (xy 141.328033 -73.374327) (xy 141.349845 -73.425656)
			(xy 141.363951 -73.479613) (xy 141.370051 -73.53505) (xy 141.368014 -73.590784) (xy 141.362967 -73.618108)
			(xy 143.604741 -73.618108) (xy 143.610841 -73.562671) (xy 143.624947 -73.508714) (xy 143.646759 -73.457385)
			(xy 143.675813 -73.409779) (xy 143.711488 -73.366911) (xy 143.753025 -73.329694) (xy 143.799538 -73.298921)
			(xy 143.850035 -73.275249) (xy 143.903442 -73.259181) (xy 143.958618 -73.251061) (xy 143.986504 -73.250552)
			(xy 144.01439 -73.251061) (xy 144.069566 -73.259181) (xy 144.122973 -73.275249) (xy 144.17347 -73.298921)
			(xy 144.219983 -73.329694) (xy 144.26152 -73.366911) (xy 144.297195 -73.409779) (xy 144.326249 -73.457385)
			(xy 144.348061 -73.508714) (xy 144.362167 -73.562671) (xy 144.368267 -73.618108) (xy 144.36623 -73.673842)
			(xy 144.3561 -73.728685) (xy 144.338093 -73.781469) (xy 144.312592 -73.831069) (xy 144.280141 -73.876427)
			(xy 144.241432 -73.916576) (xy 144.197289 -73.950662) (xy 144.148654 -73.977958) (xy 144.096563 -73.997881)
			(xy 144.042126 -74.010007) (xy 143.986504 -74.014078) (xy 143.930882 -74.010007) (xy 143.876445 -73.997881)
			(xy 143.824354 -73.977958) (xy 143.775719 -73.950662) (xy 143.731576 -73.916576) (xy 143.692867 -73.876427)
			(xy 143.660416 -73.831069) (xy 143.634915 -73.781469) (xy 143.616908 -73.728685) (xy 143.606778 -73.673842)
			(xy 143.604741 -73.618108) (xy 141.362967 -73.618108) (xy 141.357884 -73.645627) (xy 141.339877 -73.698411)
			(xy 141.314376 -73.748011) (xy 141.281925 -73.793369) (xy 141.243216 -73.833518) (xy 141.199073 -73.867604)
			(xy 141.150438 -73.8949) (xy 141.098347 -73.914823) (xy 141.04391 -73.926949) (xy 140.988288 -73.93102)
			(xy 140.932666 -73.926949) (xy 140.878229 -73.914823) (xy 140.826138 -73.8949) (xy 140.777503 -73.867604)
			(xy 140.73336 -73.833518) (xy 140.694651 -73.793369) (xy 140.6622 -73.748011) (xy 140.636699 -73.698411)
			(xy 140.618692 -73.645627) (xy 140.608562 -73.590784) (xy 140.606525 -73.53505) (xy 130.17705 -73.53505)
			(xy 130.94462 -74.30262) (xy 134.849616 -74.30262) (xy 136.273812 -75.726816) (xy 142.245587 -75.726816)
			(xy 142.251687 -75.671379) (xy 142.265793 -75.617422) (xy 142.287605 -75.566093) (xy 142.316659 -75.518487)
			(xy 142.352334 -75.475619) (xy 142.393871 -75.438402) (xy 142.440384 -75.407629) (xy 142.490881 -75.383957)
			(xy 142.544288 -75.367889) (xy 142.599464 -75.359769) (xy 142.62735 -75.35926) (xy 142.655236 -75.359769)
			(xy 142.710412 -75.367889) (xy 142.763819 -75.383957) (xy 142.814316 -75.407629) (xy 142.860829 -75.438402)
			(xy 142.902366 -75.475619) (xy 142.938041 -75.518487) (xy 142.967095 -75.566093) (xy 142.988907 -75.617422)
			(xy 143.003013 -75.671379) (xy 143.009113 -75.726816) (xy 143.007076 -75.78255) (xy 142.996946 -75.837393)
			(xy 142.978939 -75.890177) (xy 142.953438 -75.939777) (xy 142.920987 -75.985135) (xy 142.882278 -76.025284)
			(xy 142.838135 -76.05937) (xy 142.7895 -76.086666) (xy 142.737409 -76.106589) (xy 142.682972 -76.118715)
			(xy 142.62735 -76.122786) (xy 142.571728 -76.118715) (xy 142.517291 -76.106589) (xy 142.4652 -76.086666)
			(xy 142.416565 -76.05937) (xy 142.372422 -76.025284) (xy 142.333713 -75.985135) (xy 142.301262 -75.939777)
			(xy 142.275761 -75.890177) (xy 142.257754 -75.837393) (xy 142.247624 -75.78255) (xy 142.245587 -75.726816)
			(xy 136.273812 -75.726816) (xy 137.148334 -76.601338) (xy 143.370299 -76.601338) (xy 143.376399 -76.545901)
			(xy 143.390505 -76.491944) (xy 143.412317 -76.440615) (xy 143.441371 -76.393009) (xy 143.477046 -76.350141)
			(xy 143.518583 -76.312924) (xy 143.565096 -76.282151) (xy 143.615593 -76.258479) (xy 143.669 -76.242411)
			(xy 143.724176 -76.234291) (xy 143.752062 -76.233782) (xy 143.779948 -76.234291) (xy 143.835124 -76.242411)
			(xy 143.888531 -76.258479) (xy 143.939028 -76.282151) (xy 143.985541 -76.312924) (xy 144.027078 -76.350141)
			(xy 144.062753 -76.393009) (xy 144.091807 -76.440615) (xy 144.09869 -76.456812) (xy 160.062925 -76.456812)
			(xy 160.069025 -76.401375) (xy 160.083131 -76.347418) (xy 160.104943 -76.296089) (xy 160.133997 -76.248483)
			(xy 160.169672 -76.205615) (xy 160.211209 -76.168398) (xy 160.257722 -76.137625) (xy 160.308219 -76.113953)
			(xy 160.361626 -76.097885) (xy 160.416802 -76.089765) (xy 160.444688 -76.089256) (xy 160.472574 -76.089765)
			(xy 160.52775 -76.097885) (xy 160.581157 -76.113953) (xy 160.631654 -76.137625) (xy 160.678167 -76.168398)
			(xy 160.719704 -76.205615) (xy 160.755379 -76.248483) (xy 160.784433 -76.296089) (xy 160.806245 -76.347418)
			(xy 160.820351 -76.401375) (xy 160.826451 -76.456812) (xy 160.824414 -76.512546) (xy 160.814284 -76.567389)
			(xy 160.796277 -76.620173) (xy 160.770776 -76.669773) (xy 160.738325 -76.715131) (xy 160.699616 -76.75528)
			(xy 160.655473 -76.789366) (xy 160.606838 -76.816662) (xy 160.554747 -76.836585) (xy 160.50031 -76.848711)
			(xy 160.444688 -76.852782) (xy 160.389066 -76.848711) (xy 160.334629 -76.836585) (xy 160.282538 -76.816662)
			(xy 160.233903 -76.789366) (xy 160.18976 -76.75528) (xy 160.151051 -76.715131) (xy 160.1186 -76.669773)
			(xy 160.093099 -76.620173) (xy 160.075092 -76.567389) (xy 160.064962 -76.512546) (xy 160.062925 -76.456812)
			(xy 144.09869 -76.456812) (xy 144.113619 -76.491944) (xy 144.127725 -76.545901) (xy 144.133825 -76.601338)
			(xy 144.131788 -76.657072) (xy 144.121658 -76.711915) (xy 144.103651 -76.764699) (xy 144.07815 -76.814299)
			(xy 144.045699 -76.859657) (xy 144.00699 -76.899806) (xy 143.962847 -76.933892) (xy 143.914212 -76.961188)
			(xy 143.862121 -76.981111) (xy 143.807684 -76.993237) (xy 143.752062 -76.997308) (xy 143.69644 -76.993237)
			(xy 143.642003 -76.981111) (xy 143.589912 -76.961188) (xy 143.541277 -76.933892) (xy 143.497134 -76.899806)
			(xy 143.458425 -76.859657) (xy 143.425974 -76.814299) (xy 143.400473 -76.764699) (xy 143.382466 -76.711915)
			(xy 143.372336 -76.657072) (xy 143.370299 -76.601338) (xy 137.148334 -76.601338) (xy 138.01168 -77.464684)
			(xy 149.124415 -77.464684) (xy 149.130515 -77.409247) (xy 149.144621 -77.35529) (xy 149.166433 -77.303961)
			(xy 149.195487 -77.256355) (xy 149.231162 -77.213487) (xy 149.272699 -77.17627) (xy 149.319212 -77.145497)
			(xy 149.369709 -77.121825) (xy 149.423116 -77.105757) (xy 149.478292 -77.097637) (xy 149.506178 -77.097128)
			(xy 149.534064 -77.097637) (xy 149.58924 -77.105757) (xy 149.642647 -77.121825) (xy 149.693144 -77.145497)
			(xy 149.739657 -77.17627) (xy 149.781194 -77.213487) (xy 149.816869 -77.256355) (xy 149.845923 -77.303961)
			(xy 149.867735 -77.35529) (xy 149.881841 -77.409247) (xy 149.887941 -77.464684) (xy 150.394415 -77.464684)
			(xy 150.400515 -77.409247) (xy 150.414621 -77.35529) (xy 150.436433 -77.303961) (xy 150.465487 -77.256355)
			(xy 150.501162 -77.213487) (xy 150.542699 -77.17627) (xy 150.589212 -77.145497) (xy 150.639709 -77.121825)
			(xy 150.693116 -77.105757) (xy 150.748292 -77.097637) (xy 150.776178 -77.097128) (xy 150.804064 -77.097637)
			(xy 150.85924 -77.105757) (xy 150.912647 -77.121825) (xy 150.963144 -77.145497) (xy 151.009657 -77.17627)
			(xy 151.051194 -77.213487) (xy 151.086869 -77.256355) (xy 151.115923 -77.303961) (xy 151.137735 -77.35529)
			(xy 151.151841 -77.409247) (xy 151.157941 -77.464684) (xy 151.155904 -77.520418) (xy 151.145774 -77.575261)
			(xy 151.127767 -77.628045) (xy 151.102266 -77.677645) (xy 151.069815 -77.723003) (xy 151.031106 -77.763152)
			(xy 150.986963 -77.797238) (xy 150.938328 -77.824534) (xy 150.886237 -77.844457) (xy 150.8318 -77.856583)
			(xy 150.776178 -77.860654) (xy 150.720556 -77.856583) (xy 150.666119 -77.844457) (xy 150.614028 -77.824534)
			(xy 150.565393 -77.797238) (xy 150.52125 -77.763152) (xy 150.482541 -77.723003) (xy 150.45009 -77.677645)
			(xy 150.424589 -77.628045) (xy 150.406582 -77.575261) (xy 150.396452 -77.520418) (xy 150.394415 -77.464684)
			(xy 149.887941 -77.464684) (xy 149.885904 -77.520418) (xy 149.875774 -77.575261) (xy 149.857767 -77.628045)
			(xy 149.832266 -77.677645) (xy 149.799815 -77.723003) (xy 149.761106 -77.763152) (xy 149.716963 -77.797238)
			(xy 149.668328 -77.824534) (xy 149.616237 -77.844457) (xy 149.5618 -77.856583) (xy 149.506178 -77.860654)
			(xy 149.450556 -77.856583) (xy 149.396119 -77.844457) (xy 149.344028 -77.824534) (xy 149.295393 -77.797238)
			(xy 149.25125 -77.763152) (xy 149.212541 -77.723003) (xy 149.18009 -77.677645) (xy 149.154589 -77.628045)
			(xy 149.136582 -77.575261) (xy 149.126452 -77.520418) (xy 149.124415 -77.464684) (xy 138.01168 -77.464684)
			(xy 138.988818 -78.441822) (xy 148.356573 -78.441822) (xy 148.362673 -78.386385) (xy 148.376779 -78.332428)
			(xy 148.398591 -78.281099) (xy 148.427645 -78.233493) (xy 148.46332 -78.190625) (xy 148.504857 -78.153408)
			(xy 148.55137 -78.122635) (xy 148.601867 -78.098963) (xy 148.655274 -78.082895) (xy 148.71045 -78.074775)
			(xy 148.738336 -78.074266) (xy 148.766222 -78.074775) (xy 148.821398 -78.082895) (xy 148.874805 -78.098963)
			(xy 148.925302 -78.122635) (xy 148.971815 -78.153408) (xy 149.013352 -78.190625) (xy 149.049027 -78.233493)
			(xy 149.078081 -78.281099) (xy 149.099893 -78.332428) (xy 149.113999 -78.386385) (xy 149.120099 -78.441822)
			(xy 149.119106 -78.469) (xy 150.037291 -78.469) (xy 150.043391 -78.413563) (xy 150.057497 -78.359606)
			(xy 150.079309 -78.308277) (xy 150.108363 -78.260671) (xy 150.144038 -78.217803) (xy 150.185575 -78.180586)
			(xy 150.232088 -78.149813) (xy 150.282585 -78.126141) (xy 150.335992 -78.110073) (xy 150.391168 -78.101953)
			(xy 150.419054 -78.101444) (xy 150.44694 -78.101953) (xy 150.502116 -78.110073) (xy 150.555523 -78.126141)
			(xy 150.60602 -78.149813) (xy 150.652533 -78.180586) (xy 150.69407 -78.217803) (xy 150.70006 -78.225001)
			(xy 160.071018 -78.225001) (xy 160.071505 -78.171286) (xy 160.07952 -78.11817) (xy 160.094905 -78.066703)
			(xy 160.117355 -78.017903) (xy 160.146427 -77.972732) (xy 160.181547 -77.932086) (xy 160.222019 -77.896765)
			(xy 160.244282 -77.881734) (xy 160.257227 -77.872767) (xy 160.278601 -77.849654) (xy 160.293677 -77.822017)
			(xy 160.30154 -77.791533) (xy 160.301712 -77.760051) (xy 160.294182 -77.729483) (xy 160.287208 -77.715364)
			(xy 160.274601 -77.690814) (xy 160.255833 -77.638916) (xy 160.24474 -77.584855) (xy 160.241552 -77.529759)
			(xy 160.246337 -77.47478) (xy 160.258994 -77.421063) (xy 160.279259 -77.369731) (xy 160.30671 -77.321855)
			(xy 160.340772 -77.278434) (xy 160.380737 -77.240375) (xy 160.425768 -77.208472) (xy 160.474926 -77.18339)
			(xy 160.527186 -77.165654) (xy 160.581456 -77.155633) (xy 160.636604 -77.153537) (xy 160.691478 -77.159409)
			(xy 160.744933 -77.173128) (xy 160.795854 -77.194405) (xy 160.843177 -77.222799) (xy 160.885915 -77.257715)
			(xy 160.923175 -77.298425) (xy 160.95418 -77.344079) (xy 160.978284 -77.393725) (xy 160.994981 -77.446326)
			(xy 161.003925 -77.500784) (xy 161.004929 -77.555962) (xy 160.997971 -77.610709) (xy 160.983196 -77.663882)
			(xy 160.960914 -77.714371) (xy 160.931589 -77.761123) (xy 160.895834 -77.803161) (xy 160.854394 -77.839607)
			(xy 160.83153 -77.855064) (xy 160.818588 -77.864035) (xy 160.797212 -77.887147) (xy 160.782135 -77.914783)
			(xy 160.774272 -77.945267) (xy 160.7741 -77.976747) (xy 160.781629 -78.007315) (xy 160.788604 -78.021434)
			(xy 160.800154 -78.043873) (xy 160.817927 -78.091107) (xy 160.829308 -78.140274) (xy 160.834097 -78.190513)
			(xy 160.833562 -78.215744) (xy 160.83317 -78.238569) (xy 160.839611 -78.283759) (xy 160.854023 -78.327072)
			(xy 160.87594 -78.367113) (xy 160.904659 -78.402593) (xy 160.939254 -78.432373) (xy 160.978613 -78.455492)
			(xy 161.021469 -78.471208) (xy 161.043874 -78.475586) (xy 161.069378 -78.480458) (xy 161.118838 -78.496263)
			(xy 161.165698 -78.518629) (xy 161.209092 -78.547143) (xy 161.248219 -78.581278) (xy 161.265616 -78.600554)
			(xy 161.280635 -78.617004) (xy 161.315334 -78.644929) (xy 161.354371 -78.666375) (xy 161.396549 -78.680686)
			(xy 161.440577 -78.687423) (xy 161.485105 -78.686379) (xy 161.528768 -78.677586) (xy 161.57023 -78.661315)
			(xy 161.589466 -78.650084) (xy 161.613402 -78.636022) (xy 161.664485 -78.614284) (xy 161.718178 -78.600177)
			(xy 161.773348 -78.593996) (xy 161.828831 -78.595873) (xy 161.883457 -78.605769) (xy 161.936074 -78.623473)
			(xy 161.98557 -78.648614) (xy 162.030902 -78.68066) (xy 162.071113 -78.718935) (xy 162.105356 -78.762631)
			(xy 162.119564 -78.786482) (xy 162.131685 -78.806632) (xy 162.162088 -78.842496) (xy 162.198567 -78.87216)
			(xy 162.239877 -78.894611) (xy 162.284611 -78.909084) (xy 162.331244 -78.915087) (xy 162.378185 -78.912414)
			(xy 162.423834 -78.901157) (xy 162.445446 -78.891892) (xy 162.471366 -78.880668) (xy 162.525658 -78.865099)
			(xy 162.581653 -78.857708) (xy 162.638126 -78.858655) (xy 162.693841 -78.867921) (xy 162.747581 -78.885303)
			(xy 162.798169 -78.91042) (xy 162.8445 -78.942723) (xy 162.88556 -78.981506) (xy 162.903408 -79.003398)
			(xy 162.918007 -79.021163) (xy 162.952464 -79.051603) (xy 162.991835 -79.075348) (xy 163.034836 -79.091622)
			(xy 163.080063 -79.099894) (xy 163.126041 -79.099894) (xy 163.171268 -79.091622) (xy 163.214269 -79.075348)
			(xy 163.25364 -79.051603) (xy 163.288097 -79.021163) (xy 163.302696 -79.003398) (xy 163.320251 -78.981846)
			(xy 163.360571 -78.943582) (xy 163.406017 -78.911574) (xy 163.455627 -78.8865) (xy 163.50835 -78.86889)
			(xy 163.56307 -78.859118) (xy 163.618629 -78.857389) (xy 163.673851 -78.863741) (xy 163.727567 -78.878039)
			(xy 163.77864 -78.89998) (xy 163.825988 -78.9291) (xy 163.868609 -78.964783) (xy 163.9056 -79.006273)
			(xy 163.93618 -79.052692) (xy 163.9597 -79.103057) (xy 163.975663 -79.156301) (xy 163.98373 -79.211299)
			(xy 163.983732 -79.266885) (xy 163.975667 -79.321883) (xy 163.959706 -79.375129) (xy 163.936188 -79.425494)
			(xy 163.90561 -79.471914) (xy 163.86862 -79.513406) (xy 163.826 -79.54909) (xy 163.778654 -79.578213)
			(xy 163.727582 -79.600156) (xy 163.673867 -79.614456) (xy 163.618645 -79.62081) (xy 163.563086 -79.619084)
			(xy 163.508365 -79.609313) (xy 163.455641 -79.591706) (xy 163.406031 -79.566634) (xy 163.360584 -79.534628)
			(xy 163.320262 -79.496366) (xy 163.302696 -79.474822) (xy 163.288097 -79.457057) (xy 163.25364 -79.426617)
			(xy 163.214269 -79.402872) (xy 163.171268 -79.386598) (xy 163.126041 -79.378326) (xy 163.080063 -79.378326)
			(xy 163.034836 -79.386598) (xy 162.991835 -79.402872) (xy 162.952464 -79.426617) (xy 162.918007 -79.457057)
			(xy 162.903408 -79.474822) (xy 162.886629 -79.495557) (xy 162.848146 -79.532494) (xy 162.804893 -79.563711)
			(xy 162.757714 -79.588599) (xy 162.707528 -79.606673) (xy 162.655314 -79.61758) (xy 162.602089 -79.621108)
			(xy 162.548892 -79.617187) (xy 162.49676 -79.605895) (xy 162.446709 -79.587451) (xy 162.399714 -79.562215)
			(xy 162.356694 -79.530679) (xy 162.318485 -79.493458) (xy 162.285833 -79.451278) (xy 162.272218 -79.42834)
			(xy 162.260139 -79.408164) (xy 162.229724 -79.372306) (xy 162.193237 -79.342649) (xy 162.15192 -79.320203)
			(xy 162.107182 -79.305734) (xy 162.060546 -79.299734) (xy 162.013602 -79.302408) (xy 161.96795 -79.313665)
			(xy 161.946336 -79.32293) (xy 161.915856 -79.335376) (xy 161.902194 -79.340668) (xy 161.877548 -79.356492)
			(xy 161.85717 -79.37753) (xy 161.84214 -79.402669) (xy 161.833252 -79.430577) (xy 161.830977 -79.459777)
			(xy 161.832798 -79.474314) (xy 161.83639 -79.50066) (xy 161.83704 -79.553828) (xy 161.830302 -79.606571)
			(xy 161.816306 -79.657869) (xy 161.795325 -79.706726) (xy 161.767764 -79.752198) (xy 161.734156 -79.793402)
			(xy 161.695154 -79.829542) (xy 161.651512 -79.859918) (xy 161.604076 -79.88394) (xy 161.553764 -79.901144)
			(xy 161.527744 -79.906622) (xy 161.505931 -79.911306) (xy 161.464287 -79.927301) (xy 161.426072 -79.950316)
			(xy 161.392457 -79.979644) (xy 161.364474 -80.014386) (xy 161.34298 -80.053477) (xy 161.328635 -80.095718)
			(xy 161.324798 -80.117696) (xy 161.320234 -80.14479) (xy 161.304303 -80.197374) (xy 161.280994 -80.247129)
			(xy 161.250788 -80.293025) (xy 161.214311 -80.334113) (xy 161.172317 -80.369544) (xy 161.125674 -80.398585)
			(xy 161.075348 -80.420634) (xy 161.02238 -80.435236) (xy 160.967865 -80.442089) (xy 160.912931 -80.44105)
			(xy 160.858714 -80.432142) (xy 160.806335 -80.415548) (xy 160.756879 -80.391613) (xy 160.711367 -80.36083)
			(xy 160.670742 -80.323837) (xy 160.635844 -80.281399) (xy 160.607395 -80.234394) (xy 160.585982 -80.183794)
			(xy 160.57205 -80.130646) (xy 160.565886 -80.076049) (xy 160.567618 -80.021132) (xy 160.571942 -79.993998)
			(xy 160.57418 -79.978023) (xy 160.571596 -79.945884) (xy 160.561039 -79.915418) (xy 160.543183 -79.88857)
			(xy 160.519169 -79.867054) (xy 160.490528 -79.852244) (xy 160.474914 -79.848202) (xy 160.448381 -79.841818)
			(xy 160.3974 -79.822339) (xy 160.349715 -79.795796) (xy 160.306298 -79.762729) (xy 160.268035 -79.723813)
			(xy 160.235708 -79.679842) (xy 160.209976 -79.631714) (xy 160.191363 -79.580411) (xy 160.180251 -79.526979)
			(xy 160.176864 -79.472509) (xy 160.181274 -79.418112) (xy 160.193389 -79.364899) (xy 160.212962 -79.313954)
			(xy 160.239595 -79.266318) (xy 160.272743 -79.222963) (xy 160.31173 -79.184774) (xy 160.355761 -79.152528)
			(xy 160.403937 -79.126886) (xy 160.429448 -79.11719) (xy 160.450917 -79.108913) (xy 160.490672 -79.085757)
			(xy 160.525615 -79.055829) (xy 160.554605 -79.020104) (xy 160.576696 -78.979747) (xy 160.591169 -78.936075)
			(xy 160.597551 -78.890512) (xy 160.597088 -78.867508) (xy 160.597088 -78.837282) (xy 160.597414 -78.814458)
			(xy 160.590979 -78.769274) (xy 160.576575 -78.725966) (xy 160.554666 -78.685928) (xy 160.525958 -78.650448)
			(xy 160.491372 -78.620667) (xy 160.452023 -78.597544) (xy 160.409177 -78.581822) (xy 160.386776 -78.57744)
			(xy 160.360382 -78.572453) (xy 160.309284 -78.555884) (xy 160.261015 -78.532313) (xy 160.216528 -78.502206)
			(xy 160.176703 -78.466158) (xy 160.142327 -78.42488) (xy 160.114079 -78.37919) (xy 160.092517 -78.329991)
			(xy 160.078069 -78.278253) (xy 160.071018 -78.225001) (xy 150.70006 -78.225001) (xy 150.729745 -78.260671)
			(xy 150.758799 -78.308277) (xy 150.780611 -78.359606) (xy 150.794717 -78.413563) (xy 150.800817 -78.469)
			(xy 150.79878 -78.524734) (xy 150.78865 -78.579577) (xy 150.770643 -78.632361) (xy 150.745142 -78.681961)
			(xy 150.712691 -78.727319) (xy 150.673982 -78.767468) (xy 150.629839 -78.801554) (xy 150.581204 -78.82885)
			(xy 150.529113 -78.848773) (xy 150.474676 -78.860899) (xy 150.419054 -78.86497) (xy 150.363432 -78.860899)
			(xy 150.308995 -78.848773) (xy 150.256904 -78.82885) (xy 150.208269 -78.801554) (xy 150.164126 -78.767468)
			(xy 150.125417 -78.727319) (xy 150.092966 -78.681961) (xy 150.067465 -78.632361) (xy 150.049458 -78.579577)
			(xy 150.039328 -78.524734) (xy 150.037291 -78.469) (xy 149.119106 -78.469) (xy 149.118062 -78.497556)
			(xy 149.107932 -78.552399) (xy 149.089925 -78.605183) (xy 149.064424 -78.654783) (xy 149.031973 -78.700141)
			(xy 148.993264 -78.74029) (xy 148.949121 -78.774376) (xy 148.900486 -78.801672) (xy 148.848395 -78.821595)
			(xy 148.793958 -78.833721) (xy 148.738336 -78.837792) (xy 148.682714 -78.833721) (xy 148.628277 -78.821595)
			(xy 148.576186 -78.801672) (xy 148.527551 -78.774376) (xy 148.483408 -78.74029) (xy 148.444699 -78.700141)
			(xy 148.412248 -78.654783) (xy 148.386747 -78.605183) (xy 148.36874 -78.552399) (xy 148.35861 -78.497556)
			(xy 148.356573 -78.441822) (xy 138.988818 -78.441822) (xy 139.627716 -79.08072) (xy 146.087926 -79.08072)
			(xy 146.095675 -79.026347) (xy 146.111138 -78.973647) (xy 146.133997 -78.923709) (xy 146.163779 -78.877563)
			(xy 146.199869 -78.836164) (xy 146.241522 -78.800367) (xy 146.287876 -78.770911) (xy 146.337975 -78.748404)
			(xy 146.390782 -78.733313) (xy 146.445208 -78.725948) (xy 146.500127 -78.726462) (xy 146.554406 -78.734845)
			(xy 146.606921 -78.750922) (xy 146.65659 -78.774362) (xy 146.702385 -78.804681) (xy 146.74336 -78.841252)
			(xy 146.778669 -78.88332) (xy 146.807582 -78.930015) (xy 146.829502 -78.980372) (xy 146.843976 -79.033353)
			(xy 146.847814 -79.060548) (xy 146.851208 -79.083522) (xy 146.865156 -79.127809) (xy 146.886925 -79.168822)
			(xy 146.915789 -79.205193) (xy 146.950785 -79.235708) (xy 146.990747 -79.259351) (xy 147.034342 -79.275333)
			(xy 147.080117 -79.28312) (xy 147.103338 -79.283306) (xy 147.108418 -79.283306) (xy 147.131406 -79.282812)
			(xy 147.176628 -79.274506) (xy 147.219619 -79.258205) (xy 147.258978 -79.23444) (xy 147.293423 -79.203985)
			(xy 147.321831 -79.167834) (xy 147.343276 -79.127163) (xy 147.357059 -79.0833) (xy 147.360386 -79.060548)
			(xy 147.364338 -79.032586) (xy 147.379459 -78.978176) (xy 147.402435 -78.92659) (xy 147.432764 -78.878953)
			(xy 147.469783 -78.836308) (xy 147.512684 -78.799586) (xy 147.56053 -78.769588) (xy 147.612275 -78.746971)
			(xy 147.666788 -78.732228) (xy 147.722879 -78.725682) (xy 147.779322 -78.727476) (xy 147.834885 -78.737569)
			(xy 147.888352 -78.755743) (xy 147.938556 -78.7816) (xy 147.984401 -78.814574) (xy 148.024884 -78.853947)
			(xy 148.059122 -78.898856) (xy 148.086365 -78.948322) (xy 148.10602 -79.001263) (xy 148.117655 -79.056523)
			(xy 148.119846 -79.084678) (xy 148.121659 -79.106757) (xy 148.131887 -79.149853) (xy 148.149436 -79.190522)
			(xy 148.173775 -79.227529) (xy 148.204165 -79.259753) (xy 148.239685 -79.286216) (xy 148.279257 -79.306115)
			(xy 148.321681 -79.318847) (xy 148.34362 -79.321914) (xy 148.370943 -79.32569) (xy 148.424209 -79.340003)
			(xy 148.474858 -79.361838) (xy 148.521835 -79.390739) (xy 148.56416 -79.426104) (xy 148.600951 -79.467196)
			(xy 148.631442 -79.513157) (xy 148.654995 -79.56303) (xy 148.671121 -79.615775) (xy 148.679484 -79.670293)
			(xy 148.679908 -79.725447) (xy 148.672385 -79.780087) (xy 148.657072 -79.833074) (xy 148.634288 -79.883303)
			(xy 148.604509 -79.929728) (xy 148.568354 -79.97138) (xy 148.526577 -80.007392) (xy 148.480051 -80.037013)
			(xy 148.429743 -80.059624) (xy 148.376704 -80.074755) (xy 148.322039 -80.08209) (xy 148.266887 -80.081477)
			(xy 148.212398 -80.072928) (xy 148.159709 -80.056621) (xy 148.109917 -80.032896) (xy 148.06406 -80.002248)
			(xy 148.023095 -79.965316) (xy 147.987875 -79.92287) (xy 147.959136 -79.875794) (xy 147.937475 -79.82507)
			(xy 147.923344 -79.771756) (xy 147.917038 -79.716962) (xy 147.918689 -79.661832) (xy 147.922996 -79.634588)
			(xy 147.925387 -79.617822) (xy 147.922376 -79.584108) (xy 147.910593 -79.552376) (xy 147.890871 -79.524867)
			(xy 147.864601 -79.503521) (xy 147.833638 -79.489846) (xy 147.800167 -79.484806) (xy 147.783296 -79.486252)
			(xy 147.77235 -79.487445) (xy 147.750365 -79.488715) (xy 147.739354 -79.488792) (xy 147.716368 -79.489353)
			(xy 147.67115 -79.497647) (xy 147.62816 -79.513936) (xy 147.588801 -79.537691) (xy 147.554355 -79.568137)
			(xy 147.525945 -79.60428) (xy 147.504499 -79.644944) (xy 147.490714 -79.688801) (xy 147.487386 -79.71155)
			(xy 147.483514 -79.738922) (xy 147.468898 -79.792234) (xy 147.446742 -79.84288) (xy 147.41751 -79.889798)
			(xy 147.381813 -79.932007) (xy 147.3404 -79.968624) (xy 147.294136 -79.998882) (xy 147.243991 -80.022147)
			(xy 147.191013 -80.037934) (xy 147.136312 -80.04591) (xy 147.081032 -80.04591) (xy 147.026331 -80.037934)
			(xy 146.973353 -80.022147) (xy 146.923208 -79.998882) (xy 146.876944 -79.968624) (xy 146.835531 -79.932007)
			(xy 146.799834 -79.889798) (xy 146.770602 -79.84288) (xy 146.748446 -79.792234) (xy 146.73383 -79.738922)
			(xy 146.729958 -79.71155) (xy 146.726593 -79.688571) (xy 146.712643 -79.644281) (xy 146.69087 -79.603266)
			(xy 146.662002 -79.566895) (xy 146.627001 -79.536379) (xy 146.587035 -79.512738) (xy 146.543435 -79.496759)
			(xy 146.497657 -79.488975) (xy 146.474434 -79.488792) (xy 146.44697 -79.488758) (xy 146.392511 -79.481645)
			(xy 146.339634 -79.466798) (xy 146.289432 -79.444523) (xy 146.242942 -79.415281) (xy 146.201125 -79.379677)
			(xy 146.164844 -79.338445) (xy 146.134849 -79.292437) (xy 146.111759 -79.242605) (xy 146.096053 -79.189977)
			(xy 146.088053 -79.135641) (xy 146.087926 -79.08072) (xy 139.627716 -79.08072) (xy 141.205984 -80.658988)
			(xy 159.165797 -80.658988) (xy 159.171897 -80.603551) (xy 159.186003 -80.549594) (xy 159.207815 -80.498265)
			(xy 159.236869 -80.450659) (xy 159.272544 -80.407791) (xy 159.314081 -80.370574) (xy 159.360594 -80.339801)
			(xy 159.411091 -80.316129) (xy 159.464498 -80.300061) (xy 159.519674 -80.291941) (xy 159.54756 -80.291432)
			(xy 159.575446 -80.291941) (xy 159.630622 -80.300061) (xy 159.684029 -80.316129) (xy 159.734526 -80.339801)
			(xy 159.781039 -80.370574) (xy 159.822576 -80.407791) (xy 159.858251 -80.450659) (xy 159.887305 -80.498265)
			(xy 159.909117 -80.549594) (xy 159.923223 -80.603551) (xy 159.929323 -80.658988) (xy 159.927286 -80.714722)
			(xy 159.917156 -80.769565) (xy 159.899149 -80.822349) (xy 159.873648 -80.871949) (xy 159.841197 -80.917307)
			(xy 159.802488 -80.957456) (xy 159.758345 -80.991542) (xy 159.70971 -81.018838) (xy 159.657619 -81.038761)
			(xy 159.603182 -81.050887) (xy 159.54756 -81.054958) (xy 159.491938 -81.050887) (xy 159.437501 -81.038761)
			(xy 159.38541 -81.018838) (xy 159.336775 -80.991542) (xy 159.292632 -80.957456) (xy 159.253923 -80.917307)
			(xy 159.221472 -80.871949) (xy 159.195971 -80.822349) (xy 159.177964 -80.769565) (xy 159.167834 -80.714722)
			(xy 159.165797 -80.658988) (xy 141.205984 -80.658988) (xy 141.650484 -81.103488) (xy 149.980395 -81.103488)
			(xy 149.986495 -81.048051) (xy 150.000601 -80.994094) (xy 150.022413 -80.942765) (xy 150.051467 -80.895159)
			(xy 150.087142 -80.852291) (xy 150.128679 -80.815074) (xy 150.175192 -80.784301) (xy 150.225689 -80.760629)
			(xy 150.279096 -80.744561) (xy 150.334272 -80.736441) (xy 150.362158 -80.735932) (xy 150.390044 -80.736441)
			(xy 150.44522 -80.744561) (xy 150.498627 -80.760629) (xy 150.549124 -80.784301) (xy 150.595637 -80.815074)
			(xy 150.637174 -80.852291) (xy 150.672849 -80.895159) (xy 150.701903 -80.942765) (xy 150.723715 -80.994094)
			(xy 150.737821 -81.048051) (xy 150.743921 -81.103488) (xy 150.741884 -81.159222) (xy 150.731754 -81.214065)
			(xy 150.713747 -81.266849) (xy 150.688246 -81.316449) (xy 150.655795 -81.361807) (xy 150.617086 -81.401956)
			(xy 150.572943 -81.436042) (xy 150.524308 -81.463338) (xy 150.472217 -81.483261) (xy 150.41778 -81.495387)
			(xy 150.362158 -81.499458) (xy 150.306536 -81.495387) (xy 150.252099 -81.483261) (xy 150.200008 -81.463338)
			(xy 150.151373 -81.436042) (xy 150.10723 -81.401956) (xy 150.068521 -81.361807) (xy 150.03607 -81.316449)
			(xy 150.010569 -81.266849) (xy 149.992562 -81.214065) (xy 149.982432 -81.159222) (xy 149.980395 -81.103488)
			(xy 141.650484 -81.103488) (xy 142.125032 -81.578036) (xy 147.887353 -81.578036) (xy 147.892383 -81.523543)
			(xy 147.905148 -81.470329) (xy 147.925388 -81.419486) (xy 147.952686 -81.372057) (xy 147.986482 -81.329016)
			(xy 148.026083 -81.291247) (xy 148.070675 -81.259526) (xy 148.119342 -81.234502) (xy 148.171087 -81.216692)
			(xy 148.224845 -81.206459) (xy 148.279515 -81.204014) (xy 148.333972 -81.209407) (xy 148.3871 -81.222527)
			(xy 148.437807 -81.243106) (xy 148.485052 -81.270721) (xy 148.527866 -81.304804) (xy 148.56537 -81.344656)
			(xy 148.596793 -81.389458) (xy 148.621491 -81.438292) (xy 148.638955 -81.490154) (xy 148.644356 -81.516982)
			(xy 148.648229 -81.535796) (xy 158.068517 -81.535796) (xy 158.074617 -81.480359) (xy 158.088723 -81.426402)
			(xy 158.110535 -81.375073) (xy 158.139589 -81.327467) (xy 158.175264 -81.284599) (xy 158.216801 -81.247382)
			(xy 158.263314 -81.216609) (xy 158.313811 -81.192937) (xy 158.367218 -81.176869) (xy 158.422394 -81.168749)
			(xy 158.45028 -81.16824) (xy 158.478166 -81.168749) (xy 158.533342 -81.176869) (xy 158.586749 -81.192937)
			(xy 158.637246 -81.216609) (xy 158.683759 -81.247382) (xy 158.725296 -81.284599) (xy 158.760971 -81.327467)
			(xy 158.790025 -81.375073) (xy 158.811837 -81.426402) (xy 158.825943 -81.480359) (xy 158.832043 -81.535796)
			(xy 158.830006 -81.59153) (xy 158.821863 -81.635618) (xy 160.110677 -81.635618) (xy 160.116777 -81.580181)
			(xy 160.130883 -81.526224) (xy 160.152695 -81.474895) (xy 160.181749 -81.427289) (xy 160.217424 -81.384421)
			(xy 160.258961 -81.347204) (xy 160.305474 -81.316431) (xy 160.355971 -81.292759) (xy 160.409378 -81.276691)
			(xy 160.464554 -81.268571) (xy 160.49244 -81.268062) (xy 160.520326 -81.268571) (xy 160.575502 -81.276691)
			(xy 160.628909 -81.292759) (xy 160.679406 -81.316431) (xy 160.725919 -81.347204) (xy 160.767456 -81.384421)
			(xy 160.803131 -81.427289) (xy 160.832185 -81.474895) (xy 160.853997 -81.526224) (xy 160.868103 -81.580181)
			(xy 160.874203 -81.635618) (xy 160.872166 -81.691352) (xy 160.862036 -81.746195) (xy 160.844029 -81.798979)
			(xy 160.818528 -81.848579) (xy 160.786077 -81.893937) (xy 160.747368 -81.934086) (xy 160.703225 -81.968172)
			(xy 160.65459 -81.995468) (xy 160.602499 -82.015391) (xy 160.548062 -82.027517) (xy 160.49244 -82.031588)
			(xy 160.436818 -82.027517) (xy 160.382381 -82.015391) (xy 160.33029 -81.995468) (xy 160.281655 -81.968172)
			(xy 160.237512 -81.934086) (xy 160.198803 -81.893937) (xy 160.166352 -81.848579) (xy 160.140851 -81.798979)
			(xy 160.122844 -81.746195) (xy 160.112714 -81.691352) (xy 160.110677 -81.635618) (xy 158.821863 -81.635618)
			(xy 158.819876 -81.646373) (xy 158.801869 -81.699157) (xy 158.776368 -81.748757) (xy 158.743917 -81.794115)
			(xy 158.705208 -81.834264) (xy 158.661065 -81.86835) (xy 158.61243 -81.895646) (xy 158.560339 -81.915569)
			(xy 158.505902 -81.927695) (xy 158.45028 -81.931766) (xy 158.394658 -81.927695) (xy 158.340221 -81.915569)
			(xy 158.28813 -81.895646) (xy 158.239495 -81.86835) (xy 158.195352 -81.834264) (xy 158.156643 -81.794115)
			(xy 158.124192 -81.748757) (xy 158.098691 -81.699157) (xy 158.080684 -81.646373) (xy 158.070554 -81.59153)
			(xy 158.068517 -81.535796) (xy 148.648229 -81.535796) (xy 148.649134 -81.540191) (xy 148.666112 -81.584422)
			(xy 148.690993 -81.624741) (xy 148.722916 -81.659749) (xy 148.760775 -81.688234) (xy 148.803257 -81.709208)
			(xy 148.848891 -81.721945) (xy 148.872448 -81.7245) (xy 148.899666 -81.727313) (xy 148.952957 -81.739726)
			(xy 149.003927 -81.759628) (xy 149.05153 -81.78661) (xy 149.094788 -81.820117) (xy 149.132814 -81.859463)
			(xy 149.164826 -81.903839) (xy 149.190168 -81.952335) (xy 149.208319 -82.003955) (xy 149.218906 -82.057638)
			(xy 149.220596 -82.090532) (xy 149.728173 -82.090532) (xy 149.734273 -82.035095) (xy 149.748379 -81.981138)
			(xy 149.770191 -81.929809) (xy 149.799245 -81.882203) (xy 149.83492 -81.839335) (xy 149.876457 -81.802118)
			(xy 149.92297 -81.771345) (xy 149.973467 -81.747673) (xy 150.026874 -81.731605) (xy 150.08205 -81.723485)
			(xy 150.109936 -81.722976) (xy 150.137822 -81.723485) (xy 150.192998 -81.731605) (xy 150.246405 -81.747673)
			(xy 150.296902 -81.771345) (xy 150.343415 -81.802118) (xy 150.384952 -81.839335) (xy 150.420627 -81.882203)
			(xy 150.449681 -81.929809) (xy 150.471493 -81.981138) (xy 150.485599 -82.035095) (xy 150.491699 -82.090532)
			(xy 150.489662 -82.146266) (xy 150.479532 -82.201109) (xy 150.461525 -82.253893) (xy 150.436024 -82.303493)
			(xy 150.403573 -82.348851) (xy 150.364864 -82.389) (xy 150.320721 -82.423086) (xy 150.272086 -82.450382)
			(xy 150.219995 -82.470305) (xy 150.165558 -82.482431) (xy 150.109936 -82.486502) (xy 150.054314 -82.482431)
			(xy 149.999877 -82.470305) (xy 149.947786 -82.450382) (xy 149.899151 -82.423086) (xy 149.855008 -82.389)
			(xy 149.816299 -82.348851) (xy 149.783848 -82.303493) (xy 149.758347 -82.253893) (xy 149.74034 -82.201109)
			(xy 149.73021 -82.146266) (xy 149.728173 -82.090532) (xy 149.220596 -82.090532) (xy 149.221713 -82.112284)
			(xy 149.216681 -82.16677) (xy 149.203915 -82.219978) (xy 149.183675 -82.270814) (xy 149.156378 -82.318237)
			(xy 149.122584 -82.361272) (xy 149.082986 -82.399035) (xy 149.038398 -82.430752) (xy 148.989735 -82.455771)
			(xy 148.937996 -82.473578) (xy 148.884243 -82.483809) (xy 148.82958 -82.486253) (xy 148.775129 -82.480859)
			(xy 148.722007 -82.46774) (xy 148.671306 -82.447163) (xy 148.624066 -82.419551) (xy 148.581257 -82.385472)
			(xy 148.543757 -82.345625) (xy 148.512337 -82.300827) (xy 148.487642 -82.251999) (xy 148.470178 -82.200143)
			(xy 148.464778 -82.173318) (xy 148.459971 -82.150116) (xy 148.442996 -82.105887) (xy 148.418119 -82.06557)
			(xy 148.3862 -82.030562) (xy 148.348347 -82.002076) (xy 148.30587 -81.981099) (xy 148.260241 -81.968357)
			(xy 148.236686 -81.9658) (xy 148.209462 -81.963025) (xy 148.156163 -81.950615) (xy 148.105186 -81.930715)
			(xy 148.057576 -81.903735) (xy 148.01431 -81.870226) (xy 147.976278 -81.830879) (xy 147.944259 -81.7865)
			(xy 147.918911 -81.738001) (xy 147.900755 -81.686376) (xy 147.890163 -81.632687) (xy 147.887353 -81.578036)
			(xy 142.125032 -81.578036) (xy 143.46633 -82.919334) (xy 152.386537 -82.919334) (xy 152.392637 -82.863897)
			(xy 152.406743 -82.80994) (xy 152.428555 -82.758611) (xy 152.457609 -82.711005) (xy 152.493284 -82.668137)
			(xy 152.534821 -82.63092) (xy 152.581334 -82.600147) (xy 152.631831 -82.576475) (xy 152.685238 -82.560407)
			(xy 152.740414 -82.552287) (xy 152.7683 -82.551778) (xy 152.796186 -82.552287) (xy 152.851362 -82.560407)
			(xy 152.904769 -82.576475) (xy 152.941526 -82.593706) (xy 157.832297 -82.593706) (xy 157.838397 -82.538269)
			(xy 157.852503 -82.484312) (xy 157.874315 -82.432983) (xy 157.903369 -82.385377) (xy 157.939044 -82.342509)
			(xy 157.980581 -82.305292) (xy 158.027094 -82.274519) (xy 158.077591 -82.250847) (xy 158.130998 -82.234779)
			(xy 158.186174 -82.226659) (xy 158.21406 -82.22615) (xy 158.241946 -82.226659) (xy 158.297122 -82.234779)
			(xy 158.350529 -82.250847) (xy 158.401026 -82.274519) (xy 158.447539 -82.305292) (xy 158.489076 -82.342509)
			(xy 158.524751 -82.385377) (xy 158.553805 -82.432983) (xy 158.575617 -82.484312) (xy 158.589723 -82.538269)
			(xy 158.595823 -82.593706) (xy 158.593786 -82.64944) (xy 158.583656 -82.704283) (xy 158.565649 -82.757067)
			(xy 158.540148 -82.806667) (xy 158.507697 -82.852025) (xy 158.468988 -82.892174) (xy 158.424845 -82.92626)
			(xy 158.37621 -82.953556) (xy 158.324119 -82.973479) (xy 158.269682 -82.985605) (xy 158.21406 -82.989676)
			(xy 158.158438 -82.985605) (xy 158.104001 -82.973479) (xy 158.05191 -82.953556) (xy 158.003275 -82.92626)
			(xy 157.959132 -82.892174) (xy 157.920423 -82.852025) (xy 157.887972 -82.806667) (xy 157.862471 -82.757067)
			(xy 157.844464 -82.704283) (xy 157.834334 -82.64944) (xy 157.832297 -82.593706) (xy 152.941526 -82.593706)
			(xy 152.955266 -82.600147) (xy 153.001779 -82.63092) (xy 153.043316 -82.668137) (xy 153.078991 -82.711005)
			(xy 153.108045 -82.758611) (xy 153.129857 -82.80994) (xy 153.143963 -82.863897) (xy 153.150063 -82.919334)
			(xy 153.148026 -82.975068) (xy 153.137896 -83.029911) (xy 153.119889 -83.082695) (xy 153.094388 -83.132295)
			(xy 153.061937 -83.177653) (xy 153.023228 -83.217802) (xy 152.979085 -83.251888) (xy 152.93045 -83.279184)
			(xy 152.878359 -83.299107) (xy 152.823922 -83.311233) (xy 152.7683 -83.315304) (xy 152.712678 -83.311233)
			(xy 152.658241 -83.299107) (xy 152.60615 -83.279184) (xy 152.557515 -83.251888) (xy 152.513372 -83.217802)
			(xy 152.474663 -83.177653) (xy 152.442212 -83.132295) (xy 152.416711 -83.082695) (xy 152.398704 -83.029911)
			(xy 152.388574 -82.975068) (xy 152.386537 -82.919334) (xy 143.46633 -82.919334) (xy 144.236458 -83.689462)
			(xy 151.650191 -83.689462) (xy 151.656291 -83.634025) (xy 151.670397 -83.580068) (xy 151.692209 -83.528739)
			(xy 151.721263 -83.481133) (xy 151.756938 -83.438265) (xy 151.798475 -83.401048) (xy 151.844988 -83.370275)
			(xy 151.895485 -83.346603) (xy 151.948892 -83.330535) (xy 152.004068 -83.322415) (xy 152.031954 -83.321906)
			(xy 152.05984 -83.322415) (xy 152.115016 -83.330535) (xy 152.168423 -83.346603) (xy 152.21892 -83.370275)
			(xy 152.265433 -83.401048) (xy 152.296188 -83.428604) (xy 154.342337 -83.428604) (xy 154.348437 -83.373167)
			(xy 154.362543 -83.31921) (xy 154.384355 -83.267881) (xy 154.413409 -83.220275) (xy 154.449084 -83.177407)
			(xy 154.490621 -83.14019) (xy 154.537134 -83.109417) (xy 154.587631 -83.085745) (xy 154.641038 -83.069677)
			(xy 154.696214 -83.061557) (xy 154.7241 -83.061048) (xy 154.751986 -83.061557) (xy 154.807162 -83.069677)
			(xy 154.860569 -83.085745) (xy 154.911066 -83.109417) (xy 154.957579 -83.14019) (xy 154.999116 -83.177407)
			(xy 155.001011 -83.179684) (xy 156.206697 -83.179684) (xy 156.212797 -83.124247) (xy 156.226903 -83.07029)
			(xy 156.248715 -83.018961) (xy 156.277769 -82.971355) (xy 156.313444 -82.928487) (xy 156.354981 -82.89127)
			(xy 156.401494 -82.860497) (xy 156.451991 -82.836825) (xy 156.505398 -82.820757) (xy 156.560574 -82.812637)
			(xy 156.58846 -82.812128) (xy 156.616346 -82.812637) (xy 156.671522 -82.820757) (xy 156.724929 -82.836825)
			(xy 156.775426 -82.860497) (xy 156.821939 -82.89127) (xy 156.863476 -82.928487) (xy 156.899151 -82.971355)
			(xy 156.928205 -83.018961) (xy 156.950017 -83.07029) (xy 156.964123 -83.124247) (xy 156.970223 -83.179684)
			(xy 156.968186 -83.235418) (xy 156.960089 -83.279252) (xy 158.876237 -83.279252) (xy 158.882337 -83.223815)
			(xy 158.896443 -83.169858) (xy 158.918255 -83.118529) (xy 158.947309 -83.070923) (xy 158.982984 -83.028055)
			(xy 159.024521 -82.990838) (xy 159.071034 -82.960065) (xy 159.121531 -82.936393) (xy 159.174938 -82.920325)
			(xy 159.230114 -82.912205) (xy 159.258 -82.911696) (xy 159.285886 -82.912205) (xy 159.341062 -82.920325)
			(xy 159.394469 -82.936393) (xy 159.444966 -82.960065) (xy 159.460569 -82.970388) (xy 160.519617 -82.970388)
			(xy 160.525717 -82.914951) (xy 160.539823 -82.860994) (xy 160.561635 -82.809665) (xy 160.590689 -82.762059)
			(xy 160.626364 -82.719191) (xy 160.667901 -82.681974) (xy 160.714414 -82.651201) (xy 160.764911 -82.627529)
			(xy 160.818318 -82.611461) (xy 160.873494 -82.603341) (xy 160.90138 -82.602832) (xy 160.929266 -82.603341)
			(xy 160.984442 -82.611461) (xy 161.037849 -82.627529) (xy 161.088346 -82.651201) (xy 161.134859 -82.681974)
			(xy 161.176396 -82.719191) (xy 161.212071 -82.762059) (xy 161.241125 -82.809665) (xy 161.262937 -82.860994)
			(xy 161.277043 -82.914951) (xy 161.283143 -82.970388) (xy 161.281106 -83.026122) (xy 161.270976 -83.080965)
			(xy 161.252969 -83.133749) (xy 161.227468 -83.183349) (xy 161.195017 -83.228707) (xy 161.156308 -83.268856)
			(xy 161.112165 -83.302942) (xy 161.06353 -83.330238) (xy 161.011439 -83.350161) (xy 160.957002 -83.362287)
			(xy 160.90138 -83.366358) (xy 160.845758 -83.362287) (xy 160.791321 -83.350161) (xy 160.73923 -83.330238)
			(xy 160.690595 -83.302942) (xy 160.646452 -83.268856) (xy 160.607743 -83.228707) (xy 160.575292 -83.183349)
			(xy 160.549791 -83.133749) (xy 160.531784 -83.080965) (xy 160.521654 -83.026122) (xy 160.519617 -82.970388)
			(xy 159.460569 -82.970388) (xy 159.491479 -82.990838) (xy 159.533016 -83.028055) (xy 159.568691 -83.070923)
			(xy 159.597745 -83.118529) (xy 159.619557 -83.169858) (xy 159.633663 -83.223815) (xy 159.639763 -83.279252)
			(xy 159.637726 -83.334986) (xy 159.627596 -83.389829) (xy 159.609589 -83.442613) (xy 159.584088 -83.492213)
			(xy 159.551637 -83.537571) (xy 159.512928 -83.57772) (xy 159.468785 -83.611806) (xy 159.42015 -83.639102)
			(xy 159.368059 -83.659025) (xy 159.313622 -83.671151) (xy 159.258 -83.675222) (xy 159.202378 -83.671151)
			(xy 159.147941 -83.659025) (xy 159.09585 -83.639102) (xy 159.047215 -83.611806) (xy 159.003072 -83.57772)
			(xy 158.964363 -83.537571) (xy 158.931912 -83.492213) (xy 158.906411 -83.442613) (xy 158.888404 -83.389829)
			(xy 158.878274 -83.334986) (xy 158.876237 -83.279252) (xy 156.960089 -83.279252) (xy 156.958056 -83.290261)
			(xy 156.940049 -83.343045) (xy 156.914548 -83.392645) (xy 156.882097 -83.438003) (xy 156.843388 -83.478152)
			(xy 156.799245 -83.512238) (xy 156.75061 -83.539534) (xy 156.698519 -83.559457) (xy 156.644082 -83.571583)
			(xy 156.58846 -83.575654) (xy 156.532838 -83.571583) (xy 156.478401 -83.559457) (xy 156.42631 -83.539534)
			(xy 156.377675 -83.512238) (xy 156.333532 -83.478152) (xy 156.294823 -83.438003) (xy 156.262372 -83.392645)
			(xy 156.236871 -83.343045) (xy 156.218864 -83.290261) (xy 156.208734 -83.235418) (xy 156.206697 -83.179684)
			(xy 155.001011 -83.179684) (xy 155.034791 -83.220275) (xy 155.063845 -83.267881) (xy 155.085657 -83.31921)
			(xy 155.099763 -83.373167) (xy 155.105863 -83.428604) (xy 155.103826 -83.484338) (xy 155.093696 -83.539181)
			(xy 155.075689 -83.591965) (xy 155.050188 -83.641565) (xy 155.017737 -83.686923) (xy 154.979028 -83.727072)
			(xy 154.934885 -83.761158) (xy 154.88625 -83.788454) (xy 154.834159 -83.808377) (xy 154.779722 -83.820503)
			(xy 154.7241 -83.824574) (xy 154.668478 -83.820503) (xy 154.614041 -83.808377) (xy 154.56195 -83.788454)
			(xy 154.513315 -83.761158) (xy 154.469172 -83.727072) (xy 154.430463 -83.686923) (xy 154.398012 -83.641565)
			(xy 154.372511 -83.591965) (xy 154.354504 -83.539181) (xy 154.344374 -83.484338) (xy 154.342337 -83.428604)
			(xy 152.296188 -83.428604) (xy 152.30697 -83.438265) (xy 152.342645 -83.481133) (xy 152.371699 -83.528739)
			(xy 152.393511 -83.580068) (xy 152.407617 -83.634025) (xy 152.413717 -83.689462) (xy 152.41168 -83.745196)
			(xy 152.40155 -83.800039) (xy 152.383543 -83.852823) (xy 152.358042 -83.902423) (xy 152.325591 -83.947781)
			(xy 152.286882 -83.98793) (xy 152.242739 -84.022016) (xy 152.194104 -84.049312) (xy 152.142013 -84.069235)
			(xy 152.087576 -84.081361) (xy 152.031954 -84.085432) (xy 151.976332 -84.081361) (xy 151.921895 -84.069235)
			(xy 151.869804 -84.049312) (xy 151.821169 -84.022016) (xy 151.777026 -83.98793) (xy 151.738317 -83.947781)
			(xy 151.705866 -83.902423) (xy 151.680365 -83.852823) (xy 151.662358 -83.800039) (xy 151.652228 -83.745196)
			(xy 151.650191 -83.689462) (xy 144.236458 -83.689462) (xy 146.127488 -85.580492) (xy 155.482797 -85.580492)
			(xy 155.488897 -85.525055) (xy 155.503003 -85.471098) (xy 155.524815 -85.419769) (xy 155.553869 -85.372163)
			(xy 155.589544 -85.329295) (xy 155.631081 -85.292078) (xy 155.677594 -85.261305) (xy 155.728091 -85.237633)
			(xy 155.781498 -85.221565) (xy 155.836674 -85.213445) (xy 155.86456 -85.212936) (xy 155.892446 -85.213445)
			(xy 155.947622 -85.221565) (xy 156.001029 -85.237633) (xy 156.051526 -85.261305) (xy 156.098039 -85.292078)
			(xy 156.139576 -85.329295) (xy 156.175251 -85.372163) (xy 156.204305 -85.419769) (xy 156.226117 -85.471098)
			(xy 156.240223 -85.525055) (xy 156.246323 -85.580492) (xy 156.892497 -85.580492) (xy 156.898597 -85.525055)
			(xy 156.912703 -85.471098) (xy 156.934515 -85.419769) (xy 156.963569 -85.372163) (xy 156.999244 -85.329295)
			(xy 157.040781 -85.292078) (xy 157.087294 -85.261305) (xy 157.137791 -85.237633) (xy 157.191198 -85.221565)
			(xy 157.246374 -85.213445) (xy 157.27426 -85.212936) (xy 157.302146 -85.213445) (xy 157.357322 -85.221565)
			(xy 157.410729 -85.237633) (xy 157.461226 -85.261305) (xy 157.507739 -85.292078) (xy 157.549276 -85.329295)
			(xy 157.584951 -85.372163) (xy 157.614005 -85.419769) (xy 157.635817 -85.471098) (xy 157.649923 -85.525055)
			(xy 157.656023 -85.580492) (xy 158.416497 -85.580492) (xy 158.422597 -85.525055) (xy 158.436703 -85.471098)
			(xy 158.458515 -85.419769) (xy 158.487569 -85.372163) (xy 158.523244 -85.329295) (xy 158.564781 -85.292078)
			(xy 158.611294 -85.261305) (xy 158.661791 -85.237633) (xy 158.715198 -85.221565) (xy 158.770374 -85.213445)
			(xy 158.79826 -85.212936) (xy 158.826146 -85.213445) (xy 158.881322 -85.221565) (xy 158.934729 -85.237633)
			(xy 158.985226 -85.261305) (xy 159.031739 -85.292078) (xy 159.073276 -85.329295) (xy 159.108951 -85.372163)
			(xy 159.138005 -85.419769) (xy 159.159817 -85.471098) (xy 159.173923 -85.525055) (xy 159.180023 -85.580492)
			(xy 159.686497 -85.580492) (xy 159.692597 -85.525055) (xy 159.706703 -85.471098) (xy 159.728515 -85.419769)
			(xy 159.757569 -85.372163) (xy 159.793244 -85.329295) (xy 159.834781 -85.292078) (xy 159.881294 -85.261305)
			(xy 159.931791 -85.237633) (xy 159.985198 -85.221565) (xy 160.040374 -85.213445) (xy 160.06826 -85.212936)
			(xy 160.096146 -85.213445) (xy 160.151322 -85.221565) (xy 160.204729 -85.237633) (xy 160.255226 -85.261305)
			(xy 160.301739 -85.292078) (xy 160.343276 -85.329295) (xy 160.378951 -85.372163) (xy 160.408005 -85.419769)
			(xy 160.429817 -85.471098) (xy 160.443923 -85.525055) (xy 160.450023 -85.580492) (xy 160.447986 -85.636226)
			(xy 160.437856 -85.691069) (xy 160.419849 -85.743853) (xy 160.394348 -85.793453) (xy 160.361897 -85.838811)
			(xy 160.323188 -85.87896) (xy 160.279045 -85.913046) (xy 160.23041 -85.940342) (xy 160.178319 -85.960265)
			(xy 160.123882 -85.972391) (xy 160.06826 -85.976462) (xy 160.012638 -85.972391) (xy 159.958201 -85.960265)
			(xy 159.90611 -85.940342) (xy 159.857475 -85.913046) (xy 159.813332 -85.87896) (xy 159.774623 -85.838811)
			(xy 159.742172 -85.793453) (xy 159.716671 -85.743853) (xy 159.698664 -85.691069) (xy 159.688534 -85.636226)
			(xy 159.686497 -85.580492) (xy 159.180023 -85.580492) (xy 159.177986 -85.636226) (xy 159.167856 -85.691069)
			(xy 159.149849 -85.743853) (xy 159.124348 -85.793453) (xy 159.091897 -85.838811) (xy 159.053188 -85.87896)
			(xy 159.009045 -85.913046) (xy 158.96041 -85.940342) (xy 158.908319 -85.960265) (xy 158.853882 -85.972391)
			(xy 158.79826 -85.976462) (xy 158.742638 -85.972391) (xy 158.688201 -85.960265) (xy 158.63611 -85.940342)
			(xy 158.587475 -85.913046) (xy 158.543332 -85.87896) (xy 158.504623 -85.838811) (xy 158.472172 -85.793453)
			(xy 158.446671 -85.743853) (xy 158.428664 -85.691069) (xy 158.418534 -85.636226) (xy 158.416497 -85.580492)
			(xy 157.656023 -85.580492) (xy 157.653986 -85.636226) (xy 157.643856 -85.691069) (xy 157.625849 -85.743853)
			(xy 157.600348 -85.793453) (xy 157.567897 -85.838811) (xy 157.529188 -85.87896) (xy 157.485045 -85.913046)
			(xy 157.43641 -85.940342) (xy 157.384319 -85.960265) (xy 157.329882 -85.972391) (xy 157.27426 -85.976462)
			(xy 157.218638 -85.972391) (xy 157.164201 -85.960265) (xy 157.11211 -85.940342) (xy 157.063475 -85.913046)
			(xy 157.019332 -85.87896) (xy 156.980623 -85.838811) (xy 156.948172 -85.793453) (xy 156.922671 -85.743853)
			(xy 156.904664 -85.691069) (xy 156.894534 -85.636226) (xy 156.892497 -85.580492) (xy 156.246323 -85.580492)
			(xy 156.244286 -85.636226) (xy 156.234156 -85.691069) (xy 156.216149 -85.743853) (xy 156.190648 -85.793453)
			(xy 156.158197 -85.838811) (xy 156.119488 -85.87896) (xy 156.075345 -85.913046) (xy 156.02671 -85.940342)
			(xy 155.974619 -85.960265) (xy 155.920182 -85.972391) (xy 155.86456 -85.976462) (xy 155.808938 -85.972391)
			(xy 155.754501 -85.960265) (xy 155.70241 -85.940342) (xy 155.653775 -85.913046) (xy 155.609632 -85.87896)
			(xy 155.570923 -85.838811) (xy 155.538472 -85.793453) (xy 155.512971 -85.743853) (xy 155.494964 -85.691069)
			(xy 155.484834 -85.636226) (xy 155.482797 -85.580492) (xy 146.127488 -85.580492) (xy 146.85596 -86.308964)
			(xy 162.342575 -86.308964) (xy 162.348675 -86.253527) (xy 162.362781 -86.19957) (xy 162.384593 -86.148241)
			(xy 162.413647 -86.100635) (xy 162.449322 -86.057767) (xy 162.490859 -86.02055) (xy 162.537372 -85.989777)
			(xy 162.587869 -85.966105) (xy 162.641276 -85.950037) (xy 162.696452 -85.941917) (xy 162.724338 -85.941408)
			(xy 162.752224 -85.941917) (xy 162.8074 -85.950037) (xy 162.860807 -85.966105) (xy 162.911304 -85.989777)
			(xy 162.954933 -86.018642) (xy 164.324537 -86.018642) (xy 164.330637 -85.963205) (xy 164.344743 -85.909248)
			(xy 164.366555 -85.857919) (xy 164.395609 -85.810313) (xy 164.431284 -85.767445) (xy 164.472821 -85.730228)
			(xy 164.519334 -85.699455) (xy 164.569831 -85.675783) (xy 164.623238 -85.659715) (xy 164.678414 -85.651595)
			(xy 164.7063 -85.651086) (xy 164.734186 -85.651595) (xy 164.789362 -85.659715) (xy 164.842769 -85.675783)
			(xy 164.893266 -85.699455) (xy 164.939779 -85.730228) (xy 164.981316 -85.767445) (xy 165.016991 -85.810313)
			(xy 165.046045 -85.857919) (xy 165.067857 -85.909248) (xy 165.081963 -85.963205) (xy 165.088063 -86.018642)
			(xy 165.086026 -86.074376) (xy 165.075896 -86.129219) (xy 165.057889 -86.182003) (xy 165.032388 -86.231603)
			(xy 164.999937 -86.276961) (xy 164.961228 -86.31711) (xy 164.917085 -86.351196) (xy 164.86845 -86.378492)
			(xy 164.816359 -86.398415) (xy 164.761922 -86.410541) (xy 164.7063 -86.414612) (xy 164.650678 -86.410541)
			(xy 164.596241 -86.398415) (xy 164.54415 -86.378492) (xy 164.495515 -86.351196) (xy 164.451372 -86.31711)
			(xy 164.412663 -86.276961) (xy 164.380212 -86.231603) (xy 164.354711 -86.182003) (xy 164.336704 -86.129219)
			(xy 164.326574 -86.074376) (xy 164.324537 -86.018642) (xy 162.954933 -86.018642) (xy 162.957817 -86.02055)
			(xy 162.999354 -86.057767) (xy 163.035029 -86.100635) (xy 163.064083 -86.148241) (xy 163.085895 -86.19957)
			(xy 163.100001 -86.253527) (xy 163.106101 -86.308964) (xy 163.104064 -86.364698) (xy 163.093934 -86.419541)
			(xy 163.075927 -86.472325) (xy 163.050426 -86.521925) (xy 163.017975 -86.567283) (xy 162.979266 -86.607432)
			(xy 162.935123 -86.641518) (xy 162.886488 -86.668814) (xy 162.834397 -86.688737) (xy 162.77996 -86.700863)
			(xy 162.724338 -86.704934) (xy 162.668716 -86.700863) (xy 162.614279 -86.688737) (xy 162.562188 -86.668814)
			(xy 162.513553 -86.641518) (xy 162.46941 -86.607432) (xy 162.430701 -86.567283) (xy 162.39825 -86.521925)
			(xy 162.372749 -86.472325) (xy 162.354742 -86.419541) (xy 162.344612 -86.364698) (xy 162.342575 -86.308964)
			(xy 146.85596 -86.308964) (xy 148.116816 -87.56982) (xy 153.966671 -87.56982) (xy 153.972771 -87.514383)
			(xy 153.986877 -87.460426) (xy 154.008689 -87.409097) (xy 154.037743 -87.361491) (xy 154.073418 -87.318623)
			(xy 154.114955 -87.281406) (xy 154.161468 -87.250633) (xy 154.211965 -87.226961) (xy 154.265372 -87.210893)
			(xy 154.320548 -87.202773) (xy 154.348434 -87.202264) (xy 154.37632 -87.202773) (xy 154.431496 -87.210893)
			(xy 154.484903 -87.226961) (xy 154.5354 -87.250633) (xy 154.581913 -87.281406) (xy 154.62345 -87.318623)
			(xy 154.659125 -87.361491) (xy 154.688179 -87.409097) (xy 154.709991 -87.460426) (xy 154.724097 -87.514383)
			(xy 154.730197 -87.56982) (xy 159.166051 -87.56982) (xy 159.172151 -87.514383) (xy 159.186257 -87.460426)
			(xy 159.208069 -87.409097) (xy 159.237123 -87.361491) (xy 159.272798 -87.318623) (xy 159.314335 -87.281406)
			(xy 159.360848 -87.250633) (xy 159.411345 -87.226961) (xy 159.464752 -87.210893) (xy 159.519928 -87.202773)
			(xy 159.547814 -87.202264) (xy 159.5757 -87.202773) (xy 159.630876 -87.210893) (xy 159.684283 -87.226961)
			(xy 159.73478 -87.250633) (xy 159.781293 -87.281406) (xy 159.82283 -87.318623) (xy 159.858505 -87.361491)
			(xy 159.887559 -87.409097) (xy 159.909371 -87.460426) (xy 159.923477 -87.514383) (xy 159.929577 -87.56982)
			(xy 159.92754 -87.625554) (xy 159.91741 -87.680397) (xy 159.899403 -87.733181) (xy 159.873902 -87.782781)
			(xy 159.841451 -87.828139) (xy 159.802742 -87.868288) (xy 159.758599 -87.902374) (xy 159.709964 -87.92967)
			(xy 159.657873 -87.949593) (xy 159.603436 -87.961719) (xy 159.547814 -87.96579) (xy 159.492192 -87.961719)
			(xy 159.437755 -87.949593) (xy 159.385664 -87.92967) (xy 159.337029 -87.902374) (xy 159.292886 -87.868288)
			(xy 159.254177 -87.828139) (xy 159.221726 -87.782781) (xy 159.196225 -87.733181) (xy 159.178218 -87.680397)
			(xy 159.168088 -87.625554) (xy 159.166051 -87.56982) (xy 154.730197 -87.56982) (xy 154.72816 -87.625554)
			(xy 154.71803 -87.680397) (xy 154.700023 -87.733181) (xy 154.674522 -87.782781) (xy 154.642071 -87.828139)
			(xy 154.603362 -87.868288) (xy 154.559219 -87.902374) (xy 154.510584 -87.92967) (xy 154.458493 -87.949593)
			(xy 154.404056 -87.961719) (xy 154.348434 -87.96579) (xy 154.292812 -87.961719) (xy 154.238375 -87.949593)
			(xy 154.186284 -87.92967) (xy 154.137649 -87.902374) (xy 154.093506 -87.868288) (xy 154.054797 -87.828139)
			(xy 154.022346 -87.782781) (xy 153.996845 -87.733181) (xy 153.978838 -87.680397) (xy 153.968708 -87.625554)
			(xy 153.966671 -87.56982) (xy 148.116816 -87.56982) (xy 149.386816 -88.83982) (xy 162.137089 -88.83982)
			(xy 162.143189 -88.784383) (xy 162.157295 -88.730426) (xy 162.179107 -88.679097) (xy 162.208161 -88.631491)
			(xy 162.243836 -88.588623) (xy 162.285373 -88.551406) (xy 162.331886 -88.520633) (xy 162.382383 -88.496961)
			(xy 162.43579 -88.480893) (xy 162.490966 -88.472773) (xy 162.518852 -88.472264) (xy 162.546738 -88.472773)
			(xy 162.601914 -88.480893) (xy 162.655321 -88.496961) (xy 162.705818 -88.520633) (xy 162.752331 -88.551406)
			(xy 162.793868 -88.588623) (xy 162.829543 -88.631491) (xy 162.858597 -88.679097) (xy 162.880409 -88.730426)
			(xy 162.894515 -88.784383) (xy 162.900615 -88.83982) (xy 162.898578 -88.895554) (xy 162.888448 -88.950397)
			(xy 162.870441 -89.003181) (xy 162.84494 -89.052781) (xy 162.812489 -89.098139) (xy 162.77378 -89.138288)
			(xy 162.729637 -89.172374) (xy 162.681002 -89.19967) (xy 162.628911 -89.219593) (xy 162.574474 -89.231719)
			(xy 162.518852 -89.23579) (xy 162.46323 -89.231719) (xy 162.408793 -89.219593) (xy 162.356702 -89.19967)
			(xy 162.308067 -89.172374) (xy 162.263924 -89.138288) (xy 162.225215 -89.098139) (xy 162.192764 -89.052781)
			(xy 162.167263 -89.003181) (xy 162.149256 -88.950397) (xy 162.139126 -88.895554) (xy 162.137089 -88.83982)
			(xy 149.386816 -88.83982) (xy 150.027658 -89.480662) (xy 154.013407 -89.480662) (xy 154.019507 -89.425225)
			(xy 154.033613 -89.371268) (xy 154.055425 -89.319939) (xy 154.084479 -89.272333) (xy 154.120154 -89.229465)
			(xy 154.161691 -89.192248) (xy 154.208204 -89.161475) (xy 154.258701 -89.137803) (xy 154.312108 -89.121735)
			(xy 154.367284 -89.113615) (xy 154.39517 -89.113106) (xy 154.423056 -89.113615) (xy 154.478232 -89.121735)
			(xy 154.531639 -89.137803) (xy 154.582136 -89.161475) (xy 154.628649 -89.192248) (xy 154.670186 -89.229465)
			(xy 154.705861 -89.272333) (xy 154.734915 -89.319939) (xy 154.756727 -89.371268) (xy 154.770833 -89.425225)
			(xy 154.776933 -89.480662) (xy 154.774896 -89.536396) (xy 154.764766 -89.591239) (xy 154.746759 -89.644023)
			(xy 154.721258 -89.693623) (xy 154.688807 -89.738981) (xy 154.650098 -89.77913) (xy 154.605955 -89.813216)
			(xy 154.55732 -89.840512) (xy 154.505229 -89.860435) (xy 154.450792 -89.872561) (xy 154.39517 -89.876632)
			(xy 154.339548 -89.872561) (xy 154.285111 -89.860435) (xy 154.23302 -89.840512) (xy 154.184385 -89.813216)
			(xy 154.140242 -89.77913) (xy 154.101533 -89.738981) (xy 154.069082 -89.693623) (xy 154.043581 -89.644023)
			(xy 154.025574 -89.591239) (xy 154.015444 -89.536396) (xy 154.013407 -89.480662) (xy 150.027658 -89.480662)
			(xy 150.656816 -90.10982) (xy 156.737811 -90.10982) (xy 156.743911 -90.054383) (xy 156.758017 -90.000426)
			(xy 156.779829 -89.949097) (xy 156.808883 -89.901491) (xy 156.844558 -89.858623) (xy 156.886095 -89.821406)
			(xy 156.932608 -89.790633) (xy 156.983105 -89.766961) (xy 157.036512 -89.750893) (xy 157.091688 -89.742773)
			(xy 157.119574 -89.742264) (xy 157.14746 -89.742773) (xy 157.202636 -89.750893) (xy 157.256043 -89.766961)
			(xy 157.30654 -89.790633) (xy 157.353053 -89.821406) (xy 157.39459 -89.858623) (xy 157.430265 -89.901491)
			(xy 157.459319 -89.949097) (xy 157.481131 -90.000426) (xy 157.495237 -90.054383) (xy 157.501337 -90.10982)
			(xy 157.4993 -90.165554) (xy 157.48917 -90.220397) (xy 157.471163 -90.273181) (xy 157.445662 -90.322781)
			(xy 157.413211 -90.368139) (xy 157.374502 -90.408288) (xy 157.330359 -90.442374) (xy 157.281724 -90.46967)
			(xy 157.229633 -90.489593) (xy 157.175196 -90.501719) (xy 157.119574 -90.50579) (xy 157.063952 -90.501719)
			(xy 157.009515 -90.489593) (xy 156.957424 -90.46967) (xy 156.908789 -90.442374) (xy 156.864646 -90.408288)
			(xy 156.825937 -90.368139) (xy 156.793486 -90.322781) (xy 156.767985 -90.273181) (xy 156.749978 -90.220397)
			(xy 156.739848 -90.165554) (xy 156.737811 -90.10982) (xy 150.656816 -90.10982) (xy 151.643352 -91.096356)
			(xy 152.213817 -91.096356) (xy 152.219917 -91.040919) (xy 152.234023 -90.986962) (xy 152.255835 -90.935633)
			(xy 152.284889 -90.888027) (xy 152.320564 -90.845159) (xy 152.362101 -90.807942) (xy 152.408614 -90.777169)
			(xy 152.459111 -90.753497) (xy 152.512518 -90.737429) (xy 152.567694 -90.729309) (xy 152.59558 -90.7288)
			(xy 152.623466 -90.729309) (xy 152.678642 -90.737429) (xy 152.732049 -90.753497) (xy 152.782546 -90.777169)
			(xy 152.829059 -90.807942) (xy 152.870596 -90.845159) (xy 152.906271 -90.888027) (xy 152.935325 -90.935633)
			(xy 152.939725 -90.945988) (xy 163.705539 -90.945988) (xy 163.711639 -90.890551) (xy 163.725745 -90.836594)
			(xy 163.747557 -90.785265) (xy 163.776611 -90.737659) (xy 163.812286 -90.694791) (xy 163.853823 -90.657574)
			(xy 163.900336 -90.626801) (xy 163.950833 -90.603129) (xy 164.00424 -90.587061) (xy 164.059416 -90.578941)
			(xy 164.087302 -90.578432) (xy 164.115188 -90.578941) (xy 164.170364 -90.587061) (xy 164.223771 -90.603129)
			(xy 164.274268 -90.626801) (xy 164.320781 -90.657574) (xy 164.362318 -90.694791) (xy 164.397993 -90.737659)
			(xy 164.427047 -90.785265) (xy 164.448859 -90.836594) (xy 164.462965 -90.890551) (xy 164.469065 -90.945988)
			(xy 164.467028 -91.001722) (xy 164.456898 -91.056565) (xy 164.438891 -91.109349) (xy 164.41339 -91.158949)
			(xy 164.380939 -91.204307) (xy 164.34223 -91.244456) (xy 164.298087 -91.278542) (xy 164.249452 -91.305838)
			(xy 164.197361 -91.325761) (xy 164.142924 -91.337887) (xy 164.087302 -91.341958) (xy 164.03168 -91.337887)
			(xy 163.977243 -91.325761) (xy 163.925152 -91.305838) (xy 163.876517 -91.278542) (xy 163.832374 -91.244456)
			(xy 163.793665 -91.204307) (xy 163.761214 -91.158949) (xy 163.735713 -91.109349) (xy 163.717706 -91.056565)
			(xy 163.707576 -91.001722) (xy 163.705539 -90.945988) (xy 152.939725 -90.945988) (xy 152.957137 -90.986962)
			(xy 152.971243 -91.040919) (xy 152.977343 -91.096356) (xy 152.975306 -91.15209) (xy 152.965176 -91.206933)
			(xy 152.947169 -91.259717) (xy 152.921668 -91.309317) (xy 152.889217 -91.354675) (xy 152.8733 -91.371184)
			(xy 155.027629 -91.371184) (xy 155.033729 -91.315747) (xy 155.047835 -91.26179) (xy 155.069647 -91.210461)
			(xy 155.098701 -91.162855) (xy 155.134376 -91.119987) (xy 155.175913 -91.08277) (xy 155.222426 -91.051997)
			(xy 155.272923 -91.028325) (xy 155.32633 -91.012257) (xy 155.381506 -91.004137) (xy 155.409392 -91.003628)
			(xy 155.437278 -91.004137) (xy 155.492454 -91.012257) (xy 155.545861 -91.028325) (xy 155.596358 -91.051997)
			(xy 155.642871 -91.08277) (xy 155.684408 -91.119987) (xy 155.720083 -91.162855) (xy 155.749137 -91.210461)
			(xy 155.770949 -91.26179) (xy 155.785055 -91.315747) (xy 155.791155 -91.371184) (xy 155.789118 -91.426918)
			(xy 155.778988 -91.481761) (xy 155.760981 -91.534545) (xy 155.73548 -91.584145) (xy 155.703029 -91.629503)
			(xy 155.66432 -91.669652) (xy 155.620177 -91.703738) (xy 155.571542 -91.731034) (xy 155.519451 -91.750957)
			(xy 155.465014 -91.763083) (xy 155.409392 -91.767154) (xy 155.35377 -91.763083) (xy 155.299333 -91.750957)
			(xy 155.247242 -91.731034) (xy 155.198607 -91.703738) (xy 155.154464 -91.669652) (xy 155.115755 -91.629503)
			(xy 155.083304 -91.584145) (xy 155.057803 -91.534545) (xy 155.039796 -91.481761) (xy 155.029666 -91.426918)
			(xy 155.027629 -91.371184) (xy 152.8733 -91.371184) (xy 152.850508 -91.394824) (xy 152.806365 -91.42891)
			(xy 152.75773 -91.456206) (xy 152.705639 -91.476129) (xy 152.651202 -91.488255) (xy 152.59558 -91.492326)
			(xy 152.539958 -91.488255) (xy 152.485521 -91.476129) (xy 152.43343 -91.456206) (xy 152.384795 -91.42891)
			(xy 152.340652 -91.394824) (xy 152.301943 -91.354675) (xy 152.269492 -91.309317) (xy 152.243991 -91.259717)
			(xy 152.225984 -91.206933) (xy 152.215854 -91.15209) (xy 152.213817 -91.096356) (xy 151.643352 -91.096356)
			(xy 153.80462 -93.257624)
		)
		(stroke
			(width 0)
			(type solid)
		)
		(fill yes)
		(layer "In6.Cu")
		(net "P3V3_NODE1")
	)
	(gr_poly
		(pts
			(xy 46.92142 -164.267896) (xy 40.18534 -164.267896) (xy 40.18534 -167.674544) (xy 46.92142 -167.674544)
		)
		(stroke
			(width 0)
			(type solid)
		)
		(fill yes)
		(layer "In7.Cu")
		(net "GND")
	)
	(gr_poly
		(pts
			(xy 165.3159 -140.901674) (xy 158.83636 -140.901674) (xy 158.83636 -143.152114) (xy 165.3159 -143.152114)
		)
		(stroke
			(width 0)
			(type solid)
		)
		(fill yes)
		(layer "In7.Cu")
		(net "GND")
	)
	(gr_poly
		(pts
			(xy 85.51926 -86.813644) (xy 85.51926 -82.564224) (xy 85.45068 -82.495644) (xy 83.48472 -82.495644)
			(xy 83.37804 -82.602324) (xy 83.37804 -86.760304) (xy 83.5279 -86.910164) (xy 85.42274 -86.910164)
		)
		(stroke
			(width 0)
			(type solid)
		)
		(fill yes)
		(layer "In7.Cu")
		(net "GND")
	)
	(gr_poly
		(pts
			(xy 163.676838 -155.690062) (xy 163.676838 -150.496778) (xy 163.592764 -150.412704) (xy 158.305246 -150.412704)
			(xy 158.252668 -150.465282) (xy 158.252668 -155.731972) (xy 158.305246 -155.78455) (xy 163.58235 -155.78455)
		)
		(stroke
			(width 0)
			(type solid)
		)
		(fill yes)
		(layer "In7.Cu")
		(net "GND")
	)
	(gr_poly
		(pts
			(xy 39.9542 -78.347316) (xy 39.9542 -75.280266) (xy 39.646352 -74.972418) (xy 38.190678 -74.972418)
			(xy 36.642548 -74.972418) (xy 36.467796 -75.14717) (xy 36.467796 -76.127102) (xy 36.467796 -78.36281)
			(xy 36.788598 -78.683612) (xy 38.291008 -78.683612) (xy 39.617904 -78.683612)
		)
		(stroke
			(width 0)
			(type solid)
		)
		(fill yes)
		(layer "In7.Cu")
		(net "P1V8_VCCASFRHPLL_NODE1")
	)
	(gr_poly
		(pts
			(xy 142.253716 -160.98266) (xy 142.253716 -158.190438) (xy 142.226538 -158.16326) (xy 138.788394 -158.16326)
			(xy 138.66114 -158.290514)
			(arc
				(start 138.66114 -160.919414)
				(mid 138.698337 -161.009217)
				(end 138.78814 -161.046414)
			)
			(xy 142.189962 -161.046414)
		)
		(stroke
			(width 0)
			(type solid)
		)
		(fill yes)
		(layer "In7.Cu")
		(net "GND")
	)
	(gr_poly
		(pts
			(arc
				(start 109.879638 -131.529328)
				(mid 109.928185 -131.519578)
				(end 109.9693 -131.49199)
			)
			(xy 110.3884 -131.07289) (xy 110.3884 -125.648974) (xy 112.135412 -123.901962) (xy 113.671858 -123.901962)
			(xy 113.987834 -123.585986) (xy 113.987834 -122.982228) (xy 113.837466 -122.83186) (xy 110.872778 -122.83186)
			(xy 109.187234 -124.517404) (xy 109.187234 -131.477004) (xy 109.239558 -131.529328)
		)
		(stroke
			(width 0)
			(type solid)
		)
		(fill yes)
		(layer "In7.Cu")
		(net "VR_PVCCP_NODE1_UGATE1")
	)
	(gr_poly
		(pts
			(arc
				(start 135.70712 -120.358408)
				(mid 135.796923 -120.321211)
				(end 135.83412 -120.231408)
			)
			(arc
				(start 135.83412 -114.775742)
				(mid 135.796923 -114.685939)
				(end 135.70712 -114.648742)
			)
			(xy 131.435348 -114.648742) (xy 130.268472 -114.648742) (xy 130.05943 -114.857784) (xy 130.05943 -115.183412)
			(xy 130.05943 -115.183666)
			(arc
				(start 130.05943 -120.231408)
				(mid 130.096627 -120.321211)
				(end 130.18643 -120.358408)
			)
		)
		(stroke
			(width 0)
			(type solid)
		)
		(fill yes)
		(layer "In7.Cu")
		(net "GND")
	)
	(gr_poly
		(pts
			(xy 108.682028 -131.360164) (xy 108.682028 -128.502918) (xy 106.899202 -126.720092) (xy 106.899202 -123.2535)
			(xy 106.621834 -122.976132) (xy 104.91724 -122.976132)
			(arc
				(start 104.889808 -122.990356)
				(mid 104.71404 -123.033261)
				(end 104.538272 -122.990356)
			)
			(xy 104.51084 -122.976132) (xy 104.169972 -122.976132)
			(arc
				(start 104.135428 -123.00331)
				(mid 104.102752 -123.02628)
				(end 104.067864 -123.045728)
			)
			(arc
				(start 104.067864 -123.045728)
				(mid 104.016079 -123.092609)
				(end 103.996998 -123.159774)
			)
			(xy 103.996998 -123.652534) (xy 104.14635 -123.801886) (xy 105.64368 -123.801886) (xy 105.834688 -123.992894)
			(xy 105.834688 -127.316992) (xy 107.612434 -129.094738) (xy 107.612434 -131.225798) (xy 107.95508 -131.568444)
			(xy 108.473748 -131.568444)
		)
		(stroke
			(width 0)
			(type solid)
		)
		(fill yes)
		(layer "In7.Cu")
		(net "VR_PVCCP_NODE1_LGATE1")
	)
	(gr_poly
		(pts
			(arc
				(start 117.36578 -46.18228)
				(mid 117.431566 -46.176563)
				(end 117.497352 -46.18228)
			)
			(xy 117.508274 -46.184058)
			(arc
				(start 117.990874 -46.184058)
				(mid 118.080677 -46.146861)
				(end 118.117874 -46.057058)
			)
			(arc
				(start 118.117874 -38.945058)
				(mid 118.080677 -38.855255)
				(end 117.990874 -38.818058)
			)
			(arc
				(start 112.910874 -38.818058)
				(mid 112.821071 -38.855255)
				(end 112.783874 -38.945058)
			)
			(arc
				(start 112.783874 -46.057058)
				(mid 112.821071 -46.146861)
				(end 112.910874 -46.184058)
			)
			(xy 113.137442 -46.184058) (xy 114.094768 -46.184058) (xy 117.354858 -46.184058)
		)
		(stroke
			(width 0)
			(type solid)
		)
		(fill yes)
		(layer "In7.Cu")
		(net "GND")
	)
	(gr_poly
		(pts
			(arc
				(start 56.08574 -119.913146)
				(mid 56.175543 -119.875949)
				(end 56.21274 -119.786146)
			)
			(arc
				(start 56.21274 -116.88699)
				(mid 56.175543 -116.797187)
				(end 56.08574 -116.75999)
			)
			(xy 54.666896 -116.75999) (xy 54.66334 -116.763546)
			(arc
				(start 52.45354 -116.763546)
				(mid 52.363737 -116.800743)
				(end 52.32654 -116.890546)
			)
			(xy 52.32654 -117.348254)
			(arc
				(start 52.331366 -117.365272)
				(mid 52.345854 -117.469412)
				(end 52.331366 -117.573552)
			)
			(xy 52.32654 -117.59057)
			(arc
				(start 52.32654 -119.786146)
				(mid 52.363737 -119.875949)
				(end 52.45354 -119.913146)
			)
		)
		(stroke
			(width 0)
			(type solid)
		)
		(fill yes)
		(layer "In7.Cu")
		(net "GND")
	)
	(gr_poly
		(pts
			(arc
				(start 129.249678 -109.84611)
				(mid 129.409444 -109.811047)
				(end 129.56921 -109.84611)
			)
			(xy 129.59461 -109.857794)
			(arc
				(start 131.572 -109.857794)
				(mid 131.661803 -109.820597)
				(end 131.699 -109.730794)
			)
			(arc
				(start 131.699 -106.71048)
				(mid 131.661803 -106.620677)
				(end 131.572 -106.58348)
			)
			(arc
				(start 126.814072 -106.58348)
				(mid 126.724269 -106.620677)
				(end 126.687072 -106.71048)
			)
			(arc
				(start 126.687072 -109.730794)
				(mid 126.724269 -109.820597)
				(end 126.814072 -109.857794)
			)
			(xy 129.224278 -109.857794)
		)
		(stroke
			(width 0)
			(type solid)
		)
		(fill yes)
		(layer "In7.Cu")
		(net "GND")
	)
	(gr_poly
		(pts
			(xy 40.827198 -182.114952) (xy 40.827198 -179.1716) (xy 40.04183 -178.386232)
			(arc
				(start 34.156904 -178.386232)
				(mid 33.939947 -178.508149)
				(end 33.931352 -178.756818)
			)
			(arc
				(start 33.931352 -178.756818)
				(mid 33.99756 -178.871256)
				(end 34.02076 -179.00142)
			)
			(arc
				(start 34.02076 -179.00142)
				(mid 33.828998 -179.339843)
				(end 33.440116 -179.33416)
			)
			(arc
				(start 33.440116 -179.33416)
				(mid 33.183345 -179.329236)
				(end 33.053528 -179.550822)
			)
			(xy 33.053528 -182.115206) (xy 33.109916 -182.171594) (xy 40.770556 -182.171594)
		)
		(stroke
			(width 0)
			(type solid)
		)
		(fill yes)
		(layer "In7.Cu")
		(net "VSENSE_HSC_NODE1")
	)
	(gr_poly
		(pts
			(arc
				(start 169.470578 -92.547186)
				(mid 169.533189 -92.53068)
				(end 169.579544 -92.485464)
			)
			(arc
				(start 169.579544 -92.485464)
				(mid 169.90695 -92.299794)
				(end 170.234356 -92.485464)
			)
			(xy 170.251628 -92.514166) (xy 170.30954 -92.547186)
			(arc
				(start 172.11802 -92.547186)
				(mid 172.207823 -92.509989)
				(end 172.24502 -92.420186)
			)
			(arc
				(start 172.24502 -90.177366)
				(mid 172.207823 -90.087563)
				(end 172.11802 -90.050366)
			)
			(arc
				(start 166.6113 -90.050366)
				(mid 166.521497 -90.087563)
				(end 166.4843 -90.177366)
			)
			(arc
				(start 166.4843 -92.420186)
				(mid 166.521497 -92.509989)
				(end 166.6113 -92.547186)
			)
		)
		(stroke
			(width 0)
			(type solid)
		)
		(fill yes)
		(layer "In7.Cu")
		(net "GND")
	)
	(gr_poly
		(pts
			(arc
				(start 60.056776 -133.695186)
				(mid 60.141104 -133.685519)
				(end 60.225432 -133.695186)
			)
			(xy 60.239656 -133.698488) (xy 60.386468 -133.698488) (xy 60.579508 -133.505194) (xy 60.579508 -133.350508)
			(arc
				(start 60.576714 -133.337046)
				(mid 60.5683 -133.258306)
				(end 60.576714 -133.179566)
			)
			(xy 60.579508 -133.166104)
			(arc
				(start 60.579508 -132.91693)
				(mid 60.48528 -132.80859)
				(end 60.347352 -132.768594)
			)
			(arc
				(start 60.347352 -132.768594)
				(mid 60.071407 -132.824295)
				(end 59.835288 -132.671058)
			)
			(arc
				(start 59.835288 -132.671058)
				(mid 59.741054 -132.652937)
				(end 59.64682 -132.671058)
			)
			(arc
				(start 59.64682 -132.671058)
				(mid 59.608979 -132.717168)
				(end 59.56427 -132.756656)
			)
			(arc
				(start 59.56427 -132.756656)
				(mid 59.513368 -132.858256)
				(end 59.56427 -132.959856)
			)
			(arc
				(start 59.56427 -132.959856)
				(mid 59.707048 -133.188079)
				(end 59.658758 -133.45287)
			)
			(arc
				(start 59.658758 -133.45287)
				(mid 59.736043 -133.62713)
				(end 59.912758 -133.698488)
			)
			(xy 60.042552 -133.698488)
		)
		(stroke
			(width 0)
			(type solid)
		)
		(fill yes)
		(layer "In7.Cu")
		(net "P0V75_BMC_VTTREF_NODE1")
	)
	(gr_poly
		(pts
			(arc
				(start 70.742048 -127.953262)
				(mid 70.763076 -127.952348)
				(end 70.783958 -127.949706)
			)
			(xy 71.332852 -127.949706) (xy 71.713344 -127.569214) (xy 71.75627 -127.569214) (xy 71.816976 -127.53213)
			(arc
				(start 71.833232 -127.50038)
				(mid 71.851687 -127.468839)
				(end 71.873364 -127.43942)
			)
			(arc
				(start 71.873364 -127.43942)
				(mid 71.930662 -127.272425)
				(end 71.865236 -127.108458)
			)
			(arc
				(start 71.865236 -127.108458)
				(mid 72.142096 -126.486383)
				(end 72.418956 -127.108458)
			)
			(arc
				(start 72.418956 -127.108458)
				(mid 72.353568 -127.272426)
				(end 72.410828 -127.43942)
			)
			(arc
				(start 72.410828 -127.43942)
				(mid 72.432497 -127.468844)
				(end 72.45096 -127.50038)
			)
			(arc
				(start 72.45096 -127.50038)
				(mid 72.497702 -127.550571)
				(end 72.563736 -127.569214)
			)
			(xy 73.356216 -127.569214) (xy 73.416922 -127.53213)
			(arc
				(start 73.433178 -127.50038)
				(mid 73.733802 -127.311955)
				(end 74.043032 -127.485902)
			)
			(xy 74.051414 -127.50038) (xy 74.100436 -127.549656) (xy 74.205338 -127.549656) (xy 74.214736 -127.540258)
			(xy 76.182982 -127.540258) (xy 76.620878 -127.102362) (xy 76.620878 -125.824234) (xy 76.455778 -125.659134)
			(xy 74.834496 -125.659134) (xy 74.722736 -125.547374) (xy 71.01332 -125.547374) (xy 70.270624 -126.29007)
			(xy 70.270624 -127.826262) (xy 70.397624 -127.953262)
		)
		(stroke
			(width 0)
			(type solid)
		)
		(fill yes)
		(layer "In7.Cu")
		(net "BMC_NODE1_VCC_1V8_PCIEA")
	)
	(gr_poly
		(pts
			(xy 92.15628 -10.94232) (xy 92.15628 -10.468356) (xy 92.08008 -10.392156) (xy 92.08008 -7.993126)
			(xy 91.78544 -7.698486) (xy 88.847422 -7.698486) (xy 87.5665 -8.979408) (xy 87.5665 -9.750405) (xy 89.064349 -9.750405)
			(xy 89.072055 -9.665303) (xy 89.08745 -9.58125) (xy 89.110408 -9.498942) (xy 89.140739 -9.419055)
			(xy 89.178194 -9.342251) (xy 89.222464 -9.269162) (xy 89.273182 -9.20039) (xy 89.329931 -9.136505)
			(xy 89.360756 -9.106916) (xy 89.44864 -9.106916) (xy 89.465289 -9.106392) (xy 89.49745 -9.097766)
			(xy 89.526284 -9.081112) (xy 89.549827 -9.057565) (xy 89.566475 -9.028728) (xy 89.575095 -8.996565)
			(xy 89.57564 -8.979916) (xy 89.57564 -8.955532) (xy 89.615755 -8.935545) (xy 89.69906 -8.902468)
			(xy 89.785135 -8.877468) (xy 89.873199 -8.860773) (xy 89.962451 -8.852535) (xy 90.052082 -8.852827)
			(xy 90.141279 -8.861648) (xy 90.229232 -8.878917) (xy 90.315142 -8.904478) (xy 90.398229 -8.938099)
			(xy 90.438224 -8.958326) (xy 90.438224 -8.979408) (xy 90.438881 -8.996035) (xy 90.447554 -9.028141)
			(xy 90.464208 -9.056928) (xy 90.487718 -9.08045) (xy 90.516496 -9.09712) (xy 90.548598 -9.10581)
			(xy 90.565224 -9.106408) (xy 90.647266 -9.106408) (xy 90.678125 -9.135996) (xy 90.734975 -9.199856)
			(xy 90.785794 -9.268611) (xy 90.830163 -9.341696) (xy 90.867716 -9.418505) (xy 90.898142 -9.498406)
			(xy 90.921191 -9.580739) (xy 90.936672 -9.664824) (xy 90.944458 -9.749967) (xy 90.944954 -9.792716)
			(xy 90.944434 -9.835465) (xy 90.936654 -9.920608) (xy 90.921179 -10.004694) (xy 90.898135 -10.087029)
			(xy 90.867714 -10.166931) (xy 90.830166 -10.243743) (xy 90.785801 -10.31683) (xy 90.734986 -10.385589)
			(xy 90.67814 -10.449451) (xy 90.647266 -10.479024) (xy 90.565224 -10.479024) (xy 90.548586 -10.479599)
			(xy 90.516455 -10.488258) (xy 90.487648 -10.504918) (xy 90.464118 -10.528448) (xy 90.447458 -10.557255)
			(xy 90.438799 -10.589386) (xy 90.438224 -10.606024) (xy 90.438224 -10.627106) (xy 90.398233 -10.647268)
			(xy 90.315199 -10.680845) (xy 90.22935 -10.706379) (xy 90.141463 -10.723638) (xy 90.052333 -10.732468)
			(xy 89.962768 -10.732787) (xy 89.873578 -10.724593) (xy 89.78557 -10.70796) (xy 89.699541 -10.683038)
			(xy 89.61627 -10.650054) (xy 89.576148 -10.630154) (xy 89.576148 -10.606024) (xy 89.575536 -10.589381)
			(xy 89.566928 -10.557227) (xy 89.550292 -10.528395) (xy 89.526762 -10.504852) (xy 89.49794 -10.488199)
			(xy 89.465791 -10.479573) (xy 89.449148 -10.479024) (xy 89.361518 -10.479024) (xy 89.330672 -10.449456)
			(xy 89.273851 -10.385635) (xy 89.223055 -10.316921) (xy 89.178703 -10.243882) (xy 89.141162 -10.16712)
			(xy 89.11074 -10.087268) (xy 89.087689 -10.004985) (xy 89.072199 -9.92095) (xy 89.064398 -9.835856)
			(xy 89.064349 -9.750405) (xy 87.5665 -9.750405) (xy 87.5665 -10.4775) (xy 88.353646 -11.264646) (xy 91.833954 -11.264646)
		)
		(stroke
			(width 0)
			(type solid)
		)
		(fill yes)
		(layer "In7.Cu")
		(net "P5V_STB_NODE1")
	)
	(gr_poly
		(pts
			(xy 13.83792 -95.216726) (xy 13.83792 -79.836772) (xy 13.196824 -79.195676) (xy 13.184697 -79.184274)
			(xy 13.155916 -79.167578) (xy 13.123797 -79.158887) (xy 13.107162 -79.158338) (xy 2.878074 -79.158338)
			(xy 1.840484 -80.195928) (xy 1.840484 -81.774992) (xy 10.396718 -81.774992) (xy 10.396718 -81.68112)
			(xy 10.404679 -81.587586) (xy 10.420543 -81.495064) (xy 10.444197 -81.404221) (xy 10.475469 -81.315712)
			(xy 10.514135 -81.230173) (xy 10.559916 -81.148221) (xy 10.612482 -81.070447) (xy 10.671455 -80.997412)
			(xy 10.736408 -80.92964) (xy 10.806875 -80.867621) (xy 10.882348 -80.811802) (xy 10.962283 -80.762584)
			(xy 11.046104 -80.720322) (xy 11.133207 -80.685322) (xy 11.222964 -80.657834) (xy 11.314729 -80.638057)
			(xy 11.407841 -80.626134) (xy 11.501628 -80.62215) (xy 11.595415 -80.626134) (xy 11.688527 -80.638057)
			(xy 11.780292 -80.657834) (xy 11.870049 -80.685322) (xy 11.957152 -80.720322) (xy 12.040973 -80.762584)
			(xy 12.120908 -80.811802) (xy 12.196381 -80.867621) (xy 12.266848 -80.92964) (xy 12.331801 -80.997412)
			(xy 12.390774 -81.070447) (xy 12.44334 -81.148221) (xy 12.489121 -81.230173) (xy 12.527787 -81.315712)
			(xy 12.559059 -81.404221) (xy 12.582713 -81.495064) (xy 12.598577 -81.587586) (xy 12.606538 -81.68112)
			(xy 12.607036 -81.728056) (xy 12.606538 -81.774992) (xy 12.598577 -81.868526) (xy 12.582713 -81.961048)
			(xy 12.559059 -82.051891) (xy 12.527787 -82.1404) (xy 12.489121 -82.225939) (xy 12.44334 -82.307891)
			(xy 12.390774 -82.385665) (xy 12.331801 -82.4587) (xy 12.266848 -82.526472) (xy 12.196381 -82.588491)
			(xy 12.120908 -82.64431) (xy 12.040973 -82.693528) (xy 11.957152 -82.73579) (xy 11.870049 -82.77079)
			(xy 11.780292 -82.798278) (xy 11.688527 -82.818055) (xy 11.595415 -82.829978) (xy 11.501628 -82.833963)
			(xy 11.407841 -82.829978) (xy 11.314729 -82.818055) (xy 11.222964 -82.798278) (xy 11.133207 -82.77079)
			(xy 11.046104 -82.73579) (xy 10.962283 -82.693528) (xy 10.882348 -82.64431) (xy 10.806875 -82.588491)
			(xy 10.736408 -82.526472) (xy 10.671455 -82.4587) (xy 10.612482 -82.385665) (xy 10.559916 -82.307891)
			(xy 10.514135 -82.225939) (xy 10.475469 -82.1404) (xy 10.444197 -82.051891) (xy 10.420543 -81.961048)
			(xy 10.404679 -81.868526) (xy 10.396718 -81.774992) (xy 1.840484 -81.774992) (xy 1.840484 -85.975136)
			(xy 10.396718 -85.975136) (xy 10.396718 -85.881264) (xy 10.404679 -85.78773) (xy 10.420543 -85.695208)
			(xy 10.444197 -85.604365) (xy 10.475469 -85.515856) (xy 10.514135 -85.430317) (xy 10.559916 -85.348365)
			(xy 10.612482 -85.270591) (xy 10.671455 -85.197556) (xy 10.736408 -85.129784) (xy 10.806875 -85.067765)
			(xy 10.882348 -85.011946) (xy 10.962283 -84.962728) (xy 11.046104 -84.920466) (xy 11.133207 -84.885466)
			(xy 11.222964 -84.857978) (xy 11.314729 -84.838201) (xy 11.407841 -84.826278) (xy 11.501628 -84.822294)
			(xy 11.595415 -84.826278) (xy 11.688527 -84.838201) (xy 11.780292 -84.857978) (xy 11.870049 -84.885466)
			(xy 11.957152 -84.920466) (xy 12.040973 -84.962728) (xy 12.120908 -85.011946) (xy 12.196381 -85.067765)
			(xy 12.266848 -85.129784) (xy 12.331801 -85.197556) (xy 12.390774 -85.270591) (xy 12.44334 -85.348365)
			(xy 12.489121 -85.430317) (xy 12.527787 -85.515856) (xy 12.559059 -85.604365) (xy 12.582713 -85.695208)
			(xy 12.598577 -85.78773) (xy 12.606538 -85.881264) (xy 12.607036 -85.9282) (xy 12.606538 -85.975136)
			(xy 12.598577 -86.06867) (xy 12.582713 -86.161192) (xy 12.559059 -86.252035) (xy 12.527787 -86.340544)
			(xy 12.489121 -86.426083) (xy 12.44334 -86.508035) (xy 12.390774 -86.585809) (xy 12.331801 -86.658844)
			(xy 12.266848 -86.726616) (xy 12.196381 -86.788635) (xy 12.120908 -86.844454) (xy 12.040973 -86.893672)
			(xy 11.957152 -86.935934) (xy 11.870049 -86.970934) (xy 11.780292 -86.998422) (xy 11.688527 -87.018199)
			(xy 11.595415 -87.030122) (xy 11.501628 -87.034107) (xy 11.407841 -87.030122) (xy 11.314729 -87.018199)
			(xy 11.222964 -86.998422) (xy 11.133207 -86.970934) (xy 11.046104 -86.935934) (xy 10.962283 -86.893672)
			(xy 10.882348 -86.844454) (xy 10.806875 -86.788635) (xy 10.736408 -86.726616) (xy 10.671455 -86.658844)
			(xy 10.612482 -86.585809) (xy 10.559916 -86.508035) (xy 10.514135 -86.426083) (xy 10.475469 -86.340544)
			(xy 10.444197 -86.252035) (xy 10.420543 -86.161192) (xy 10.404679 -86.06867) (xy 10.396718 -85.975136)
			(xy 1.840484 -85.975136) (xy 1.840484 -90.697241) (xy 4.534904 -90.697241) (xy 4.534904 -90.573415)
			(xy 4.542837 -90.449844) (xy 4.558672 -90.327036) (xy 4.582342 -90.205494) (xy 4.613751 -90.085718)
			(xy 4.652769 -89.968201) (xy 4.699237 -89.853425) (xy 4.752963 -89.741862) (xy 4.813726 -89.633971)
			(xy 4.881277 -89.530194) (xy 4.955339 -89.430959) (xy 5.035606 -89.336672) (xy 5.121749 -89.247722)
			(xy 5.213414 -89.164474) (xy 5.310225 -89.087271) (xy 5.411783 -89.016428) (xy 5.517671 -88.952238)
			(xy 5.627455 -88.894964) (xy 5.740682 -88.844841) (xy 5.856889 -88.802076) (xy 5.975596 -88.766845)
			(xy 6.096317 -88.739291) (xy 6.218555 -88.719528) (xy 6.341808 -88.707638) (xy 6.46557 -88.70367)
			(xy 6.589332 -88.707638) (xy 6.712585 -88.719528) (xy 6.834823 -88.739291) (xy 6.955544 -88.766845)
			(xy 7.074251 -88.802076) (xy 7.190458 -88.844841) (xy 7.303685 -88.894964) (xy 7.413469 -88.952238)
			(xy 7.519357 -89.016428) (xy 7.620915 -89.087271) (xy 7.717726 -89.164474) (xy 7.809391 -89.247722)
			(xy 7.895534 -89.336672) (xy 7.975801 -89.430959) (xy 8.049863 -89.530194) (xy 8.117414 -89.633971)
			(xy 8.178177 -89.741862) (xy 8.231903 -89.853425) (xy 8.278371 -89.968201) (xy 8.317389 -90.085718)
			(xy 8.348798 -90.205494) (xy 8.372468 -90.327036) (xy 8.388303 -90.449844) (xy 8.396236 -90.573415)
			(xy 8.396732 -90.635328) (xy 8.396236 -90.697241) (xy 8.388303 -90.820812) (xy 8.372468 -90.94362)
			(xy 8.348798 -91.065162) (xy 8.317389 -91.184938) (xy 8.278371 -91.302455) (xy 8.231903 -91.417231)
			(xy 8.178177 -91.528794) (xy 8.177831 -91.529408) (xy 12.125958 -91.529408) (xy 12.130029 -91.473786)
			(xy 12.142155 -91.419349) (xy 12.162078 -91.367258) (xy 12.189374 -91.318623) (xy 12.22346 -91.27448)
			(xy 12.263609 -91.235771) (xy 12.308967 -91.20332) (xy 12.358567 -91.177819) (xy 12.411351 -91.159812)
			(xy 12.466194 -91.149682) (xy 12.521928 -91.147645) (xy 12.577365 -91.153745) (xy 12.631322 -91.167851)
			(xy 12.682651 -91.189663) (xy 12.730257 -91.218717) (xy 12.773125 -91.254392) (xy 12.810342 -91.295929)
			(xy 12.841115 -91.342442) (xy 12.864787 -91.392939) (xy 12.880855 -91.446346) (xy 12.888975 -91.501522)
			(xy 12.889484 -91.529408) (xy 12.888975 -91.557294) (xy 12.880855 -91.61247) (xy 12.864787 -91.665877)
			(xy 12.841115 -91.716374) (xy 12.810342 -91.762887) (xy 12.773125 -91.804424) (xy 12.730257 -91.840099)
			(xy 12.682651 -91.869153) (xy 12.631322 -91.890965) (xy 12.577365 -91.905071) (xy 12.521928 -91.911171)
			(xy 12.466194 -91.909134) (xy 12.411351 -91.899004) (xy 12.358567 -91.880997) (xy 12.308967 -91.855496)
			(xy 12.263609 -91.823045) (xy 12.22346 -91.784336) (xy 12.189374 -91.740193) (xy 12.162078 -91.691558)
			(xy 12.142155 -91.639467) (xy 12.130029 -91.58503) (xy 12.125958 -91.529408) (xy 8.177831 -91.529408)
			(xy 8.117414 -91.636685) (xy 8.049863 -91.740462) (xy 7.975801 -91.839697) (xy 7.895534 -91.933984)
			(xy 7.809391 -92.022934) (xy 7.717726 -92.106182) (xy 7.620915 -92.183385) (xy 7.519357 -92.254228)
			(xy 7.413469 -92.318418) (xy 7.303685 -92.375692) (xy 7.190458 -92.425815) (xy 7.074251 -92.46858)
			(xy 6.955544 -92.503811) (xy 6.834823 -92.531365) (xy 6.712585 -92.551128) (xy 6.589332 -92.563018)
			(xy 6.46557 -92.566987) (xy 6.341808 -92.563018) (xy 6.218555 -92.551128) (xy 6.096317 -92.531365)
			(xy 5.975596 -92.503811) (xy 5.856889 -92.46858) (xy 5.740682 -92.425815) (xy 5.627455 -92.375692)
			(xy 5.517671 -92.318418) (xy 5.411783 -92.254228) (xy 5.310225 -92.183385) (xy 5.213414 -92.106182)
			(xy 5.121749 -92.022934) (xy 5.035606 -91.933984) (xy 4.955339 -91.839697) (xy 4.881277 -91.740462)
			(xy 4.813726 -91.636685) (xy 4.752963 -91.528794) (xy 4.699237 -91.417231) (xy 4.652769 -91.302455)
			(xy 4.613751 -91.184938) (xy 4.582342 -91.065162) (xy 4.558672 -90.94362) (xy 4.542837 -90.820812)
			(xy 4.534904 -90.697241) (xy 1.840484 -90.697241) (xy 1.840484 -95.52813) (xy 2.60858 -96.296226)
			(xy 12.75842 -96.296226)
		)
		(stroke
			(width 0)
			(type solid)
		)
		(fill yes)
		(layer "In7.Cu")
		(net "P12V_DBG")
	)
	(gr_poly
		(pts
			(xy 184.75198 -60.791598) (xy 184.75198 -57.383172) (xy 184.722674 -57.327673) (xy 184.670561 -57.213484)
			(xy 184.626078 -57.096113) (xy 184.589417 -56.976068) (xy 184.560736 -56.853871) (xy 184.540161 -56.730051)
			(xy 184.52778 -56.605145) (xy 184.523647 -56.479695) (xy 184.527781 -56.354245) (xy 184.540162 -56.229339)
			(xy 184.560738 -56.105519) (xy 184.589419 -55.983321) (xy 184.626082 -55.863277) (xy 184.670566 -55.745906)
			(xy 184.722678 -55.631717) (xy 184.75198 -55.576216) (xy 184.75198 -51.130708) (xy 183.94172 -50.320448)
			(xy 182.596536 -50.320448) (xy 182.581897 -50.320863) (xy 182.553391 -50.327542) (xy 182.527152 -50.340533)
			(xy 182.50456 -50.359156) (xy 182.486799 -50.382432) (xy 182.480458 -50.395632) (xy 182.455205 -50.451115)
			(xy 182.398569 -50.559075) (xy 182.335145 -50.663194) (xy 182.265195 -50.763044) (xy 182.189003 -50.858218)
			(xy 182.106882 -50.948325) (xy 182.019168 -51.032998) (xy 181.92622 -51.111889) (xy 181.828419 -51.184677)
			(xy 181.726163 -51.251062) (xy 181.619872 -51.310773) (xy 181.509981 -51.363567) (xy 181.39694 -51.409226)
			(xy 181.28121 -51.447565) (xy 181.163266 -51.478426) (xy 181.04359 -51.501683) (xy 180.922673 -51.51724)
			(xy 180.801007 -51.525035) (xy 180.679093 -51.525035) (xy 180.557427 -51.51724) (xy 180.43651 -51.501683)
			(xy 180.316834 -51.478426) (xy 180.19889 -51.447565) (xy 180.08316 -51.409226) (xy 179.970119 -51.363567)
			(xy 179.860228 -51.310773) (xy 179.753937 -51.251062) (xy 179.651681 -51.184677) (xy 179.55388 -51.111889)
			(xy 179.460932 -51.032998) (xy 179.373218 -50.948325) (xy 179.291097 -50.858218) (xy 179.214905 -50.763044)
			(xy 179.144955 -50.663194) (xy 179.081531 -50.559075) (xy 179.024895 -50.451115) (xy 178.999642 -50.395632)
			(xy 178.993304 -50.382425) (xy 178.97558 -50.35911) (xy 178.952991 -50.340469) (xy 178.926736 -50.327492)
			(xy 178.898209 -50.320866) (xy 178.883564 -50.320448) (xy 171.983654 -50.320448) (xy 171.74464 -50.559462)
			(xy 171.74464 -53.881528) (xy 177.84648 -53.881528) (xy 177.850551 -53.825906) (xy 177.862677 -53.771469)
			(xy 177.8826 -53.719378) (xy 177.909896 -53.670743) (xy 177.943982 -53.6266) (xy 177.984131 -53.587891)
			(xy 178.029489 -53.55544) (xy 178.079089 -53.529939) (xy 178.131873 -53.511932) (xy 178.186716 -53.501802)
			(xy 178.24245 -53.499765) (xy 178.297887 -53.505865) (xy 178.351844 -53.519971) (xy 178.403173 -53.541783)
			(xy 178.450779 -53.570837) (xy 178.493647 -53.606512) (xy 178.530864 -53.648049) (xy 178.561637 -53.694562)
			(xy 178.585309 -53.745059) (xy 178.601377 -53.798466) (xy 178.609497 -53.853642) (xy 178.610006 -53.881528)
			(xy 178.609497 -53.909414) (xy 178.601377 -53.96459) (xy 178.585309 -54.017997) (xy 178.561637 -54.068494)
			(xy 178.530864 -54.115007) (xy 178.493647 -54.156544) (xy 178.450779 -54.192219) (xy 178.403173 -54.221273)
			(xy 178.351844 -54.243085) (xy 178.297887 -54.257191) (xy 178.24245 -54.263291) (xy 178.186716 -54.261254)
			(xy 178.131873 -54.251124) (xy 178.079089 -54.233117) (xy 178.029489 -54.207616) (xy 177.984131 -54.175165)
			(xy 177.943982 -54.136456) (xy 177.909896 -54.092313) (xy 177.8826 -54.043678) (xy 177.862677 -53.991587)
			(xy 177.850551 -53.93715) (xy 177.84648 -53.881528) (xy 171.74464 -53.881528) (xy 171.74464 -55.084472)
			(xy 177.65852 -55.084472) (xy 177.662591 -55.02885) (xy 177.674717 -54.974413) (xy 177.69464 -54.922322)
			(xy 177.721936 -54.873687) (xy 177.756022 -54.829544) (xy 177.796171 -54.790835) (xy 177.841529 -54.758384)
			(xy 177.891129 -54.732883) (xy 177.943913 -54.714876) (xy 177.998756 -54.704746) (xy 178.05449 -54.702709)
			(xy 178.109927 -54.708809) (xy 178.163884 -54.722915) (xy 178.215213 -54.744727) (xy 178.262819 -54.773781)
			(xy 178.305687 -54.809456) (xy 178.342904 -54.850993) (xy 178.373677 -54.897506) (xy 178.397349 -54.948003)
			(xy 178.413417 -55.00141) (xy 178.421537 -55.056586) (xy 178.422046 -55.084472) (xy 178.421537 -55.112358)
			(xy 178.413417 -55.167534) (xy 178.397349 -55.220941) (xy 178.373677 -55.271438) (xy 178.342904 -55.317951)
			(xy 178.305687 -55.359488) (xy 178.262819 -55.395163) (xy 178.215213 -55.424217) (xy 178.163884 -55.446029)
			(xy 178.109927 -55.460135) (xy 178.05449 -55.466235) (xy 177.998756 -55.464198) (xy 177.943913 -55.454068)
			(xy 177.891129 -55.436061) (xy 177.841529 -55.41056) (xy 177.796171 -55.378109) (xy 177.756022 -55.3394)
			(xy 177.721936 -55.295257) (xy 177.69464 -55.246622) (xy 177.674717 -55.194531) (xy 177.662591 -55.140094)
			(xy 177.65852 -55.084472) (xy 171.74464 -55.084472) (xy 171.74464 -56.227472) (xy 177.670458 -56.227472)
			(xy 177.674529 -56.17185) (xy 177.686655 -56.117413) (xy 177.706578 -56.065322) (xy 177.733874 -56.016687)
			(xy 177.76796 -55.972544) (xy 177.808109 -55.933835) (xy 177.853467 -55.901384) (xy 177.903067 -55.875883)
			(xy 177.955851 -55.857876) (xy 178.010694 -55.847746) (xy 178.066428 -55.845709) (xy 178.121865 -55.851809)
			(xy 178.175822 -55.865915) (xy 178.227151 -55.887727) (xy 178.274757 -55.916781) (xy 178.317625 -55.952456)
			(xy 178.354842 -55.993993) (xy 178.385615 -56.040506) (xy 178.409287 -56.091003) (xy 178.425355 -56.14441)
			(xy 178.433475 -56.199586) (xy 178.433984 -56.227472) (xy 178.433475 -56.255358) (xy 178.425355 -56.310534)
			(xy 178.409287 -56.363941) (xy 178.385615 -56.414438) (xy 178.354842 -56.460951) (xy 178.338048 -56.479694)
			(xy 178.834042 -56.479694) (xy 178.838039 -56.356318) (xy 178.850014 -56.23346) (xy 178.869917 -56.111635)
			(xy 178.897663 -55.991354) (xy 178.933137 -55.87312) (xy 178.97619 -55.757431) (xy 179.026641 -55.644772)
			(xy 179.084278 -55.535614) (xy 179.148861 -55.430416) (xy 179.220118 -55.329619) (xy 179.297749 -55.233646)
			(xy 179.381431 -55.142899) (xy 179.47081 -55.05776) (xy 179.565514 -54.978584) (xy 179.665143 -54.905705)
			(xy 179.769282 -54.839427) (xy 179.877492 -54.780029) (xy 179.98932 -54.727761) (xy 180.104296 -54.68284)
			(xy 180.22194 -54.645456) (xy 180.341756 -54.615766) (xy 180.463243 -54.593893) (xy 180.585891 -54.57993)
			(xy 180.709186 -54.573936) (xy 180.83261 -54.575935) (xy 180.955646 -54.585919) (xy 181.077777 -54.603846)
			(xy 181.198492 -54.629641) (xy 181.317285 -54.663196) (xy 181.433656 -54.704369) (xy 181.547118 -54.752989)
			(xy 181.657194 -54.808852) (xy 181.763424 -54.871723) (xy 181.865362 -54.941338) (xy 181.962579 -55.017405)
			(xy 182.054669 -55.099606) (xy 182.141245 -55.187595) (xy 182.221944 -55.281004) (xy 182.296427 -55.379441)
			(xy 182.364382 -55.482492) (xy 182.425524 -55.589726) (xy 182.479597 -55.700693) (xy 182.526373 -55.814927)
			(xy 182.565657 -55.93195) (xy 182.597284 -56.05127) (xy 182.621121 -56.172387) (xy 182.637068 -56.294792)
			(xy 182.645058 -56.417974) (xy 182.645558 -56.479694) (xy 182.645058 -56.541414) (xy 182.637068 -56.664596)
			(xy 182.621121 -56.787001) (xy 182.597284 -56.908118) (xy 182.565657 -57.027438) (xy 182.526373 -57.144461)
			(xy 182.479597 -57.258695) (xy 182.425524 -57.369662) (xy 182.364382 -57.476896) (xy 182.296427 -57.579947)
			(xy 182.221944 -57.678384) (xy 182.141245 -57.771793) (xy 182.054669 -57.859782) (xy 181.962579 -57.941983)
			(xy 181.865362 -58.01805) (xy 181.763424 -58.087665) (xy 181.657194 -58.150536) (xy 181.547118 -58.206399)
			(xy 181.433656 -58.255019) (xy 181.317285 -58.296192) (xy 181.198492 -58.329747) (xy 181.077777 -58.355542)
			(xy 180.955646 -58.373469) (xy 180.83261 -58.383453) (xy 180.709186 -58.385452) (xy 180.585891 -58.379458)
			(xy 180.463243 -58.365495) (xy 180.341756 -58.343622) (xy 180.22194 -58.313932) (xy 180.104296 -58.276548)
			(xy 179.98932 -58.231627) (xy 179.877492 -58.179359) (xy 179.769282 -58.119961) (xy 179.665143 -58.053683)
			(xy 179.565514 -57.980804) (xy 179.47081 -57.901628) (xy 179.381431 -57.816489) (xy 179.297749 -57.725742)
			(xy 179.220118 -57.629769) (xy 179.148861 -57.528972) (xy 179.084278 -57.423774) (xy 179.026641 -57.314616)
			(xy 178.97619 -57.201957) (xy 178.933137 -57.086268) (xy 178.897663 -56.968034) (xy 178.869917 -56.847753)
			(xy 178.850014 -56.725928) (xy 178.838039 -56.60307) (xy 178.834042 -56.479694) (xy 178.338048 -56.479694)
			(xy 178.317625 -56.502488) (xy 178.274757 -56.538163) (xy 178.227151 -56.567217) (xy 178.175822 -56.589029)
			(xy 178.121865 -56.603135) (xy 178.066428 -56.609235) (xy 178.010694 -56.607198) (xy 177.955851 -56.597068)
			(xy 177.903067 -56.579061) (xy 177.853467 -56.55356) (xy 177.808109 -56.521109) (xy 177.76796 -56.4824)
			(xy 177.733874 -56.438257) (xy 177.706578 -56.389622) (xy 177.686655 -56.337531) (xy 177.674529 -56.283094)
			(xy 177.670458 -56.227472) (xy 171.74464 -56.227472) (xy 171.74464 -60.570364) (xy 172.301154 -61.126878)
			(xy 184.4167 -61.126878)
		)
		(stroke
			(width 0)
			(type solid)
		)
		(fill yes)
		(layer "In7.Cu")
		(net "USBPWR_P1")
	)
	(gr_poly
		(pts
			(xy 61.999368 -130.550666) (xy 62.008766 -130.522218) (xy 62.019596 -130.49132) (xy 62.048098 -130.432376)
			(xy 62.083935 -130.377581) (xy 62.126515 -130.327844) (xy 62.150498 -130.305556) (xy 62.161045 -130.295477)
			(xy 62.177671 -130.271513) (xy 62.188416 -130.244398) (xy 62.192716 -130.215551) (xy 62.190348 -130.186481)
			(xy 62.186312 -130.17246) (xy 62.178499 -130.146651) (xy 62.169535 -130.093477) (xy 62.168329 -130.039567)
			(xy 62.174906 -129.986046) (xy 62.189129 -129.934032) (xy 62.210701 -129.884611) (xy 62.23917 -129.838816)
			(xy 62.256162 -129.817876) (xy 62.275209 -129.796102) (xy 62.318867 -129.758149) (xy 62.367877 -129.727416)
			(xy 62.421055 -129.704645) (xy 62.448948 -129.696972) (xy 62.465078 -129.692302) (xy 62.494292 -129.675768)
			(xy 62.518193 -129.652197) (xy 62.535129 -129.623213) (xy 62.543932 -129.590819) (xy 62.544452 -129.574036)
			(xy 62.544452 -128.09855) (xy 62.491366 -128.030224) (xy 62.448948 -128.019302) (xy 62.422412 -128.011993)
			(xy 62.371681 -127.990649) (xy 62.32463 -127.962091) (xy 62.303152 -127.94488) (xy 62.28591 -127.931212)
			(xy 62.2477 -127.909407) (xy 62.206309 -127.894499) (xy 62.16297 -127.886932) (xy 62.118976 -127.886932)
			(xy 62.075637 -127.894499) (xy 62.034246 -127.909407) (xy 61.996036 -127.931212) (xy 61.978794 -127.94488)
			(xy 61.957532 -127.961866) (xy 61.911034 -127.990137) (xy 61.860917 -128.011342) (xy 61.808249 -128.02503)
			(xy 61.754149 -128.03091) (xy 61.699769 -128.028856) (xy 61.646267 -128.018913) (xy 61.594781 -128.001291)
			(xy 61.546406 -127.976366) (xy 61.502173 -127.944669) (xy 61.463021 -127.906873) (xy 61.429786 -127.863783)
			(xy 61.403172 -127.816317) (xy 61.383748 -127.765483) (xy 61.371926 -127.712364) (xy 61.367958 -127.658091)
			(xy 61.371929 -127.603818) (xy 61.383753 -127.5507) (xy 61.40318 -127.499867) (xy 61.429795 -127.452402)
			(xy 61.463033 -127.409314) (xy 61.502187 -127.37152) (xy 61.546422 -127.339824) (xy 61.594798 -127.314902)
			(xy 61.646285 -127.297283) (xy 61.699787 -127.287342) (xy 61.754167 -127.285291) (xy 61.808266 -127.291173)
			(xy 61.860934 -127.304864) (xy 61.91105 -127.326071) (xy 61.957547 -127.354344) (xy 61.978794 -127.371348)
			(xy 61.996021 -127.385049) (xy 62.034219 -127.406914) (xy 62.075614 -127.421864) (xy 62.118967 -127.429454)
			(xy 62.162979 -127.429454) (xy 62.206332 -127.421864) (xy 62.247727 -127.406914) (xy 62.285925 -127.385049)
			(xy 62.303152 -127.371348) (xy 62.324626 -127.354129) (xy 62.371666 -127.325549) (xy 62.422406 -127.304219)
			(xy 62.448948 -127.296926) (xy 62.465075 -127.292254) (xy 62.494283 -127.275719) (xy 62.518175 -127.252146)
			(xy 62.535101 -127.223163) (xy 62.543893 -127.190771) (xy 62.544452 -127.17399) (xy 62.544452 -126.101602)
			(xy 61.0235 -124.58065) (xy 56.871616 -124.58065) (xy 56.470042 -124.98197) (xy 56.468264 -124.98197)
			(xy 55.933086 -125.517148) (xy 55.933086 -125.711712) (xy 56.567068 -125.711712) (xy 56.571139 -125.65609)
			(xy 56.583265 -125.601653) (xy 56.603188 -125.549562) (xy 56.630484 -125.500927) (xy 56.66457 -125.456784)
			(xy 56.704719 -125.418075) (xy 56.750077 -125.385624) (xy 56.799677 -125.360123) (xy 56.852461 -125.342116)
			(xy 56.907304 -125.331986) (xy 56.963038 -125.329949) (xy 57.018475 -125.336049) (xy 57.072432 -125.350155)
			(xy 57.123761 -125.371967) (xy 57.171367 -125.401021) (xy 57.214235 -125.436696) (xy 57.251452 -125.478233)
			(xy 57.282225 -125.524746) (xy 57.305897 -125.575243) (xy 57.321965 -125.62865) (xy 57.330085 -125.683826)
			(xy 57.330594 -125.711712) (xy 57.330085 -125.739598) (xy 57.321965 -125.794774) (xy 57.305897 -125.848181)
			(xy 57.282225 -125.898678) (xy 57.251452 -125.945191) (xy 57.214235 -125.986728) (xy 57.171367 -126.022403)
			(xy 57.123761 -126.051457) (xy 57.072432 -126.073269) (xy 57.018475 -126.087375) (xy 56.963038 -126.093475)
			(xy 56.907304 -126.091438) (xy 56.852461 -126.081308) (xy 56.799677 -126.063301) (xy 56.750077 -126.0378)
			(xy 56.704719 -126.005349) (xy 56.66457 -125.96664) (xy 56.630484 -125.922497) (xy 56.603188 -125.873862)
			(xy 56.583265 -125.821771) (xy 56.571139 -125.767334) (xy 56.567068 -125.711712) (xy 55.933086 -125.711712)
			(xy 55.933086 -126.370842) (xy 57.022746 -127.460502) (xy 57.384442 -127.460502) (xy 57.401739 -127.459879)
			(xy 57.435044 -127.450517) (xy 57.464622 -127.432572) (xy 57.476898 -127.42037) (xy 57.494907 -127.401876)
			(xy 57.535418 -127.369886) (xy 57.580217 -127.344244) (xy 57.628317 -127.325513) (xy 57.67866 -127.314107)
			(xy 57.730136 -127.310277) (xy 57.781612 -127.314107) (xy 57.831955 -127.325513) (xy 57.880055 -127.344244)
			(xy 57.924854 -127.369886) (xy 57.965365 -127.401876) (xy 57.983374 -127.42037) (xy 57.995628 -127.432597)
			(xy 58.025208 -127.450553) (xy 58.058529 -127.459884) (xy 58.07583 -127.460502) (xy 58.19521 -127.460502)
			(xy 58.212508 -127.459883) (xy 58.245819 -127.450528) (xy 58.275404 -127.432587) (xy 58.287666 -127.42037)
			(xy 58.305675 -127.401876) (xy 58.346186 -127.369886) (xy 58.390985 -127.344244) (xy 58.439085 -127.325513)
			(xy 58.489428 -127.314107) (xy 58.540904 -127.310277) (xy 58.59238 -127.314107) (xy 58.642723 -127.325513)
			(xy 58.690823 -127.344244) (xy 58.735622 -127.369886) (xy 58.776133 -127.401876) (xy 58.794142 -127.42037)
			(xy 58.806395 -127.432601) (xy 58.835974 -127.450563) (xy 58.869296 -127.459903) (xy 58.886598 -127.460502)
			(xy 58.99531 -127.460502) (xy 59.012608 -127.459883) (xy 59.045919 -127.450528) (xy 59.075504 -127.432587)
			(xy 59.087766 -127.42037) (xy 59.106417 -127.401213) (xy 59.148546 -127.368293) (xy 59.195223 -127.342219)
			(xy 59.245344 -127.323607) (xy 59.297726 -127.312897) (xy 59.35113 -127.310342) (xy 59.404295 -127.316002)
			(xy 59.455964 -127.329744) (xy 59.504917 -127.351243) (xy 59.549996 -127.37999) (xy 59.590137 -127.415307)
			(xy 59.62439 -127.456359) (xy 59.651946 -127.502176) (xy 59.672155 -127.551675) (xy 59.684539 -127.603687)
			(xy 59.688804 -127.656982) (xy 59.684851 -127.710301) (xy 59.672772 -127.762384) (xy 59.66333 -127.7874)
			(xy 59.648852 -127.823214) (xy 59.664092 -127.897382) (xy 59.808872 -128.042162) (xy 59.808872 -128.636522)
			(xy 59.809329 -128.658072) (xy 59.816609 -128.700554) (xy 59.830956 -128.741196) (xy 59.851959 -128.778834)
			(xy 59.879014 -128.812385) (xy 59.911345 -128.840887) (xy 59.948023 -128.863522) (xy 59.987997 -128.87964)
			(xy 60.030118 -128.888779) (xy 60.073176 -128.890675) (xy 60.094622 -128.88849) (xy 60.121963 -128.885549)
			(xy 60.176939 -128.886783) (xy 60.231136 -128.896081) (xy 60.283379 -128.913241) (xy 60.332534 -128.93789)
			(xy 60.377534 -128.969495) (xy 60.417402 -129.007368) (xy 60.451272 -129.050688) (xy 60.47841 -129.098514)
			(xy 60.498226 -129.149809) (xy 60.510291 -129.203458) (xy 60.514342 -129.258298) (xy 60.514341 -129.258314)
			(xy 61.393321 -129.258314) (xy 61.397396 -129.205233) (xy 61.409526 -129.153397) (xy 61.429427 -129.10402)
			(xy 61.456632 -129.058259) (xy 61.490504 -129.017187) (xy 61.530248 -128.981768) (xy 61.574933 -128.95283)
			(xy 61.623512 -128.931052) (xy 61.674845 -128.916946) (xy 61.727731 -128.91084) (xy 61.780929 -128.912879)
			(xy 61.833192 -128.923015) (xy 61.883295 -128.94101) (xy 61.930064 -128.966442) (xy 61.972403 -128.998716)
			(xy 62.009319 -129.037074) (xy 62.039947 -129.080618) (xy 62.063569 -129.128327) (xy 62.079632 -129.179083)
			(xy 62.087759 -129.231696) (xy 62.088268 -129.258314) (xy 62.087759 -129.284932) (xy 62.079632 -129.337545)
			(xy 62.063569 -129.388301) (xy 62.039947 -129.43601) (xy 62.009319 -129.479554) (xy 61.972403 -129.517912)
			(xy 61.930064 -129.550186) (xy 61.883295 -129.575618) (xy 61.833192 -129.593613) (xy 61.780929 -129.603749)
			(xy 61.727731 -129.605788) (xy 61.674845 -129.599682) (xy 61.623512 -129.585576) (xy 61.574933 -129.563798)
			(xy 61.530248 -129.53486) (xy 61.490504 -129.499441) (xy 61.456632 -129.458369) (xy 61.429427 -129.412608)
			(xy 61.409526 -129.363231) (xy 61.397396 -129.311395) (xy 61.393321 -129.258314) (xy 60.514341 -129.258314)
			(xy 60.510291 -129.313138) (xy 60.498227 -129.366788) (xy 60.478411 -129.418082) (xy 60.451274 -129.465909)
			(xy 60.417404 -129.509229) (xy 60.377537 -129.547103) (xy 60.332537 -129.578708) (xy 60.283383 -129.603358)
			(xy 60.23114 -129.620519) (xy 60.176942 -129.629817) (xy 60.121967 -129.631051) (xy 60.094622 -129.628138)
			(xy 60.073182 -129.625898) (xy 60.030121 -129.62781) (xy 59.988 -129.636961) (xy 59.948028 -129.653089)
			(xy 59.91135 -129.67573) (xy 59.879019 -129.704237) (xy 59.851962 -129.73779) (xy 59.830956 -129.775429)
			(xy 59.816602 -129.816072) (xy 59.809312 -129.858554) (xy 59.808872 -129.880106) (xy 59.808872 -130.345688)
			(xy 59.958732 -130.495548) (xy 60.054744 -130.495548) (xy 60.06719 -130.493008) (xy 60.093989 -130.488066)
			(xy 60.148405 -130.485149) (xy 60.202665 -130.490195) (xy 60.255611 -130.503094) (xy 60.306111 -130.523572)
			(xy 60.353088 -130.551191) (xy 60.395538 -130.585361) (xy 60.414408 -130.605022) (xy 60.426681 -130.617475)
			(xy 60.456498 -130.635712) (xy 60.490149 -130.645155) (xy 60.507626 -130.645662) (xy 61.904372 -130.645662)
		)
		(stroke
			(width 0)
			(type solid)
		)
		(fill yes)
		(layer "In7.Cu")
		(net "BMC_NODE1_HPLLAV33")
	)
	(gr_poly
		(pts
			(xy 192.3288 -39.97706) (xy 192.3288 -30.222444) (xy 192.328311 -30.205785) (xy 192.319697 -30.173601)
			(xy 192.303045 -30.144744) (xy 192.279491 -30.121182) (xy 192.250639 -30.10452) (xy 192.218458 -30.095895)
			(xy 192.2018 -30.095444) (xy 175.720502 -30.095444) (xy 175.697812 -30.095918) (xy 175.653144 -30.103925)
			(xy 175.610609 -30.119738) (xy 175.571559 -30.142856) (xy 175.537237 -30.172542) (xy 175.508732 -30.207852)
			(xy 175.486953 -30.247663) (xy 175.472591 -30.29071) (xy 175.466104 -30.335624) (xy 175.467697 -30.380975)
			(xy 175.477321 -30.425323) (xy 175.485552 -30.446472) (xy 175.495674 -30.472297) (xy 175.50919 -30.526091)
			(xy 175.514771 -30.581275) (xy 175.512301 -30.636686) (xy 175.50183 -30.691155) (xy 175.483581 -30.743532)
			(xy 175.457937 -30.792714) (xy 175.42544 -30.837663) (xy 175.386775 -30.877431) (xy 175.342758 -30.911179)
			(xy 175.294316 -30.938196) (xy 175.242472 -30.957911) (xy 175.18832 -30.969909) (xy 175.133 -30.973936)
			(xy 175.07768 -30.969909) (xy 175.023528 -30.957911) (xy 174.971684 -30.938196) (xy 174.923242 -30.911179)
			(xy 174.879225 -30.877431) (xy 174.84056 -30.837663) (xy 174.808063 -30.792714) (xy 174.782419 -30.743532)
			(xy 174.76417 -30.691155) (xy 174.753699 -30.636686) (xy 174.751229 -30.581275) (xy 174.75681 -30.526091)
			(xy 174.770326 -30.472297) (xy 174.780448 -30.446472) (xy 174.788657 -30.425313) (xy 174.798276 -30.380965)
			(xy 174.799867 -30.335613) (xy 174.793379 -30.290699) (xy 174.77902 -30.247652) (xy 174.757244 -30.207838)
			(xy 174.728745 -30.172523) (xy 174.694428 -30.142831) (xy 174.655383 -30.119704) (xy 174.612853 -30.103878)
			(xy 174.568188 -30.095855) (xy 174.545498 -30.095444) (xy 174.128176 -30.095444) (xy 173.86808 -30.35554)
			(xy 173.86808 -35.59556) (xy 175.169574 -35.59556) (xy 175.173645 -35.539938) (xy 175.185771 -35.485501)
			(xy 175.205694 -35.43341) (xy 175.23299 -35.384775) (xy 175.267076 -35.340632) (xy 175.307225 -35.301923)
			(xy 175.352583 -35.269472) (xy 175.402183 -35.243971) (xy 175.454967 -35.225964) (xy 175.50981 -35.215834)
			(xy 175.565544 -35.213797) (xy 175.620981 -35.219897) (xy 175.674938 -35.234003) (xy 175.726267 -35.255815)
			(xy 175.773873 -35.284869) (xy 175.816741 -35.320544) (xy 175.853958 -35.362081) (xy 175.884731 -35.408594)
			(xy 175.908403 -35.459091) (xy 175.924471 -35.512498) (xy 175.932591 -35.567674) (xy 175.9331 -35.59556)
			(xy 175.932591 -35.623446) (xy 175.924471 -35.678622) (xy 175.908403 -35.732029) (xy 175.884731 -35.782526)
			(xy 175.853958 -35.829039) (xy 175.816741 -35.870576) (xy 175.773873 -35.906251) (xy 175.726267 -35.935305)
			(xy 175.674938 -35.957117) (xy 175.620981 -35.971223) (xy 175.565544 -35.977323) (xy 175.50981 -35.975286)
			(xy 175.454967 -35.965156) (xy 175.402183 -35.947149) (xy 175.352583 -35.921648) (xy 175.307225 -35.889197)
			(xy 175.267076 -35.850488) (xy 175.23299 -35.806345) (xy 175.205694 -35.75771) (xy 175.185771 -35.705619)
			(xy 175.173645 -35.651182) (xy 175.169574 -35.59556) (xy 173.86808 -35.59556) (xy 173.86808 -36.46297)
			(xy 178.834042 -36.46297) (xy 178.838039 -36.339594) (xy 178.850014 -36.216736) (xy 178.869917 -36.094911)
			(xy 178.897663 -35.97463) (xy 178.933137 -35.856396) (xy 178.97619 -35.740707) (xy 179.026641 -35.628048)
			(xy 179.084278 -35.51889) (xy 179.148861 -35.413692) (xy 179.220118 -35.312895) (xy 179.297749 -35.216922)
			(xy 179.381431 -35.126175) (xy 179.47081 -35.041036) (xy 179.565514 -34.96186) (xy 179.665143 -34.888981)
			(xy 179.769282 -34.822703) (xy 179.877492 -34.763305) (xy 179.98932 -34.711037) (xy 180.104296 -34.666116)
			(xy 180.22194 -34.628732) (xy 180.341756 -34.599042) (xy 180.463243 -34.577169) (xy 180.585891 -34.563206)
			(xy 180.709186 -34.557212) (xy 180.83261 -34.559211) (xy 180.955646 -34.569195) (xy 181.077777 -34.587122)
			(xy 181.198492 -34.612917) (xy 181.317285 -34.646472) (xy 181.433656 -34.687645) (xy 181.547118 -34.736265)
			(xy 181.657194 -34.792128) (xy 181.763424 -34.854999) (xy 181.865362 -34.924614) (xy 181.962579 -35.000681)
			(xy 182.054669 -35.082882) (xy 182.141245 -35.170871) (xy 182.221944 -35.26428) (xy 182.296427 -35.362717)
			(xy 182.364382 -35.465768) (xy 182.425524 -35.573002) (xy 182.479597 -35.683969) (xy 182.526373 -35.798203)
			(xy 182.565657 -35.915226) (xy 182.597284 -36.034546) (xy 182.621121 -36.155663) (xy 182.637068 -36.278068)
			(xy 182.645058 -36.40125) (xy 182.645558 -36.46297) (xy 184.523642 -36.46297) (xy 184.527639 -36.339594)
			(xy 184.539614 -36.216736) (xy 184.559517 -36.094911) (xy 184.587263 -35.97463) (xy 184.622737 -35.856396)
			(xy 184.66579 -35.740707) (xy 184.716241 -35.628048) (xy 184.773878 -35.51889) (xy 184.838461 -35.413692)
			(xy 184.909718 -35.312895) (xy 184.987349 -35.216922) (xy 185.071031 -35.126175) (xy 185.16041 -35.041036)
			(xy 185.255114 -34.96186) (xy 185.354743 -34.888981) (xy 185.458882 -34.822703) (xy 185.567092 -34.763305)
			(xy 185.67892 -34.711037) (xy 185.793896 -34.666116) (xy 185.91154 -34.628732) (xy 186.031356 -34.599042)
			(xy 186.152843 -34.577169) (xy 186.275491 -34.563206) (xy 186.398786 -34.557212) (xy 186.52221 -34.559211)
			(xy 186.645246 -34.569195) (xy 186.767377 -34.587122) (xy 186.888092 -34.612917) (xy 187.006885 -34.646472)
			(xy 187.123256 -34.687645) (xy 187.236718 -34.736265) (xy 187.346794 -34.792128) (xy 187.453024 -34.854999)
			(xy 187.554962 -34.924614) (xy 187.652179 -35.000681) (xy 187.744269 -35.082882) (xy 187.830845 -35.170871)
			(xy 187.911544 -35.26428) (xy 187.986027 -35.362717) (xy 188.053982 -35.465768) (xy 188.115124 -35.573002)
			(xy 188.169197 -35.683969) (xy 188.215973 -35.798203) (xy 188.255257 -35.915226) (xy 188.286884 -36.034546)
			(xy 188.310721 -36.155663) (xy 188.326668 -36.278068) (xy 188.334658 -36.40125) (xy 188.335158 -36.46297)
			(xy 188.334658 -36.52469) (xy 188.326668 -36.647872) (xy 188.310721 -36.770277) (xy 188.286884 -36.891394)
			(xy 188.255257 -37.010714) (xy 188.215973 -37.127737) (xy 188.169197 -37.241971) (xy 188.115124 -37.352938)
			(xy 188.053982 -37.460172) (xy 187.986027 -37.563223) (xy 187.911544 -37.66166) (xy 187.830845 -37.755069)
			(xy 187.744269 -37.843058) (xy 187.652179 -37.925259) (xy 187.554962 -38.001326) (xy 187.453024 -38.070941)
			(xy 187.346794 -38.133812) (xy 187.236718 -38.189675) (xy 187.123256 -38.238295) (xy 187.006885 -38.279468)
			(xy 186.888092 -38.313023) (xy 186.767377 -38.338818) (xy 186.645246 -38.356745) (xy 186.52221 -38.366729)
			(xy 186.398786 -38.368728) (xy 186.275491 -38.362734) (xy 186.152843 -38.348771) (xy 186.031356 -38.326898)
			(xy 185.91154 -38.297208) (xy 185.793896 -38.259824) (xy 185.67892 -38.214903) (xy 185.567092 -38.162635)
			(xy 185.458882 -38.103237) (xy 185.354743 -38.036959) (xy 185.255114 -37.96408) (xy 185.16041 -37.884904)
			(xy 185.071031 -37.799765) (xy 184.987349 -37.709018) (xy 184.909718 -37.613045) (xy 184.838461 -37.512248)
			(xy 184.773878 -37.40705) (xy 184.716241 -37.297892) (xy 184.66579 -37.185233) (xy 184.622737 -37.069544)
			(xy 184.587263 -36.95131) (xy 184.559517 -36.831029) (xy 184.539614 -36.709204) (xy 184.527639 -36.586346)
			(xy 184.523642 -36.46297) (xy 182.645558 -36.46297) (xy 182.645058 -36.52469) (xy 182.637068 -36.647872)
			(xy 182.621121 -36.770277) (xy 182.597284 -36.891394) (xy 182.565657 -37.010714) (xy 182.526373 -37.127737)
			(xy 182.479597 -37.241971) (xy 182.425524 -37.352938) (xy 182.364382 -37.460172) (xy 182.296427 -37.563223)
			(xy 182.221944 -37.66166) (xy 182.141245 -37.755069) (xy 182.054669 -37.843058) (xy 181.962579 -37.925259)
			(xy 181.865362 -38.001326) (xy 181.763424 -38.070941) (xy 181.657194 -38.133812) (xy 181.547118 -38.189675)
			(xy 181.433656 -38.238295) (xy 181.317285 -38.279468) (xy 181.198492 -38.313023) (xy 181.077777 -38.338818)
			(xy 180.955646 -38.356745) (xy 180.83261 -38.366729) (xy 180.709186 -38.368728) (xy 180.585891 -38.362734)
			(xy 180.463243 -38.348771) (xy 180.341756 -38.326898) (xy 180.22194 -38.297208) (xy 180.104296 -38.259824)
			(xy 179.98932 -38.214903) (xy 179.877492 -38.162635) (xy 179.769282 -38.103237) (xy 179.665143 -38.036959)
			(xy 179.565514 -37.96408) (xy 179.47081 -37.884904) (xy 179.381431 -37.799765) (xy 179.297749 -37.709018)
			(xy 179.220118 -37.613045) (xy 179.148861 -37.512248) (xy 179.084278 -37.40705) (xy 179.026641 -37.297892)
			(xy 178.97619 -37.185233) (xy 178.933137 -37.069544) (xy 178.897663 -36.95131) (xy 178.869917 -36.831029)
			(xy 178.850014 -36.709204) (xy 178.838039 -36.586346) (xy 178.834042 -36.46297) (xy 173.86808 -36.46297)
			(xy 173.86808 -36.848034) (xy 175.211738 -36.848034) (xy 175.215809 -36.792412) (xy 175.227935 -36.737975)
			(xy 175.247858 -36.685884) (xy 175.275154 -36.637249) (xy 175.30924 -36.593106) (xy 175.349389 -36.554397)
			(xy 175.394747 -36.521946) (xy 175.444347 -36.496445) (xy 175.497131 -36.478438) (xy 175.551974 -36.468308)
			(xy 175.607708 -36.466271) (xy 175.663145 -36.472371) (xy 175.717102 -36.486477) (xy 175.768431 -36.508289)
			(xy 175.816037 -36.537343) (xy 175.858905 -36.573018) (xy 175.896122 -36.614555) (xy 175.926895 -36.661068)
			(xy 175.950567 -36.711565) (xy 175.966635 -36.764972) (xy 175.974755 -36.820148) (xy 175.975264 -36.848034)
			(xy 175.974755 -36.87592) (xy 175.966635 -36.931096) (xy 175.950567 -36.984503) (xy 175.926895 -37.035)
			(xy 175.896122 -37.081513) (xy 175.858905 -37.12305) (xy 175.816037 -37.158725) (xy 175.768431 -37.187779)
			(xy 175.717102 -37.209591) (xy 175.663145 -37.223697) (xy 175.607708 -37.229797) (xy 175.551974 -37.22776)
			(xy 175.497131 -37.21763) (xy 175.444347 -37.199623) (xy 175.394747 -37.174122) (xy 175.349389 -37.141671)
			(xy 175.30924 -37.102962) (xy 175.275154 -37.058819) (xy 175.247858 -37.010184) (xy 175.227935 -36.958093)
			(xy 175.215809 -36.903656) (xy 175.211738 -36.848034) (xy 173.86808 -36.848034) (xy 173.86808 -37.991034)
			(xy 175.203102 -37.991034) (xy 175.207173 -37.935412) (xy 175.219299 -37.880975) (xy 175.239222 -37.828884)
			(xy 175.266518 -37.780249) (xy 175.300604 -37.736106) (xy 175.340753 -37.697397) (xy 175.386111 -37.664946)
			(xy 175.435711 -37.639445) (xy 175.488495 -37.621438) (xy 175.543338 -37.611308) (xy 175.599072 -37.609271)
			(xy 175.654509 -37.615371) (xy 175.708466 -37.629477) (xy 175.759795 -37.651289) (xy 175.807401 -37.680343)
			(xy 175.850269 -37.716018) (xy 175.887486 -37.757555) (xy 175.918259 -37.804068) (xy 175.941931 -37.854565)
			(xy 175.957999 -37.907972) (xy 175.966119 -37.963148) (xy 175.966628 -37.991034) (xy 175.966119 -38.01892)
			(xy 175.957999 -38.074096) (xy 175.941931 -38.127503) (xy 175.918259 -38.178) (xy 175.887486 -38.224513)
			(xy 175.850269 -38.26605) (xy 175.807401 -38.301725) (xy 175.759795 -38.330779) (xy 175.708466 -38.352591)
			(xy 175.654509 -38.366697) (xy 175.599072 -38.372797) (xy 175.543338 -38.37076) (xy 175.488495 -38.36063)
			(xy 175.435711 -38.342623) (xy 175.386111 -38.317122) (xy 175.340753 -38.284671) (xy 175.300604 -38.245962)
			(xy 175.266518 -38.201819) (xy 175.239222 -38.153184) (xy 175.219299 -38.101093) (xy 175.207173 -38.046656)
			(xy 175.203102 -37.991034) (xy 173.86808 -37.991034) (xy 173.86808 -40.1193) (xy 174.26686 -40.51808)
			(xy 191.78778 -40.51808)
		)
		(stroke
			(width 0)
			(type solid)
		)
		(fill yes)
		(layer "In7.Cu")
		(net "USBPWR_P0")
	)
	(gr_poly
		(pts
			(xy 102.570788 -157.839156) (xy 102.587054 -157.822164) (xy 102.613622 -157.783351) (xy 102.632595 -157.740312)
			(xy 102.643324 -157.694517) (xy 102.645444 -157.647529) (xy 102.638882 -157.600954) (xy 102.623863 -157.556382)
			(xy 102.600898 -157.515334) (xy 102.570772 -157.479213) (xy 102.534515 -157.449251) (xy 102.493364 -157.426472)
			(xy 102.47122 -157.418532) (xy 102.445358 -157.409429) (xy 102.396346 -157.384855) (xy 102.351359 -157.353517)
			(xy 102.311322 -157.31606) (xy 102.27706 -157.273257) (xy 102.24928 -157.225989) (xy 102.228554 -157.17523)
			(xy 102.215309 -157.122027) (xy 102.209818 -157.067476) (xy 102.212195 -157.012701) (xy 102.222389 -156.95883)
			(xy 102.240192 -156.906974) (xy 102.265236 -156.858201) (xy 102.297006 -156.813517) (xy 102.334845 -156.773841)
			(xy 102.377976 -156.739993) (xy 102.425509 -156.712668) (xy 102.476464 -156.692431) (xy 102.529792 -156.679698)
			(xy 102.584393 -156.674732) (xy 102.639143 -156.677634) (xy 102.692914 -156.688346) (xy 102.744596 -156.706646)
			(xy 102.793126 -156.732158) (xy 102.837503 -156.764355) (xy 102.876813 -156.802574) (xy 102.910246 -156.846028)
			(xy 102.937112 -156.893822) (xy 102.956859 -156.944969) (xy 102.969079 -156.998417) (xy 102.97352 -157.053063)
			(xy 102.972362 -157.080458) (xy 102.971435 -157.103503) (xy 102.976927 -157.149291) (xy 102.990591 -157.193337)
			(xy 103.011976 -157.234195) (xy 103.040382 -157.270525) (xy 103.074876 -157.301134) (xy 103.114326 -157.325017)
			(xy 103.157438 -157.341392) (xy 103.202796 -157.34972) (xy 103.225854 -157.350206) (xy 103.527352 -157.350206)
			(xy 103.550436 -157.349696) (xy 103.595843 -157.341348) (xy 103.638996 -157.324935) (xy 103.678474 -157.300998)
			(xy 103.712979 -157.270324) (xy 103.741376 -157.233921) (xy 103.762731 -157.192989) (xy 103.776341 -157.148872)
			(xy 103.781759 -157.103023) (xy 103.780844 -157.07995) (xy 103.779586 -157.052846) (xy 103.783825 -156.998753)
			(xy 103.795684 -156.945807) (xy 103.814925 -156.895074) (xy 103.841159 -156.84758) (xy 103.873857 -156.804281)
			(xy 103.91236 -156.766051) (xy 103.955891 -156.733662) (xy 104.003571 -156.707767) (xy 104.054439 -156.688888)
			(xy 104.107469 -156.677406) (xy 104.16159 -156.673552) (xy 104.215711 -156.677406) (xy 104.268741 -156.688888)
			(xy 104.319609 -156.707767) (xy 104.367289 -156.733662) (xy 104.41082 -156.766051) (xy 104.449323 -156.804281)
			(xy 104.482021 -156.84758) (xy 104.508255 -156.895074) (xy 104.527496 -156.945807) (xy 104.539355 -156.998753)
			(xy 104.543594 -157.052846) (xy 104.542336 -157.07995) (xy 104.541363 -157.103022) (xy 104.546782 -157.148877)
			(xy 104.560396 -157.192998) (xy 104.581757 -157.233933) (xy 104.610163 -157.270336) (xy 104.644677 -157.301008)
			(xy 104.684165 -157.324941) (xy 104.727326 -157.341345) (xy 104.772741 -157.349682) (xy 104.795828 -157.350206)
			(xy 105.793032 -157.350206) (xy 106.64952 -156.493718) (xy 106.64952 -152.436322) (xy 105.588308 -151.37511)
			(xy 102.59187 -151.37511) (xy 102.570357 -151.375557) (xy 102.527945 -151.3828) (xy 102.487362 -151.397091)
			(xy 102.44977 -151.418021) (xy 102.416245 -151.44499) (xy 102.387748 -151.477225) (xy 102.365094 -151.513804)
			(xy 102.348933 -151.553679) (xy 102.339727 -151.595709) (xy 102.337739 -151.638689) (xy 102.339902 -151.660098)
			(xy 102.342581 -151.685299) (xy 102.342043 -151.735975) (xy 102.334795 -151.786133) (xy 102.320964 -151.834888)
			(xy 102.300793 -151.88138) (xy 102.274639 -151.924789) (xy 102.25913 -151.944832) (xy 102.231444 -151.97963)
			(xy 102.231444 -152.06853) (xy 102.25913 -152.103328) (xy 102.275942 -152.125122) (xy 102.303786 -152.172603)
			(xy 102.324517 -152.223591) (xy 102.337705 -152.27703) (xy 102.343076 -152.33181) (xy 102.340519 -152.386792)
			(xy 102.330087 -152.440837) (xy 102.311995 -152.492821) (xy 102.286621 -152.541665) (xy 102.254491 -152.586356)
			(xy 102.216271 -152.625966) (xy 102.172756 -152.659671) (xy 102.124849 -152.686773) (xy 102.073543 -152.706708)
			(xy 102.019906 -152.719064) (xy 101.96505 -152.723582) (xy 101.910113 -152.72017) (xy 101.856238 -152.708898)
			(xy 101.804541 -152.690001) (xy 101.780086 -152.677368) (xy 101.76623 -152.670412) (xy 101.736197 -152.662742)
			(xy 101.705201 -152.662547) (xy 101.675074 -152.669836) (xy 101.647596 -152.68418) (xy 101.624391 -152.70473)
			(xy 101.61524 -152.717246) (xy 101.599299 -152.739612) (xy 101.562035 -152.779959) (xy 101.51937 -152.814544)
			(xy 101.472186 -152.842652) (xy 101.421458 -152.863703) (xy 101.368236 -152.877261) (xy 101.313619 -152.883046)
			(xy 101.258738 -152.880938) (xy 101.204725 -152.870981) (xy 101.1527 -152.853381) (xy 101.103736 -152.828501)
			(xy 101.058847 -152.796856) (xy 101.01896 -152.7591) (xy 100.984901 -152.716014) (xy 100.957373 -152.668489)
			(xy 100.936945 -152.617507) (xy 100.92404 -152.564122) (xy 100.918925 -152.509439) (xy 100.921706 -152.454587)
			(xy 100.932324 -152.400701) (xy 100.950561 -152.348895) (xy 100.976039 -152.30024) (xy 101.008232 -152.255742)
			(xy 101.046474 -152.216321) (xy 101.089974 -152.182793) (xy 101.137833 -152.155849) (xy 101.189062 -152.136048)
			(xy 101.242601 -152.123799) (xy 101.297343 -152.119354) (xy 101.352156 -152.122807) (xy 101.405908 -152.134085)
			(xy 101.457486 -152.152956) (xy 101.48189 -152.165558) (xy 101.495723 -152.172514) (xy 101.525707 -152.180204)
			(xy 101.55666 -152.180453) (xy 101.571806 -152.177242) (xy 101.619304 -152.165812) (xy 101.64699 -152.125426)
			(xy 101.663246 -152.103328) (xy 101.673497 -152.089579) (xy 101.686969 -152.058056) (xy 101.691567 -152.024084)
			(xy 101.68696 -151.990114) (xy 101.673481 -151.958594) (xy 101.663246 -151.944832) (xy 101.644722 -151.920709)
			(xy 101.614763 -151.867782) (xy 101.593571 -151.810776) (xy 101.581681 -151.751131) (xy 101.579393 -151.690357)
			(xy 101.582474 -151.660098) (xy 101.584642 -151.638697) (xy 101.58261 -151.595735) (xy 101.573372 -151.553727)
			(xy 101.557193 -151.513875) (xy 101.534534 -151.477317) (xy 101.506043 -151.445096) (xy 101.472534 -151.418132)
			(xy 101.434962 -151.397196) (xy 101.394402 -151.382885) (xy 101.352011 -151.375608) (xy 101.330506 -151.37511)
			(xy 99.540314 -151.37511) (xy 99.07524 -151.840184) (xy 99.07524 -153.429462) (xy 99.792788 -153.429462)
			(xy 99.796859 -153.37384) (xy 99.808985 -153.319403) (xy 99.828908 -153.267312) (xy 99.856204 -153.218677)
			(xy 99.89029 -153.174534) (xy 99.930439 -153.135825) (xy 99.975797 -153.103374) (xy 100.025397 -153.077873)
			(xy 100.078181 -153.059866) (xy 100.133024 -153.049736) (xy 100.188758 -153.047699) (xy 100.244195 -153.053799)
			(xy 100.298152 -153.067905) (xy 100.349481 -153.089717) (xy 100.397087 -153.118771) (xy 100.439955 -153.154446)
			(xy 100.477172 -153.195983) (xy 100.507945 -153.242496) (xy 100.531617 -153.292993) (xy 100.547685 -153.3464)
			(xy 100.555805 -153.401576) (xy 100.556314 -153.429462) (xy 100.555805 -153.457348) (xy 100.547685 -153.512524)
			(xy 100.531617 -153.565931) (xy 100.507945 -153.616428) (xy 100.477172 -153.662941) (xy 100.439955 -153.704478)
			(xy 100.397087 -153.740153) (xy 100.349481 -153.769207) (xy 100.298152 -153.791019) (xy 100.275274 -153.797)
			(xy 104.464864 -153.797) (xy 104.468935 -153.741378) (xy 104.481061 -153.686941) (xy 104.500984 -153.63485)
			(xy 104.52828 -153.586215) (xy 104.562366 -153.542072) (xy 104.602515 -153.503363) (xy 104.647873 -153.470912)
			(xy 104.697473 -153.445411) (xy 104.750257 -153.427404) (xy 104.8051 -153.417274) (xy 104.860834 -153.415237)
			(xy 104.916271 -153.421337) (xy 104.970228 -153.435443) (xy 105.021557 -153.457255) (xy 105.069163 -153.486309)
			(xy 105.112031 -153.521984) (xy 105.149248 -153.563521) (xy 105.180021 -153.610034) (xy 105.203693 -153.660531)
			(xy 105.219761 -153.713938) (xy 105.227881 -153.769114) (xy 105.22839 -153.797) (xy 105.227881 -153.824886)
			(xy 105.219761 -153.880062) (xy 105.203693 -153.933469) (xy 105.180021 -153.983966) (xy 105.149248 -154.030479)
			(xy 105.112031 -154.072016) (xy 105.069163 -154.107691) (xy 105.021557 -154.136745) (xy 104.970228 -154.158557)
			(xy 104.916271 -154.172663) (xy 104.860834 -154.178763) (xy 104.8051 -154.176726) (xy 104.750257 -154.166596)
			(xy 104.697473 -154.148589) (xy 104.647873 -154.123088) (xy 104.602515 -154.090637) (xy 104.562366 -154.051928)
			(xy 104.52828 -154.007785) (xy 104.500984 -153.95915) (xy 104.481061 -153.907059) (xy 104.468935 -153.852622)
			(xy 104.464864 -153.797) (xy 100.275274 -153.797) (xy 100.244195 -153.805125) (xy 100.188758 -153.811225)
			(xy 100.133024 -153.809188) (xy 100.078181 -153.799058) (xy 100.025397 -153.781051) (xy 99.975797 -153.75555)
			(xy 99.930439 -153.723099) (xy 99.89029 -153.68439) (xy 99.856204 -153.640247) (xy 99.828908 -153.591612)
			(xy 99.808985 -153.539521) (xy 99.796859 -153.485084) (xy 99.792788 -153.429462) (xy 99.07524 -153.429462)
			(xy 99.07524 -154.813254) (xy 99.075707 -154.835193) (xy 99.083252 -154.878418) (xy 99.098108 -154.919705)
			(xy 99.119833 -154.957827) (xy 99.147783 -154.991651) (xy 99.181127 -155.020173) (xy 99.218873 -155.042545)
			(xy 99.259901 -155.058102) (xy 99.302991 -155.066382) (xy 99.346863 -155.067138) (xy 99.36861 -155.064206)
			(xy 99.395798 -155.060441) (xy 99.450681 -155.059827) (xy 99.505086 -155.067085) (xy 99.557888 -155.082066)
			(xy 99.607999 -155.10446) (xy 99.654383 -155.133804) (xy 99.696082 -155.169493) (xy 99.732236 -155.21079)
			(xy 99.762098 -155.256842) (xy 99.785051 -155.306699) (xy 99.800622 -155.35933) (xy 99.808489 -155.41365)
			(xy 99.80849 -155.468537) (xy 99.800625 -155.522857) (xy 99.785056 -155.575489) (xy 99.762104 -155.625346)
			(xy 99.732243 -155.6714) (xy 99.696091 -155.712698) (xy 99.654393 -155.748388) (xy 99.60801 -155.777734)
			(xy 99.557901 -155.800129) (xy 99.505098 -155.815112) (xy 99.450694 -155.822372) (xy 99.395811 -155.82176)
			(xy 99.36861 -155.818078) (xy 99.34686 -155.815131) (xy 99.30298 -155.815871) (xy 99.259879 -155.824141)
			(xy 99.218839 -155.839692) (xy 99.181082 -155.862063) (xy 99.148762 -155.889706) (xy 104.546652 -155.889706)
			(xy 104.550723 -155.834084) (xy 104.562849 -155.779647) (xy 104.582772 -155.727556) (xy 104.610068 -155.678921)
			(xy 104.644154 -155.634778) (xy 104.684303 -155.596069) (xy 104.729661 -155.563618) (xy 104.779261 -155.538117)
			(xy 104.832045 -155.52011) (xy 104.886888 -155.50998) (xy 104.942622 -155.507943) (xy 104.998059 -155.514043)
			(xy 105.052016 -155.528149) (xy 105.103345 -155.549961) (xy 105.150951 -155.579015) (xy 105.193819 -155.61469)
			(xy 105.231036 -155.656227) (xy 105.261809 -155.70274) (xy 105.285481 -155.753237) (xy 105.301549 -155.806644)
			(xy 105.309669 -155.86182) (xy 105.310178 -155.889706) (xy 105.309669 -155.917592) (xy 105.301549 -155.972768)
			(xy 105.285481 -156.026175) (xy 105.261809 -156.076672) (xy 105.231036 -156.123185) (xy 105.193819 -156.164722)
			(xy 105.150951 -156.200397) (xy 105.103345 -156.229451) (xy 105.052016 -156.251263) (xy 104.998059 -156.265369)
			(xy 104.942622 -156.271469) (xy 104.886888 -156.269432) (xy 104.832045 -156.259302) (xy 104.779261 -156.241295)
			(xy 104.729661 -156.215794) (xy 104.684303 -156.183343) (xy 104.644154 -156.144634) (xy 104.610068 -156.100491)
			(xy 104.582772 -156.051856) (xy 104.562849 -155.999765) (xy 104.550723 -155.945328) (xy 104.546652 -155.889706)
			(xy 99.148762 -155.889706) (xy 99.14773 -155.890589) (xy 99.119775 -155.924421) (xy 99.098049 -155.962553)
			(xy 99.083198 -156.003851) (xy 99.075662 -156.047086) (xy 99.07524 -156.06903) (xy 99.07524 -157.175708)
			(xy 99.867974 -157.968442) (xy 102.441502 -157.968442)
		)
		(stroke
			(width 0)
			(type solid)
		)
		(fill yes)
		(layer "In7.Cu")
		(net "GND")
	)
	(gr_poly
		(pts
			(xy 158.281624 -159.369506) (xy 158.304198 -159.356199) (xy 158.352215 -159.33522) (xy 158.402652 -159.321011)
			(xy 158.45456 -159.313839) (xy 158.50696 -159.313839) (xy 158.558868 -159.321011) (xy 158.609305 -159.33522)
			(xy 158.657322 -159.356199) (xy 158.679896 -159.369506) (xy 158.710376 -159.388048) (xy 159.687006 -159.388048)
			(xy 159.722312 -159.359092) (xy 159.746912 -159.339713) (xy 159.801165 -159.308441) (xy 159.830262 -159.296862)
			(xy 159.851509 -159.28837) (xy 159.890776 -159.264888) (xy 159.925207 -159.234757) (xy 159.953689 -159.198951)
			(xy 159.975302 -159.158625) (xy 159.98935 -159.115082) (xy 159.995377 -159.069728) (xy 159.99319 -159.024028)
			(xy 159.982859 -158.979457) (xy 159.964717 -158.937454) (xy 159.952436 -158.918148) (xy 159.937397 -158.894655)
			(xy 159.913562 -158.844226) (xy 159.897322 -158.790864) (xy 159.889025 -158.735706) (xy 159.888847 -158.679927)
			(xy 159.896792 -158.624717) (xy 159.91269 -158.571252) (xy 159.936204 -158.520672) (xy 159.966831 -158.474054)
			(xy 160.003919 -158.432392) (xy 160.046677 -158.396574) (xy 160.094195 -158.367363) (xy 160.14546 -158.345381)
			(xy 160.199379 -158.331098) (xy 160.254803 -158.324817) (xy 160.310551 -158.326672) (xy 160.365434 -158.336625)
			(xy 160.418284 -158.354462) (xy 160.467974 -158.379804) (xy 160.513444 -158.41211) (xy 160.553726 -158.450692)
			(xy 160.587962 -158.494728) (xy 160.615421 -158.54328) (xy 160.635519 -158.595312) (xy 160.647827 -158.649716)
			(xy 160.651108 -158.692596) (xy 164.388036 -158.692596) (xy 164.392107 -158.636974) (xy 164.404233 -158.582537)
			(xy 164.424156 -158.530446) (xy 164.451452 -158.481811) (xy 164.485538 -158.437668) (xy 164.525687 -158.398959)
			(xy 164.571045 -158.366508) (xy 164.620645 -158.341007) (xy 164.673429 -158.323) (xy 164.728272 -158.31287)
			(xy 164.784006 -158.310833) (xy 164.839443 -158.316933) (xy 164.8934 -158.331039) (xy 164.944729 -158.352851)
			(xy 164.992335 -158.381905) (xy 165.035203 -158.41758) (xy 165.07242 -158.459117) (xy 165.103193 -158.50563)
			(xy 165.126865 -158.556127) (xy 165.142933 -158.609534) (xy 165.151053 -158.66471) (xy 165.151562 -158.692596)
			(xy 165.151053 -158.720482) (xy 165.142933 -158.775658) (xy 165.126865 -158.829065) (xy 165.103193 -158.879562)
			(xy 165.07242 -158.926075) (xy 165.035203 -158.967612) (xy 164.992335 -159.003287) (xy 164.944729 -159.032341)
			(xy 164.8934 -159.054153) (xy 164.839443 -159.068259) (xy 164.784006 -159.074359) (xy 164.728272 -159.072322)
			(xy 164.673429 -159.062192) (xy 164.620645 -159.044185) (xy 164.571045 -159.018684) (xy 164.525687 -158.986233)
			(xy 164.485538 -158.947524) (xy 164.451452 -158.903381) (xy 164.424156 -158.854746) (xy 164.404233 -158.802655)
			(xy 164.392107 -158.748218) (xy 164.388036 -158.692596) (xy 160.651108 -158.692596) (xy 160.652083 -158.705332)
			(xy 160.648197 -158.760975) (xy 160.63625 -158.815459) (xy 160.616498 -158.867623) (xy 160.589361 -158.916356)
			(xy 160.555419 -158.960618) (xy 160.515394 -158.999467) (xy 160.470139 -159.032075) (xy 160.420619 -159.057746)
			(xy 160.367888 -159.075933) (xy 160.313072 -159.08625) (xy 160.257338 -159.088476) (xy 160.22955 -159.086042)
			(xy 160.213836 -159.08488) (xy 160.182662 -159.089401) (xy 160.15355 -159.10143) (xy 160.128277 -159.120231)
			(xy 160.108387 -159.144657) (xy 160.095096 -159.173215) (xy 160.089215 -159.204161) (xy 160.091103 -159.235604)
			(xy 160.100646 -159.265624) (xy 160.11726 -159.292386) (xy 160.139931 -159.314255) (xy 160.15335 -159.322516)
			(xy 160.167278 -159.330669) (xy 160.193857 -159.34898) (xy 160.206436 -159.359092) (xy 160.241742 -159.388048)
			(xy 161.313114 -159.388048) (xy 161.386774 -159.317436) (xy 161.388806 -159.266382) (xy 161.390456 -159.238622)
			(xy 161.400791 -159.183982) (xy 161.418949 -159.131421) (xy 161.444543 -159.082052) (xy 161.477033 -159.036921)
			(xy 161.515729 -158.996984) (xy 161.559813 -158.963087) (xy 161.608349 -158.935948) (xy 161.660312 -158.916141)
			(xy 161.714598 -158.904087) (xy 161.77006 -158.90004) (xy 161.825522 -158.904087) (xy 161.879808 -158.916141)
			(xy 161.931771 -158.935948) (xy 161.980307 -158.963087) (xy 162.024391 -158.996984) (xy 162.063087 -159.036921)
			(xy 162.095577 -159.082052) (xy 162.121171 -159.131421) (xy 162.139329 -159.183982) (xy 162.149664 -159.238622)
			(xy 162.151314 -159.266382) (xy 162.152494 -159.282533) (xy 162.161982 -159.313486) (xy 162.178951 -159.341056)
			(xy 162.20231 -159.363471) (xy 162.230557 -159.379288) (xy 162.261874 -159.387492) (xy 162.27806 -159.388048)
			(xy 163.232846 -159.388048) (xy 163.248197 -159.38763) (xy 163.27801 -159.380295) (xy 163.305201 -159.366039)
			(xy 163.32819 -159.345689) (xy 163.34564 -159.320429) (xy 163.356539 -159.291727) (xy 163.35883 -159.276542)
			(xy 163.362702 -159.24917) (xy 163.377318 -159.195858) (xy 163.399474 -159.145212) (xy 163.428706 -159.098294)
			(xy 163.464403 -159.056085) (xy 163.505816 -159.019468) (xy 163.55208 -158.98921) (xy 163.602225 -158.965945)
			(xy 163.655203 -158.950158) (xy 163.709904 -158.942182) (xy 163.765184 -158.942182) (xy 163.819885 -158.950158)
			(xy 163.872863 -158.965945) (xy 163.923008 -158.98921) (xy 163.969272 -159.019468) (xy 164.010685 -159.056085)
			(xy 164.046382 -159.098294) (xy 164.075614 -159.145212) (xy 164.09777 -159.195858) (xy 164.112386 -159.24917)
			(xy 164.116258 -159.276542) (xy 164.118591 -159.291715) (xy 164.129509 -159.320395) (xy 164.146961 -159.345638)
			(xy 164.169937 -159.365982) (xy 164.197107 -159.380251) (xy 164.226898 -159.387617) (xy 164.242242 -159.388048)
			(xy 165.48735 -159.388048) (xy 166.93388 -157.941518) (xy 166.93388 -156.976572) (xy 166.933457 -156.954827)
			(xy 166.926095 -156.911964) (xy 166.911538 -156.870983) (xy 166.890213 -156.83308) (xy 166.862743 -156.799363)
			(xy 166.829931 -156.770819) (xy 166.792736 -156.748282) (xy 166.752246 -156.73241) (xy 166.709644 -156.723668)
			(xy 166.666175 -156.722311) (xy 166.644574 -156.724858) (xy 166.617671 -156.728143) (xy 166.563474 -156.727983)
			(xy 166.509845 -156.720154) (xy 166.457863 -156.704816) (xy 166.408575 -156.682276) (xy 166.362973 -156.652988)
			(xy 166.321974 -156.617541) (xy 166.286404 -156.576649) (xy 166.256978 -156.531136) (xy 166.234289 -156.481916)
			(xy 166.218794 -156.429981) (xy 166.210804 -156.376375) (xy 166.21048 -156.322179) (xy 166.217829 -156.268482)
			(xy 166.232703 -156.216365) (xy 166.254801 -156.166878) (xy 166.283681 -156.121016) (xy 166.31876 -156.079702)
			(xy 166.338758 -156.06141) (xy 166.350754 -156.050154) (xy 166.36904 -156.022825) (xy 166.379715 -155.991724)
			(xy 166.382066 -155.958925) (xy 166.375937 -155.926619) (xy 166.361735 -155.896961) (xy 166.351458 -155.884118)
			(xy 166.333771 -155.86258) (xy 166.304182 -155.815355) (xy 166.281779 -155.764326) (xy 166.26704 -155.710581)
			(xy 166.260278 -155.655263) (xy 166.261638 -155.59955) (xy 166.27109 -155.544628) (xy 166.288433 -155.491666)
			(xy 166.313298 -155.441791) (xy 166.345155 -155.396065) (xy 166.383328 -155.355461) (xy 166.427002 -155.320844)
			(xy 166.475248 -155.29295) (xy 166.52704 -155.272374) (xy 166.581275 -155.259553) (xy 166.636798 -155.25476)
			(xy 166.66464 -155.255976) (xy 166.687653 -155.256852) (xy 166.733362 -155.251274) (xy 166.777318 -155.237554)
			(xy 166.818084 -155.21614) (xy 166.854326 -155.187732) (xy 166.884857 -155.153261) (xy 166.908678 -155.113854)
			(xy 166.925012 -155.0708) (xy 166.933322 -155.025508) (xy 166.93388 -155.002484) (xy 166.93388 -153.468324)
			(xy 166.933382 -153.445632) (xy 166.925325 -153.40097) (xy 166.909464 -153.358449) (xy 166.886303 -153.319421)
			(xy 166.856577 -153.285128) (xy 166.821234 -153.256659) (xy 166.781395 -153.234921) (xy 166.73833 -153.220605)
			(xy 166.693406 -153.214165) (xy 166.648052 -153.215807) (xy 166.625778 -153.220166) (xy 166.599046 -153.225475)
			(xy 166.544685 -153.229345) (xy 166.490326 -153.225442) (xy 166.437075 -153.213843) (xy 166.386017 -153.194786)
			(xy 166.338189 -153.168658) (xy 166.294566 -153.13599) (xy 166.256035 -153.097448) (xy 166.223381 -153.053815)
			(xy 166.197267 -153.00598) (xy 166.178224 -152.954916) (xy 166.166642 -152.901662) (xy 166.162755 -152.847301)
			(xy 166.166642 -152.792941) (xy 166.178224 -152.739687) (xy 166.197265 -152.688623) (xy 166.223379 -152.640787)
			(xy 166.256034 -152.597154) (xy 166.294564 -152.558612) (xy 166.338187 -152.525944) (xy 166.386014 -152.499815)
			(xy 166.437073 -152.480757) (xy 166.490323 -152.469158) (xy 166.544682 -152.465255) (xy 166.599044 -152.469125)
			(xy 166.625778 -152.474422) (xy 166.648056 -152.478768) (xy 166.693412 -152.480408) (xy 166.738339 -152.473969)
			(xy 166.781408 -152.459654) (xy 166.82125 -152.437918) (xy 166.8566 -152.409453) (xy 166.886333 -152.375163)
			(xy 166.909504 -152.336138) (xy 166.925378 -152.293619) (xy 166.933448 -152.248957) (xy 166.93388 -152.226264)
			(xy 166.93388 -150.951438) (xy 166.933426 -150.92965) (xy 166.925983 -150.886714) (xy 166.911327 -150.845676)
			(xy 166.889886 -150.807739) (xy 166.86229 -150.774014) (xy 166.829345 -150.745491) (xy 166.792019 -150.723004)
			(xy 166.751404 -150.707212) (xy 166.708691 -150.698579) (xy 166.665132 -150.697357) (xy 166.622002 -150.703583)
			(xy 166.60114 -150.709884) (xy 166.574671 -150.717986) (xy 166.520113 -150.727343) (xy 166.464776 -150.728715)
			(xy 166.409822 -150.722075) (xy 166.356405 -150.707561) (xy 166.305646 -150.685478) (xy 166.258613 -150.65629)
			(xy 166.216293 -150.62061) (xy 166.179574 -150.579188) (xy 166.149228 -150.532894) (xy 166.125892 -150.482699)
			(xy 166.110057 -150.429658) (xy 166.102054 -150.374886) (xy 166.102053 -150.319532) (xy 166.110053 -150.264759)
			(xy 166.125886 -150.211717) (xy 166.149219 -150.161522) (xy 166.179563 -150.115226) (xy 166.21628 -150.073802)
			(xy 166.258599 -150.03812) (xy 166.305631 -150.00893) (xy 166.356388 -149.986845) (xy 166.409805 -149.972329)
			(xy 166.464759 -149.965685) (xy 166.520096 -149.967055) (xy 166.574654 -149.976409) (xy 166.60114 -149.98446)
			(xy 166.621998 -149.99079) (xy 166.665135 -149.997037) (xy 166.708705 -149.99583) (xy 166.75143 -149.987205)
			(xy 166.792056 -149.971416) (xy 166.829392 -149.948925) (xy 166.862341 -149.920392) (xy 166.889938 -149.886655)
			(xy 166.911373 -149.848703) (xy 166.926016 -149.807649) (xy 166.933439 -149.764699) (xy 166.93388 -149.742906)
			(xy 166.93388 -146.756374) (xy 165.4937 -145.316194) (xy 162.165284 -145.316194) (xy 162.151128 -145.316552)
			(xy 162.123506 -145.322756) (xy 162.097942 -145.334921) (xy 162.075705 -145.352442) (xy 162.066478 -145.363184)
			(xy 162.048264 -145.384858) (xy 162.006526 -145.423105) (xy 161.959592 -145.454762) (xy 161.908495 -145.479135)
			(xy 161.854356 -145.495687) (xy 161.798366 -145.504055) (xy 161.741754 -145.504055) (xy 161.685764 -145.495687)
			(xy 161.631625 -145.479135) (xy 161.580528 -145.454762) (xy 161.533594 -145.423105) (xy 161.491856 -145.384858)
			(xy 161.473642 -145.363184) (xy 161.455354 -145.340832) (xy 161.403792 -145.316194) (xy 159.352488 -145.316194)
			(xy 159.330123 -145.316666) (xy 159.286084 -145.324499) (xy 159.244097 -145.33992) (xy 159.205457 -145.362453)
			(xy 159.17136 -145.391403) (xy 159.142856 -145.425875) (xy 159.120828 -145.464805) (xy 159.105955 -145.506989)
			(xy 159.098696 -145.551126) (xy 159.098488 -145.573496) (xy 159.098322 -145.601934) (xy 159.090592 -145.658273)
			(xy 159.074586 -145.712842) (xy 159.050661 -145.764431) (xy 159.019345 -145.811899) (xy 158.981331 -145.854193)
			(xy 158.937462 -145.890379) (xy 158.888709 -145.919654) (xy 158.836152 -145.94137) (xy 158.780954 -145.955047)
			(xy 158.724337 -145.960381) (xy 158.667556 -145.957254) (xy 158.611868 -145.945736) (xy 158.558505 -145.926082)
			(xy 158.533338 -145.91284) (xy 158.496254 -145.892266) (xy 158.412688 -145.904204) (xy 158.288736 -146.028156)
			(xy 158.278326 -146.039138) (xy 158.262533 -146.064941) (xy 158.253278 -146.093742) (xy 158.251082 -146.123914)
			(xy 158.253176 -146.1389) (xy 158.376861 -146.877278) (xy 158.897318 -146.877278) (xy 158.901389 -146.821656)
			(xy 158.913515 -146.767219) (xy 158.933438 -146.715128) (xy 158.960734 -146.666493) (xy 158.99482 -146.62235)
			(xy 159.034969 -146.583641) (xy 159.080327 -146.55119) (xy 159.129927 -146.525689) (xy 159.182711 -146.507682)
			(xy 159.237554 -146.497552) (xy 159.293288 -146.495515) (xy 159.348725 -146.501615) (xy 159.402682 -146.515721)
			(xy 159.43523 -146.529552) (xy 162.094924 -146.529552) (xy 162.098995 -146.47393) (xy 162.111121 -146.419493)
			(xy 162.131044 -146.367402) (xy 162.15834 -146.318767) (xy 162.192426 -146.274624) (xy 162.232575 -146.235915)
			(xy 162.277933 -146.203464) (xy 162.327533 -146.177963) (xy 162.380317 -146.159956) (xy 162.43516 -146.149826)
			(xy 162.490894 -146.147789) (xy 162.546331 -146.153889) (xy 162.600288 -146.167995) (xy 162.651617 -146.189807)
			(xy 162.699223 -146.218861) (xy 162.742091 -146.254536) (xy 162.779308 -146.296073) (xy 162.810081 -146.342586)
			(xy 162.820927 -146.365722) (xy 163.922962 -146.365722) (xy 163.927033 -146.3101) (xy 163.939159 -146.255663)
			(xy 163.959082 -146.203572) (xy 163.986378 -146.154937) (xy 164.020464 -146.110794) (xy 164.060613 -146.072085)
			(xy 164.105971 -146.039634) (xy 164.155571 -146.014133) (xy 164.208355 -145.996126) (xy 164.263198 -145.985996)
			(xy 164.318932 -145.983959) (xy 164.374369 -145.990059) (xy 164.428326 -146.004165) (xy 164.479655 -146.025977)
			(xy 164.527261 -146.055031) (xy 164.570129 -146.090706) (xy 164.607346 -146.132243) (xy 164.638119 -146.178756)
			(xy 164.661791 -146.229253) (xy 164.677859 -146.28266) (xy 164.685979 -146.337836) (xy 164.686488 -146.365722)
			(xy 164.685979 -146.393608) (xy 164.677859 -146.448784) (xy 164.661791 -146.502191) (xy 164.638119 -146.552688)
			(xy 164.607346 -146.599201) (xy 164.570129 -146.640738) (xy 164.527261 -146.676413) (xy 164.479655 -146.705467)
			(xy 164.428326 -146.727279) (xy 164.374369 -146.741385) (xy 164.318932 -146.747485) (xy 164.263198 -146.745448)
			(xy 164.208355 -146.735318) (xy 164.155571 -146.717311) (xy 164.105971 -146.69181) (xy 164.060613 -146.659359)
			(xy 164.020464 -146.62065) (xy 163.986378 -146.576507) (xy 163.959082 -146.527872) (xy 163.939159 -146.475781)
			(xy 163.927033 -146.421344) (xy 163.922962 -146.365722) (xy 162.820927 -146.365722) (xy 162.833753 -146.393083)
			(xy 162.849821 -146.44649) (xy 162.857941 -146.501666) (xy 162.85845 -146.529552) (xy 162.857941 -146.557438)
			(xy 162.849821 -146.612614) (xy 162.833753 -146.666021) (xy 162.810081 -146.716518) (xy 162.779308 -146.763031)
			(xy 162.742091 -146.804568) (xy 162.699223 -146.840243) (xy 162.651617 -146.869297) (xy 162.600288 -146.891109)
			(xy 162.546331 -146.905215) (xy 162.490894 -146.911315) (xy 162.43516 -146.909278) (xy 162.380317 -146.899148)
			(xy 162.327533 -146.881141) (xy 162.277933 -146.85564) (xy 162.232575 -146.823189) (xy 162.192426 -146.78448)
			(xy 162.15834 -146.740337) (xy 162.131044 -146.691702) (xy 162.111121 -146.639611) (xy 162.098995 -146.585174)
			(xy 162.094924 -146.529552) (xy 159.43523 -146.529552) (xy 159.454011 -146.537533) (xy 159.501617 -146.566587)
			(xy 159.544485 -146.602262) (xy 159.581702 -146.643799) (xy 159.612475 -146.690312) (xy 159.636147 -146.740809)
			(xy 159.652215 -146.794216) (xy 159.660335 -146.849392) (xy 159.660844 -146.877278) (xy 159.660335 -146.905164)
			(xy 159.652215 -146.96034) (xy 159.636147 -147.013747) (xy 159.618439 -147.051522) (xy 165.08298 -147.051522)
			(xy 165.087051 -146.9959) (xy 165.099177 -146.941463) (xy 165.1191 -146.889372) (xy 165.146396 -146.840737)
			(xy 165.180482 -146.796594) (xy 165.220631 -146.757885) (xy 165.265989 -146.725434) (xy 165.315589 -146.699933)
			(xy 165.368373 -146.681926) (xy 165.423216 -146.671796) (xy 165.47895 -146.669759) (xy 165.534387 -146.675859)
			(xy 165.588344 -146.689965) (xy 165.639673 -146.711777) (xy 165.687279 -146.740831) (xy 165.730147 -146.776506)
			(xy 165.767364 -146.818043) (xy 165.798137 -146.864556) (xy 165.821809 -146.915053) (xy 165.837877 -146.96846)
			(xy 165.845997 -147.023636) (xy 165.846506 -147.051522) (xy 165.845997 -147.079408) (xy 165.837877 -147.134584)
			(xy 165.821809 -147.187991) (xy 165.798137 -147.238488) (xy 165.767364 -147.285001) (xy 165.730147 -147.326538)
			(xy 165.687279 -147.362213) (xy 165.639673 -147.391267) (xy 165.588344 -147.413079) (xy 165.534387 -147.427185)
			(xy 165.47895 -147.433285) (xy 165.423216 -147.431248) (xy 165.368373 -147.421118) (xy 165.315589 -147.403111)
			(xy 165.265989 -147.37761) (xy 165.220631 -147.345159) (xy 165.180482 -147.30645) (xy 165.146396 -147.262307)
			(xy 165.1191 -147.213672) (xy 165.099177 -147.161581) (xy 165.087051 -147.107144) (xy 165.08298 -147.051522)
			(xy 159.618439 -147.051522) (xy 159.612475 -147.064244) (xy 159.581702 -147.110757) (xy 159.544485 -147.152294)
			(xy 159.501617 -147.187969) (xy 159.454011 -147.217023) (xy 159.402682 -147.238835) (xy 159.348725 -147.252941)
			(xy 159.293288 -147.259041) (xy 159.237554 -147.257004) (xy 159.182711 -147.246874) (xy 159.129927 -147.228867)
			(xy 159.080327 -147.203366) (xy 159.034969 -147.170915) (xy 158.99482 -147.132206) (xy 158.960734 -147.088063)
			(xy 158.933438 -147.039428) (xy 158.913515 -146.987337) (xy 158.901389 -146.9329) (xy 158.897318 -146.877278)
			(xy 158.376861 -146.877278) (xy 158.421578 -147.144232) (xy 158.391029 -147.508722) (xy 162.652962 -147.508722)
			(xy 162.657033 -147.4531) (xy 162.669159 -147.398663) (xy 162.689082 -147.346572) (xy 162.716378 -147.297937)
			(xy 162.750464 -147.253794) (xy 162.790613 -147.215085) (xy 162.835971 -147.182634) (xy 162.885571 -147.157133)
			(xy 162.938355 -147.139126) (xy 162.993198 -147.128996) (xy 163.048932 -147.126959) (xy 163.104369 -147.133059)
			(xy 163.158326 -147.147165) (xy 163.209655 -147.168977) (xy 163.257261 -147.198031) (xy 163.300129 -147.233706)
			(xy 163.337346 -147.275243) (xy 163.368119 -147.321756) (xy 163.391791 -147.372253) (xy 163.407859 -147.42566)
			(xy 163.415979 -147.480836) (xy 163.416488 -147.508722) (xy 163.416312 -147.518374) (xy 163.88791 -147.518374)
			(xy 163.891981 -147.462752) (xy 163.904107 -147.408315) (xy 163.92403 -147.356224) (xy 163.951326 -147.307589)
			(xy 163.985412 -147.263446) (xy 164.025561 -147.224737) (xy 164.070919 -147.192286) (xy 164.120519 -147.166785)
			(xy 164.173303 -147.148778) (xy 164.228146 -147.138648) (xy 164.28388 -147.136611) (xy 164.339317 -147.142711)
			(xy 164.393274 -147.156817) (xy 164.444603 -147.178629) (xy 164.492209 -147.207683) (xy 164.535077 -147.243358)
			(xy 164.572294 -147.284895) (xy 164.603067 -147.331408) (xy 164.626739 -147.381905) (xy 164.642807 -147.435312)
			(xy 164.650927 -147.490488) (xy 164.651436 -147.518374) (xy 164.650927 -147.54626) (xy 164.642807 -147.601436)
			(xy 164.626739 -147.654843) (xy 164.603067 -147.70534) (xy 164.572294 -147.751853) (xy 164.535077 -147.79339)
			(xy 164.492209 -147.829065) (xy 164.444603 -147.858119) (xy 164.393274 -147.879931) (xy 164.339317 -147.894037)
			(xy 164.28388 -147.900137) (xy 164.228146 -147.8981) (xy 164.173303 -147.88797) (xy 164.120519 -147.869963)
			(xy 164.070919 -147.844462) (xy 164.025561 -147.812011) (xy 163.985412 -147.773302) (xy 163.951326 -147.729159)
			(xy 163.92403 -147.680524) (xy 163.904107 -147.628433) (xy 163.891981 -147.573996) (xy 163.88791 -147.518374)
			(xy 163.416312 -147.518374) (xy 163.415979 -147.536608) (xy 163.407859 -147.591784) (xy 163.391791 -147.645191)
			(xy 163.368119 -147.695688) (xy 163.337346 -147.742201) (xy 163.300129 -147.783738) (xy 163.257261 -147.819413)
			(xy 163.209655 -147.848467) (xy 163.158326 -147.870279) (xy 163.104369 -147.884385) (xy 163.048932 -147.890485)
			(xy 162.993198 -147.888448) (xy 162.938355 -147.878318) (xy 162.885571 -147.860311) (xy 162.835971 -147.83481)
			(xy 162.790613 -147.802359) (xy 162.750464 -147.76365) (xy 162.716378 -147.719507) (xy 162.689082 -147.670872)
			(xy 162.669159 -147.618781) (xy 162.657033 -147.564344) (xy 162.652962 -147.508722) (xy 158.391029 -147.508722)
			(xy 158.310326 -148.471636) (xy 156.722318 -152.938988) (xy 156.56306 -153.1112) (xy 156.56306 -155.344114)
			(xy 156.069792 -155.837382) (xy 157.99816 -155.837382) (xy 157.99816 -150.359872) (xy 158.199836 -150.158196)
			(xy 163.698174 -150.158196) (xy 163.931092 -150.391368) (xy 163.931092 -155.795472) (xy 163.68776 -156.038804)
			(xy 158.199836 -156.038804) (xy 157.99816 -155.837382) (xy 156.069792 -155.837382) (xy 155.926028 -155.981146)
			(xy 155.921964 -156.026866) (xy 155.918858 -156.055221) (xy 155.905302 -156.110626) (xy 155.883646 -156.163394)
			(xy 155.854374 -156.21235) (xy 155.818138 -156.2564) (xy 155.775746 -156.294563) (xy 155.728144 -156.325987)
			(xy 155.676393 -156.349973) (xy 155.621647 -156.365984) (xy 155.565127 -156.373665) (xy 155.508094 -156.372843)
			(xy 155.451819 -156.363537) (xy 155.397557 -156.345954) (xy 155.3718 -156.333698) (xy 155.34513 -156.32049)
			(xy 155.129992 -156.32049) (xy 154.7114 -156.739082) (xy 154.7114 -158.18866) (xy 154.80538 -158.28264)
			(xy 156.885894 -158.28264) (xy 157.21076 -158.607506) (xy 157.21076 -159.151828) (xy 157.44698 -159.388048)
			(xy 158.251144 -159.388048)
		)
		(stroke
			(width 0)
			(type solid)
		)
		(fill yes)
		(layer "In7.Cu")
		(net "P1V05_LAN2")
	)
	(gr_poly
		(pts
			(xy 21.482812 -73.998328) (xy 24.545036 -73.998328) (xy 24.561656 -73.997795) (xy 24.593767 -73.989211)
			(xy 24.622564 -73.972612) (xy 24.634698 -73.961244) (xy 27.25547 -71.340218) (xy 29.77134 -62.841632)
			(xy 29.77134 -58.642504) (xy 28.2067 -57.077864) (xy 28.2067 -49.636934) (xy 28.206166 -49.613493)
			(xy 28.197574 -49.567406) (xy 28.180676 -49.523676) (xy 28.156045 -49.483787) (xy 28.124516 -49.449092)
			(xy 28.087159 -49.420767) (xy 28.045241 -49.399774) (xy 28.000183 -49.386824) (xy 27.953515 -49.382357)
			(xy 27.90682 -49.386525) (xy 27.861681 -49.399186) (xy 27.840432 -49.409096) (xy 27.815408 -49.421676)
			(xy 27.762546 -49.440179) (xy 27.707547 -49.450755) (xy 27.651592 -49.453175) (xy 27.595885 -49.44739)
			(xy 27.541622 -49.433522) (xy 27.48997 -49.411869) (xy 27.442039 -49.382898) (xy 27.398858 -49.34723)
			(xy 27.361356 -49.305632) (xy 27.330338 -49.258999) (xy 27.306472 -49.208332) (xy 27.29027 -49.154719)
			(xy 27.28208 -49.099315) (xy 27.282078 -49.043308) (xy 27.290265 -48.987902) (xy 27.306464 -48.934289)
			(xy 27.330327 -48.883621) (xy 27.361342 -48.836985) (xy 27.398842 -48.795385) (xy 27.44202 -48.759715)
			(xy 27.48995 -48.730741) (xy 27.541601 -48.709086) (xy 27.595863 -48.695214) (xy 27.65157 -48.689425)
			(xy 27.707525 -48.691843) (xy 27.762525 -48.702415) (xy 27.815388 -48.720915) (xy 27.840432 -48.733456)
			(xy 27.861694 -48.743333) (xy 27.90683 -48.75599) (xy 27.953521 -48.760155) (xy 28.000185 -48.755689)
			(xy 28.045238 -48.742741) (xy 28.087153 -48.721752) (xy 28.124509 -48.693432) (xy 28.156038 -48.658743)
			(xy 28.180672 -48.618861) (xy 28.197575 -48.575138) (xy 28.206174 -48.529056) (xy 28.2067 -48.505618)
			(xy 28.2067 -47.401988) (xy 28.20543 -47.39259) (xy 28.201754 -47.364513) (xy 28.201754 -47.307891)
			(xy 28.20543 -47.279814) (xy 28.2067 -47.270416) (xy 28.2067 -41.313354) (xy 28.160218 -41.247314)
			(xy 28.122118 -41.233852) (xy 28.096279 -41.224148) (xy 28.047481 -41.19836) (xy 28.002908 -41.165808)
			(xy 27.963492 -41.127172) (xy 27.930055 -41.08326) (xy 27.903295 -41.034988) (xy 27.883771 -40.983363)
			(xy 27.87189 -40.929463) (xy 27.867901 -40.874414) (xy 27.871886 -40.819365) (xy 27.883763 -40.765464)
			(xy 27.903283 -40.713838) (xy 27.93004 -40.665563) (xy 27.963474 -40.621649) (xy 28.002887 -40.58301)
			(xy 28.047457 -40.550455) (xy 28.096253 -40.524663) (xy 28.122118 -40.515032) (xy 28.160472 -40.501316)
			(xy 28.2067 -40.43553) (xy 28.2067 -30.92323) (xy 32.42564 -26.70429) (xy 32.42564 -26.655268) (xy 32.60344 -26.477468)
			(xy 32.60344 -25.477724) (xy 32.507936 -25.356566) (xy 32.47263 -25.344374) (xy 32.446412 -25.33489)
			(xy 32.39683 -25.309396) (xy 32.351488 -25.276954) (xy 32.311352 -25.238256) (xy 32.277278 -25.194128)
			(xy 32.249992 -25.145509) (xy 32.230075 -25.093435) (xy 32.217952 -25.039017) (xy 32.213881 -24.983413)
			(xy 32.217948 -24.927809) (xy 32.230068 -24.87339) (xy 32.249981 -24.821315) (xy 32.277264 -24.772694)
			(xy 32.311335 -24.728563) (xy 32.351468 -24.689863) (xy 32.396808 -24.657418) (xy 32.446388 -24.63192)
			(xy 32.47263 -24.622506) (xy 32.507936 -24.610314) (xy 32.60344 -24.489156) (xy 32.60344 -23.64105)
			(xy 32.59836 -23.62327) (xy 32.591062 -23.596881) (xy 32.58323 -23.542694) (xy 32.583227 -23.487944)
			(xy 32.591054 -23.433756) (xy 32.59836 -23.40737) (xy 32.60344 -23.38959) (xy 32.60344 -22.281896)
			(xy 32.58566 -22.251924) (xy 32.571112 -22.226473) (xy 32.549151 -22.17212) (xy 32.535764 -22.115047)
			(xy 32.531267 -22.056598) (xy 32.535765 -21.998149) (xy 32.549152 -21.941077) (xy 32.571113 -21.886724)
			(xy 32.58566 -21.861272) (xy 32.60344 -21.8313) (xy 32.60344 -20.044156) (xy 32.42564 -19.866356)
			(xy 29.3878 -19.866356) (xy 29.37115 -19.866899) (xy 29.338983 -19.875516) (xy 29.310142 -19.892163)
			(xy 29.28659 -19.915706) (xy 29.269933 -19.944542) (xy 29.261305 -19.976706) (xy 29.2608 -19.993356)
			(xy 29.2608 -24.053331) (xy 31.152294 -24.053331) (xy 31.15432 -23.997593) (xy 31.164439 -23.942744)
			(xy 31.182436 -23.889953) (xy 31.207927 -23.840344) (xy 31.240369 -23.794975) (xy 31.279071 -23.754813)
			(xy 31.323208 -23.720714) (xy 31.371839 -23.693404) (xy 31.397702 -23.68296) (xy 31.419659 -23.674008)
			(xy 31.460015 -23.64912) (xy 31.495051 -23.617176) (xy 31.52355 -23.579284) (xy 31.544522 -23.536762)
			(xy 31.557238 -23.491086) (xy 31.561257 -23.443844) (xy 31.556438 -23.396677) (xy 31.54295 -23.351223)
			(xy 31.532576 -23.3299) (xy 31.520257 -23.304873) (xy 31.502242 -23.252083) (xy 31.492104 -23.197232)
			(xy 31.49006 -23.14149) (xy 31.496154 -23.086044) (xy 31.510256 -23.032077) (xy 31.532065 -22.980737)
			(xy 31.561116 -22.93312) (xy 31.596791 -22.89024) (xy 31.638328 -22.853011) (xy 31.684844 -22.822226)
			(xy 31.735345 -22.798542) (xy 31.788757 -22.782463) (xy 31.843941 -22.774331) (xy 31.899721 -22.774321)
			(xy 31.954908 -22.782433) (xy 32.008326 -22.798492) (xy 32.058836 -22.822158) (xy 32.105362 -22.852926)
			(xy 32.146913 -22.89014) (xy 32.182603 -22.933008) (xy 32.211672 -22.980614) (xy 32.233499 -23.031946)
			(xy 32.247621 -23.085909) (xy 32.253735 -23.141352) (xy 32.251711 -23.197095) (xy 32.241593 -23.25195)
			(xy 32.223597 -23.304746) (xy 32.198105 -23.35436) (xy 32.165662 -23.399734) (xy 32.126957 -23.439901)
			(xy 32.082818 -23.474004) (xy 32.034183 -23.501318) (xy 32.008318 -23.511764) (xy 31.986406 -23.520819)
			(xy 31.946055 -23.545693) (xy 31.911021 -23.577623) (xy 31.882521 -23.6155) (xy 31.861546 -23.658008)
			(xy 31.848823 -23.70367) (xy 31.844795 -23.750901) (xy 31.849602 -23.798058) (xy 31.863078 -23.843504)
			(xy 31.873444 -23.864824) (xy 31.885728 -23.889866) (xy 31.903737 -23.942653) (xy 31.91387 -23.9975)
			(xy 31.915909 -24.053237) (xy 31.909812 -24.108678) (xy 31.895707 -24.16264) (xy 31.873897 -24.213973)
			(xy 31.844845 -24.261584) (xy 31.80917 -24.304458) (xy 31.767634 -24.341681) (xy 31.721121 -24.37246)
			(xy 31.670622 -24.396139) (xy 31.617214 -24.412214) (xy 31.562034 -24.420341) (xy 31.50626 -24.420348)
			(xy 31.451078 -24.412234) (xy 31.397666 -24.396173) (xy 31.347161 -24.372506) (xy 31.300641 -24.341739)
			(xy 31.259095 -24.304526) (xy 31.22341 -24.261661) (xy 31.194346 -24.214057) (xy 31.172523 -24.162729)
			(xy 31.158406 -24.10877) (xy 31.152294 -24.053331) (xy 29.2608 -24.053331) (xy 29.2608 -26.062178)
			(xy 29.33192 -26.135838) (xy 29.383228 -26.137616) (xy 29.413864 -26.139333) (xy 29.474039 -26.151313)
			(xy 29.531529 -26.172747) (xy 29.558488 -26.1874) (xy 29.583218 -26.202097) (xy 29.628353 -26.237765)
			(xy 29.667619 -26.279807) (xy 29.700128 -26.327267) (xy 29.725141 -26.379071) (xy 29.742091 -26.434044)
			(xy 29.750595 -26.490939) (xy 29.750459 -26.548465) (xy 29.741686 -26.605319) (xy 29.724475 -26.660211)
			(xy 29.699217 -26.711896) (xy 29.666484 -26.759202) (xy 29.647134 -26.78049) (xy 29.627691 -26.800384)
			(xy 29.584065 -26.834892) (xy 29.535889 -26.862699) (xy 29.484186 -26.883216) (xy 29.430052 -26.896007)
			(xy 29.374635 -26.900802) (xy 29.319108 -26.897499) (xy 29.26465 -26.886167) (xy 29.212414 -26.867047)
			(xy 29.163509 -26.840545) (xy 29.118971 -26.807222) (xy 29.099002 -26.787856) (xy 29.082919 -26.772869)
			(xy 29.046599 -26.748109) (xy 29.006559 -26.729971) (xy 28.963994 -26.718996) (xy 28.920175 -26.715513)
			(xy 28.876411 -26.719624) (xy 28.834008 -26.731209) (xy 28.794232 -26.749919) (xy 28.75827 -26.775198)
			(xy 28.742386 -26.790396) (xy 25.318466 -30.214316) (xy 25.303594 -30.229819) (xy 25.278759 -30.264867)
			(xy 25.260174 -30.303594) (xy 25.248371 -30.344896) (xy 25.243684 -30.387595) (xy 25.246249 -30.430474)
			(xy 25.255992 -30.47231) (xy 25.272634 -30.51191) (xy 25.295702 -30.548146) (xy 25.30983 -30.564328)
			(xy 25.32797 -30.585102) (xy 25.358696 -30.630901) (xy 25.382509 -30.680645) (xy 25.398911 -30.7333)
			(xy 25.407561 -30.787768) (xy 25.408278 -30.842914) (xy 25.401049 -30.897589) (xy 25.386023 -30.950653)
			(xy 25.363513 -31.001) (xy 25.3492 -31.024576) (xy 25.334045 -31.047574) (xy 25.29817 -31.089365)
			(xy 25.25666 -31.125564) (xy 25.210378 -31.15542) (xy 25.160284 -31.178314) (xy 25.10742 -31.193768)
			(xy 25.080214 -31.198058) (xy 25.06527 -31.200614) (xy 25.037109 -31.211825) (xy 25.012392 -31.229368)
			(xy 24.992516 -31.252251) (xy 24.978605 -31.279181) (xy 24.971445 -31.308633) (xy 24.970994 -31.323788)
			(xy 24.970994 -42.666669) (xy 25.59125 -42.666669) (xy 25.594319 -42.611786) (xy 25.605233 -42.557911)
			(xy 25.623767 -42.50616) (xy 25.649537 -42.457605) (xy 25.682009 -42.413252) (xy 25.72051 -42.374018)
			(xy 25.764244 -42.340717) (xy 25.812304 -42.314037) (xy 25.863697 -42.294531) (xy 25.917356 -42.282604)
			(xy 25.972172 -42.278501) (xy 26.02701 -42.282309) (xy 26.080733 -42.293948) (xy 26.132229 -42.313176)
			(xy 26.180433 -42.339597) (xy 26.224345 -42.372663) (xy 26.244042 -42.391838) (xy 26.260119 -42.407301)
			(xy 26.29658 -42.43299) (xy 26.336966 -42.451916) (xy 26.380038 -42.463498) (xy 26.42447 -42.467378)
			(xy 26.468897 -42.463438) (xy 26.511953 -42.451799) (xy 26.552314 -42.432819) (xy 26.58874 -42.407081)
			(xy 26.620111 -42.375377) (xy 26.63317 -42.357294) (xy 26.649214 -42.334977) (xy 26.686644 -42.29473)
			(xy 26.729463 -42.260272) (xy 26.776784 -42.232316) (xy 26.827627 -42.211441) (xy 26.88094 -42.198079)
			(xy 26.935619 -42.192508) (xy 26.990532 -42.194841) (xy 27.044541 -42.205032) (xy 27.096528 -42.222869)
			(xy 27.145417 -42.247982) (xy 27.190196 -42.279852) (xy 27.229937 -42.317818) (xy 27.263817 -42.361096)
			(xy 27.291136 -42.408788) (xy 27.311327 -42.459907) (xy 27.323972 -42.513394) (xy 27.328809 -42.568143)
			(xy 27.325739 -42.623019) (xy 27.314825 -42.676887) (xy 27.296292 -42.72863) (xy 27.270525 -42.777178)
			(xy 27.238057 -42.821525) (xy 27.199561 -42.860753) (xy 27.155833 -42.89405) (xy 27.107778 -42.920726)
			(xy 27.056393 -42.940229) (xy 27.002741 -42.952155) (xy 26.947932 -42.956258) (xy 26.893102 -42.952451)
			(xy 26.839386 -42.940815) (xy 26.787896 -42.92159) (xy 26.739698 -42.895174) (xy 26.695791 -42.862114)
			(xy 26.676096 -42.842942) (xy 26.660078 -42.827415) (xy 26.623607 -42.80173) (xy 26.58321 -42.782809)
			(xy 26.540129 -42.771233) (xy 26.495689 -42.76736) (xy 26.451256 -42.771307) (xy 26.408195 -42.782953)
			(xy 26.36783 -42.801941) (xy 26.331401 -42.827687) (xy 26.300028 -42.859399) (xy 26.286968 -42.877486)
			(xy 26.270942 -42.89982) (xy 26.23351 -42.940076) (xy 26.190689 -42.974542) (xy 26.143364 -43.002506)
			(xy 26.092515 -43.023388) (xy 26.039196 -43.036756) (xy 25.98451 -43.042333) (xy 25.92959 -43.040003)
			(xy 25.875573 -43.029814) (xy 25.823578 -43.011979) (xy 25.774681 -42.986865) (xy 25.729894 -42.954993)
			(xy 25.690146 -42.917024) (xy 25.656259 -42.873742) (xy 25.628934 -42.826045) (xy 25.608739 -42.77492)
			(xy 25.59609 -42.721425) (xy 25.59125 -42.666669) (xy 24.970994 -42.666669) (xy 24.970994 -44.54398)
			(xy 26.735022 -44.54398) (xy 26.739093 -44.488358) (xy 26.751219 -44.433921) (xy 26.771142 -44.38183)
			(xy 26.798438 -44.333195) (xy 26.832524 -44.289052) (xy 26.872673 -44.250343) (xy 26.918031 -44.217892)
			(xy 26.967631 -44.192391) (xy 27.020415 -44.174384) (xy 27.075258 -44.164254) (xy 27.130992 -44.162217)
			(xy 27.186429 -44.168317) (xy 27.240386 -44.182423) (xy 27.291715 -44.204235) (xy 27.339321 -44.233289)
			(xy 27.382189 -44.268964) (xy 27.419406 -44.310501) (xy 27.450179 -44.357014) (xy 27.473851 -44.407511)
			(xy 27.489919 -44.460918) (xy 27.498039 -44.516094) (xy 27.498548 -44.54398) (xy 27.498039 -44.571866)
			(xy 27.489919 -44.627042) (xy 27.473851 -44.680449) (xy 27.450179 -44.730946) (xy 27.419406 -44.777459)
			(xy 27.382189 -44.818996) (xy 27.339321 -44.854671) (xy 27.291715 -44.883725) (xy 27.240386 -44.905537)
			(xy 27.186429 -44.919643) (xy 27.130992 -44.925743) (xy 27.075258 -44.923706) (xy 27.020415 -44.913576)
			(xy 26.967631 -44.895569) (xy 26.918031 -44.870068) (xy 26.872673 -44.837617) (xy 26.832524 -44.798908)
			(xy 26.798438 -44.754765) (xy 26.771142 -44.70613) (xy 26.751219 -44.654039) (xy 26.739093 -44.599602)
			(xy 26.735022 -44.54398) (xy 24.970994 -44.54398) (xy 24.970994 -49.369472) (xy 25.386028 -49.369472)
			(xy 25.390099 -49.31385) (xy 25.402225 -49.259413) (xy 25.422148 -49.207322) (xy 25.449444 -49.158687)
			(xy 25.48353 -49.114544) (xy 25.523679 -49.075835) (xy 25.569037 -49.043384) (xy 25.618637 -49.017883)
			(xy 25.671421 -48.999876) (xy 25.726264 -48.989746) (xy 25.781998 -48.987709) (xy 25.837435 -48.993809)
			(xy 25.891392 -49.007915) (xy 25.942721 -49.029727) (xy 25.990327 -49.058781) (xy 26.033195 -49.094456)
			(xy 26.070412 -49.135993) (xy 26.101185 -49.182506) (xy 26.124857 -49.233003) (xy 26.140925 -49.28641)
			(xy 26.149045 -49.341586) (xy 26.149554 -49.369472) (xy 26.149045 -49.397358) (xy 26.140925 -49.452534)
			(xy 26.124857 -49.505941) (xy 26.101185 -49.556438) (xy 26.070412 -49.602951) (xy 26.033195 -49.644488)
			(xy 25.990327 -49.680163) (xy 25.942721 -49.709217) (xy 25.891392 -49.731029) (xy 25.837435 -49.745135)
			(xy 25.781998 -49.751235) (xy 25.726264 -49.749198) (xy 25.671421 -49.739068) (xy 25.618637 -49.721061)
			(xy 25.569037 -49.69556) (xy 25.523679 -49.663109) (xy 25.48353 -49.6244) (xy 25.449444 -49.580257)
			(xy 25.422148 -49.531622) (xy 25.402225 -49.479531) (xy 25.390099 -49.425094) (xy 25.386028 -49.369472)
			(xy 24.970994 -49.369472) (xy 24.970994 -53.542184) (xy 26.6733 -53.542184) (xy 26.677371 -53.486562)
			(xy 26.689497 -53.432125) (xy 26.70942 -53.380034) (xy 26.736716 -53.331399) (xy 26.770802 -53.287256)
			(xy 26.810951 -53.248547) (xy 26.856309 -53.216096) (xy 26.905909 -53.190595) (xy 26.958693 -53.172588)
			(xy 27.013536 -53.162458) (xy 27.06927 -53.160421) (xy 27.124707 -53.166521) (xy 27.178664 -53.180627)
			(xy 27.229993 -53.202439) (xy 27.277599 -53.231493) (xy 27.320467 -53.267168) (xy 27.357684 -53.308705)
			(xy 27.388457 -53.355218) (xy 27.412129 -53.405715) (xy 27.428197 -53.459122) (xy 27.436317 -53.514298)
			(xy 27.436826 -53.542184) (xy 27.436317 -53.57007) (xy 27.428197 -53.625246) (xy 27.412129 -53.678653)
			(xy 27.388457 -53.72915) (xy 27.357684 -53.775663) (xy 27.320467 -53.8172) (xy 27.277599 -53.852875)
			(xy 27.229993 -53.881929) (xy 27.178664 -53.903741) (xy 27.124707 -53.917847) (xy 27.06927 -53.923947)
			(xy 27.013536 -53.92191) (xy 26.958693 -53.91178) (xy 26.905909 -53.893773) (xy 26.856309 -53.868272)
			(xy 26.810951 -53.835821) (xy 26.770802 -53.797112) (xy 26.736716 -53.752969) (xy 26.70942 -53.704334)
			(xy 26.689497 -53.652243) (xy 26.677371 -53.597806) (xy 26.6733 -53.542184) (xy 24.970994 -53.542184)
			(xy 24.970994 -56.057038) (xy 24.39924 -56.628792) (xy 24.39924 -56.730392) (xy 25.277062 -56.730392)
			(xy 25.281133 -56.67477) (xy 25.293259 -56.620333) (xy 25.313182 -56.568242) (xy 25.340478 -56.519607)
			(xy 25.374564 -56.475464) (xy 25.414713 -56.436755) (xy 25.460071 -56.404304) (xy 25.509671 -56.378803)
			(xy 25.562455 -56.360796) (xy 25.617298 -56.350666) (xy 25.673032 -56.348629) (xy 25.728469 -56.354729)
			(xy 25.782426 -56.368835) (xy 25.833755 -56.390647) (xy 25.881361 -56.419701) (xy 25.924229 -56.455376)
			(xy 25.961446 -56.496913) (xy 25.992219 -56.543426) (xy 26.015891 -56.593923) (xy 26.031959 -56.64733)
			(xy 26.040079 -56.702506) (xy 26.040588 -56.730392) (xy 26.040079 -56.758278) (xy 26.031959 -56.813454)
			(xy 26.015891 -56.866861) (xy 25.992219 -56.917358) (xy 25.961446 -56.963871) (xy 25.924229 -57.005408)
			(xy 25.881361 -57.041083) (xy 25.833755 -57.070137) (xy 25.782426 -57.091949) (xy 25.728469 -57.106055)
			(xy 25.673032 -57.112155) (xy 25.617298 -57.110118) (xy 25.562455 -57.099988) (xy 25.509671 -57.081981)
			(xy 25.460071 -57.05648) (xy 25.414713 -57.024029) (xy 25.374564 -56.98532) (xy 25.340478 -56.941177)
			(xy 25.313182 -56.892542) (xy 25.293259 -56.840451) (xy 25.281133 -56.786014) (xy 25.277062 -56.730392)
			(xy 24.39924 -56.730392) (xy 24.39924 -58.195718) (xy 25.4889 -59.285378) (xy 25.4889 -60.553346)
			(xy 25.489443 -60.576797) (xy 25.498057 -60.622902) (xy 25.514984 -60.666644) (xy 25.539649 -60.706538)
			(xy 25.571216 -60.741229) (xy 25.608611 -60.769539) (xy 25.650566 -60.790507) (xy 25.695656 -60.803421)
			(xy 25.74235 -60.807843) (xy 25.76576 -60.80633) (xy 25.82931 -60.79937) (xy 25.956984 -60.792566)
			(xy 26.084833 -60.793901) (xy 26.212337 -60.803371) (xy 26.338981 -60.820936) (xy 26.464249 -60.846526)
			(xy 26.587635 -60.880036) (xy 26.708638 -60.921332) (xy 26.826768 -60.970245) (xy 26.941544 -61.026577)
			(xy 27.052503 -61.0901) (xy 27.159194 -61.160556) (xy 27.261185 -61.23766) (xy 27.358062 -61.321099)
			(xy 27.449431 -61.410534) (xy 27.534924 -61.505603) (xy 27.614192 -61.60592) (xy 27.686915 -61.711079)
			(xy 27.752798 -61.820653) (xy 27.811573 -61.934198) (xy 27.863003 -62.051254) (xy 27.906878 -62.171346)
			(xy 27.943022 -62.293986) (xy 27.971286 -62.418679) (xy 27.991557 -62.544917) (xy 28.003753 -62.67219)
			(xy 28.007824 -62.79998) (xy 28.003753 -62.927771) (xy 27.991557 -63.055044) (xy 27.971286 -63.181282)
			(xy 27.943021 -63.305975) (xy 27.906878 -63.428615) (xy 27.863003 -63.548707) (xy 27.811573 -63.665762)
			(xy 27.752798 -63.779308) (xy 27.686915 -63.888882) (xy 27.614192 -63.994041) (xy 27.534923 -64.094358)
			(xy 27.449431 -64.189427) (xy 27.358061 -64.278862) (xy 27.261184 -64.3623) (xy 27.159194 -64.439404)
			(xy 27.052503 -64.50986) (xy 26.941544 -64.573383) (xy 26.826767 -64.629715) (xy 26.708637 -64.678628)
			(xy 26.587634 -64.719924) (xy 26.464248 -64.753434) (xy 26.33898 -64.779024) (xy 26.212336 -64.796589)
			(xy 26.084832 -64.806059) (xy 25.956983 -64.807394) (xy 25.829309 -64.80059) (xy 25.76576 -64.793622)
			(xy 25.742351 -64.792048) (xy 25.69565 -64.796471) (xy 25.650552 -64.809389) (xy 25.608592 -64.830363)
			(xy 25.571192 -64.858681) (xy 25.539624 -64.893381) (xy 25.51496 -64.933284) (xy 25.498037 -64.977036)
			(xy 25.48943 -65.023151) (xy 25.4889 -65.046606) (xy 25.4889 -65.46469) (xy 25.072594 -65.880996)
			(xy 25.072594 -67.470639) (xy 26.102739 -67.470639) (xy 26.107733 -67.41614) (xy 26.120465 -67.362915)
			(xy 26.140674 -67.312055) (xy 26.167945 -67.264606) (xy 26.201717 -67.221542) (xy 26.221182 -67.202304)
			(xy 26.237535 -67.186089) (xy 26.264573 -67.148812) (xy 26.284458 -67.107277) (xy 26.29654 -67.06284)
			(xy 26.300424 -67.016954) (xy 26.295983 -66.971118) (xy 26.283362 -66.926831) (xy 26.262975 -66.88554)
			(xy 26.24963 -66.86677) (xy 26.233689 -66.844526) (xy 26.207648 -66.796394) (xy 26.188754 -66.745034)
			(xy 26.177395 -66.691501) (xy 26.173804 -66.636894) (xy 26.178054 -66.582334) (xy 26.190059 -66.528942)
			(xy 26.209572 -66.477814) (xy 26.236192 -66.43) (xy 26.269373 -66.386481) (xy 26.308433 -66.348152)
			(xy 26.35257 -66.315799) (xy 26.400878 -66.290086) (xy 26.452366 -66.271543) (xy 26.505975 -66.260548)
			(xy 26.560605 -66.257328) (xy 26.615135 -66.26195) (xy 26.668444 -66.274318) (xy 26.719438 -66.294178)
			(xy 26.767069 -66.321123) (xy 26.810361 -66.354599) (xy 26.848424 -66.393919) (xy 26.880476 -66.438276)
			(xy 26.905859 -66.486758) (xy 26.924052 -66.53837) (xy 26.934682 -66.592053) (xy 26.937529 -66.646703)
			(xy 26.932537 -66.7012) (xy 26.919806 -66.754424) (xy 26.8996 -66.805282) (xy 26.872331 -66.852729)
			(xy 26.838561 -66.895792) (xy 26.819098 -66.91503) (xy 26.802807 -66.931306) (xy 26.77576 -66.968568)
			(xy 26.755865 -67.010091) (xy 26.743773 -67.054519) (xy 26.73988 -67.100397) (xy 26.744312 -67.146227)
			(xy 26.756926 -67.190509) (xy 26.777308 -67.231796) (xy 26.79065 -67.250564) (xy 26.806594 -67.272808)
			(xy 26.832638 -67.320941) (xy 26.851534 -67.372303) (xy 26.862895 -67.425838) (xy 26.866488 -67.480447)
			(xy 26.862238 -67.535009) (xy 26.850234 -67.588404) (xy 26.830721 -67.639534) (xy 26.804101 -67.687351)
			(xy 26.77092 -67.730872) (xy 26.731858 -67.769204) (xy 26.68772 -67.801559) (xy 26.639409 -67.827273)
			(xy 26.58792 -67.845818) (xy 26.534309 -67.856813) (xy 26.479676 -67.860033) (xy 26.425144 -67.855411)
			(xy 26.371833 -67.843043) (xy 26.320837 -67.823182) (xy 26.273203 -67.796236) (xy 26.229909 -67.762758)
			(xy 26.191845 -67.723436) (xy 26.159792 -67.679077) (xy 26.134409 -67.630593) (xy 26.116215 -67.578978)
			(xy 26.105586 -67.525293) (xy 26.102739 -67.470639) (xy 25.072594 -67.470639) (xy 25.072594 -71.0184)
			(xy 23.92172 -72.169274) (xy 23.5077 -72.169274) (xy 23.461218 -72.215756) (xy 20.631912 -72.215756)
			(xy 20.62226 -72.225662) (xy 19.548094 -72.225662) (xy 19.14906 -72.624696) (xy 19.14906 -73.83907)
			(xy 19.324574 -74.014584) (xy 21.466302 -74.014584)
		)
		(stroke
			(width 0)
			(type solid)
		)
		(fill yes)
		(layer "In7.Cu")
		(net "P5V_NODE1")
	)
	(gr_poly
		(pts
			(xy 95.931482 -129.774442) (xy 95.941812 -129.763534) (xy 95.957511 -129.737929) (xy 95.966779 -129.709361)
			(xy 95.969103 -129.679417) (xy 95.964353 -129.649761) (xy 95.958914 -129.635758) (xy 95.94852 -129.609561)
			(xy 95.934685 -129.554929) (xy 95.929037 -129.498855) (xy 95.931698 -129.442561) (xy 95.94261 -129.38727)
			(xy 95.961537 -129.334186) (xy 95.988066 -129.284463) (xy 96.02162 -129.239184) (xy 96.06147 -129.199332)
			(xy 96.106748 -129.165776) (xy 96.156469 -129.139244) (xy 96.209553 -129.120315) (xy 96.264843 -129.1094)
			(xy 96.321137 -129.106736) (xy 96.377211 -129.112382) (xy 96.431844 -129.126214) (xy 96.458024 -129.136648)
			(xy 96.472046 -129.142011) (xy 96.501687 -129.146724) (xy 96.53161 -129.144395) (xy 96.560165 -129.135153)
			(xy 96.585778 -129.119508) (xy 96.596708 -129.109216) (xy 97.894648 -127.811276) (xy 97.905997 -127.799104)
			(xy 97.92258 -127.770265) (xy 97.93116 -127.738124) (xy 97.931158 -127.704857) (xy 97.922573 -127.672718)
			(xy 97.905986 -127.643881) (xy 97.894648 -127.631698) (xy 96.60763 -126.344426) (xy 96.585395 -126.321482)
			(xy 96.546234 -126.270996) (xy 96.513709 -126.216) (xy 96.488334 -126.157361) (xy 96.470508 -126.096004)
			(xy 96.460513 -126.032897) (xy 96.458506 -125.969035) (xy 96.464519 -125.905424) (xy 96.478457 -125.84307)
			(xy 96.5001 -125.782953) (xy 96.529107 -125.726023) (xy 96.565021 -125.673178) (xy 96.607275 -125.625251)
			(xy 96.655202 -125.582997) (xy 96.708047 -125.547083) (xy 96.764977 -125.518076) (xy 96.825094 -125.496433)
			(xy 96.887448 -125.482495) (xy 96.951059 -125.476482) (xy 97.014921 -125.478489) (xy 97.078028 -125.488484)
			(xy 97.139385 -125.50631) (xy 97.198024 -125.531685) (xy 97.25302 -125.56421) (xy 97.303506 -125.603371)
			(xy 97.32645 -125.625606) (xy 97.995486 -126.294388) (xy 98.01222 -126.310386) (xy 98.05035 -126.336634)
			(xy 98.0926 -126.355548) (xy 98.137577 -126.366501) (xy 98.183792 -126.369132) (xy 98.229721 -126.363354)
			(xy 98.273845 -126.349358) (xy 98.314707 -126.327606) (xy 98.350957 -126.298818) (xy 98.381397 -126.263943)
			(xy 98.405022 -126.224135) (xy 98.421051 -126.180708) (xy 98.425508 -126.15799) (xy 98.430558 -126.131394)
			(xy 98.447176 -126.079874) (xy 98.470909 -126.03122) (xy 98.501282 -125.986409) (xy 98.537685 -125.946342)
			(xy 98.579386 -125.911824) (xy 98.625547 -125.883546) (xy 98.675243 -125.862078) (xy 98.727474 -125.847851)
			(xy 98.781192 -125.84115) (xy 98.835317 -125.842109) (xy 98.888764 -125.850711) (xy 98.940458 -125.866781)
			(xy 98.989361 -125.889997) (xy 99.034491 -125.919892) (xy 99.074942 -125.955868) (xy 99.109901 -125.9972)
			(xy 99.138667 -126.043059) (xy 99.15017 -126.067566) (xy 99.159692 -126.087843) (xy 99.184764 -126.124961)
			(xy 99.215957 -126.157108) (xy 99.252302 -126.183289) (xy 99.292674 -126.202692) (xy 99.335823 -126.214716)
			(xy 99.380411 -126.218989) (xy 99.425058 -126.215378) (xy 99.468381 -126.203996) (xy 99.509037 -126.185194)
			(xy 99.545766 -126.159556) (xy 99.561904 -126.14402) (xy 99.9871 -125.718824) (xy 99.9871 -120.62206)
			(xy 99.15652 -119.79148) (xy 96.43618 -119.79148) (xy 96.414497 -119.791921) (xy 96.37176 -119.799284)
			(xy 96.330893 -119.813793) (xy 96.293081 -119.835027) (xy 96.259421 -119.86237) (xy 96.23089 -119.895029)
			(xy 96.208315 -119.932056) (xy 96.192351 -119.972377) (xy 96.183462 -120.014822) (xy 96.181905 -120.058161)
			(xy 96.187725 -120.101134) (xy 96.193864 -120.121934) (xy 96.201713 -120.148353) (xy 96.210601 -120.202745)
			(xy 96.21157 -120.257849) (xy 96.2046 -120.312519) (xy 96.189835 -120.365617) (xy 96.167583 -120.416038)
			(xy 96.138308 -120.462732) (xy 96.102618 -120.504728) (xy 96.061256 -120.541151) (xy 96.015084 -120.571243)
			(xy 95.965062 -120.594378) (xy 95.912231 -120.610074) (xy 95.857692 -120.618004) (xy 95.80258 -120.618004)
			(xy 95.748041 -120.610074) (xy 95.69521 -120.594378) (xy 95.645188 -120.571243) (xy 95.599016 -120.541151)
			(xy 95.557654 -120.504728) (xy 95.521964 -120.462732) (xy 95.492689 -120.416038) (xy 95.470437 -120.365617)
			(xy 95.455672 -120.312519) (xy 95.448702 -120.257849) (xy 95.449671 -120.202745) (xy 95.458559 -120.148353)
			(xy 95.466408 -120.121934) (xy 95.472513 -120.101123) (xy 95.478352 -120.058152) (xy 95.47681 -120.014813)
			(xy 95.467931 -119.972365) (xy 95.451973 -119.932042) (xy 95.4294 -119.895013) (xy 95.400868 -119.862355)
			(xy 95.367204 -119.835016) (xy 95.329387 -119.813791) (xy 95.288515 -119.799295) (xy 95.245775 -119.791949)
			(xy 95.224092 -119.79148) (xy 94.30004 -119.79148) (xy 94.278154 -119.791935) (xy 94.23503 -119.799434)
			(xy 94.193831 -119.814217) (xy 94.155777 -119.835846) (xy 94.121996 -119.863681) (xy 94.093488 -119.896895)
			(xy 94.071099 -119.934507) (xy 94.05549 -119.9754) (xy 94.047125 -120.018365) (xy 94.046252 -120.062127)
			(xy 94.049088 -120.083834) (xy 94.05276 -120.110989) (xy 94.053207 -120.165785) (xy 94.04581 -120.22008)
			(xy 94.030723 -120.272759) (xy 94.008255 -120.322739) (xy 93.978869 -120.36899) (xy 93.943169 -120.410562)
			(xy 93.901889 -120.446599) (xy 93.855879 -120.476361) (xy 93.806085 -120.499236) (xy 93.75353 -120.514752)
			(xy 93.699297 -120.52259) (xy 93.644499 -120.52259) (xy 93.590266 -120.514752) (xy 93.537711 -120.499236)
			(xy 93.487917 -120.476361) (xy 93.441907 -120.446599) (xy 93.400627 -120.410562) (xy 93.364927 -120.36899)
			(xy 93.335541 -120.322739) (xy 93.313073 -120.272759) (xy 93.297986 -120.22008) (xy 93.290589 -120.165785)
			(xy 93.291036 -120.110989) (xy 93.294708 -120.083834) (xy 93.297558 -120.062134) (xy 93.296653 -120.018381)
			(xy 93.288266 -119.975429) (xy 93.272644 -119.934549) (xy 93.25025 -119.89695) (xy 93.221746 -119.863744)
			(xy 93.187974 -119.835911) (xy 93.149933 -119.814276) (xy 93.108748 -119.799478) (xy 93.065637 -119.791954)
			(xy 93.043756 -119.79148) (xy 89.55024 -119.79148) (xy 87.486744 -121.854976) (xy 87.486744 -122.320266)
			(xy 93.872309 -122.320266) (xy 93.876805 -122.264976) (xy 93.889261 -122.210919) (xy 93.909416 -122.159237)
			(xy 93.936843 -122.111018) (xy 93.970964 -122.067281) (xy 94.01106 -122.028946) (xy 94.056286 -121.996823)
			(xy 94.105687 -121.971588) (xy 94.158222 -121.953775) (xy 94.212783 -121.943758) (xy 94.26822 -121.941749)
			(xy 94.323363 -121.94779) (xy 94.350332 -121.95429) (xy 94.372108 -121.959463) (xy 94.416724 -121.962972)
			(xy 94.461266 -121.958614) (xy 94.504356 -121.946523) (xy 94.544663 -121.927074) (xy 94.580941 -121.900867)
			(xy 94.61207 -121.868712) (xy 94.637087 -121.831603) (xy 94.655219 -121.790686) (xy 94.665905 -121.747227)
			(xy 94.667832 -121.724928) (xy 94.670149 -121.69687) (xy 94.682008 -121.641835) (xy 94.701827 -121.58914)
			(xy 94.729175 -121.539931) (xy 94.763459 -121.495275) (xy 94.803933 -121.456143) (xy 94.84972 -121.423385)
			(xy 94.899824 -121.397712) (xy 94.953157 -121.379682) (xy 95.00856 -121.369686) (xy 95.064832 -121.367942)
			(xy 95.120748 -121.374487) (xy 95.175095 -121.389179) (xy 95.226693 -121.411699) (xy 95.274421 -121.441559)
			(xy 95.317241 -121.478108) (xy 95.354225 -121.520555) (xy 95.384569 -121.567976) (xy 95.407613 -121.619342)
			(xy 95.422858 -121.673537) (xy 95.429972 -121.729384) (xy 95.428801 -121.78567) (xy 95.419369 -121.841172)
			(xy 95.401883 -121.894686) (xy 95.376722 -121.945049) (xy 95.344431 -121.991166) (xy 95.325438 -122.011948)
			(xy 95.314698 -122.023896) (xy 95.299126 -122.051988) (xy 95.291063 -122.083079) (xy 95.291022 -122.115198)
			(xy 95.299005 -122.14631) (xy 95.314506 -122.174441) (xy 95.325184 -122.186446) (xy 95.343707 -122.206733)
			(xy 95.375264 -122.251699) (xy 95.400046 -122.300726) (xy 95.41754 -122.352801) (xy 95.427384 -122.406846)
			(xy 95.429374 -122.461745) (xy 95.423469 -122.516361) (xy 95.409793 -122.569566) (xy 95.388626 -122.620259)
			(xy 95.360407 -122.667392) (xy 95.32572 -122.70999) (xy 95.285282 -122.747173) (xy 95.239929 -122.778171)
			(xy 95.190599 -122.802344) (xy 95.138311 -122.819192) (xy 95.084148 -122.828365) (xy 95.029229 -122.829676)
			(xy 94.97469 -122.823095) (xy 94.921659 -122.808761) (xy 94.871231 -122.786968) (xy 94.824452 -122.758168)
			(xy 94.782286 -122.722956) (xy 94.76359 -122.702828) (xy 94.748784 -122.686924) (xy 94.714692 -122.659983)
			(xy 94.676513 -122.639238) (xy 94.635361 -122.625293) (xy 94.592435 -122.618556) (xy 94.548989 -122.619222)
			(xy 94.50629 -122.627274) (xy 94.465584 -122.642474) (xy 94.446598 -122.653044) (xy 94.422365 -122.666548)
			(xy 94.370908 -122.687272) (xy 94.316993 -122.700325) (xy 94.261755 -122.705432) (xy 94.20636 -122.702485)
			(xy 94.151977 -122.691545) (xy 94.099751 -122.672845) (xy 94.050784 -122.646778) (xy 94.006108 -122.613894)
			(xy 93.966667 -122.574886) (xy 93.933291 -122.530577) (xy 93.906684 -122.481901) (xy 93.887408 -122.429885)
			(xy 93.875868 -122.375625) (xy 93.872309 -122.320266) (xy 87.486744 -122.320266) (xy 87.486744 -123.566936)
			(xy 88.065862 -123.566936) (xy 88.069933 -123.511314) (xy 88.082059 -123.456877) (xy 88.101982 -123.404786)
			(xy 88.129278 -123.356151) (xy 88.163364 -123.312008) (xy 88.203513 -123.273299) (xy 88.248871 -123.240848)
			(xy 88.298471 -123.215347) (xy 88.351255 -123.19734) (xy 88.406098 -123.18721) (xy 88.461832 -123.185173)
			(xy 88.517269 -123.191273) (xy 88.571226 -123.205379) (xy 88.622555 -123.227191) (xy 88.670161 -123.256245)
			(xy 88.713029 -123.29192) (xy 88.750246 -123.333457) (xy 88.781019 -123.37997) (xy 88.804691 -123.430467)
			(xy 88.820759 -123.483874) (xy 88.828879 -123.53905) (xy 88.829388 -123.566936) (xy 88.828879 -123.594822)
			(xy 88.822741 -123.636532) (xy 89.826082 -123.636532) (xy 89.830153 -123.58091) (xy 89.842279 -123.526473)
			(xy 89.862202 -123.474382) (xy 89.889498 -123.425747) (xy 89.923584 -123.381604) (xy 89.963733 -123.342895)
			(xy 90.009091 -123.310444) (xy 90.058691 -123.284943) (xy 90.111475 -123.266936) (xy 90.166318 -123.256806)
			(xy 90.222052 -123.254769) (xy 90.277489 -123.260869) (xy 90.331446 -123.274975) (xy 90.382775 -123.296787)
			(xy 90.430381 -123.325841) (xy 90.473249 -123.361516) (xy 90.510466 -123.403053) (xy 90.541239 -123.449566)
			(xy 90.564911 -123.500063) (xy 90.580979 -123.55347) (xy 90.589099 -123.608646) (xy 90.589608 -123.636532)
			(xy 90.589099 -123.664418) (xy 90.580979 -123.719594) (xy 90.564911 -123.773001) (xy 90.541239 -123.823498)
			(xy 90.510466 -123.870011) (xy 90.473249 -123.911548) (xy 90.430381 -123.947223) (xy 90.382775 -123.976277)
			(xy 90.331446 -123.998089) (xy 90.277489 -124.012195) (xy 90.222052 -124.018295) (xy 90.166318 -124.016258)
			(xy 90.111475 -124.006128) (xy 90.058691 -123.988121) (xy 90.009091 -123.96262) (xy 89.963733 -123.930169)
			(xy 89.923584 -123.89146) (xy 89.889498 -123.847317) (xy 89.862202 -123.798682) (xy 89.842279 -123.746591)
			(xy 89.830153 -123.692154) (xy 89.826082 -123.636532) (xy 88.822741 -123.636532) (xy 88.820759 -123.649998)
			(xy 88.804691 -123.703405) (xy 88.781019 -123.753902) (xy 88.750246 -123.800415) (xy 88.713029 -123.841952)
			(xy 88.670161 -123.877627) (xy 88.622555 -123.906681) (xy 88.571226 -123.928493) (xy 88.517269 -123.942599)
			(xy 88.461832 -123.948699) (xy 88.406098 -123.946662) (xy 88.351255 -123.936532) (xy 88.298471 -123.918525)
			(xy 88.248871 -123.893024) (xy 88.203513 -123.860573) (xy 88.163364 -123.821864) (xy 88.129278 -123.777721)
			(xy 88.101982 -123.729086) (xy 88.082059 -123.676995) (xy 88.069933 -123.622558) (xy 88.065862 -123.566936)
			(xy 87.486744 -123.566936) (xy 87.486744 -123.92406) (xy 87.2871 -124.123958) (xy 87.2871 -124.721366)
			(xy 94.665544 -124.721366) (xy 94.669615 -124.665744) (xy 94.681741 -124.611307) (xy 94.701664 -124.559216)
			(xy 94.72896 -124.510581) (xy 94.763046 -124.466438) (xy 94.803195 -124.427729) (xy 94.848553 -124.395278)
			(xy 94.898153 -124.369777) (xy 94.950937 -124.35177) (xy 95.00578 -124.34164) (xy 95.061514 -124.339603)
			(xy 95.116951 -124.345703) (xy 95.170908 -124.359809) (xy 95.222237 -124.381621) (xy 95.269843 -124.410675)
			(xy 95.312711 -124.44635) (xy 95.349928 -124.487887) (xy 95.380701 -124.5344) (xy 95.404373 -124.584897)
			(xy 95.420441 -124.638304) (xy 95.428561 -124.69348) (xy 95.42907 -124.721366) (xy 95.428561 -124.749252)
			(xy 95.420441 -124.804428) (xy 95.404373 -124.857835) (xy 95.380701 -124.908332) (xy 95.349928 -124.954845)
			(xy 95.316066 -124.992638) (xy 98.45116 -124.992638) (xy 98.455231 -124.937016) (xy 98.467357 -124.882579)
			(xy 98.48728 -124.830488) (xy 98.514576 -124.781853) (xy 98.548662 -124.73771) (xy 98.588811 -124.699001)
			(xy 98.634169 -124.66655) (xy 98.683769 -124.641049) (xy 98.736553 -124.623042) (xy 98.791396 -124.612912)
			(xy 98.84713 -124.610875) (xy 98.902567 -124.616975) (xy 98.956524 -124.631081) (xy 99.007853 -124.652893)
			(xy 99.055459 -124.681947) (xy 99.098327 -124.717622) (xy 99.135544 -124.759159) (xy 99.166317 -124.805672)
			(xy 99.189989 -124.856169) (xy 99.206057 -124.909576) (xy 99.214177 -124.964752) (xy 99.214686 -124.992638)
			(xy 99.214177 -125.020524) (xy 99.206057 -125.0757) (xy 99.189989 -125.129107) (xy 99.166317 -125.179604)
			(xy 99.135544 -125.226117) (xy 99.098327 -125.267654) (xy 99.055459 -125.303329) (xy 99.007853 -125.332383)
			(xy 98.956524 -125.354195) (xy 98.902567 -125.368301) (xy 98.84713 -125.374401) (xy 98.791396 -125.372364)
			(xy 98.736553 -125.362234) (xy 98.683769 -125.344227) (xy 98.634169 -125.318726) (xy 98.588811 -125.286275)
			(xy 98.548662 -125.247566) (xy 98.514576 -125.203423) (xy 98.48728 -125.154788) (xy 98.467357 -125.102697)
			(xy 98.455231 -125.04826) (xy 98.45116 -124.992638) (xy 95.316066 -124.992638) (xy 95.312711 -124.996382)
			(xy 95.269843 -125.032057) (xy 95.222237 -125.061111) (xy 95.170908 -125.082923) (xy 95.116951 -125.097029)
			(xy 95.061514 -125.103129) (xy 95.00578 -125.101092) (xy 94.950937 -125.090962) (xy 94.898153 -125.072955)
			(xy 94.848553 -125.047454) (xy 94.803195 -125.015003) (xy 94.763046 -124.976294) (xy 94.72896 -124.932151)
			(xy 94.701664 -124.883516) (xy 94.681741 -124.831425) (xy 94.669615 -124.776988) (xy 94.665544 -124.721366)
			(xy 87.2871 -124.721366) (xy 87.2871 -126.009654) (xy 87.287508 -126.024888) (xy 87.294668 -126.0545)
			(xy 87.30866 -126.081562) (xy 87.328683 -126.104523) (xy 87.353589 -126.122068) (xy 87.367618 -126.128018)
			(xy 87.367872 -126.128018) (xy 87.376347 -126.131505) (xy 94.575951 -126.131505) (xy 94.580214 -126.075683)
			(xy 94.592591 -126.021084) (xy 94.612817 -125.968881) (xy 94.640456 -125.920195) (xy 94.674915 -125.876073)
			(xy 94.715454 -125.837462) (xy 94.761202 -125.805192) (xy 94.811176 -125.779955) (xy 94.864302 -125.762295)
			(xy 94.919438 -125.752591) (xy 94.975401 -125.75105) (xy 95.030988 -125.757707) (xy 95.085005 -125.772419)
			(xy 95.136291 -125.794868) (xy 95.183745 -125.824573) (xy 95.226346 -125.860896) (xy 95.26318 -125.903056)
			(xy 95.293456 -125.950148) (xy 95.316522 -126.001159) (xy 95.324676 -126.027942) (xy 95.331265 -126.049326)
			(xy 95.350844 -126.089555) (xy 95.377166 -126.125733) (xy 95.409416 -126.156743) (xy 95.446599 -126.181626)
			(xy 95.487564 -126.199613) (xy 95.531047 -126.210148) (xy 95.575702 -126.212906) (xy 95.59798 -126.210822)
			(xy 95.625849 -126.208125) (xy 95.68181 -126.209981) (xy 95.736898 -126.219998) (xy 95.78993 -126.237961)
			(xy 95.839766 -126.263482) (xy 95.885336 -126.296016) (xy 95.92566 -126.334861) (xy 95.959873 -126.379184)
			(xy 95.987238 -126.428032) (xy 96.007169 -126.480356) (xy 96.019237 -126.535031) (xy 96.023182 -126.590883)
			(xy 96.01892 -126.646712) (xy 96.006543 -126.701318) (xy 95.986316 -126.753528) (xy 95.958673 -126.80222)
			(xy 95.92421 -126.846348) (xy 95.883666 -126.884964) (xy 95.837912 -126.917238) (xy 95.787932 -126.942477)
			(xy 95.734799 -126.960139) (xy 95.679656 -126.969843) (xy 95.623686 -126.971382) (xy 95.568092 -126.964722)
			(xy 95.514069 -126.950007) (xy 95.462777 -126.927553) (xy 95.415319 -126.897841) (xy 95.372715 -126.861512)
			(xy 95.335879 -126.819344) (xy 95.305603 -126.772244) (xy 95.282537 -126.721225) (xy 95.274384 -126.694438)
			(xy 95.267847 -126.673037) (xy 95.248261 -126.632806) (xy 95.221931 -126.596626) (xy 95.189673 -126.565617)
			(xy 95.152483 -126.540736) (xy 95.11151 -126.522752) (xy 95.068021 -126.512222) (xy 95.02336 -126.509471)
			(xy 95.00108 -126.511558) (xy 94.973213 -126.514244) (xy 94.91726 -126.512382) (xy 94.862179 -126.502362)
			(xy 94.809156 -126.484397) (xy 94.759328 -126.458875) (xy 94.713766 -126.426343) (xy 94.673449 -126.3875)
			(xy 94.639243 -126.34318) (xy 94.611883 -126.294337) (xy 94.591958 -126.242019) (xy 94.579894 -126.18735)
			(xy 94.575951 -126.131505) (xy 87.376347 -126.131505) (xy 87.392749 -126.138254) (xy 87.439588 -126.164709)
			(xy 87.482249 -126.197479) (xy 87.519885 -126.235915) (xy 87.551751 -126.279254) (xy 87.577216 -126.326639)
			(xy 87.595775 -126.37713) (xy 87.607061 -126.429727) (xy 87.610849 -126.483387) (xy 87.607064 -126.537047)
			(xy 87.595783 -126.589645) (xy 87.577227 -126.640137) (xy 87.551765 -126.687524) (xy 87.519902 -126.730865)
			(xy 87.482268 -126.769303) (xy 87.43961 -126.802076) (xy 87.392773 -126.828534) (xy 87.367872 -126.83871)
			(xy 87.367618 -126.83871) (xy 87.353613 -126.844703) (xy 87.328727 -126.862259) (xy 87.308711 -126.885212)
			(xy 87.294704 -126.912255) (xy 87.287505 -126.941846) (xy 87.2871 -126.957074) (xy 87.2871 -127.399034)
			(xy 88.230962 -127.399034) (xy 88.235033 -127.343412) (xy 88.247159 -127.288975) (xy 88.267082 -127.236884)
			(xy 88.294378 -127.188249) (xy 88.328464 -127.144106) (xy 88.368613 -127.105397) (xy 88.413971 -127.072946)
			(xy 88.463571 -127.047445) (xy 88.516355 -127.029438) (xy 88.571198 -127.019308) (xy 88.626932 -127.017271)
			(xy 88.682369 -127.023371) (xy 88.736326 -127.037477) (xy 88.787655 -127.059289) (xy 88.835261 -127.088343)
			(xy 88.878129 -127.124018) (xy 88.915346 -127.165555) (xy 88.946119 -127.212068) (xy 88.969791 -127.262565)
			(xy 88.985859 -127.315972) (xy 88.993979 -127.371148) (xy 88.994488 -127.399034) (xy 88.993979 -127.42692)
			(xy 88.985859 -127.482096) (xy 88.969791 -127.535503) (xy 88.946119 -127.586) (xy 88.915346 -127.632513)
			(xy 88.878129 -127.67405) (xy 88.835261 -127.709725) (xy 88.787655 -127.738779) (xy 88.736326 -127.760591)
			(xy 88.682369 -127.774697) (xy 88.626932 -127.780797) (xy 88.571198 -127.77876) (xy 88.516355 -127.76863)
			(xy 88.463571 -127.750623) (xy 88.413971 -127.725122) (xy 88.368613 -127.692671) (xy 88.328464 -127.653962)
			(xy 88.294378 -127.609819) (xy 88.267082 -127.561184) (xy 88.247159 -127.509093) (xy 88.235033 -127.454656)
			(xy 88.230962 -127.399034) (xy 87.2871 -127.399034) (xy 87.2871 -128.614424) (xy 93.329504 -128.614424)
			(xy 93.333575 -128.558802) (xy 93.345701 -128.504365) (xy 93.365624 -128.452274) (xy 93.39292 -128.403639)
			(xy 93.427006 -128.359496) (xy 93.467155 -128.320787) (xy 93.512513 -128.288336) (xy 93.562113 -128.262835)
			(xy 93.614897 -128.244828) (xy 93.66974 -128.234698) (xy 93.725474 -128.232661) (xy 93.780911 -128.238761)
			(xy 93.834868 -128.252867) (xy 93.886197 -128.274679) (xy 93.933803 -128.303733) (xy 93.976671 -128.339408)
			(xy 94.013888 -128.380945) (xy 94.044661 -128.427458) (xy 94.068333 -128.477955) (xy 94.084401 -128.531362)
			(xy 94.092521 -128.586538) (xy 94.09303 -128.614424) (xy 94.092521 -128.64231) (xy 94.084401 -128.697486)
			(xy 94.068333 -128.750893) (xy 94.044661 -128.80139) (xy 94.013888 -128.847903) (xy 93.976671 -128.88944)
			(xy 93.933803 -128.925115) (xy 93.886197 -128.954169) (xy 93.834868 -128.975981) (xy 93.780911 -128.990087)
			(xy 93.725474 -128.996187) (xy 93.66974 -128.99415) (xy 93.614897 -128.98402) (xy 93.562113 -128.966013)
			(xy 93.512513 -128.940512) (xy 93.467155 -128.908061) (xy 93.427006 -128.869352) (xy 93.39292 -128.825209)
			(xy 93.365624 -128.776574) (xy 93.345701 -128.724483) (xy 93.333575 -128.670046) (xy 93.329504 -128.614424)
			(xy 87.2871 -128.614424) (xy 87.2871 -129.128266) (xy 88.225884 -130.067304) (xy 88.238032 -130.078654)
			(xy 88.266828 -130.095243) (xy 88.29893 -130.103837) (xy 88.315546 -130.104388) (xy 88.46058 -130.104388)
			(xy 88.538304 -130.182112) (xy 88.550436 -130.193573) (xy 88.579315 -130.210282) (xy 88.611538 -130.218933)
			(xy 88.644902 -130.218933) (xy 88.677125 -130.210282) (xy 88.706004 -130.193573) (xy 88.718136 -130.182112)
			(xy 88.746584 -130.15341) (xy 88.753442 -130.114294) (xy 88.75869 -130.087205) (xy 88.775957 -130.034799)
			(xy 88.800595 -129.985428) (xy 88.832091 -129.940123) (xy 88.869786 -129.899829) (xy 88.912894 -129.865387)
			(xy 88.960516 -129.837518) (xy 89.011656 -129.816801) (xy 89.065248 -129.80367) (xy 89.120173 -129.798399)
			(xy 89.175285 -129.801097) (xy 89.229432 -129.811709) (xy 89.281485 -129.830013) (xy 89.330357 -129.855627)
			(xy 89.375027 -129.888016) (xy 89.414565 -129.926504) (xy 89.448143 -129.970288) (xy 89.475062 -130.018453)
			(xy 89.494759 -130.069995) (xy 89.506824 -130.123837) (xy 89.511003 -130.178856) (xy 89.507211 -130.233903)
			(xy 89.495526 -130.287829) (xy 89.476192 -130.339508) (xy 89.449613 -130.387862) (xy 89.416343 -130.431881)
			(xy 89.377078 -130.470646) (xy 89.355168 -130.48742) (xy 89.337399 -130.501076) (xy 89.306514 -130.533544)
			(xy 89.281804 -130.570927) (xy 89.264034 -130.612065) (xy 89.253758 -130.655682) (xy 89.251292 -130.700425)
			(xy 89.256714 -130.744907) (xy 89.269855 -130.787748) (xy 89.290308 -130.82762) (xy 89.317438 -130.863285)
			(xy 89.333578 -130.878834) (xy 89.354151 -130.898465) (xy 89.38983 -130.942741) (xy 89.41854 -130.991824)
			(xy 89.42959 -131.018026) (xy 89.444068 -131.054348) (xy 89.508584 -131.098036) (xy 94.607888 -131.098036)
		)
		(stroke
			(width 0)
			(type solid)
		)
		(fill yes)
		(layer "In7.Cu")
		(net "P1V8_NODE1")
	)
	(gr_poly
		(pts
			(xy 114.863118 -141.131798) (xy 114.872889 -141.121503) (xy 114.888044 -141.097511) (xy 114.897503 -141.070757)
			(xy 114.900795 -141.042572) (xy 114.899694 -141.02842) (xy 114.897167 -141.000135) (xy 114.899513 -140.943398)
			(xy 114.910245 -140.887636) (xy 114.929126 -140.834081) (xy 114.955738 -140.783917) (xy 114.989494 -140.738254)
			(xy 115.029647 -140.6981) (xy 115.07531 -140.664343) (xy 115.125473 -140.637729) (xy 115.179027 -140.618847)
			(xy 115.234789 -140.608114) (xy 115.291526 -140.605767) (xy 115.31981 -140.608304) (xy 115.333962 -140.609422)
			(xy 115.362149 -140.606118) (xy 115.388908 -140.596661) (xy 115.412912 -140.58152) (xy 115.423188 -140.571728)
			(xy 115.771676 -140.22324) (xy 115.771676 -140.170154) (xy 115.771286 -140.155356) (xy 115.764466 -140.126556)
			(xy 115.751183 -140.100109) (xy 115.732153 -140.077442) (xy 115.708405 -140.05978) (xy 115.694968 -140.053568)
			(xy 115.626642 -140.024358) (xy 115.611961 -140.018589) (xy 115.580815 -140.013665) (xy 115.549412 -140.016523)
			(xy 115.519666 -140.026989) (xy 115.506246 -140.03528) (xy 115.482774 -140.050288) (xy 115.432396 -140.074072)
			(xy 115.379094 -140.090278) (xy 115.324003 -140.09856) (xy 115.268293 -140.098742) (xy 115.213148 -140.090821)
			(xy 115.159742 -140.074965) (xy 115.109209 -140.051511) (xy 115.062624 -140.020957) (xy 115.020978 -139.983954)
			(xy 114.985156 -139.941288) (xy 114.955919 -139.893865) (xy 114.933889 -139.842695) (xy 114.919535 -139.788866)
			(xy 114.913162 -139.733521) (xy 114.914905 -139.677838) (xy 114.924727 -139.623) (xy 114.942419 -139.570174)
			(xy 114.967605 -139.520482) (xy 114.99975 -139.47498) (xy 115.038171 -139.434638) (xy 115.08205 -139.400311)
			(xy 115.130454 -139.372731) (xy 115.182354 -139.352482) (xy 115.236648 -139.339997) (xy 115.29218 -139.33554)
			(xy 115.347769 -139.339206) (xy 115.402235 -139.350917) (xy 115.428522 -139.360148) (xy 115.449556 -139.367539)
			(xy 115.49339 -139.375666) (xy 115.537969 -139.376022) (xy 115.581926 -139.368594) (xy 115.623913 -139.35361)
			(xy 115.662642 -139.33153) (xy 115.696924 -139.303032) (xy 115.725709 -139.26899) (xy 115.748112 -139.230448)
			(xy 115.763447 -139.188588) (xy 115.771243 -139.144694) (xy 115.771676 -139.122404) (xy 115.771676 -139.013438)
			(xy 115.771148 -138.990065) (xy 115.762602 -138.944108) (xy 115.745793 -138.900489) (xy 115.721287 -138.860683)
			(xy 115.689912 -138.826031) (xy 115.652727 -138.797705) (xy 115.610986 -138.77666) (xy 115.566101 -138.763607)
			(xy 115.519584 -138.758986) (xy 115.473008 -138.762954) (xy 115.427943 -138.775376) (xy 115.406678 -138.785092)
			(xy 115.381653 -138.796719) (xy 115.32907 -138.813451) (xy 115.274625 -138.822434) (xy 115.219455 -138.823482)
			(xy 115.164708 -138.816573) (xy 115.111528 -138.801852) (xy 115.061022 -138.779624) (xy 115.014244 -138.750354)
			(xy 114.97217 -138.714651) (xy 114.935677 -138.673261) (xy 114.905525 -138.627047) (xy 114.882344 -138.576971)
			(xy 114.866617 -138.524079) (xy 114.858672 -138.469474) (xy 114.858674 -138.414293) (xy 114.866624 -138.359688)
			(xy 114.882356 -138.306798) (xy 114.905541 -138.256724) (xy 114.935697 -138.210512) (xy 114.972194 -138.169126)
			(xy 115.014271 -138.133427) (xy 115.061051 -138.104161) (xy 115.111559 -138.081937) (xy 115.164741 -138.06722)
			(xy 115.219488 -138.060316) (xy 115.274658 -138.061369) (xy 115.329102 -138.070357) (xy 115.381684 -138.087093)
			(xy 115.406678 -138.098784) (xy 115.427931 -138.108521) (xy 115.472999 -138.120918) (xy 115.519575 -138.124866)
			(xy 115.566087 -138.120232) (xy 115.610967 -138.107173) (xy 115.652704 -138.086127) (xy 115.689889 -138.057806)
			(xy 115.721269 -138.023163) (xy 115.745786 -137.983367) (xy 115.762614 -137.939759) (xy 115.771185 -137.893809)
			(xy 115.771676 -137.870438) (xy 115.771676 -134.858506) (xy 115.77116 -134.842068) (xy 115.762749 -134.810285)
			(xy 115.746487 -134.781712) (xy 115.735354 -134.769606) (xy 115.716784 -134.750058) (xy 115.684769 -134.706673)
			(xy 115.659182 -134.659214) (xy 115.640531 -134.608625) (xy 115.629187 -134.555914) (xy 115.625378 -134.502131)
			(xy 115.629179 -134.448348) (xy 115.640513 -134.395635) (xy 115.659156 -134.345043) (xy 115.684736 -134.29758)
			(xy 115.716743 -134.25419) (xy 115.735354 -134.234682) (xy 115.746496 -134.222583) (xy 115.762754 -134.194005)
			(xy 115.771174 -134.162221) (xy 115.771676 -134.145782) (xy 115.771676 -133.19379) (xy 115.15471 -132.576824)
			(xy 115.138447 -132.561251) (xy 115.101495 -132.535528) (xy 115.060589 -132.516717) (xy 115.01701 -132.505406)
			(xy 114.972119 -132.50195) (xy 114.927321 -132.506457) (xy 114.884019 -132.518785) (xy 114.843565 -132.538548)
			(xy 114.807225 -132.56513) (xy 114.776137 -132.597697) (xy 114.763296 -132.616194) (xy 114.748526 -132.639563)
			(xy 114.713306 -132.682174) (xy 114.672306 -132.719256) (xy 114.626383 -132.750033) (xy 114.576499 -132.77386)
			(xy 114.523699 -132.790239) (xy 114.469088 -132.798827) (xy 114.413809 -132.799443) (xy 114.35902 -132.792075)
			(xy 114.305868 -132.776878) (xy 114.255466 -132.754169) (xy 114.208868 -132.724424) (xy 114.167051 -132.688265)
			(xy 114.13089 -132.64645) (xy 114.101142 -132.599854) (xy 114.07843 -132.549453) (xy 114.063229 -132.496301)
			(xy 114.055858 -132.441513) (xy 114.056471 -132.386234) (xy 114.065056 -132.331622) (xy 114.081432 -132.278821)
			(xy 114.105256 -132.228936) (xy 114.13603 -132.183012) (xy 114.17311 -132.142009) (xy 114.215719 -132.106787)
			(xy 114.23904 -132.091938) (xy 114.257546 -132.079108) (xy 114.290124 -132.048029) (xy 114.316713 -132.011693)
			(xy 114.336481 -131.97124) (xy 114.348809 -131.927935) (xy 114.35331 -131.883135) (xy 114.349843 -131.838243)
			(xy 114.338518 -131.794666) (xy 114.319689 -131.753767) (xy 114.293945 -131.716827) (xy 114.27841 -131.700524)
			(xy 113.295684 -130.717798) (xy 113.295684 -129.102104) (xy 112.330484 -128.136904) (xy 111.512096 -128.136904)
			(xy 111.008414 -128.640586) (xy 111.008414 -128.951482) (xy 111.046768 -129.041652) (xy 111.062008 -129.057908)
			(xy 111.081197 -129.079217) (xy 111.113616 -129.126515) (xy 111.138593 -129.178131) (xy 111.155565 -129.232903)
			(xy 111.164149 -129.289599) (xy 111.164154 -129.34694) (xy 111.155578 -129.403637) (xy 111.138615 -129.458412)
			(xy 111.113647 -129.510032) (xy 111.081235 -129.557335) (xy 111.062008 -129.578608) (xy 111.046768 -129.594864)
			(xy 111.008414 -129.685034) (xy 111.008414 -130.94716) (xy 111.31753 -130.94716) (xy 111.321601 -130.891538)
			(xy 111.333727 -130.837101) (xy 111.35365 -130.78501) (xy 111.380946 -130.736375) (xy 111.415032 -130.692232)
			(xy 111.455181 -130.653523) (xy 111.500539 -130.621072) (xy 111.550139 -130.595571) (xy 111.602923 -130.577564)
			(xy 111.657766 -130.567434) (xy 111.7135 -130.565397) (xy 111.768937 -130.571497) (xy 111.822894 -130.585603)
			(xy 111.874223 -130.607415) (xy 111.921829 -130.636469) (xy 111.964697 -130.672144) (xy 112.001914 -130.713681)
			(xy 112.032687 -130.760194) (xy 112.056359 -130.810691) (xy 112.072427 -130.864098) (xy 112.080547 -130.919274)
			(xy 112.081056 -130.94716) (xy 112.080547 -130.975046) (xy 112.072427 -131.030222) (xy 112.056359 -131.083629)
			(xy 112.032687 -131.134126) (xy 112.001914 -131.180639) (xy 111.964697 -131.222176) (xy 111.921829 -131.257851)
			(xy 111.874223 -131.286905) (xy 111.822894 -131.308717) (xy 111.768937 -131.322823) (xy 111.7135 -131.328923)
			(xy 111.657766 -131.326886) (xy 111.602923 -131.316756) (xy 111.550139 -131.298749) (xy 111.500539 -131.273248)
			(xy 111.455181 -131.240797) (xy 111.415032 -131.202088) (xy 111.380946 -131.157945) (xy 111.35365 -131.10931)
			(xy 111.333727 -131.057219) (xy 111.321601 -131.002782) (xy 111.31753 -130.94716) (xy 111.008414 -130.94716)
			(xy 111.008414 -133.034278) (xy 111.31753 -133.034278) (xy 111.321601 -132.978656) (xy 111.333727 -132.924219)
			(xy 111.35365 -132.872128) (xy 111.380946 -132.823493) (xy 111.415032 -132.77935) (xy 111.455181 -132.740641)
			(xy 111.500539 -132.70819) (xy 111.550139 -132.682689) (xy 111.602923 -132.664682) (xy 111.657766 -132.654552)
			(xy 111.7135 -132.652515) (xy 111.768937 -132.658615) (xy 111.822894 -132.672721) (xy 111.874223 -132.694533)
			(xy 111.921829 -132.723587) (xy 111.964697 -132.759262) (xy 112.001914 -132.800799) (xy 112.032687 -132.847312)
			(xy 112.056359 -132.897809) (xy 112.072427 -132.951216) (xy 112.080547 -133.006392) (xy 112.081056 -133.034278)
			(xy 112.080547 -133.062164) (xy 112.072427 -133.11734) (xy 112.056359 -133.170747) (xy 112.032687 -133.221244)
			(xy 112.001914 -133.267757) (xy 111.964697 -133.309294) (xy 111.921829 -133.344969) (xy 111.874223 -133.374023)
			(xy 111.822894 -133.395835) (xy 111.768937 -133.409941) (xy 111.7135 -133.416041) (xy 111.657766 -133.414004)
			(xy 111.602923 -133.403874) (xy 111.550139 -133.385867) (xy 111.500539 -133.360366) (xy 111.455181 -133.327915)
			(xy 111.415032 -133.289206) (xy 111.380946 -133.245063) (xy 111.35365 -133.196428) (xy 111.333727 -133.144337)
			(xy 111.321601 -133.0899) (xy 111.31753 -133.034278) (xy 111.008414 -133.034278) (xy 111.008414 -133.577705)
			(xy 114.255194 -133.577705) (xy 114.26243 -133.522195) (xy 114.277701 -133.468339) (xy 114.300679 -133.417293)
			(xy 114.330871 -133.370153) (xy 114.367627 -133.327932) (xy 114.410159 -133.291535) (xy 114.457554 -133.261746)
			(xy 114.508793 -133.239202) (xy 114.562777 -133.224389) (xy 114.618346 -133.217625) (xy 114.674307 -133.219054)
			(xy 114.729459 -133.228646) (xy 114.782616 -133.246195) (xy 114.832638 -133.271325) (xy 114.87845 -133.303495)
			(xy 114.919069 -133.342015) (xy 114.953622 -133.386058) (xy 114.981368 -133.434677) (xy 115.001711 -133.486829)
			(xy 115.014213 -133.541395) (xy 115.018606 -133.597201) (xy 115.014797 -133.653051) (xy 115.002866 -133.707744)
			(xy 114.983071 -133.760106) (xy 114.955835 -133.809014) (xy 114.921745 -133.853415) (xy 114.90198 -133.87324)
			(xy 114.886758 -133.888554) (xy 114.861248 -133.923389) (xy 114.841994 -133.962034) (xy 114.829549 -134.003378)
			(xy 114.824271 -134.04623) (xy 114.826314 -134.089358) (xy 114.835616 -134.131521) (xy 114.851912 -134.171504)
			(xy 114.874732 -134.208157) (xy 114.903419 -134.240425) (xy 114.920014 -134.25424) (xy 114.941572 -134.2721)
			(xy 114.979749 -134.313045) (xy 115.011532 -134.359128) (xy 115.03624 -134.409363) (xy 115.05334 -134.462668)
			(xy 115.062467 -134.517901) (xy 115.063424 -134.573874) (xy 115.056191 -134.629386) (xy 115.040922 -134.683245)
			(xy 115.017946 -134.734294) (xy 114.987757 -134.781438) (xy 114.951002 -134.823663) (xy 114.90847 -134.860063)
			(xy 114.861076 -134.889857) (xy 114.809836 -134.912405) (xy 114.755851 -134.927222) (xy 114.70028 -134.933991)
			(xy 114.644317 -134.932565) (xy 114.589163 -134.922976) (xy 114.536003 -134.90543) (xy 114.485977 -134.880303)
			(xy 114.440161 -134.848135) (xy 114.399538 -134.809617) (xy 114.36498 -134.765575) (xy 114.337229 -134.716956)
			(xy 114.316882 -134.664803) (xy 114.304375 -134.610237) (xy 114.299977 -134.554428) (xy 114.303782 -134.498576)
			(xy 114.315709 -134.44388) (xy 114.335501 -134.391514) (xy 114.362734 -134.342603) (xy 114.396822 -134.298197)
			(xy 114.416586 -134.27837) (xy 114.431771 -134.263024) (xy 114.457272 -134.228194) (xy 114.476519 -134.189554)
			(xy 114.48896 -134.148218) (xy 114.494236 -134.105374) (xy 114.492196 -134.062254) (xy 114.482898 -134.020099)
			(xy 114.46661 -133.980122) (xy 114.4438 -133.943473) (xy 114.415124 -133.911206) (xy 114.398552 -133.89737)
			(xy 114.377024 -133.879474) (xy 114.338851 -133.838529) (xy 114.307071 -133.792445) (xy 114.282367 -133.742211)
			(xy 114.26527 -133.688907) (xy 114.256147 -133.633676) (xy 114.255194 -133.577705) (xy 111.008414 -133.577705)
			(xy 111.008414 -136.67359) (xy 112.860834 -136.67359) (xy 112.864905 -136.617968) (xy 112.877031 -136.563531)
			(xy 112.896954 -136.51144) (xy 112.92425 -136.462805) (xy 112.958336 -136.418662) (xy 112.998485 -136.379953)
			(xy 113.043843 -136.347502) (xy 113.093443 -136.322001) (xy 113.146227 -136.303994) (xy 113.20107 -136.293864)
			(xy 113.256804 -136.291827) (xy 113.312241 -136.297927) (xy 113.366198 -136.312033) (xy 113.417527 -136.333845)
			(xy 113.465133 -136.362899) (xy 113.508001 -136.398574) (xy 113.545218 -136.440111) (xy 113.575991 -136.486624)
			(xy 113.599663 -136.537121) (xy 113.615731 -136.590528) (xy 113.623851 -136.645704) (xy 113.62436 -136.67359)
			(xy 113.623851 -136.701476) (xy 113.615731 -136.756652) (xy 113.599663 -136.810059) (xy 113.575991 -136.860556)
			(xy 113.545218 -136.907069) (xy 113.508001 -136.948606) (xy 113.465133 -136.984281) (xy 113.417527 -137.013335)
			(xy 113.366198 -137.035147) (xy 113.312241 -137.049253) (xy 113.256804 -137.055353) (xy 113.20107 -137.053316)
			(xy 113.146227 -137.043186) (xy 113.093443 -137.025179) (xy 113.043843 -136.999678) (xy 112.998485 -136.967227)
			(xy 112.958336 -136.928518) (xy 112.92425 -136.884375) (xy 112.896954 -136.83574) (xy 112.877031 -136.783649)
			(xy 112.864905 -136.729212) (xy 112.860834 -136.67359) (xy 111.008414 -136.67359) (xy 111.008414 -136.81202)
			(xy 111.037624 -136.847326) (xy 111.054278 -136.868176) (xy 111.082209 -136.913645) (xy 111.103533 -136.962562)
			(xy 111.117833 -137.013972) (xy 111.12483 -137.066874) (xy 111.124389 -137.120234) (xy 111.116516 -137.173013)
			(xy 111.101368 -137.22418) (xy 111.079237 -137.272737) (xy 111.050557 -137.317737) (xy 111.03356 -137.338308)
			(xy 111.029641 -137.34288) (xy 114.0112 -137.34288) (xy 114.015271 -137.287258) (xy 114.027397 -137.232821)
			(xy 114.04732 -137.18073) (xy 114.074616 -137.132095) (xy 114.108702 -137.087952) (xy 114.148851 -137.049243)
			(xy 114.194209 -137.016792) (xy 114.243809 -136.991291) (xy 114.296593 -136.973284) (xy 114.351436 -136.963154)
			(xy 114.40717 -136.961117) (xy 114.462607 -136.967217) (xy 114.516564 -136.981323) (xy 114.567893 -137.003135)
			(xy 114.615499 -137.032189) (xy 114.658367 -137.067864) (xy 114.695584 -137.109401) (xy 114.726357 -137.155914)
			(xy 114.750029 -137.206411) (xy 114.766097 -137.259818) (xy 114.774217 -137.314994) (xy 114.774726 -137.34288)
			(xy 114.774217 -137.370766) (xy 114.766097 -137.425942) (xy 114.750029 -137.479349) (xy 114.726357 -137.529846)
			(xy 114.695584 -137.576359) (xy 114.658367 -137.617896) (xy 114.615499 -137.653571) (xy 114.567893 -137.682625)
			(xy 114.516564 -137.704437) (xy 114.462607 -137.718543) (xy 114.40717 -137.724643) (xy 114.351436 -137.722606)
			(xy 114.296593 -137.712476) (xy 114.243809 -137.694469) (xy 114.194209 -137.668968) (xy 114.148851 -137.636517)
			(xy 114.108702 -137.597808) (xy 114.074616 -137.553665) (xy 114.04732 -137.50503) (xy 114.027397 -137.452939)
			(xy 114.015271 -137.398502) (xy 114.0112 -137.34288) (xy 111.029641 -137.34288) (xy 111.00308 -137.373868)
			(xy 111.00308 -138.388852) (xy 110.41126 -138.980672) (xy 109.357414 -138.980672) (xy 109.335517 -138.981137)
			(xy 109.292372 -138.988657) (xy 109.251155 -139.003459) (xy 109.213083 -139.025105) (xy 109.179285 -139.052956)
			(xy 109.150759 -139.086186) (xy 109.128349 -139.123814) (xy 109.11272 -139.164725) (xy 109.104332 -139.207709)
			(xy 109.103414 -139.229592) (xy 109.102444 -139.256586) (xy 109.093834 -139.309911) (xy 109.07779 -139.361488)
			(xy 109.054633 -139.410287) (xy 109.024826 -139.455333) (xy 108.988964 -139.495726) (xy 108.947764 -139.530657)
			(xy 108.90205 -139.559429) (xy 108.852735 -139.581467) (xy 108.800805 -139.596331) (xy 108.795021 -139.59713)
			(xy 112.079784 -139.59713) (xy 112.083855 -139.541508) (xy 112.095981 -139.487071) (xy 112.115904 -139.43498)
			(xy 112.1432 -139.386345) (xy 112.177286 -139.342202) (xy 112.217435 -139.303493) (xy 112.262793 -139.271042)
			(xy 112.312393 -139.245541) (xy 112.365177 -139.227534) (xy 112.42002 -139.217404) (xy 112.475754 -139.215367)
			(xy 112.531191 -139.221467) (xy 112.585148 -139.235573) (xy 112.636477 -139.257385) (xy 112.684083 -139.286439)
			(xy 112.726951 -139.322114) (xy 112.764168 -139.363651) (xy 112.794941 -139.410164) (xy 112.818613 -139.460661)
			(xy 112.834681 -139.514068) (xy 112.842801 -139.569244) (xy 112.84331 -139.59713) (xy 112.842801 -139.625016)
			(xy 112.834681 -139.680192) (xy 112.818613 -139.733599) (xy 112.794941 -139.784096) (xy 112.764168 -139.830609)
			(xy 112.726951 -139.872146) (xy 112.684083 -139.907821) (xy 112.636477 -139.936875) (xy 112.585148 -139.958687)
			(xy 112.531191 -139.972793) (xy 112.475754 -139.978893) (xy 112.42002 -139.976856) (xy 112.365177 -139.966726)
			(xy 112.312393 -139.948719) (xy 112.262793 -139.923218) (xy 112.217435 -139.890767) (xy 112.177286 -139.852058)
			(xy 112.1432 -139.807915) (xy 112.115904 -139.75928) (xy 112.095981 -139.707189) (xy 112.083855 -139.652752)
			(xy 112.079784 -139.59713) (xy 108.795021 -139.59713) (xy 108.747299 -139.603722) (xy 108.693284 -139.603494)
			(xy 108.639841 -139.595651) (xy 108.588039 -139.58035) (xy 108.538912 -139.557897) (xy 108.493442 -139.528739)
			(xy 108.452539 -139.493461) (xy 108.417019 -139.452768) (xy 108.387593 -139.407472) (xy 108.364849 -139.358478)
			(xy 108.349241 -139.306768) (xy 108.344716 -139.280138) (xy 108.340881 -139.258399) (xy 108.326719 -139.216594)
			(xy 108.305561 -139.177858) (xy 108.278039 -139.14335) (xy 108.244978 -139.114106) (xy 108.20737 -139.091001)
			(xy 108.16634 -139.074728) (xy 108.144818 -139.069826) (xy 108.118368 -139.063931) (xy 108.067352 -139.045662)
			(xy 108.019441 -139.020346) (xy 107.997244 -139.004802) (xy 107.963716 -138.980672) (xy 107.675426 -138.980672)
			(xy 107.653461 -138.981168) (xy 107.610193 -138.98878) (xy 107.568877 -139.003715) (xy 107.530742 -139.025526)
			(xy 107.496922 -139.053566) (xy 107.468424 -139.087001) (xy 107.446094 -139.124835) (xy 107.430598 -139.165943)
			(xy 107.425998 -139.187428) (xy 107.42034 -139.214655) (xy 107.402189 -139.267219) (xy 107.376599 -139.31659)
			(xy 107.344114 -139.361724) (xy 107.30542 -139.401664) (xy 107.261339 -139.435563) (xy 107.212804 -139.462705)
			(xy 107.160842 -139.482513) (xy 107.106556 -139.494568) (xy 107.051094 -139.498615) (xy 106.995632 -139.494568)
			(xy 106.941346 -139.482513) (xy 106.889384 -139.462705) (xy 106.840849 -139.435563) (xy 106.796768 -139.401664)
			(xy 106.758074 -139.361724) (xy 106.725589 -139.31659) (xy 106.699999 -139.267219) (xy 106.681848 -139.214655)
			(xy 106.67619 -139.187428) (xy 106.671657 -139.165918) (xy 106.656194 -139.124773) (xy 106.633879 -139.086905)
			(xy 106.605378 -139.053443) (xy 106.571542 -139.025387) (xy 106.533382 -139.003574) (xy 106.492036 -138.988657)
			(xy 106.448739 -138.98108) (xy 106.426762 -138.980672) (xy 106.251502 -138.980672) (xy 106.177842 -139.052046)
			(xy 106.176064 -139.103608) (xy 106.174646 -139.131519) (xy 106.164655 -139.186505) (xy 106.146749 -139.239444)
			(xy 106.121311 -139.289205) (xy 106.088884 -139.334721) (xy 106.050164 -139.375019) (xy 106.005978 -139.409236)
			(xy 105.957272 -139.43664) (xy 105.905089 -139.456644) (xy 105.850546 -139.46882) (xy 105.79481 -139.472908)
			(xy 105.739074 -139.46882) (xy 105.684531 -139.456644) (xy 105.632348 -139.43664) (xy 105.583642 -139.409236)
			(xy 105.539456 -139.375019) (xy 105.500736 -139.334721) (xy 105.468309 -139.289205) (xy 105.442871 -139.239444)
			(xy 105.424965 -139.186505) (xy 105.414974 -139.131519) (xy 105.413556 -139.103608) (xy 105.412542 -139.087314)
			(xy 105.403265 -139.056023) (xy 105.386347 -139.028114) (xy 105.362897 -139.005415) (xy 105.334451 -138.989416)
			(xy 105.302875 -138.981164) (xy 105.286556 -138.980672) (xy 103.38562 -138.980672) (xy 103.368969 -138.981213)
			(xy 103.336799 -138.989827) (xy 103.307955 -139.006473) (xy 103.284402 -139.030017) (xy 103.267745 -139.058855)
			(xy 103.259119 -139.091021) (xy 103.25862 -139.107672) (xy 103.25862 -140.053822) (xy 103.26116 -140.066268)
			(xy 103.264208 -140.082524) (xy 103.270812 -140.122402) (xy 103.48722 -140.33881) (xy 103.48722 -141.409166)
			(xy 106.522264 -141.409166) (xy 106.526335 -141.353544) (xy 106.538461 -141.299107) (xy 106.558384 -141.247016)
			(xy 106.58568 -141.198381) (xy 106.619766 -141.154238) (xy 106.659915 -141.115529) (xy 106.705273 -141.083078)
			(xy 106.754873 -141.057577) (xy 106.807657 -141.03957) (xy 106.8625 -141.02944) (xy 106.918234 -141.027403)
			(xy 106.973671 -141.033503) (xy 107.027628 -141.047609) (xy 107.078957 -141.069421) (xy 107.126563 -141.098475)
			(xy 107.169431 -141.13415) (xy 107.206648 -141.175687) (xy 107.237421 -141.2222) (xy 107.261093 -141.272697)
			(xy 107.277161 -141.326104) (xy 107.284862 -141.378432) (xy 109.128812 -141.378432) (xy 109.132883 -141.32281)
			(xy 109.145009 -141.268373) (xy 109.164932 -141.216282) (xy 109.192228 -141.167647) (xy 109.226314 -141.123504)
			(xy 109.266463 -141.084795) (xy 109.311821 -141.052344) (xy 109.361421 -141.026843) (xy 109.414205 -141.008836)
			(xy 109.469048 -140.998706) (xy 109.524782 -140.996669) (xy 109.580219 -141.002769) (xy 109.634176 -141.016875)
			(xy 109.685505 -141.038687) (xy 109.733111 -141.067741) (xy 109.775979 -141.103416) (xy 109.813196 -141.144953)
			(xy 109.843969 -141.191466) (xy 109.867641 -141.241963) (xy 109.883709 -141.29537) (xy 109.888283 -141.326448)
			(xy 110.827472 -141.326448) (xy 110.830503 -141.270521) (xy 110.841679 -141.215639) (xy 110.86076 -141.162981)
			(xy 110.887336 -141.113679) (xy 110.920835 -141.068793) (xy 110.960538 -141.029288) (xy 111.005591 -140.996013)
			(xy 111.055025 -140.969684) (xy 111.107778 -140.950866) (xy 111.162715 -140.939965) (xy 111.218656 -140.937213)
			(xy 111.274398 -140.942671) (xy 111.328743 -140.956222) (xy 111.380522 -140.977573) (xy 111.428622 -141.006267)
			(xy 111.450628 -141.023594) (xy 111.467907 -141.03712) (xy 111.506176 -141.058587) (xy 111.547562 -141.073163)
			(xy 111.590838 -141.080413) (xy 111.634715 -141.080123) (xy 111.677891 -141.072301) (xy 111.719082 -141.057179)
			(xy 111.757063 -141.035208) (xy 111.790706 -141.00704) (xy 111.805212 -140.990574) (xy 111.823647 -140.969491)
			(xy 111.865639 -140.932435) (xy 111.912598 -140.901919) (xy 111.963514 -140.878596) (xy 112.017293 -140.862969)
			(xy 112.07278 -140.855374) (xy 112.12878 -140.855974) (xy 112.184091 -140.864756) (xy 112.237523 -140.881531)
			(xy 112.287929 -140.905939) (xy 112.334223 -140.937454) (xy 112.375412 -140.975401) (xy 112.410609 -141.018962)
			(xy 112.439059 -141.067201) (xy 112.460149 -141.119082) (xy 112.473426 -141.173489) (xy 112.478605 -141.229253)
			(xy 112.475575 -141.285174) (xy 112.4644 -141.340052) (xy 112.445321 -141.392706) (xy 112.418748 -141.442004)
			(xy 112.385252 -141.486886) (xy 112.345553 -141.526389) (xy 112.300505 -141.559662) (xy 112.251076 -141.58599)
			(xy 112.198329 -141.604808) (xy 112.143396 -141.615711) (xy 112.08746 -141.618464) (xy 112.031723 -141.613008)
			(xy 111.977382 -141.599462) (xy 111.925607 -141.578115) (xy 111.877509 -141.549427) (xy 111.855504 -141.532102)
			(xy 111.838199 -141.518611) (xy 111.799936 -141.497142) (xy 111.758554 -141.482564) (xy 111.715283 -141.475311)
			(xy 111.67141 -141.475597) (xy 111.628237 -141.483414) (xy 111.587049 -141.49853) (xy 111.549069 -141.520496)
			(xy 111.515426 -141.548659) (xy 111.50092 -141.565122) (xy 111.482486 -141.586209) (xy 111.440493 -141.62327)
			(xy 111.393531 -141.653792) (xy 111.342612 -141.677119) (xy 111.288828 -141.69275) (xy 111.233338 -141.700348)
			(xy 111.177332 -141.699751) (xy 111.122016 -141.69097) (xy 111.068579 -141.674195) (xy 111.018168 -141.649787)
			(xy 110.971869 -141.618269) (xy 110.930676 -141.580321) (xy 110.895475 -141.536756) (xy 110.867022 -141.488513)
			(xy 110.84593 -141.436628) (xy 110.832651 -141.382216) (xy 110.827472 -141.326448) (xy 109.888283 -141.326448)
			(xy 109.891829 -141.350546) (xy 109.892338 -141.378432) (xy 109.891829 -141.406318) (xy 109.883709 -141.461494)
			(xy 109.867641 -141.514901) (xy 109.843969 -141.565398) (xy 109.813196 -141.611911) (xy 109.775979 -141.653448)
			(xy 109.733111 -141.689123) (xy 109.685505 -141.718177) (xy 109.634176 -141.739989) (xy 109.580219 -141.754095)
			(xy 109.524782 -141.760195) (xy 109.469048 -141.758158) (xy 109.414205 -141.748028) (xy 109.361421 -141.730021)
			(xy 109.311821 -141.70452) (xy 109.266463 -141.672069) (xy 109.226314 -141.63336) (xy 109.192228 -141.589217)
			(xy 109.164932 -141.540582) (xy 109.145009 -141.488491) (xy 109.132883 -141.434054) (xy 109.128812 -141.378432)
			(xy 107.284862 -141.378432) (xy 107.285281 -141.38128) (xy 107.28579 -141.409166) (xy 107.285281 -141.437052)
			(xy 107.277161 -141.492228) (xy 107.261093 -141.545635) (xy 107.237421 -141.596132) (xy 107.206648 -141.642645)
			(xy 107.169431 -141.684182) (xy 107.126563 -141.719857) (xy 107.078957 -141.748911) (xy 107.027628 -141.770723)
			(xy 106.973671 -141.784829) (xy 106.918234 -141.790929) (xy 106.8625 -141.788892) (xy 106.807657 -141.778762)
			(xy 106.754873 -141.760755) (xy 106.705273 -141.735254) (xy 106.659915 -141.702803) (xy 106.619766 -141.664094)
			(xy 106.58568 -141.619951) (xy 106.558384 -141.571316) (xy 106.538461 -141.519225) (xy 106.526335 -141.464788)
			(xy 106.522264 -141.409166) (xy 103.48722 -141.409166) (xy 103.48722 -142.436088) (xy 103.636572 -142.58544)
			(xy 113.409476 -142.58544)
		)
		(stroke
			(width 0)
			(type solid)
		)
		(fill yes)
		(layer "In7.Cu")
		(net "AGND_PVCCP_NODE1")
	)
	(gr_poly
		(pts
			(xy 51.245516 -83.707732) (xy 51.245516 -82.901536) (xy 51.244278 -82.878794) (xy 51.234732 -82.834265)
			(xy 51.217406 -82.792149) (xy 51.192857 -82.753791) (xy 51.161868 -82.72042) (xy 51.125431 -82.693102)
			(xy 51.08471 -82.672711) (xy 51.041009 -82.659898) (xy 50.995725 -82.655074) (xy 50.972974 -82.656172)
			(xy 50.945364 -82.657687) (xy 50.890213 -82.653694) (xy 50.836217 -82.641781) (xy 50.784507 -82.622196)
			(xy 50.736166 -82.595351) (xy 50.692207 -82.561809) (xy 50.653551 -82.52227) (xy 50.621009 -82.477566)
			(xy 50.595262 -82.428631) (xy 50.57685 -82.376492) (xy 50.566159 -82.32224) (xy 50.563412 -82.267014)
			(xy 50.568667 -82.211969) (xy 50.581814 -82.15826) (xy 50.602578 -82.107012) (xy 50.616104 -82.082894)
			(xy 50.624297 -82.067804) (xy 50.63313 -82.034636) (xy 50.632797 -82.000314) (xy 50.623323 -81.967324)
			(xy 50.605394 -81.938056) (xy 50.593244 -81.925922) (xy 50.573786 -81.907084) (xy 50.53985 -81.864877)
			(xy 50.512224 -81.818296) (xy 50.491463 -81.768276) (xy 50.477983 -81.715822) (xy 50.472055 -81.66199)
			(xy 50.4738 -81.607861) (xy 50.483181 -81.554522) (xy 50.50001 -81.503045) (xy 50.52395 -81.454466)
			(xy 50.554518 -81.40976) (xy 50.5911 -81.369826) (xy 50.632962 -81.335465) (xy 50.679263 -81.30737)
			(xy 50.72907 -81.286104) (xy 50.781385 -81.272095) (xy 50.835154 -81.265624) (xy 50.889299 -81.266822)
			(xy 50.916078 -81.270856) (xy 50.937895 -81.273985) (xy 50.981963 -81.273563) (xy 51.025297 -81.265543)
			(xy 51.066597 -81.250166) (xy 51.104624 -81.227894) (xy 51.138238 -81.199393) (xy 51.16643 -81.165521)
			(xy 51.188354 -81.127291) (xy 51.203353 -81.085852) (xy 51.210976 -81.042447) (xy 51.21148 -81.020412)
			(xy 51.21148 -80.272128) (xy 51.207416 -80.25638) (xy 51.201702 -80.232854) (xy 51.195574 -80.184829)
			(xy 51.195571 -80.136414) (xy 51.201694 -80.088388) (xy 51.207416 -80.064864) (xy 51.21148 -80.049116)
			(xy 51.21148 -79.630016) (xy 51.232816 -79.60868) (xy 51.249834 -79.540354) (xy 51.23942 -79.506572)
			(xy 51.231922 -79.480568) (xy 51.223495 -79.427109) (xy 51.222706 -79.372996) (xy 51.229572 -79.319315)
			(xy 51.243956 -79.267143) (xy 51.265568 -79.217526) (xy 51.293974 -79.171462) (xy 51.328605 -79.129875)
			(xy 51.368766 -79.093598) (xy 51.41365 -79.063362) (xy 51.462356 -79.039771) (xy 51.513908 -79.0233)
			(xy 51.56727 -79.01428) (xy 51.621371 -79.012891) (xy 51.675125 -79.019161) (xy 51.727454 -79.032965)
			(xy 51.777306 -79.054025) (xy 51.823683 -79.081919) (xy 51.844956 -79.098648) (xy 51.861894 -79.111891)
			(xy 51.899303 -79.133075) (xy 51.939747 -79.147652) (xy 51.98207 -79.155205) (xy 52.02506 -79.155516)
			(xy 52.067487 -79.148578) (xy 52.108139 -79.134589) (xy 52.145851 -79.113949) (xy 52.162964 -79.100934)
			(xy 52.185746 -79.08354) (xy 52.235487 -79.055062) (xy 52.288928 -79.034343) (xy 52.344866 -79.021847)
			(xy 52.402043 -79.017855) (xy 52.459175 -79.022458) (xy 52.514976 -79.035551) (xy 52.568192 -79.056841)
			(xy 52.617626 -79.085848) (xy 52.64023 -79.103474) (xy 52.657304 -79.116736) (xy 52.695024 -79.137855)
			(xy 52.735775 -79.152282) (xy 52.778381 -79.159601) (xy 52.821611 -79.159601) (xy 52.864217 -79.152282)
			(xy 52.904968 -79.137855) (xy 52.942688 -79.116736) (xy 52.959762 -79.103474) (xy 52.981123 -79.08677)
			(xy 53.027656 -79.05893) (xy 53.077662 -79.037959) (xy 53.130134 -79.024282) (xy 53.184014 -79.018172)
			(xy 53.238216 -79.019754) (xy 53.291648 -79.028996) (xy 53.343233 -79.04571) (xy 53.391932 -79.069561)
			(xy 53.436762 -79.100068) (xy 53.47682 -79.136616) (xy 53.511299 -79.178467) (xy 53.539504 -79.22478)
			(xy 53.560867 -79.27462) (xy 53.574957 -79.326982) (xy 53.58149 -79.380813) (xy 53.580334 -79.435026)
			(xy 53.576474 -79.461868) (xy 53.573342 -79.483697) (xy 53.573768 -79.52779) (xy 53.5818 -79.571147)
			(xy 53.597197 -79.612466) (xy 53.619498 -79.650506) (xy 53.648033 -79.684123) (xy 53.681943 -79.712309)
			(xy 53.720211 -79.734217) (xy 53.761687 -79.749187) (xy 53.805124 -79.756772) (xy 53.827172 -79.75727)
			(xy 54.63286 -79.75727) (xy 54.937152 -80.061562) (xy 55.818786 -80.061562) (xy 56.110378 -79.76997)
			(xy 56.110378 -79.650844) (xy 56.087518 -79.618078) (xy 56.070264 -79.592321) (xy 56.043456 -79.536424)
			(xy 56.026053 -79.476925) (xy 56.018513 -79.415392) (xy 56.019192 -79.384398) (xy 56.019192 -79.380588)
			(xy 56.019047 -79.363446) (xy 56.010716 -79.330207) (xy 55.993823 -79.300394) (xy 55.982108 -79.287878)
			(xy 55.76316 -79.06893) (xy 55.398416 -79.06893) (xy 55.187088 -78.857602) (xy 55.187088 -77.439266)
			(xy 55.30723 -77.319124) (xy 55.623206 -77.319124) (xy 55.639889 -77.318624) (xy 55.672113 -77.309967)
			(xy 55.700988 -77.293247) (xy 55.713122 -77.281786) (xy 55.836566 -77.158088) (xy 55.836566 -76.865988)
			(xy 55.693056 -76.722478) (xy 55.360062 -76.722478) (xy 55.244492 -76.606908) (xy 55.244492 -76.43876)
			(xy 55.216044 -76.410312) (xy 55.216044 -75.72248) (xy 55.701946 -75.236578) (xy 55.701946 -72.052688)
			(xy 55.439564 -71.790306) (xy 52.017168 -71.790306) (xy 52.017168 -71.298054) (xy 51.852322 -71.133208)
			(xy 50.265076 -71.133208) (xy 50.0761 -71.322184) (xy 50.0761 -73.007221) (xy 51.21774 -73.007221)
			(xy 51.220655 -72.951299) (xy 51.231712 -72.896404) (xy 51.250672 -72.843714) (xy 51.277128 -72.794361)
			(xy 51.310513 -72.749403) (xy 51.350109 -72.709808) (xy 51.395067 -72.676424) (xy 51.444421 -72.649968)
			(xy 51.497112 -72.63101) (xy 51.552007 -72.619954) (xy 51.607929 -72.617041) (xy 51.663675 -72.62233)
			(xy 51.718051 -72.63571) (xy 51.769887 -72.656893) (xy 51.818071 -72.685423) (xy 51.84013 -72.702674)
			(xy 51.857204 -72.715936) (xy 51.894924 -72.737055) (xy 51.935675 -72.751482) (xy 51.978281 -72.758801)
			(xy 52.021511 -72.758801) (xy 52.064117 -72.751482) (xy 52.104868 -72.737055) (xy 52.142588 -72.715936)
			(xy 52.159662 -72.702674) (xy 52.182444 -72.684892) (xy 52.232312 -72.655686) (xy 52.286013 -72.634334)
			(xy 52.342321 -72.621324) (xy 52.399946 -72.616955) (xy 52.457571 -72.621324) (xy 52.513879 -72.634334)
			(xy 52.56758 -72.655686) (xy 52.617448 -72.684892) (xy 52.64023 -72.702674) (xy 52.657304 -72.715936)
			(xy 52.695024 -72.737055) (xy 52.735775 -72.751482) (xy 52.778381 -72.758801) (xy 52.821611 -72.758801)
			(xy 52.864217 -72.751482) (xy 52.904968 -72.737055) (xy 52.942688 -72.715936) (xy 52.959762 -72.702674)
			(xy 52.982544 -72.684892) (xy 53.032412 -72.655686) (xy 53.086113 -72.634334) (xy 53.142421 -72.621324)
			(xy 53.200046 -72.616955) (xy 53.257671 -72.621324) (xy 53.313979 -72.634334) (xy 53.36768 -72.655686)
			(xy 53.417548 -72.684892) (xy 53.44033 -72.702674) (xy 53.457404 -72.715936) (xy 53.495124 -72.737055)
			(xy 53.535875 -72.751482) (xy 53.578481 -72.758801) (xy 53.621711 -72.758801) (xy 53.664317 -72.751482)
			(xy 53.705068 -72.737055) (xy 53.742788 -72.715936) (xy 53.759862 -72.702674) (xy 53.781433 -72.685781)
			(xy 53.828495 -72.657726) (xy 53.879087 -72.636692) (xy 53.932166 -72.623109) (xy 53.986643 -72.617259)
			(xy 54.041396 -72.61926) (xy 54.0953 -72.629072) (xy 54.147246 -72.646493) (xy 54.196167 -72.671164)
			(xy 54.241056 -72.70258) (xy 54.28099 -72.740092) (xy 54.315148 -72.782931) (xy 54.342827 -72.830215)
			(xy 54.363459 -72.880971) (xy 54.376619 -72.934157) (xy 54.382036 -72.988679) (xy 54.3796 -73.043414)
			(xy 54.36936 -73.097239) (xy 54.351526 -73.149045) (xy 54.326467 -73.197768) (xy 54.294696 -73.242405)
			(xy 54.256867 -73.28204) (xy 54.235604 -73.29932) (xy 54.222963 -73.309836) (xy 54.203179 -73.336089)
			(xy 54.190759 -73.366526) (xy 54.186531 -73.399126) (xy 54.190773 -73.431725) (xy 54.203204 -73.462157)
			(xy 54.223 -73.488401) (xy 54.235604 -73.498964) (xy 54.24043 -73.502774) (xy 54.257504 -73.516036)
			(xy 54.295224 -73.537155) (xy 54.335975 -73.551582) (xy 54.378581 -73.558901) (xy 54.421811 -73.558901)
			(xy 54.464417 -73.551582) (xy 54.505168 -73.537155) (xy 54.542888 -73.516036) (xy 54.559962 -73.502774)
			(xy 54.581532 -73.485959) (xy 54.628502 -73.457945) (xy 54.67899 -73.436925) (xy 54.731962 -73.423329)
			(xy 54.786334 -73.417437) (xy 54.840989 -73.419369) (xy 54.894808 -73.429086) (xy 54.946688 -73.446388)
			(xy 54.995567 -73.470921) (xy 55.040441 -73.502182) (xy 55.080391 -73.53953) (xy 55.114599 -73.582201)
			(xy 55.142363 -73.629318) (xy 55.163115 -73.679918) (xy 55.176428 -73.732962) (xy 55.182031 -73.787363)
			(xy 55.179809 -73.842008) (xy 55.169806 -73.895775) (xy 55.152228 -73.947562) (xy 55.127436 -73.996309)
			(xy 55.095937 -74.041016) (xy 55.058376 -74.080768) (xy 55.015525 -74.114748) (xy 54.96826 -74.142261)
			(xy 54.917551 -74.162744) (xy 54.864437 -74.175775) (xy 54.810006 -74.181089) (xy 54.755375 -74.178576)
			(xy 54.701662 -74.168287) (xy 54.649968 -74.150435) (xy 54.601354 -74.125383) (xy 54.556815 -74.093647)
			(xy 54.517264 -74.055876) (xy 54.500018 -74.03465) (xy 54.489456 -74.022051) (xy 54.463214 -74.002264)
			(xy 54.432787 -73.989841) (xy 54.400196 -73.985606) (xy 54.367605 -73.989841) (xy 54.337178 -74.002264)
			(xy 54.310936 -74.022051) (xy 54.300374 -74.03465) (xy 54.296564 -74.039476) (xy 54.283261 -74.05652)
			(xy 54.262143 -74.094246) (xy 54.247718 -74.135004) (xy 54.240403 -74.177615) (xy 54.240409 -74.22085)
			(xy 54.247735 -74.26346) (xy 54.26217 -74.304213) (xy 54.283297 -74.341935) (xy 54.296564 -74.359008)
			(xy 54.313461 -74.38052) (xy 54.341492 -74.427495) (xy 54.362528 -74.477992) (xy 54.376138 -74.530975)
			(xy 54.382042 -74.585359) (xy 54.380119 -74.640028) (xy 54.37041 -74.693862) (xy 54.353113 -74.745759)
			(xy 54.328582 -74.794653) (xy 54.29732 -74.839543) (xy 54.259969 -74.87951) (xy 54.217294 -74.913733)
			(xy 54.170168 -74.941511) (xy 54.119559 -74.962275) (xy 54.066504 -74.975599) (xy 54.012089 -74.981211)
			(xy 53.957431 -74.978995) (xy 53.90365 -74.968996) (xy 53.851847 -74.95142) (xy 53.803085 -74.926627)
			(xy 53.758363 -74.895125) (xy 53.718599 -74.85756) (xy 53.684605 -74.814701) (xy 53.657081 -74.767427)
			(xy 53.636589 -74.716707) (xy 53.62355 -74.663581) (xy 53.618231 -74.609137) (xy 53.62074 -74.554491)
			(xy 53.631028 -74.500764) (xy 53.648882 -74.449057) (xy 53.673937 -74.400429) (xy 53.705679 -74.355877)
			(xy 53.743457 -74.316315) (xy 53.764688 -74.299064) (xy 53.777245 -74.288455) (xy 53.797032 -74.262224)
			(xy 53.809458 -74.231808) (xy 53.813698 -74.199226) (xy 53.809471 -74.166642) (xy 53.797057 -74.136221)
			(xy 53.777282 -74.109982) (xy 53.764688 -74.09942) (xy 53.759862 -74.09561) (xy 53.742788 -74.082348)
			(xy 53.705068 -74.061229) (xy 53.664317 -74.046802) (xy 53.621711 -74.039483) (xy 53.578481 -74.039483)
			(xy 53.535875 -74.046802) (xy 53.495124 -74.061229) (xy 53.457404 -74.082348) (xy 53.44033 -74.09561)
			(xy 53.418651 -74.112594) (xy 53.371323 -74.140751) (xy 53.320439 -74.161814) (xy 53.267056 -74.175345)
			(xy 53.212282 -74.181062) (xy 53.157256 -74.178846) (xy 53.103119 -74.168745) (xy 53.050996 -74.150968)
			(xy 53.001969 -74.125883) (xy 52.957057 -74.094012) (xy 52.917193 -74.056017) (xy 52.899818 -74.03465)
			(xy 52.889256 -74.022051) (xy 52.863014 -74.002264) (xy 52.832587 -73.989841) (xy 52.799996 -73.985606)
			(xy 52.767405 -73.989841) (xy 52.736978 -74.002264) (xy 52.710736 -74.022051) (xy 52.700174 -74.03465)
			(xy 52.696364 -74.039476) (xy 52.683061 -74.05652) (xy 52.661943 -74.094246) (xy 52.647518 -74.135004)
			(xy 52.640203 -74.177615) (xy 52.640209 -74.22085) (xy 52.647535 -74.26346) (xy 52.66197 -74.304213)
			(xy 52.683097 -74.341935) (xy 52.696364 -74.359008) (xy 52.71413 -74.381733) (xy 52.743276 -74.43151)
			(xy 52.764599 -74.485107) (xy 52.777614 -74.541302) (xy 52.782024 -74.598815) (xy 52.77773 -74.656337)
			(xy 52.764828 -74.712558) (xy 52.743613 -74.766198) (xy 52.714568 -74.816034) (xy 52.696872 -74.838814)
			(xy 52.683561 -74.856025) (xy 52.662455 -74.89407) (xy 52.64813 -74.93515) (xy 52.641002 -74.97807)
			(xy 52.64128 -75.021576) (xy 52.648956 -75.0644) (xy 52.663806 -75.105295) (xy 52.685396 -75.143067)
			(xy 52.698904 -75.160124) (xy 52.716271 -75.181798) (xy 52.745088 -75.229278) (xy 52.766715 -75.280435)
			(xy 52.780694 -75.334188) (xy 52.786731 -75.3894) (xy 52.784697 -75.444903) (xy 52.774635 -75.499525)
			(xy 52.756759 -75.552111) (xy 52.731446 -75.601548) (xy 52.699231 -75.646791) (xy 52.660796 -75.686885)
			(xy 52.616953 -75.720981) (xy 52.568628 -75.748359) (xy 52.516845 -75.768439) (xy 52.462696 -75.780798)
			(xy 52.407328 -75.785173) (xy 52.351911 -75.781473) (xy 52.297616 -75.769775) (xy 52.245591 -75.750328)
			(xy 52.196936 -75.723541) (xy 52.152681 -75.689982) (xy 52.11376 -75.65036) (xy 52.080996 -75.605512)
			(xy 52.055082 -75.556387) (xy 52.036566 -75.504023) (xy 52.02584 -75.449528) (xy 52.023129 -75.394054)
			(xy 52.028493 -75.338772) (xy 52.041816 -75.284853) (xy 52.062817 -75.233436) (xy 52.091053 -75.185608)
			(xy 52.1081 -75.16368) (xy 52.121413 -75.146472) (xy 52.142513 -75.108425) (xy 52.156834 -75.067344)
			(xy 52.163958 -75.024425) (xy 52.16368 -74.98092) (xy 52.156005 -74.938096) (xy 52.141159 -74.897202)
			(xy 52.119573 -74.859428) (xy 52.106068 -74.84237) (xy 52.088832 -74.820677) (xy 52.060034 -74.773347)
			(xy 52.038389 -74.722348) (xy 52.024355 -74.668753) (xy 52.018226 -74.61369) (xy 52.020131 -74.558321)
			(xy 52.030031 -74.50381) (xy 52.047716 -74.451306) (xy 52.072815 -74.401915) (xy 52.104799 -74.356677)
			(xy 52.142994 -74.316545) (xy 52.164488 -74.299064) (xy 52.177045 -74.288455) (xy 52.196832 -74.262224)
			(xy 52.209258 -74.231808) (xy 52.213498 -74.199226) (xy 52.209271 -74.166642) (xy 52.196857 -74.136221)
			(xy 52.177082 -74.109982) (xy 52.164488 -74.09942) (xy 52.159662 -74.09561) (xy 52.142588 -74.082348)
			(xy 52.104868 -74.061229) (xy 52.064117 -74.046802) (xy 52.021511 -74.039483) (xy 51.978281 -74.039483)
			(xy 51.935675 -74.046802) (xy 51.894924 -74.061229) (xy 51.857204 -74.082348) (xy 51.84013 -74.09561)
			(xy 51.818042 -74.112817) (xy 51.769865 -74.141345) (xy 51.718037 -74.162525) (xy 51.663671 -74.175904)
			(xy 51.607932 -74.181193) (xy 51.552019 -74.178281) (xy 51.497132 -74.167228) (xy 51.44445 -74.148272)
			(xy 51.395103 -74.121821) (xy 51.350152 -74.088442) (xy 51.310562 -74.048852) (xy 51.277182 -74.003902)
			(xy 51.25073 -73.954555) (xy 51.231774 -73.901873) (xy 51.22072 -73.846986) (xy 51.217806 -73.791073)
			(xy 51.223095 -73.735335) (xy 51.236473 -73.680968) (xy 51.257653 -73.62914) (xy 51.28618 -73.580963)
			(xy 51.303428 -73.558908) (xy 51.316651 -73.541805) (xy 51.337775 -73.504092) (xy 51.352208 -73.463347)
			(xy 51.359533 -73.420746) (xy 51.359538 -73.37752) (xy 51.352224 -73.334917) (xy 51.337802 -73.294168)
			(xy 51.316688 -73.256449) (xy 51.303428 -73.239376) (xy 51.286119 -73.217365) (xy 51.257589 -73.16918)
			(xy 51.236408 -73.117343) (xy 51.223029 -73.062968) (xy 51.21774 -73.007221) (xy 50.0761 -73.007221)
			(xy 50.0761 -74.3331) (xy 50.118264 -74.396854) (xy 50.15357 -74.41184) (xy 50.17902 -74.423221)
			(xy 50.226596 -74.452282) (xy 50.269436 -74.487957) (xy 50.306628 -74.529488) (xy 50.337379 -74.575989)
			(xy 50.361035 -74.62647) (xy 50.377091 -74.679857) (xy 50.385207 -74.735013) (xy 50.385209 -74.790762)
			(xy 50.377097 -74.845918) (xy 50.361043 -74.899306) (xy 50.337391 -74.949789) (xy 50.306643 -74.996293)
			(xy 50.269454 -75.037826) (xy 50.226617 -75.073504) (xy 50.179043 -75.102567) (xy 50.15357 -75.113896)
			(xy 50.118264 -75.128882) (xy 50.0761 -75.192636) (xy 50.0761 -76.036932) (xy 51.059332 -76.036932)
			(xy 51.063403 -75.98131) (xy 51.075529 -75.926873) (xy 51.095452 -75.874782) (xy 51.122748 -75.826147)
			(xy 51.156834 -75.782004) (xy 51.196983 -75.743295) (xy 51.242341 -75.710844) (xy 51.291941 -75.685343)
			(xy 51.344725 -75.667336) (xy 51.399568 -75.657206) (xy 51.455302 -75.655169) (xy 51.510739 -75.661269)
			(xy 51.564696 -75.675375) (xy 51.616025 -75.697187) (xy 51.663631 -75.726241) (xy 51.706499 -75.761916)
			(xy 51.743716 -75.803453) (xy 51.774489 -75.849966) (xy 51.798161 -75.900463) (xy 51.814229 -75.95387)
			(xy 51.822349 -76.009046) (xy 51.822858 -76.036932) (xy 51.822349 -76.064818) (xy 51.814229 -76.119994)
			(xy 51.798161 -76.173401) (xy 51.774489 -76.223898) (xy 51.743716 -76.270411) (xy 51.706499 -76.311948)
			(xy 51.663631 -76.347623) (xy 51.616025 -76.376677) (xy 51.564696 -76.398489) (xy 51.510739 -76.412595)
			(xy 51.455302 -76.418695) (xy 51.399568 -76.416658) (xy 51.344725 -76.406528) (xy 51.291941 -76.388521)
			(xy 51.242341 -76.36302) (xy 51.196983 -76.330569) (xy 51.156834 -76.29186) (xy 51.122748 -76.247717)
			(xy 51.095452 -76.199082) (xy 51.075529 -76.146991) (xy 51.063403 -76.092554) (xy 51.059332 -76.036932)
			(xy 50.0761 -76.036932) (xy 50.0761 -76.468224) (xy 49.872138 -76.672186) (xy 49.852834 -76.719938)
			(xy 49.853342 -76.745846) (xy 49.853336 -76.773708) (xy 49.846225 -76.828968) (xy 49.831154 -76.882606)
			(xy 49.808443 -76.933483) (xy 49.778576 -76.980515) (xy 49.742186 -77.022705) (xy 49.700047 -77.059154)
			(xy 49.653056 -77.089089) (xy 49.602212 -77.111871) (xy 49.548595 -77.127018) (xy 49.493346 -77.134206)
			(xy 49.465484 -77.134212) (xy 49.46396 -77.134212) (xy 49.447122 -77.134566) (xy 49.414546 -77.143062)
			(xy 49.385332 -77.159795) (xy 49.373028 -77.171296) (xy 48.755094 -77.78923) (xy 52.018003 -77.78923)
			(xy 52.023542 -77.734043) (xy 52.037012 -77.680239) (xy 52.05813 -77.628953) (xy 52.086451 -77.581264)
			(xy 52.103528 -77.559408) (xy 52.116751 -77.542305) (xy 52.137875 -77.504592) (xy 52.152308 -77.463847)
			(xy 52.159633 -77.421246) (xy 52.159638 -77.37802) (xy 52.152324 -77.335417) (xy 52.137902 -77.294668)
			(xy 52.116788 -77.256949) (xy 52.103528 -77.239876) (xy 52.086451 -77.21802) (xy 52.05813 -77.170331)
			(xy 52.037012 -77.119045) (xy 52.023542 -77.065241) (xy 52.018003 -77.010054) (xy 52.020512 -76.954647)
			(xy 52.031017 -76.900186) (xy 52.049296 -76.847821) (xy 52.074964 -76.798653) (xy 52.107479 -76.75372)
			(xy 52.146158 -76.713967) (xy 52.190184 -76.680234) (xy 52.23863 -76.653229) (xy 52.290476 -76.633523)
			(xy 52.344628 -76.621531) (xy 52.399946 -76.617506) (xy 52.455264 -76.621531) (xy 52.509416 -76.633523)
			(xy 52.561262 -76.653229) (xy 52.609708 -76.680234) (xy 52.653734 -76.713967) (xy 52.692413 -76.75372)
			(xy 52.724928 -76.798653) (xy 52.750596 -76.847821) (xy 52.768875 -76.900186) (xy 52.77938 -76.954647)
			(xy 52.78146 -77.000587) (xy 53.617995 -77.000587) (xy 53.622249 -76.942731) (xy 53.635213 -76.886185)
			(xy 53.656588 -76.832254) (xy 53.68588 -76.78218) (xy 53.703728 -76.759308) (xy 53.716951 -76.742205)
			(xy 53.738075 -76.704492) (xy 53.752508 -76.663747) (xy 53.759833 -76.621146) (xy 53.759838 -76.57792)
			(xy 53.752524 -76.535317) (xy 53.738102 -76.494568) (xy 53.716988 -76.456849) (xy 53.703728 -76.439776)
			(xy 53.686651 -76.41792) (xy 53.65833 -76.370231) (xy 53.637212 -76.318945) (xy 53.623742 -76.265141)
			(xy 53.618203 -76.209954) (xy 53.620712 -76.154547) (xy 53.631217 -76.100086) (xy 53.649496 -76.047721)
			(xy 53.675164 -75.998553) (xy 53.707679 -75.95362) (xy 53.746358 -75.913867) (xy 53.790384 -75.880134)
			(xy 53.83883 -75.853129) (xy 53.890676 -75.833423) (xy 53.944828 -75.821431) (xy 54.000146 -75.817406)
			(xy 54.055464 -75.821431) (xy 54.109616 -75.833423) (xy 54.161462 -75.853129) (xy 54.209908 -75.880134)
			(xy 54.253934 -75.913867) (xy 54.292613 -75.95362) (xy 54.325128 -75.998553) (xy 54.350796 -76.047721)
			(xy 54.369075 -76.100086) (xy 54.37958 -76.154547) (xy 54.382089 -76.209954) (xy 54.37655 -76.265141)
			(xy 54.36308 -76.318945) (xy 54.341962 -76.370231) (xy 54.313641 -76.41792) (xy 54.296564 -76.439776)
			(xy 54.283261 -76.45682) (xy 54.262143 -76.494546) (xy 54.247718 -76.535304) (xy 54.240403 -76.577915)
			(xy 54.240409 -76.62115) (xy 54.247735 -76.66376) (xy 54.26217 -76.704513) (xy 54.283297 -76.742235)
			(xy 54.296564 -76.759308) (xy 54.314288 -76.782089) (xy 54.343487 -76.831874) (xy 54.364853 -76.88549)
			(xy 54.377898 -76.941712) (xy 54.382325 -76.999258) (xy 54.378031 -77.056814) (xy 54.365116 -77.113067)
			(xy 54.343875 -77.166732) (xy 54.314791 -77.216584) (xy 54.297072 -77.239368) (xy 54.28381 -77.256518)
			(xy 54.262702 -77.294381) (xy 54.248327 -77.335278) (xy 54.241103 -77.378022) (xy 54.241239 -77.421371)
			(xy 54.248732 -77.464068) (xy 54.263363 -77.504874) (xy 54.284708 -77.542604) (xy 54.298088 -77.559662)
			(xy 54.31532 -77.581428) (xy 54.34391 -77.629016) (xy 54.365302 -77.680245) (xy 54.379047 -77.734032)
			(xy 54.384853 -77.789244) (xy 54.382598 -77.844714) (xy 54.37233 -77.899272) (xy 54.354266 -77.951766)
			(xy 54.328787 -78.00109) (xy 54.29643 -78.046201) (xy 54.257878 -78.086148) (xy 54.213945 -78.120088)
			(xy 54.165559 -78.147304) (xy 54.113739 -78.167222) (xy 54.059581 -78.179423) (xy 54.004226 -78.183647)
			(xy 53.948843 -78.179807) (xy 53.894601 -78.167983) (xy 53.842645 -78.148424) (xy 53.79407 -78.121544)
			(xy 53.749903 -78.08791) (xy 53.711075 -78.048231) (xy 53.678406 -78.003346) (xy 53.652585 -77.9542)
			(xy 53.634157 -77.901832) (xy 53.623511 -77.847347) (xy 53.620871 -77.791894) (xy 53.626294 -77.736644)
			(xy 53.639665 -77.682762) (xy 53.660702 -77.631387) (xy 53.68896 -77.583601) (xy 53.706014 -77.561694)
			(xy 53.719313 -77.544571) (xy 53.74042 -77.506702) (xy 53.754792 -77.4658) (xy 53.762012 -77.423051)
			(xy 53.761871 -77.379697) (xy 53.754373 -77.336997) (xy 53.739734 -77.296189) (xy 53.718381 -77.258458)
			(xy 53.704998 -77.2414) (xy 53.687008 -77.218641) (xy 53.657457 -77.168719) (xy 53.635804 -77.114899)
			(xy 53.622548 -77.058421) (xy 53.617995 -77.000587) (xy 52.78146 -77.000587) (xy 52.781889 -77.010054)
			(xy 52.77635 -77.065241) (xy 52.76288 -77.119045) (xy 52.741762 -77.170331) (xy 52.713441 -77.21802)
			(xy 52.696364 -77.239876) (xy 52.683061 -77.25692) (xy 52.661943 -77.294646) (xy 52.647518 -77.335404)
			(xy 52.640203 -77.378015) (xy 52.640209 -77.42125) (xy 52.647535 -77.46386) (xy 52.66197 -77.504613)
			(xy 52.683097 -77.542335) (xy 52.696364 -77.559408) (xy 52.713441 -77.581264) (xy 52.741762 -77.628953)
			(xy 52.76288 -77.680239) (xy 52.77635 -77.734043) (xy 52.781889 -77.78923) (xy 52.77938 -77.844637)
			(xy 52.768875 -77.899098) (xy 52.750596 -77.951463) (xy 52.724928 -78.000631) (xy 52.692413 -78.045564)
			(xy 52.653734 -78.085317) (xy 52.609708 -78.11905) (xy 52.561262 -78.146055) (xy 52.509416 -78.165761)
			(xy 52.455264 -78.177753) (xy 52.399946 -78.181778) (xy 52.344628 -78.177753) (xy 52.290476 -78.165761)
			(xy 52.23863 -78.146055) (xy 52.190184 -78.11905) (xy 52.146158 -78.085317) (xy 52.107479 -78.045564)
			(xy 52.074964 -78.000631) (xy 52.049296 -77.951463) (xy 52.031017 -77.899098) (xy 52.020512 -77.844637)
			(xy 52.018003 -77.78923) (xy 48.755094 -77.78923) (xy 48.55972 -77.984604) (xy 48.55972 -78.407932)
			(xy 48.84681 -78.407932) (xy 48.848156 -78.352257) (xy 48.857584 -78.297369) (xy 48.874894 -78.244436)
			(xy 48.899717 -78.194582) (xy 48.931527 -78.148869) (xy 48.969646 -78.108267) (xy 49.013264 -78.07364)
			(xy 49.061454 -78.045725) (xy 49.113191 -78.025114) (xy 49.167376 -78.012246) (xy 49.222856 -78.007394)
			(xy 49.278451 -78.010662) (xy 49.332981 -78.021981) (xy 49.385285 -78.041108) (xy 49.434251 -78.067639)
			(xy 49.456848 -78.083918) (xy 49.47586 -78.097514) (xy 49.517743 -78.118246) (xy 49.562711 -78.130972)
			(xy 49.609248 -78.135262) (xy 49.655785 -78.130972) (xy 49.700753 -78.118246) (xy 49.742636 -78.097514)
			(xy 49.761648 -78.083918) (xy 49.784032 -78.067727) (xy 49.832554 -78.041317) (xy 49.884378 -78.022183)
			(xy 49.938421 -78.010726) (xy 49.993551 -78.007186) (xy 50.048615 -78.011635) (xy 50.102461 -78.023982)
			(xy 50.153963 -78.043969) (xy 50.202042 -78.071175) (xy 50.245694 -78.105034) (xy 50.284004 -78.144836)
			(xy 50.316172 -78.189748) (xy 50.341524 -78.238831) (xy 50.359529 -78.291058) (xy 50.365152 -78.318106)
			(xy 50.368413 -78.332939) (xy 50.380976 -78.360581) (xy 50.399721 -78.384467) (xy 50.423583 -78.403242)
			(xy 50.451209 -78.415839) (xy 50.481031 -78.421545) (xy 50.496216 -78.42123) (xy 50.523739 -78.420424)
			(xy 50.578553 -78.425576) (xy 50.632058 -78.438554) (xy 50.683141 -78.45909) (xy 50.730742 -78.486756)
			(xy 50.77387 -78.520978) (xy 50.81163 -78.561045) (xy 50.843238 -78.606124) (xy 50.868036 -78.65528)
			(xy 50.885511 -78.707489) (xy 50.895297 -78.761669) (xy 50.897193 -78.816693) (xy 50.891159 -78.871417)
			(xy 50.87732 -78.924706) (xy 50.855964 -78.975451) (xy 50.827534 -79.022599) (xy 50.792621 -79.065171)
			(xy 50.751951 -79.10228) (xy 50.706368 -79.133157) (xy 50.656819 -79.15716) (xy 50.604335 -79.173791)
			(xy 50.550004 -79.182703) (xy 50.494957 -79.183712) (xy 50.440337 -79.176796) (xy 50.387278 -79.1621)
			(xy 50.336884 -79.139929) (xy 50.2902 -79.110743) (xy 50.268886 -79.093314) (xy 50.250912 -79.078819)
			(xy 50.210879 -79.055822) (xy 50.167349 -79.040439) (xy 50.121756 -79.033176) (xy 50.075601 -79.034274)
			(xy 50.030405 -79.043694) (xy 49.987655 -79.061129) (xy 49.94876 -79.086002) (xy 49.915001 -79.117495)
			(xy 49.90084 -79.135732) (xy 49.884222 -79.157242) (xy 49.845965 -79.195849) (xy 49.802614 -79.228634)
			(xy 49.755049 -79.254933) (xy 49.704232 -79.274214) (xy 49.651193 -79.286087) (xy 49.597005 -79.29031)
			(xy 49.542767 -79.286798) (xy 49.489576 -79.275622) (xy 49.43851 -79.257009) (xy 49.390604 -79.231336)
			(xy 49.346827 -79.199122) (xy 49.308067 -79.161021) (xy 49.275107 -79.117803) (xy 49.248616 -79.070343)
			(xy 49.229131 -79.019605) (xy 49.217045 -78.966613) (xy 49.212604 -78.912443) (xy 49.21377 -78.885288)
			(xy 49.214293 -78.868132) (xy 49.20712 -78.834577) (xy 49.191268 -78.804144) (xy 49.167883 -78.779033)
			(xy 49.138654 -78.761057) (xy 49.12233 -78.755748) (xy 49.095729 -78.747499) (xy 49.045048 -78.724412)
			(xy 48.998263 -78.694201) (xy 48.956369 -78.657507) (xy 48.920256 -78.615111) (xy 48.890693 -78.567914)
			(xy 48.868307 -78.516919) (xy 48.853575 -78.463211) (xy 48.84681 -78.407932) (xy 48.55972 -78.407932)
			(xy 48.55972 -78.882494) (xy 48.95596 -79.278734) (xy 48.95596 -79.901034) (xy 48.956472 -79.924459)
			(xy 48.965012 -79.970524) (xy 48.981851 -80.014242) (xy 49.00642 -80.054133) (xy 49.037884 -80.088844)
			(xy 49.075179 -80.117199) (xy 49.117039 -80.138237) (xy 49.162046 -80.151244) (xy 49.208676 -80.155781)
			(xy 49.232058 -80.154272) (xy 49.25922 -80.152383) (xy 49.313584 -80.155397) (xy 49.366967 -80.166106)
			(xy 49.418287 -80.184292) (xy 49.466502 -80.209587) (xy 49.488852 -80.225138) (xy 49.503838 -80.23606)
			(xy 49.581562 -80.263238) (xy 49.661064 -80.23479) (xy 49.676304 -80.22336) (xy 49.69907 -80.206936)
			(xy 49.748449 -80.180237) (xy 49.801208 -80.161062) (xy 49.856207 -80.149823) (xy 49.912259 -80.146764)
			(xy 49.968154 -80.15195) (xy 50.022686 -80.16527) (xy 50.074678 -80.186436) (xy 50.123008 -80.21499)
			(xy 50.166633 -80.250318) (xy 50.204611 -80.291656) (xy 50.236122 -80.338112) (xy 50.260488 -80.388684)
			(xy 50.27718 -80.44228) (xy 50.28584 -80.497743) (xy 50.286281 -80.553876) (xy 50.278492 -80.609469)
			(xy 50.262643 -80.66332) (xy 50.239074 -80.714268) (xy 50.208296 -80.761213) (xy 50.170971 -80.803142)
			(xy 50.127906 -80.83915) (xy 50.08003 -80.868459) (xy 50.028377 -80.890438) (xy 49.97406 -80.904612)
			(xy 49.918254 -80.910675) (xy 49.862161 -80.908496) (xy 49.806992 -80.898122) (xy 49.753939 -80.879777)
			(xy 49.704147 -80.853857) (xy 49.68113 -80.837786) (xy 49.666144 -80.826864) (xy 49.58842 -80.799686)
			(xy 49.508918 -80.828134) (xy 49.493678 -80.839564) (xy 49.471097 -80.855843) (xy 49.422164 -80.882381)
			(xy 49.369893 -80.901525) (xy 49.315396 -80.912869) (xy 49.259828 -80.916173) (xy 49.232058 -80.91424)
			(xy 49.208679 -80.91274) (xy 49.162058 -80.917292) (xy 49.117061 -80.930309) (xy 49.07521 -80.95135)
			(xy 49.037924 -80.979704) (xy 49.006463 -81.01441) (xy 48.981895 -81.054292) (xy 48.965051 -81.098001)
			(xy 48.9565 -81.144056) (xy 48.95596 -81.167478) (xy 48.95596 -82.048858) (xy 48.956416 -82.07108)
			(xy 48.964145 -82.114847) (xy 48.979374 -82.156601) (xy 49.001639 -82.195066) (xy 49.03026 -82.229069)
			(xy 49.064362 -82.25757) (xy 49.102905 -82.279701) (xy 49.144711 -82.294784) (xy 49.166526 -82.299048)
			(xy 49.194174 -82.304341) (xy 49.24763 -82.32198) (xy 49.297914 -82.347283) (xy 49.343935 -82.3797)
			(xy 49.384693 -82.418526) (xy 49.419303 -82.46292) (xy 49.447015 -82.511918) (xy 49.467228 -82.564455)
			(xy 49.479501 -82.619392) (xy 49.483569 -82.675536) (xy 49.479343 -82.731669) (xy 49.466916 -82.786571)
			(xy 49.446556 -82.839052) (xy 49.418707 -82.887971) (xy 49.40173 -82.910426) (xy 49.387922 -82.928865)
			(xy 49.366513 -82.96965) (xy 49.352796 -83.013622) (xy 49.347221 -83.059346) (xy 49.349968 -83.105326)
			(xy 49.360949 -83.15006) (xy 49.379804 -83.192086) (xy 49.405917 -83.230031) (xy 49.421796 -83.246722)
			(xy 50.0761 -83.901026) (xy 51.052222 -83.901026)
		)
		(stroke
			(width 0)
			(type solid)
		)
		(fill yes)
		(layer "In7.Cu")
		(net "P1V5_NODE1")
	)
	(gr_poly
		(pts
			(xy 173.804072 -105.356152) (xy 173.826271 -105.355705) (xy 173.869996 -105.348004) (xy 173.911715 -105.332815)
			(xy 173.950156 -105.310601) (xy 173.984147 -105.282038) (xy 174.012651 -105.247999) (xy 174.034799 -105.20952)
			(xy 174.049917 -105.167775) (xy 174.057543 -105.124037) (xy 174.057444 -105.079639) (xy 174.054008 -105.057702)
			(xy 174.049664 -105.030651) (xy 174.047857 -104.975895) (xy 174.053898 -104.921443) (xy 174.067664 -104.868414)
			(xy 174.088872 -104.817899) (xy 174.117086 -104.770936) (xy 174.151726 -104.72849) (xy 174.192079 -104.691435)
			(xy 174.237317 -104.66053) (xy 174.286509 -104.636412) (xy 174.338644 -104.619577) (xy 174.392651 -104.61037)
			(xy 174.420022 -104.609138) (xy 174.436366 -104.608217) (xy 174.467792 -104.599089) (xy 174.49586 -104.582263)
			(xy 174.518721 -104.558849) (xy 174.534872 -104.530388) (xy 174.543248 -104.498754) (xy 174.54372 -104.482392)
			(xy 174.54372 -103.875078) (xy 174.543156 -103.857913) (xy 174.534006 -103.824826) (xy 174.516374 -103.79537)
			(xy 174.491534 -103.771675) (xy 174.46128 -103.755453) (xy 174.44466 -103.751126) (xy 174.418847 -103.744814)
			(xy 174.369147 -103.726007) (xy 174.322536 -103.700487) (xy 174.279917 -103.668748) (xy 174.242113 -103.631403)
			(xy 174.209856 -103.589174) (xy 174.183769 -103.542879) (xy 174.164357 -103.493412) (xy 174.151996 -103.44173)
			(xy 174.146924 -103.388834) (xy 174.14924 -103.335745) (xy 174.158898 -103.28349) (xy 174.166784 -103.258112)
			(xy 174.173482 -103.236375) (xy 174.17993 -103.191354) (xy 174.178268 -103.145904) (xy 174.168549 -103.101474)
			(xy 174.151082 -103.059481) (xy 174.126424 -103.021265) (xy 174.095363 -102.988043) (xy 174.058888 -102.960876)
			(xy 174.038768 -102.950264) (xy 174.013687 -102.937275) (xy 173.967319 -102.905025) (xy 173.926211 -102.866292)
			(xy 173.891262 -102.821923) (xy 173.863234 -102.772887) (xy 173.842741 -102.720255) (xy 173.830229 -102.665178)
			(xy 173.825973 -102.608858) (xy 173.830065 -102.552526) (xy 173.842416 -102.497412) (xy 173.862755 -102.444721)
			(xy 173.890639 -102.395603) (xy 173.925459 -102.351132) (xy 173.966453 -102.312279) (xy 174.012727 -102.279894)
			(xy 174.063269 -102.254683) (xy 174.116975 -102.237197) (xy 174.172671 -102.227819) (xy 174.229142 -102.226752)
			(xy 174.257208 -102.22992) (xy 174.27867 -102.232253) (xy 174.3218 -102.230459) (xy 174.364006 -102.221402)
			(xy 174.404075 -102.205342) (xy 174.440852 -102.182741) (xy 174.473281 -102.15425) (xy 174.500428 -102.120687)
			(xy 174.521512 -102.083019) (xy 174.535927 -102.04233) (xy 174.543257 -101.999789) (xy 174.54372 -101.978206)
			(xy 174.54372 -101.479096) (xy 174.543179 -101.462468) (xy 174.534583 -101.430343) (xy 174.517975 -101.401531)
			(xy 174.494484 -101.37799) (xy 174.465708 -101.361321) (xy 174.433601 -101.352656) (xy 174.416974 -101.352096)
			(xy 174.389781 -101.351526) (xy 174.335968 -101.343629) (xy 174.283822 -101.328168) (xy 174.2344 -101.305458)
			(xy 174.188705 -101.275959) (xy 174.147662 -101.24027) (xy 174.112105 -101.199113) (xy 174.082753 -101.153323)
			(xy 174.060202 -101.103829) (xy 174.044909 -101.051633) (xy 174.037184 -100.997795) (xy 174.037184 -100.943405)
			(xy 174.044909 -100.889567) (xy 174.060202 -100.837371) (xy 174.082753 -100.787877) (xy 174.112105 -100.742087)
			(xy 174.147662 -100.70093) (xy 174.188705 -100.66524) (xy 174.2344 -100.635742) (xy 174.283822 -100.613032)
			(xy 174.335968 -100.597571) (xy 174.389781 -100.589674) (xy 174.416974 -100.58908) (xy 174.433598 -100.588504)
			(xy 174.465698 -100.57984) (xy 174.494468 -100.563172) (xy 174.517952 -100.539634) (xy 174.534553 -100.510825)
			(xy 174.543143 -100.478705) (xy 174.54372 -100.46208) (xy 174.54372 -100.209096) (xy 174.543179 -100.192468)
			(xy 174.534583 -100.160343) (xy 174.517975 -100.131531) (xy 174.494484 -100.10799) (xy 174.465708 -100.091321)
			(xy 174.433601 -100.082656) (xy 174.416974 -100.082096) (xy 174.389781 -100.081526) (xy 174.335968 -100.073629)
			(xy 174.283822 -100.058168) (xy 174.2344 -100.035458) (xy 174.188705 -100.005959) (xy 174.147662 -99.97027)
			(xy 174.112105 -99.929113) (xy 174.082753 -99.883323) (xy 174.060202 -99.833829) (xy 174.044909 -99.781633)
			(xy 174.037184 -99.727795) (xy 174.037184 -99.673405) (xy 174.044909 -99.619567) (xy 174.060202 -99.567371)
			(xy 174.082753 -99.517877) (xy 174.112105 -99.472087) (xy 174.147662 -99.43093) (xy 174.188705 -99.39524)
			(xy 174.2344 -99.365742) (xy 174.283822 -99.343032) (xy 174.335968 -99.327571) (xy 174.389781 -99.319674)
			(xy 174.416974 -99.31908) (xy 174.433598 -99.318504) (xy 174.465698 -99.30984) (xy 174.494468 -99.293172)
			(xy 174.517952 -99.269634) (xy 174.534553 -99.240825) (xy 174.543143 -99.208705) (xy 174.54372 -99.19208)
			(xy 174.54372 -98.620834) (xy 174.516542 -98.566986) (xy 174.492158 -98.548952) (xy 174.470366 -98.53227)
			(xy 174.431342 -98.493683) (xy 174.398251 -98.449901) (xy 174.371777 -98.401829) (xy 174.352466 -98.350458)
			(xy 174.340717 -98.29685) (xy 174.336772 -98.242112) (xy 174.340714 -98.187373) (xy 174.352459 -98.133765)
			(xy 174.371767 -98.082393) (xy 174.398238 -98.034319) (xy 174.431326 -97.990535) (xy 174.470348 -97.951945)
			(xy 174.492158 -97.935288) (xy 174.503884 -97.926113) (xy 174.523067 -97.903353) (xy 174.536459 -97.87677)
			(xy 174.543333 -97.847809) (xy 174.54372 -97.832926) (xy 174.54372 -97.138744) (xy 174.543225 -97.122421)
			(xy 174.534951 -97.090842) (xy 174.518932 -97.062397) (xy 174.507906 -97.050352) (xy 174.489652 -97.030862)
			(xy 174.458215 -96.9877) (xy 174.433102 -96.940575) (xy 174.414805 -96.89041) (xy 174.403681 -96.838183)
			(xy 174.399947 -96.784916) (xy 174.403676 -96.731648) (xy 174.414796 -96.679421) (xy 174.433089 -96.629254)
			(xy 174.458198 -96.582127) (xy 174.489632 -96.538962) (xy 174.507906 -96.519492) (xy 174.518904 -96.507425)
			(xy 174.534928 -96.47899) (xy 174.54321 -96.447419) (xy 174.54372 -96.4311) (xy 174.54372 -87.681308)
			(xy 173.62424 -86.761828) (xy 168.520872 -86.761828) (xy 167.06342 -88.21928) (xy 163.027868 -88.21928)
			(xy 163.004432 -88.21982) (xy 162.958356 -88.228419) (xy 162.914638 -88.245321) (xy 162.874759 -88.269951)
			(xy 162.840073 -88.301475) (xy 162.811754 -88.338825) (xy 162.790762 -88.380733) (xy 162.777811 -88.42578)
			(xy 162.773337 -88.472437) (xy 162.777494 -88.519124) (xy 162.790141 -88.564258) (xy 162.810847 -88.606307)
			(xy 162.824414 -88.625426) (xy 162.84033 -88.647535) (xy 162.8664 -88.695366) (xy 162.8854 -88.74642)
			(xy 162.896944 -88.799658) (xy 162.900797 -88.853997) (xy 162.89688 -88.908331) (xy 162.885274 -88.961555)
			(xy 162.866213 -89.012586) (xy 162.840087 -89.060387) (xy 162.807426 -89.103985) (xy 162.768895 -89.142493)
			(xy 162.725278 -89.175129) (xy 162.677462 -89.201227) (xy 162.626419 -89.220257) (xy 162.573188 -89.231832)
			(xy 162.518852 -89.235717) (xy 162.464516 -89.231832) (xy 162.411285 -89.220257) (xy 162.360242 -89.201227)
			(xy 162.312426 -89.175129) (xy 162.268809 -89.142493) (xy 162.230278 -89.103985) (xy 162.197617 -89.060387)
			(xy 162.171491 -89.012586) (xy 162.15243 -88.961555) (xy 162.140824 -88.908331) (xy 162.136907 -88.853997)
			(xy 162.14076 -88.799658) (xy 162.152304 -88.74642) (xy 162.171304 -88.695366) (xy 162.197374 -88.647535)
			(xy 162.21329 -88.625426) (xy 162.226898 -88.606334) (xy 162.247616 -88.564282) (xy 162.260269 -88.519144)
			(xy 162.26443 -88.47245) (xy 162.259958 -88.425786) (xy 162.247003 -88.380733) (xy 162.226005 -88.33882)
			(xy 162.197678 -88.301469) (xy 162.16298 -88.269946) (xy 162.12309 -88.245321) (xy 162.079361 -88.228429)
			(xy 162.033275 -88.219844) (xy 162.009836 -88.21928) (xy 153.47442 -88.21928) (xy 152.199086 -89.494614)
			(xy 154.013152 -89.494614) (xy 154.017223 -89.438992) (xy 154.029349 -89.384555) (xy 154.049272 -89.332464)
			(xy 154.076568 -89.283829) (xy 154.110654 -89.239686) (xy 154.150803 -89.200977) (xy 154.196161 -89.168526)
			(xy 154.245761 -89.143025) (xy 154.298545 -89.125018) (xy 154.353388 -89.114888) (xy 154.409122 -89.112851)
			(xy 154.464559 -89.118951) (xy 154.518516 -89.133057) (xy 154.569845 -89.154869) (xy 154.617451 -89.183923)
			(xy 154.660319 -89.219598) (xy 154.697536 -89.261135) (xy 154.728309 -89.307648) (xy 154.751981 -89.358145)
			(xy 154.768049 -89.411552) (xy 154.776169 -89.466728) (xy 154.776678 -89.494614) (xy 154.776169 -89.5225)
			(xy 154.768049 -89.577676) (xy 154.751981 -89.631083) (xy 154.728309 -89.68158) (xy 154.697536 -89.728093)
			(xy 154.660319 -89.76963) (xy 154.617451 -89.805305) (xy 154.569845 -89.834359) (xy 154.518516 -89.856171)
			(xy 154.464559 -89.870277) (xy 154.409122 -89.876377) (xy 154.353388 -89.87434) (xy 154.298545 -89.86421)
			(xy 154.245761 -89.846203) (xy 154.196161 -89.820702) (xy 154.150803 -89.788251) (xy 154.110654 -89.749542)
			(xy 154.076568 -89.705399) (xy 154.049272 -89.656764) (xy 154.029349 -89.604673) (xy 154.017223 -89.550236)
			(xy 154.013152 -89.494614) (xy 152.199086 -89.494614) (xy 151.71674 -89.97696) (xy 151.71674 -90.123772)
			(xy 156.737556 -90.123772) (xy 156.741627 -90.06815) (xy 156.753753 -90.013713) (xy 156.773676 -89.961622)
			(xy 156.800972 -89.912987) (xy 156.835058 -89.868844) (xy 156.875207 -89.830135) (xy 156.920565 -89.797684)
			(xy 156.970165 -89.772183) (xy 157.022949 -89.754176) (xy 157.077792 -89.744046) (xy 157.133526 -89.742009)
			(xy 157.188963 -89.748109) (xy 157.24292 -89.762215) (xy 157.294249 -89.784027) (xy 157.341855 -89.813081)
			(xy 157.384723 -89.848756) (xy 157.42194 -89.890293) (xy 157.452713 -89.936806) (xy 157.476385 -89.987303)
			(xy 157.492453 -90.04071) (xy 157.500573 -90.095886) (xy 157.501082 -90.123772) (xy 157.500573 -90.151658)
			(xy 157.492453 -90.206834) (xy 157.476385 -90.260241) (xy 157.452713 -90.310738) (xy 157.42194 -90.357251)
			(xy 157.384723 -90.398788) (xy 157.341855 -90.434463) (xy 157.294249 -90.463517) (xy 157.24292 -90.485329)
			(xy 157.188963 -90.499435) (xy 157.133526 -90.505535) (xy 157.077792 -90.503498) (xy 157.022949 -90.493368)
			(xy 156.970165 -90.475361) (xy 156.920565 -90.44986) (xy 156.875207 -90.417409) (xy 156.835058 -90.3787)
			(xy 156.800972 -90.334557) (xy 156.773676 -90.285922) (xy 156.753753 -90.233831) (xy 156.741627 -90.179394)
			(xy 156.737556 -90.123772) (xy 151.71674 -90.123772) (xy 151.71674 -91.110308) (xy 152.213562 -91.110308)
			(xy 152.217633 -91.054686) (xy 152.229759 -91.000249) (xy 152.249682 -90.948158) (xy 152.276978 -90.899523)
			(xy 152.311064 -90.85538) (xy 152.351213 -90.816671) (xy 152.396571 -90.78422) (xy 152.446171 -90.758719)
			(xy 152.498955 -90.740712) (xy 152.553798 -90.730582) (xy 152.609532 -90.728545) (xy 152.664969 -90.734645)
			(xy 152.718926 -90.748751) (xy 152.770255 -90.770563) (xy 152.817861 -90.799617) (xy 152.860729 -90.835292)
			(xy 152.897946 -90.876829) (xy 152.928719 -90.923342) (xy 152.945875 -90.95994) (xy 163.705284 -90.95994)
			(xy 163.709355 -90.904318) (xy 163.721481 -90.849881) (xy 163.741404 -90.79779) (xy 163.7687 -90.749155)
			(xy 163.802786 -90.705012) (xy 163.842935 -90.666303) (xy 163.888293 -90.633852) (xy 163.937893 -90.608351)
			(xy 163.990677 -90.590344) (xy 164.04552 -90.580214) (xy 164.101254 -90.578177) (xy 164.156691 -90.584277)
			(xy 164.210648 -90.598383) (xy 164.261977 -90.620195) (xy 164.309583 -90.649249) (xy 164.352451 -90.684924)
			(xy 164.389668 -90.726461) (xy 164.420441 -90.772974) (xy 164.444113 -90.823471) (xy 164.460181 -90.876878)
			(xy 164.468301 -90.932054) (xy 164.46881 -90.95994) (xy 164.468301 -90.987826) (xy 164.460181 -91.043002)
			(xy 164.444113 -91.096409) (xy 164.420441 -91.146906) (xy 164.389668 -91.193419) (xy 164.352451 -91.234956)
			(xy 164.309583 -91.270631) (xy 164.261977 -91.299685) (xy 164.210648 -91.321497) (xy 164.156691 -91.335603)
			(xy 164.101254 -91.341703) (xy 164.04552 -91.339666) (xy 163.990677 -91.329536) (xy 163.937893 -91.311529)
			(xy 163.888293 -91.286028) (xy 163.842935 -91.253577) (xy 163.802786 -91.214868) (xy 163.7687 -91.170725)
			(xy 163.741404 -91.12209) (xy 163.721481 -91.069999) (xy 163.709355 -91.015562) (xy 163.705284 -90.95994)
			(xy 152.945875 -90.95994) (xy 152.952391 -90.973839) (xy 152.968459 -91.027246) (xy 152.976579 -91.082422)
			(xy 152.977088 -91.110308) (xy 152.976579 -91.138194) (xy 152.968459 -91.19337) (xy 152.952391 -91.246777)
			(xy 152.928719 -91.297274) (xy 152.897946 -91.343787) (xy 152.860897 -91.385136) (xy 155.027374 -91.385136)
			(xy 155.031445 -91.329514) (xy 155.043571 -91.275077) (xy 155.063494 -91.222986) (xy 155.09079 -91.174351)
			(xy 155.124876 -91.130208) (xy 155.165025 -91.091499) (xy 155.210383 -91.059048) (xy 155.259983 -91.033547)
			(xy 155.312767 -91.01554) (xy 155.36761 -91.00541) (xy 155.423344 -91.003373) (xy 155.478781 -91.009473)
			(xy 155.532738 -91.023579) (xy 155.584067 -91.045391) (xy 155.631673 -91.074445) (xy 155.674541 -91.11012)
			(xy 155.711758 -91.151657) (xy 155.742531 -91.19817) (xy 155.766203 -91.248667) (xy 155.782271 -91.302074)
			(xy 155.790391 -91.35725) (xy 155.7909 -91.385136) (xy 155.790391 -91.413022) (xy 155.782271 -91.468198)
			(xy 155.766203 -91.521605) (xy 155.742531 -91.572102) (xy 155.711758 -91.618615) (xy 155.674541 -91.660152)
			(xy 155.631673 -91.695827) (xy 155.584067 -91.724881) (xy 155.532738 -91.746693) (xy 155.478781 -91.760799)
			(xy 155.423344 -91.766899) (xy 155.36761 -91.764862) (xy 155.312767 -91.754732) (xy 155.259983 -91.736725)
			(xy 155.210383 -91.711224) (xy 155.165025 -91.678773) (xy 155.124876 -91.640064) (xy 155.09079 -91.595921)
			(xy 155.063494 -91.547286) (xy 155.043571 -91.495195) (xy 155.031445 -91.440758) (xy 155.027374 -91.385136)
			(xy 152.860897 -91.385136) (xy 152.860729 -91.385324) (xy 152.817861 -91.420999) (xy 152.770255 -91.450053)
			(xy 152.718926 -91.471865) (xy 152.664969 -91.485971) (xy 152.609532 -91.492071) (xy 152.553798 -91.490034)
			(xy 152.498955 -91.479904) (xy 152.446171 -91.461897) (xy 152.396571 -91.436396) (xy 152.351213 -91.403945)
			(xy 152.311064 -91.365236) (xy 152.276978 -91.321093) (xy 152.249682 -91.272458) (xy 152.229759 -91.220367)
			(xy 152.217633 -91.16593) (xy 152.213562 -91.110308) (xy 151.71674 -91.110308) (xy 151.71674 -92.627704)
			(xy 163.745416 -92.627704) (xy 163.749487 -92.572082) (xy 163.761613 -92.517645) (xy 163.781536 -92.465554)
			(xy 163.808832 -92.416919) (xy 163.842918 -92.372776) (xy 163.883067 -92.334067) (xy 163.928425 -92.301616)
			(xy 163.978025 -92.276115) (xy 164.030809 -92.258108) (xy 164.085652 -92.247978) (xy 164.141386 -92.245941)
			(xy 164.196823 -92.252041) (xy 164.25078 -92.266147) (xy 164.302109 -92.287959) (xy 164.349715 -92.317013)
			(xy 164.392583 -92.352688) (xy 164.4298 -92.394225) (xy 164.460573 -92.440738) (xy 164.484245 -92.491235)
			(xy 164.500313 -92.544642) (xy 164.508433 -92.599818) (xy 164.508942 -92.627704) (xy 164.508433 -92.65559)
			(xy 164.500313 -92.710766) (xy 164.484245 -92.764173) (xy 164.466775 -92.80144) (xy 166.229792 -92.80144)
			(xy 166.229792 -89.796112) (xy 171.984924 -89.796112) (xy 172.007976 -89.795676) (xy 172.053326 -89.787372)
			(xy 172.096434 -89.771024) (xy 172.135885 -89.747167) (xy 172.170386 -89.716585) (xy 172.198803 -89.68028)
			(xy 172.220205 -89.639445) (xy 172.233889 -89.595418) (xy 172.237146 -89.572592) (xy 172.241151 -89.544037)
			(xy 172.256654 -89.488501) (xy 172.28033 -89.435927) (xy 172.311641 -89.387511) (xy 172.330364 -89.365582)
			(xy 172.340921 -89.352812) (xy 172.355751 -89.323199) (xy 172.362453 -89.290766) (xy 172.360575 -89.257701)
			(xy 172.350245 -89.226235) (xy 172.332159 -89.198491) (xy 172.320204 -89.18702) (xy 172.299665 -89.167895)
			(xy 172.263872 -89.12467) (xy 172.234798 -89.076668) (xy 172.213071 -89.024924) (xy 172.19916 -88.970556)
			(xy 172.193364 -88.914735) (xy 172.195809 -88.858668) (xy 172.206442 -88.803565) (xy 172.225034 -88.750613)
			(xy 172.251183 -88.700957) (xy 172.284325 -88.655669) (xy 172.323745 -88.615724) (xy 172.368591 -88.581986)
			(xy 172.417897 -88.555183) (xy 172.470598 -88.535893) (xy 172.525557 -88.524532) (xy 172.581586 -88.521346)
			(xy 172.637478 -88.526403) (xy 172.692026 -88.539595) (xy 172.744053 -88.560636) (xy 172.792435 -88.589073)
			(xy 172.836129 -88.624291) (xy 172.874191 -88.665531) (xy 172.905801 -88.711903) (xy 172.930275 -88.762405)
			(xy 172.947086 -88.815948) (xy 172.955871 -88.871377) (xy 172.956441 -88.927494) (xy 172.948782 -88.98309)
			(xy 172.93306 -89.036963) (xy 172.909615 -89.087951) (xy 172.878953 -89.134955) (xy 172.860716 -89.156286)
			(xy 172.850091 -89.169003) (xy 172.83527 -89.198633) (xy 172.828579 -89.23108) (xy 172.83047 -89.264155)
			(xy 172.840814 -89.295629) (xy 172.858914 -89.323377) (xy 172.870876 -89.334848) (xy 172.891769 -89.354236)
			(xy 172.928027 -89.398215) (xy 172.957338 -89.4471) (xy 172.979051 -89.4998) (xy 172.992683 -89.555144)
			(xy 172.997931 -89.611901) (xy 172.994677 -89.668806) (xy 172.982993 -89.724594) (xy 172.963141 -89.778023)
			(xy 172.935562 -89.827905) (xy 172.900869 -89.873129) (xy 172.859834 -89.912689) (xy 172.813372 -89.945704)
			(xy 172.762514 -89.971441) (xy 172.708394 -89.989325) (xy 172.652216 -89.99896) (xy 172.623734 -90.000074)
			(xy 172.607332 -90.000943) (xy 172.57578 -90.010035) (xy 172.547593 -90.026877) (xy 172.524636 -90.050353)
			(xy 172.508428 -90.07891) (xy 172.500044 -90.110656) (xy 172.499528 -90.127074) (xy 172.499528 -92.80144)
			(xy 171.512484 -92.80144) (xy 171.488795 -92.801954) (xy 171.442235 -92.810719) (xy 171.398106 -92.82796)
			(xy 171.357936 -92.853081) (xy 171.323118 -92.885211) (xy 171.294857 -92.923237) (xy 171.274133 -92.965842)
			(xy 171.261663 -93.011549) (xy 171.259246 -93.03512) (xy 171.256612 -93.062874) (xy 171.244154 -93.117215)
			(xy 171.223919 -93.169164) (xy 171.196339 -93.217615) (xy 171.162001 -93.261537) (xy 171.121636 -93.299992)
			(xy 171.076105 -93.332164) (xy 171.026375 -93.357366) (xy 170.973507 -93.375063) (xy 170.918627 -93.384876)
			(xy 170.862903 -93.386597) (xy 170.807521 -93.38019) (xy 170.753662 -93.365791) (xy 170.702472 -93.343706)
			(xy 170.655041 -93.314407) (xy 170.612379 -93.278516) (xy 170.575396 -93.236798) (xy 170.544878 -93.190141)
			(xy 170.521475 -93.13954) (xy 170.505686 -93.086072) (xy 170.497847 -93.030875) (xy 170.498125 -92.975124)
			(xy 170.501818 -92.94749) (xy 170.503342 -92.938092) (xy 170.503342 -92.92844) (xy 170.502722 -92.911797)
			(xy 170.494118 -92.879642) (xy 170.477484 -92.850811) (xy 170.453955 -92.827266) (xy 170.425134 -92.810614)
			(xy 170.392985 -92.801988) (xy 170.376342 -92.80144) (xy 170.316398 -92.80144) (xy 170.257216 -92.836492)
			(xy 170.240198 -92.866718) (xy 170.226639 -92.890116) (xy 170.193935 -92.933184) (xy 170.155474 -92.971199)
			(xy 170.112028 -93.003399) (xy 170.06447 -93.02914) (xy 170.013752 -93.047904) (xy 169.960892 -93.059315)
			(xy 169.90695 -93.063144) (xy 169.853008 -93.059315) (xy 169.800148 -93.047904) (xy 169.74943 -93.02914)
			(xy 169.701872 -93.003399) (xy 169.658426 -92.971199) (xy 169.619965 -92.933184) (xy 169.587261 -92.890116)
			(xy 169.573702 -92.866718) (xy 169.556684 -92.836492) (xy 169.497502 -92.80144) (xy 169.192194 -92.80144)
			(xy 169.170507 -92.801882) (xy 169.127761 -92.809233) (xy 169.086885 -92.823738) (xy 169.049066 -92.844974)
			(xy 169.015403 -92.872326) (xy 168.986876 -92.904998) (xy 168.964312 -92.94204) (xy 168.948368 -92.982377)
			(xy 168.939506 -93.024836) (xy 168.937985 -93.068183) (xy 168.94048 -93.08973) (xy 168.943714 -93.117005)
			(xy 168.943257 -93.171926) (xy 168.934929 -93.226215) (xy 168.918902 -93.278747) (xy 168.895506 -93.328439)
			(xy 168.865226 -93.374261) (xy 168.828688 -93.415267) (xy 168.786647 -93.45061) (xy 168.739971 -93.479558)
			(xy 168.689627 -93.501512) (xy 168.636654 -93.51602) (xy 168.582148 -93.522782) (xy 168.527237 -93.521656)
			(xy 168.473054 -93.512667) (xy 168.42072 -93.496001) (xy 168.371318 -93.472002) (xy 168.325868 -93.441166)
			(xy 168.28531 -93.40413) (xy 168.250482 -93.361661) (xy 168.235884 -93.338396) (xy 168.223781 -93.319315)
			(xy 168.194011 -93.285332) (xy 168.158696 -93.257154) (xy 168.118952 -93.235671) (xy 168.076034 -93.221561)
			(xy 168.031295 -93.21527) (xy 167.986149 -93.216997) (xy 167.942022 -93.226686) (xy 167.900306 -93.244032)
			(xy 167.881046 -93.255846) (xy 167.857737 -93.270249) (xy 167.807866 -93.292942) (xy 167.755261 -93.308267)
			(xy 167.701004 -93.315907) (xy 167.646213 -93.315707) (xy 167.592014 -93.30767) (xy 167.539522 -93.291962)
			(xy 167.489817 -93.268905) (xy 167.443923 -93.238975) (xy 167.402783 -93.202787) (xy 167.367243 -93.161084)
			(xy 167.338035 -93.114727) (xy 167.31576 -93.064667) (xy 167.300876 -93.011936) (xy 167.293689 -92.957618)
			(xy 167.293544 -92.930218) (xy 167.293544 -92.92844) (xy 167.292922 -92.911797) (xy 167.284318 -92.879643)
			(xy 167.267684 -92.850811) (xy 167.244156 -92.827267) (xy 167.215335 -92.810614) (xy 167.183187 -92.801989)
			(xy 167.166544 -92.80144) (xy 166.229792 -92.80144) (xy 164.466775 -92.80144) (xy 164.460573 -92.81467)
			(xy 164.4298 -92.861183) (xy 164.392583 -92.90272) (xy 164.349715 -92.938395) (xy 164.302109 -92.967449)
			(xy 164.25078 -92.989261) (xy 164.196823 -93.003367) (xy 164.141386 -93.009467) (xy 164.085652 -93.00743)
			(xy 164.030809 -92.9973) (xy 163.978025 -92.979293) (xy 163.928425 -92.953792) (xy 163.883067 -92.921341)
			(xy 163.842918 -92.882632) (xy 163.808832 -92.838489) (xy 163.781536 -92.789854) (xy 163.761613 -92.737763)
			(xy 163.749487 -92.683326) (xy 163.745416 -92.627704) (xy 151.71674 -92.627704) (xy 151.71674 -93.654372)
			(xy 152.228296 -94.165928) (xy 170.227752 -94.165928) (xy 171.233592 -95.171768) (xy 171.249304 -95.186835)
			(xy 171.284886 -95.211905) (xy 171.32422 -95.230548) (xy 171.366154 -95.242218) (xy 171.409463 -95.246575)
			(xy 171.452881 -95.243492) (xy 171.495139 -95.233057) (xy 171.535003 -95.215577) (xy 171.571306 -95.191562)
			(xy 171.602988 -95.161714) (xy 171.629123 -95.126906) (xy 171.639484 -95.10776) (xy 171.651718 -95.084818)
			(xy 171.681467 -95.042178) (xy 171.71673 -95.003972) (xy 171.756853 -94.970907) (xy 171.801095 -94.943596)
			(xy 171.848635 -94.922545) (xy 171.898592 -94.908143) (xy 171.950043 -94.900657) (xy 171.976034 -94.899988)
			(xy 171.999266 -94.899283) (xy 172.044896 -94.890468) (xy 172.088163 -94.873503) (xy 172.127624 -94.848954)
			(xy 172.161964 -94.81764) (xy 172.190038 -94.780604) (xy 172.21091 -94.739082) (xy 172.223885 -94.694456)
			(xy 172.226732 -94.671388) (xy 172.229971 -94.644128) (xy 172.243273 -94.590869) (xy 172.264072 -94.540067)
			(xy 172.29194 -94.492772) (xy 172.3263 -94.44996) (xy 172.366443 -94.412517) (xy 172.411539 -94.381215)
			(xy 172.460657 -94.356702) (xy 172.512782 -94.339484) (xy 172.566837 -94.329917) (xy 172.621705 -94.328198)
			(xy 172.676252 -94.334362) (xy 172.729353 -94.348284) (xy 172.779909 -94.369674) (xy 172.826876 -94.398091)
			(xy 172.869284 -94.432947) (xy 172.906257 -94.473524) (xy 172.937031 -94.518982) (xy 172.96097 -94.568382)
			(xy 172.977579 -94.620704) (xy 172.986516 -94.674867) (xy 172.987596 -94.729751) (xy 172.980796 -94.784223)
			(xy 172.966257 -94.837158) (xy 172.944279 -94.887461) (xy 172.915316 -94.934094) (xy 172.879968 -94.976093)
			(xy 172.838963 -95.012591) (xy 172.793149 -95.042833) (xy 172.743473 -95.066194) (xy 172.690961 -95.082193)
			(xy 172.636698 -95.090498) (xy 172.609256 -95.09125) (xy 172.586026 -95.091956) (xy 172.5404 -95.100773)
			(xy 172.497137 -95.11774) (xy 172.457681 -95.14229) (xy 172.423347 -95.173605) (xy 172.395279 -95.210641)
			(xy 172.374413 -95.252163) (xy 172.361445 -95.296788) (xy 172.358558 -95.31985) (xy 172.355314 -95.347167)
			(xy 172.341981 -95.400536) (xy 172.32112 -95.451436) (xy 172.293165 -95.498813) (xy 172.258695 -95.541683)
			(xy 172.218425 -95.579157) (xy 172.17319 -95.61046) (xy 172.123929 -95.63494) (xy 172.071662 -95.652092)
			(xy 172.017473 -95.661558) (xy 171.962487 -95.663143) (xy 171.907843 -95.656815) (xy 171.854674 -95.642703)
			(xy 171.829222 -95.63227) (xy 171.808048 -95.623743) (xy 171.763549 -95.613587) (xy 171.717952 -95.611544)
			(xy 171.672723 -95.617677) (xy 171.629316 -95.63179) (xy 171.589129 -95.653429) (xy 171.553453 -95.681898)
			(xy 171.523435 -95.716282) (xy 171.500041 -95.755474) (xy 171.484024 -95.798214) (xy 171.475898 -95.843128)
			(xy 171.4754 -95.86595) (xy 171.4754 -95.986346) (xy 171.475996 -96.003749) (xy 171.485385 -96.037266)
			(xy 171.503457 -96.067014) (xy 171.515786 -96.07931) (xy 171.536267 -96.099111) (xy 171.571712 -96.143706)
			(xy 171.600134 -96.193074) (xy 171.6209 -96.24612) (xy 171.633549 -96.301663) (xy 171.6378 -96.35847)
			(xy 171.633558 -96.415277) (xy 171.620918 -96.470823) (xy 171.60016 -96.523871) (xy 171.571746 -96.573245)
			(xy 171.536308 -96.617845) (xy 171.515786 -96.637602) (xy 171.503404 -96.649862) (xy 171.485279 -96.679607)
			(xy 171.475888 -96.713149) (xy 171.4754 -96.730566) (xy 171.4754 -98.353179) (xy 171.816255 -98.353179)
			(xy 171.820015 -98.298108) (xy 171.831672 -98.244154) (xy 171.850982 -98.192442) (xy 171.877543 -98.144053)
			(xy 171.910799 -98.099997) (xy 171.950057 -98.061193) (xy 171.994498 -98.028451) (xy 172.043192 -98.002455)
			(xy 172.095125 -97.983747) (xy 172.149211 -97.972718) (xy 172.204322 -97.969599) (xy 172.259308 -97.974454)
			(xy 172.31302 -97.987182) (xy 172.364337 -98.007518) (xy 172.412188 -98.035036) (xy 172.455574 -98.069162)
			(xy 172.493589 -98.109184) (xy 172.52544 -98.154267) (xy 172.550462 -98.20347) (xy 172.568133 -98.255764)
			(xy 172.578083 -98.310059) (xy 172.580105 -98.365221) (xy 172.574157 -98.420099) (xy 172.560363 -98.473547)
			(xy 172.539011 -98.52445) (xy 172.510546 -98.571744) (xy 172.493432 -98.593402) (xy 172.483886 -98.605914)
			(xy 172.470538 -98.634398) (xy 172.464562 -98.665282) (xy 172.466322 -98.69669) (xy 172.475711 -98.726713)
			(xy 172.492158 -98.753528) (xy 172.503084 -98.764852) (xy 172.522507 -98.784464) (xy 172.556122 -98.828243)
			(xy 172.583077 -98.876409) (xy 172.602809 -98.927956) (xy 172.614907 -98.981809) (xy 172.619119 -99.036844)
			(xy 172.615356 -99.091911) (xy 172.603697 -99.14586) (xy 172.584385 -99.197567) (xy 172.557823 -99.245951)
			(xy 172.524567 -99.290002) (xy 172.485309 -99.328801) (xy 172.440871 -99.361538) (xy 172.392178 -99.38753)
			(xy 172.340248 -99.406233) (xy 172.286165 -99.417258) (xy 172.231058 -99.420374) (xy 172.176077 -99.415517)
			(xy 172.12237 -99.402787) (xy 172.071058 -99.382451) (xy 172.023211 -99.354932) (xy 171.97983 -99.320806)
			(xy 171.94182 -99.280785) (xy 171.909973 -99.235704) (xy 171.884955 -99.186504) (xy 171.867288 -99.134212)
			(xy 171.857341 -99.079921) (xy 171.855321 -99.024762) (xy 171.861271 -98.969889) (xy 171.875067 -98.916445)
			(xy 171.89642 -98.865548) (xy 171.924885 -98.818258) (xy 171.941998 -98.796602) (xy 171.951549 -98.784092)
			(xy 171.964906 -98.755609) (xy 171.970886 -98.724722) (xy 171.969126 -98.693311) (xy 171.959732 -98.663286)
			(xy 171.943277 -98.636473) (xy 171.932346 -98.625152) (xy 171.912889 -98.605571) (xy 171.87927 -98.561791)
			(xy 171.85231 -98.513624) (xy 171.832573 -98.462074) (xy 171.82047 -98.408217) (xy 171.816255 -98.353179)
			(xy 171.4754 -98.353179) (xy 171.4754 -101.08819) (xy 172.119034 -101.08819) (xy 172.123105 -101.032568)
			(xy 172.135231 -100.978131) (xy 172.155154 -100.92604) (xy 172.18245 -100.877405) (xy 172.216536 -100.833262)
			(xy 172.256685 -100.794553) (xy 172.302043 -100.762102) (xy 172.351643 -100.736601) (xy 172.404427 -100.718594)
			(xy 172.45927 -100.708464) (xy 172.515004 -100.706427) (xy 172.570441 -100.712527) (xy 172.624398 -100.726633)
			(xy 172.675727 -100.748445) (xy 172.723333 -100.777499) (xy 172.766201 -100.813174) (xy 172.803418 -100.854711)
			(xy 172.834191 -100.901224) (xy 172.857863 -100.951721) (xy 172.873931 -101.005128) (xy 172.882051 -101.060304)
			(xy 172.88256 -101.08819) (xy 172.882051 -101.116076) (xy 172.873931 -101.171252) (xy 172.857863 -101.224659)
			(xy 172.834191 -101.275156) (xy 172.803418 -101.321669) (xy 172.766201 -101.363206) (xy 172.723333 -101.398881)
			(xy 172.675727 -101.427935) (xy 172.624398 -101.449747) (xy 172.570441 -101.463853) (xy 172.515004 -101.469953)
			(xy 172.45927 -101.467916) (xy 172.404427 -101.457786) (xy 172.351643 -101.439779) (xy 172.302043 -101.414278)
			(xy 172.256685 -101.381827) (xy 172.216536 -101.343118) (xy 172.18245 -101.298975) (xy 172.155154 -101.25034)
			(xy 172.135231 -101.198249) (xy 172.123105 -101.143812) (xy 172.119034 -101.08819) (xy 171.4754 -101.08819)
			(xy 171.4754 -102.898668) (xy 171.916399 -102.898668) (xy 171.922923 -102.844395) (xy 171.937128 -102.79161)
			(xy 171.958723 -102.741393) (xy 171.987265 -102.694773) (xy 172.022169 -102.652705) (xy 172.062722 -102.616051)
			(xy 172.108092 -102.585561) (xy 172.157349 -102.56186) (xy 172.209486 -102.545433) (xy 172.236384 -102.540562)
			(xy 172.251411 -102.537684) (xy 172.279568 -102.525734) (xy 172.304072 -102.507426) (xy 172.323515 -102.483813)
			(xy 172.336779 -102.45625) (xy 172.343102 -102.426323) (xy 172.343064 -102.411022) (xy 172.342631 -102.383688)
			(xy 172.348626 -102.329353) (xy 172.362317 -102.276429) (xy 172.383422 -102.226002) (xy 172.41151 -102.179105)
			(xy 172.446005 -102.136697) (xy 172.4862 -102.099648) (xy 172.531273 -102.068717) (xy 172.5803 -102.044537)
			(xy 172.632277 -102.027603) (xy 172.686138 -102.018263) (xy 172.740782 -102.016708) (xy 172.795087 -102.022969)
			(xy 172.847943 -102.036918) (xy 172.898266 -102.05827) (xy 172.945026 -102.086588) (xy 172.987264 -102.12129)
			(xy 173.024115 -102.161667) (xy 173.054825 -102.206891) (xy 173.078765 -102.256035) (xy 173.095443 -102.308094)
			(xy 173.104519 -102.362001) (xy 173.105807 -102.416652) (xy 173.09928 -102.470926) (xy 173.085072 -102.523713)
			(xy 173.063473 -102.57393) (xy 173.034927 -102.620551) (xy 173.000018 -102.662618) (xy 172.959461 -102.699271)
			(xy 172.914087 -102.729759) (xy 172.864826 -102.753458) (xy 172.812686 -102.769881) (xy 172.785786 -102.77475)
			(xy 172.770775 -102.777691) (xy 172.742628 -102.789637) (xy 172.718129 -102.807935) (xy 172.698687 -102.831534)
			(xy 172.685416 -102.859082) (xy 172.679078 -102.888995) (xy 172.679106 -102.90429) (xy 172.679561 -102.931622)
			(xy 172.673565 -102.985955) (xy 172.659874 -103.038876) (xy 172.638769 -103.0893) (xy 172.610682 -103.136195)
			(xy 172.576188 -103.178601) (xy 172.535994 -103.215648) (xy 172.490922 -103.246578) (xy 172.441898 -103.270757)
			(xy 172.389923 -103.28769) (xy 172.336064 -103.29703) (xy 172.281423 -103.298586) (xy 172.227119 -103.292325)
			(xy 172.174266 -103.278377) (xy 172.123944 -103.257027) (xy 172.077186 -103.228712) (xy 172.034949 -103.194013)
			(xy 171.998098 -103.153639) (xy 171.967388 -103.108418) (xy 171.943447 -103.059276) (xy 171.926767 -103.00722)
			(xy 171.917689 -102.953316) (xy 171.916399 -102.898668) (xy 171.4754 -102.898668) (xy 171.4754 -105.229152)
			(xy 171.475889 -105.245811) (xy 171.484502 -105.277996) (xy 171.501153 -105.306854) (xy 171.524708 -105.330417)
			(xy 171.55356 -105.34708) (xy 171.585741 -105.355705) (xy 171.6024 -105.356152)
		)
		(stroke
			(width 0)
			(type solid)
		)
		(fill yes)
		(layer "In7.Cu")
		(net "P3V3_NODE1")
	)
	(gr_poly
		(pts
			(xy 138.684254 -117.858286) (xy 138.700912 -117.857797) (xy 138.733095 -117.849183) (xy 138.761951 -117.832531)
			(xy 138.785512 -117.808976) (xy 138.802171 -117.780125) (xy 138.810793 -117.747944) (xy 138.811254 -117.731286)
			(xy 138.811254 -117.691154) (xy 138.78814 -117.658134) (xy 138.772748 -117.635466) (xy 138.747922 -117.586623)
			(xy 138.730339 -117.53473) (xy 138.72036 -117.480856) (xy 138.718191 -117.426108) (xy 138.723877 -117.371613)
			(xy 138.7373 -117.318492) (xy 138.758185 -117.267838) (xy 138.786101 -117.220693) (xy 138.820475 -117.178026)
			(xy 138.860599 -117.140715) (xy 138.905648 -117.109529) (xy 138.954695 -117.085108) (xy 139.006732 -117.067954)
			(xy 139.060687 -117.058422) (xy 139.11545 -117.056706) (xy 139.169896 -117.062842) (xy 139.222904 -117.076705)
			(xy 139.273384 -117.098008) (xy 139.320297 -117.126313) (xy 139.362678 -117.161039) (xy 139.399655 -117.20147)
			(xy 139.430468 -117.246776) (xy 139.454483 -117.296023) (xy 139.471205 -117.3482) (xy 139.480291 -117.402232)
			(xy 139.481553 -117.457008) (xy 139.474967 -117.511401) (xy 139.468352 -117.537992) (xy 139.462774 -117.560639)
			(xy 139.459018 -117.607123) (xy 139.463804 -117.653513) (xy 139.476971 -117.698251) (xy 139.498078 -117.739837)
			(xy 139.526416 -117.776875) (xy 139.561035 -117.808123) (xy 139.600772 -117.832532) (xy 139.644296 -117.849284)
			(xy 139.690144 -117.857815) (xy 139.713462 -117.858286) (xy 144.935194 -117.858286) (xy 144.949795 -117.857879)
			(xy 144.97823 -117.851232) (xy 145.004406 -117.838286) (xy 145.026946 -117.81972) (xy 145.044667 -117.79651)
			(xy 145.051018 -117.783356) (xy 145.051272 -117.782848) (xy 145.062322 -117.759099) (xy 145.089979 -117.714617)
			(xy 145.10639 -117.694202) (xy 145.1356 -117.65915) (xy 145.1356 -113.902236) (xy 140.384276 -109.150912)
			(xy 140.365734 -109.141768) (xy 140.34506 -109.131011) (xy 140.306407 -109.104971) (xy 140.27141 -109.074194)
			(xy 140.255752 -109.056932) (xy 140.253212 -109.053884) (xy 136.877044 -105.677716) (xy 133.165342 -105.677716)
			(xy 133.148723 -105.678251) (xy 133.116613 -105.686836) (xy 133.087815 -105.703433) (xy 133.07568 -105.7148)
			(xy 132.230795 -106.559926) (xy 134.215226 -106.559926) (xy 134.217475 -106.504162) (xy 134.227823 -106.44932)
			(xy 134.246051 -106.39657) (xy 134.271769 -106.347039) (xy 134.304428 -106.301783) (xy 134.343331 -106.261767)
			(xy 134.387649 -106.227845) (xy 134.436436 -106.200742) (xy 134.488651 -106.181035) (xy 134.543179 -106.169144)
			(xy 134.598858 -106.165324) (xy 134.6545 -106.169656) (xy 134.708917 -106.182048) (xy 134.760948 -106.202235)
			(xy 134.809483 -106.229786) (xy 134.853487 -106.264114) (xy 134.89202 -106.304487) (xy 134.924261 -106.350042)
			(xy 134.949522 -106.399807) (xy 134.967264 -106.452722) (xy 134.977107 -106.507657) (xy 134.978843 -106.56344)
			(xy 134.972434 -106.618881) (xy 134.965694 -106.645964) (xy 134.96035 -106.66793) (xy 134.956602 -106.712976)
			(xy 134.960872 -106.757976) (xy 134.973026 -106.801513) (xy 134.992683 -106.842217) (xy 135.019222 -106.878808)
			(xy 135.051809 -106.910133) (xy 135.070342 -106.923078) (xy 135.093302 -106.938945) (xy 135.134746 -106.976326)
			(xy 135.170301 -107.019345) (xy 135.19921 -107.067085) (xy 135.220857 -107.118527) (xy 135.234778 -107.172573)
			(xy 135.240677 -107.228071) (xy 135.238428 -107.283837) (xy 135.228079 -107.33868) (xy 135.209852 -107.39143)
			(xy 135.184133 -107.440962) (xy 135.151474 -107.486219) (xy 135.11257 -107.526236) (xy 135.068251 -107.560158)
			(xy 135.019464 -107.587261) (xy 134.967248 -107.606969) (xy 134.912718 -107.618859) (xy 134.857038 -107.622678)
			(xy 134.801396 -107.618346) (xy 134.746979 -107.605953) (xy 134.694947 -107.585765) (xy 134.646411 -107.558213)
			(xy 134.602407 -107.523884) (xy 134.563874 -107.48351) (xy 134.531633 -107.437954) (xy 134.506373 -107.388187)
			(xy 134.488632 -107.335271) (xy 134.478789 -107.280335) (xy 134.477055 -107.224551) (xy 134.483465 -107.169109)
			(xy 134.490206 -107.142026) (xy 134.495559 -107.120062) (xy 134.499306 -107.075015) (xy 134.495035 -107.030015)
			(xy 134.482879 -106.986477) (xy 134.463221 -106.945773) (xy 134.43668 -106.909182) (xy 134.404092 -106.877857)
			(xy 134.385558 -106.864912) (xy 134.362595 -106.84905) (xy 134.321153 -106.811669) (xy 134.285598 -106.76865)
			(xy 134.25669 -106.720911) (xy 134.235045 -106.669469) (xy 134.221124 -106.615423) (xy 134.215226 -106.559926)
			(xy 132.230795 -106.559926) (xy 132.18668 -106.604054) (xy 132.18668 -109.134402) (xy 132.18718 -109.157091)
			(xy 132.195238 -109.201747) (xy 132.211097 -109.244263) (xy 132.234254 -109.283287) (xy 132.263972 -109.317579)
			(xy 132.299308 -109.346049) (xy 132.339137 -109.367793) (xy 132.382194 -109.382118) (xy 132.42711 -109.38857)
			(xy 132.472459 -109.386944) (xy 132.516798 -109.377292) (xy 132.537962 -109.369098) (xy 132.563972 -109.358824)
			(xy 132.618194 -109.345142) (xy 132.673832 -109.339523) (xy 132.729695 -109.342086) (xy 132.784585 -109.352777)
			(xy 132.837327 -109.371367) (xy 132.886789 -109.397458) (xy 132.931912 -109.430491) (xy 132.971729 -109.469757)
			(xy 133.005387 -109.514415) (xy 133.032165 -109.563509) (xy 133.051489 -109.615985) (xy 133.062944 -109.670721)
			(xy 133.066286 -109.726543) (xy 133.065062 -109.740626) (xy 133.333619 -109.740626) (xy 133.33855 -109.68602)
			(xy 133.351244 -109.632682) (xy 133.37144 -109.58171) (xy 133.398723 -109.534152) (xy 133.432531 -109.490988)
			(xy 133.472167 -109.453107) (xy 133.516817 -109.421287) (xy 133.565561 -109.396185) (xy 133.617395 -109.378316)
			(xy 133.671252 -109.368049) (xy 133.726025 -109.365595) (xy 133.753352 -109.367828) (xy 133.777043 -109.369676)
			(xy 133.824372 -109.36546) (xy 133.870096 -109.352529) (xy 133.912623 -109.331332) (xy 133.950474 -109.302607)
			(xy 133.982333 -109.267353) (xy 134.007092 -109.226796) (xy 134.015988 -109.20476) (xy 134.026106 -109.179059)
			(xy 134.052804 -109.130705) (xy 134.086195 -109.086704) (xy 134.125581 -109.047978) (xy 134.170138 -109.015334)
			(xy 134.218936 -108.989455) (xy 134.270955 -108.970882) (xy 134.325108 -108.960003) (xy 134.380265 -108.957044)
			(xy 134.435271 -108.962069) (xy 134.488979 -108.974971) (xy 134.540265 -108.995481) (xy 134.588058 -109.023171)
			(xy 134.63136 -109.057463) (xy 134.669266 -109.097639) (xy 134.700984 -109.14286) (xy 134.72585 -109.192181)
			(xy 134.735062 -109.218222) (xy 134.742771 -109.239849) (xy 134.764872 -109.280087) (xy 134.793851 -109.315694)
			(xy 134.828761 -109.345507) (xy 134.868465 -109.368555) (xy 134.911668 -109.384085) (xy 134.956959 -109.391591)
			(xy 134.979918 -109.391704) (xy 135.007958 -109.391789) (xy 135.063546 -109.399138) (xy 135.117459 -109.414541)
			(xy 135.168539 -109.437669) (xy 135.215684 -109.468021) (xy 135.257881 -109.504946) (xy 135.29422 -109.547648)
			(xy 135.323919 -109.595207) (xy 135.34634 -109.646601) (xy 135.360999 -109.700722) (xy 135.361912 -109.708442)
			(xy 135.873742 -109.708442) (xy 135.877813 -109.65282) (xy 135.889939 -109.598383) (xy 135.909862 -109.546292)
			(xy 135.937158 -109.497657) (xy 135.971244 -109.453514) (xy 136.011393 -109.414805) (xy 136.056751 -109.382354)
			(xy 136.106351 -109.356853) (xy 136.159135 -109.338846) (xy 136.213978 -109.328716) (xy 136.269712 -109.326679)
			(xy 136.325149 -109.332779) (xy 136.379106 -109.346885) (xy 136.430435 -109.368697) (xy 136.478041 -109.397751)
			(xy 136.520909 -109.433426) (xy 136.558126 -109.474963) (xy 136.588899 -109.521476) (xy 136.612571 -109.571973)
			(xy 136.628639 -109.62538) (xy 136.635779 -109.673898) (xy 137.143742 -109.673898) (xy 137.147813 -109.618276)
			(xy 137.159939 -109.563839) (xy 137.179862 -109.511748) (xy 137.207158 -109.463113) (xy 137.241244 -109.41897)
			(xy 137.281393 -109.380261) (xy 137.326751 -109.34781) (xy 137.376351 -109.322309) (xy 137.429135 -109.304302)
			(xy 137.483978 -109.294172) (xy 137.539712 -109.292135) (xy 137.595149 -109.298235) (xy 137.649106 -109.312341)
			(xy 137.700435 -109.334153) (xy 137.748041 -109.363207) (xy 137.790909 -109.398882) (xy 137.828126 -109.440419)
			(xy 137.858899 -109.486932) (xy 137.882571 -109.537429) (xy 137.898639 -109.590836) (xy 137.906759 -109.646012)
			(xy 137.907268 -109.673898) (xy 137.906759 -109.701784) (xy 137.898639 -109.75696) (xy 137.882571 -109.810367)
			(xy 137.858899 -109.860864) (xy 137.828126 -109.907377) (xy 137.790909 -109.948914) (xy 137.748041 -109.984589)
			(xy 137.700435 -110.013643) (xy 137.649106 -110.035455) (xy 137.595149 -110.049561) (xy 137.539712 -110.055661)
			(xy 137.483978 -110.053624) (xy 137.429135 -110.043494) (xy 137.376351 -110.025487) (xy 137.326751 -109.999986)
			(xy 137.281393 -109.967535) (xy 137.241244 -109.928826) (xy 137.207158 -109.884683) (xy 137.179862 -109.836048)
			(xy 137.159939 -109.783957) (xy 137.147813 -109.72952) (xy 137.143742 -109.673898) (xy 136.635779 -109.673898)
			(xy 136.636759 -109.680556) (xy 136.637268 -109.708442) (xy 136.636759 -109.736328) (xy 136.628639 -109.791504)
			(xy 136.612571 -109.844911) (xy 136.588899 -109.895408) (xy 136.558126 -109.941921) (xy 136.520909 -109.983458)
			(xy 136.478041 -110.019133) (xy 136.430435 -110.048187) (xy 136.379106 -110.069999) (xy 136.325149 -110.084105)
			(xy 136.269712 -110.090205) (xy 136.213978 -110.088168) (xy 136.159135 -110.078038) (xy 136.106351 -110.060031)
			(xy 136.056751 -110.03453) (xy 136.011393 -110.002079) (xy 135.971244 -109.96337) (xy 135.937158 -109.919227)
			(xy 135.909862 -109.870592) (xy 135.889939 -109.818501) (xy 135.877813 -109.764064) (xy 135.873742 -109.708442)
			(xy 135.361912 -109.708442) (xy 135.367581 -109.756405) (xy 135.365943 -109.812452) (xy 135.356122 -109.867657)
			(xy 135.338329 -109.92083) (xy 135.312947 -109.970827) (xy 135.280522 -110.016571) (xy 135.241752 -110.057079)
			(xy 135.197472 -110.091478) (xy 135.148635 -110.119026) (xy 135.096293 -110.139132) (xy 135.041572 -110.151363)
			(xy 134.98565 -110.155454) (xy 134.929732 -110.151319) (xy 134.87502 -110.139045) (xy 134.822694 -110.118898)
			(xy 134.773878 -110.091311) (xy 134.729625 -110.056878) (xy 134.690887 -110.01634) (xy 134.658498 -109.97057)
			(xy 134.633155 -109.920553) (xy 134.62381 -109.894116) (xy 134.616074 -109.872501) (xy 134.593971 -109.832268)
			(xy 134.564995 -109.796666) (xy 134.530089 -109.766854) (xy 134.490391 -109.743804) (xy 134.447196 -109.728269)
			(xy 134.401911 -109.720753) (xy 134.378954 -109.720634) (xy 134.36808 -109.720737) (xy 134.346349 -109.719846)
			(xy 134.33552 -109.718856) (xy 134.311825 -109.717086) (xy 134.264502 -109.721289) (xy 134.218782 -109.734208)
			(xy 134.176257 -109.755391) (xy 134.138406 -109.784104) (xy 134.106545 -109.819346) (xy 134.081783 -109.859893)
			(xy 134.072884 -109.881924) (xy 134.062817 -109.907426) (xy 134.036372 -109.955455) (xy 134.003327 -109.999205)
			(xy 133.964361 -110.037776) (xy 133.920276 -110.070374) (xy 133.87198 -110.096327) (xy 133.820468 -110.115103)
			(xy 133.766798 -110.126313) (xy 133.712077 -110.129727) (xy 133.65743 -110.125276) (xy 133.603983 -110.11305)
			(xy 133.552836 -110.093301) (xy 133.505041 -110.066437) (xy 133.461582 -110.033009) (xy 133.423354 -109.993706)
			(xy 133.391144 -109.949337) (xy 133.365615 -109.900816) (xy 133.347293 -109.84914) (xy 133.336554 -109.795375)
			(xy 133.333619 -109.740626) (xy 133.065062 -109.740626) (xy 133.061443 -109.782255) (xy 133.048518 -109.836662)
			(xy 133.027788 -109.8886) (xy 132.999698 -109.936955) (xy 132.96485 -109.980691) (xy 132.92399 -110.01887)
			(xy 132.877994 -110.050676) (xy 132.827847 -110.075426) (xy 132.774625 -110.092589) (xy 132.719466 -110.101799)
			(xy 132.663555 -110.102857) (xy 132.608088 -110.095742) (xy 132.554254 -110.080605) (xy 132.503206 -110.05777)
			(xy 132.456039 -110.027728) (xy 132.413764 -109.991122) (xy 132.377285 -109.948736) (xy 132.36194 -109.925358)
			(xy 132.34933 -109.906393) (xy 132.318501 -109.872877) (xy 132.282192 -109.845393) (xy 132.241564 -109.824823)
			(xy 132.197921 -109.811823) (xy 132.152659 -109.806811) (xy 132.107229 -109.809948) (xy 132.063086 -109.821133)
			(xy 132.021643 -109.840007) (xy 131.984229 -109.865966) (xy 131.967732 -109.88167) (xy 131.388612 -110.46079)
			(xy 131.384548 -110.46079) (xy 131.292092 -110.501684) (xy 131.275582 -110.51794) (xy 131.256902 -110.535706)
			(xy 131.215609 -110.566568) (xy 131.170539 -110.591594) (xy 131.122512 -110.61033) (xy 131.072401 -110.622433)
			(xy 131.021117 -110.627685) (xy 130.969593 -110.625989) (xy 130.944112 -110.62208) (xy 130.922249 -110.618833)
			(xy 130.878054 -110.619051) (xy 130.834563 -110.626913) (xy 130.793089 -110.642183) (xy 130.754884 -110.6644)
			(xy 130.721099 -110.692893) (xy 130.692755 -110.726803) (xy 130.670707 -110.765107) (xy 130.65562 -110.806647)
			(xy 130.64795 -110.850172) (xy 130.64744 -110.87227) (xy 130.64744 -111.677704) (xy 131.171948 -111.677704)
			(xy 131.176019 -111.622082) (xy 131.188145 -111.567645) (xy 131.208068 -111.515554) (xy 131.235364 -111.466919)
			(xy 131.26945 -111.422776) (xy 131.309599 -111.384067) (xy 131.354957 -111.351616) (xy 131.404557 -111.326115)
			(xy 131.457341 -111.308108) (xy 131.512184 -111.297978) (xy 131.567918 -111.295941) (xy 131.623355 -111.302041)
			(xy 131.677312 -111.316147) (xy 131.728641 -111.337959) (xy 131.775911 -111.366808) (xy 132.6294 -111.366808)
			(xy 132.633471 -111.311186) (xy 132.645597 -111.256749) (xy 132.66552 -111.204658) (xy 132.692816 -111.156023)
			(xy 132.726902 -111.11188) (xy 132.767051 -111.073171) (xy 132.812409 -111.04072) (xy 132.862009 -111.015219)
			(xy 132.914793 -110.997212) (xy 132.969636 -110.987082) (xy 133.02537 -110.985045) (xy 133.080807 -110.991145)
			(xy 133.134764 -111.005251) (xy 133.186093 -111.027063) (xy 133.233699 -111.056117) (xy 133.276567 -111.091792)
			(xy 133.313784 -111.133329) (xy 133.344557 -111.179842) (xy 133.368229 -111.230339) (xy 133.384297 -111.283746)
			(xy 133.392417 -111.338922) (xy 133.392926 -111.366808) (xy 133.392417 -111.394694) (xy 133.384297 -111.44987)
			(xy 133.368229 -111.503277) (xy 133.344557 -111.553774) (xy 133.313784 -111.600287) (xy 133.276567 -111.641824)
			(xy 133.233699 -111.677499) (xy 133.186093 -111.706553) (xy 133.134764 -111.728365) (xy 133.080807 -111.742471)
			(xy 133.02537 -111.748571) (xy 132.969636 -111.746534) (xy 132.914793 -111.736404) (xy 132.862009 -111.718397)
			(xy 132.812409 -111.692896) (xy 132.767051 -111.660445) (xy 132.726902 -111.621736) (xy 132.692816 -111.577593)
			(xy 132.66552 -111.528958) (xy 132.645597 -111.476867) (xy 132.633471 -111.42243) (xy 132.6294 -111.366808)
			(xy 131.775911 -111.366808) (xy 131.776247 -111.367013) (xy 131.819115 -111.402688) (xy 131.856332 -111.444225)
			(xy 131.887105 -111.490738) (xy 131.910777 -111.541235) (xy 131.926845 -111.594642) (xy 131.934965 -111.649818)
			(xy 131.935474 -111.677704) (xy 131.934965 -111.70559) (xy 131.926845 -111.760766) (xy 131.910777 -111.814173)
			(xy 131.910453 -111.814864) (xy 134.229854 -111.814864) (xy 134.233925 -111.759242) (xy 134.246051 -111.704805)
			(xy 134.265974 -111.652714) (xy 134.29327 -111.604079) (xy 134.327356 -111.559936) (xy 134.367505 -111.521227)
			(xy 134.412863 -111.488776) (xy 134.462463 -111.463275) (xy 134.515247 -111.445268) (xy 134.57009 -111.435138)
			(xy 134.625824 -111.433101) (xy 134.681261 -111.439201) (xy 134.735218 -111.453307) (xy 134.786547 -111.475119)
			(xy 134.834153 -111.504173) (xy 134.877021 -111.539848) (xy 134.914238 -111.581385) (xy 134.945011 -111.627898)
			(xy 134.968683 -111.678395) (xy 134.984751 -111.731802) (xy 134.992871 -111.786978) (xy 134.99338 -111.814864)
			(xy 134.992871 -111.84275) (xy 134.989574 -111.865156) (xy 135.59739 -111.865156) (xy 135.601461 -111.809534)
			(xy 135.613587 -111.755097) (xy 135.63351 -111.703006) (xy 135.660806 -111.654371) (xy 135.694892 -111.610228)
			(xy 135.735041 -111.571519) (xy 135.780399 -111.539068) (xy 135.829999 -111.513567) (xy 135.882783 -111.49556)
			(xy 135.937626 -111.48543) (xy 135.99336 -111.483393) (xy 136.048797 -111.489493) (xy 136.102754 -111.503599)
			(xy 136.154083 -111.525411) (xy 136.201689 -111.554465) (xy 136.244557 -111.59014) (xy 136.281774 -111.631677)
			(xy 136.312547 -111.67819) (xy 136.336219 -111.728687) (xy 136.352287 -111.782094) (xy 136.360407 -111.83727)
			(xy 136.360916 -111.865156) (xy 136.360407 -111.893042) (xy 136.352287 -111.948218) (xy 136.336219 -112.001625)
			(xy 136.312547 -112.052122) (xy 136.281774 -112.098635) (xy 136.244557 -112.140172) (xy 136.201689 -112.175847)
			(xy 136.154083 -112.204901) (xy 136.102754 -112.226713) (xy 136.048797 -112.240819) (xy 135.99336 -112.246919)
			(xy 135.937626 -112.244882) (xy 135.882783 -112.234752) (xy 135.829999 -112.216745) (xy 135.780399 -112.191244)
			(xy 135.735041 -112.158793) (xy 135.694892 -112.120084) (xy 135.660806 -112.075941) (xy 135.63351 -112.027306)
			(xy 135.613587 -111.975215) (xy 135.601461 -111.920778) (xy 135.59739 -111.865156) (xy 134.989574 -111.865156)
			(xy 134.984751 -111.897926) (xy 134.968683 -111.951333) (xy 134.945011 -112.00183) (xy 134.914238 -112.048343)
			(xy 134.877021 -112.08988) (xy 134.834153 -112.125555) (xy 134.786547 -112.154609) (xy 134.735218 -112.176421)
			(xy 134.681261 -112.190527) (xy 134.625824 -112.196627) (xy 134.57009 -112.19459) (xy 134.515247 -112.18446)
			(xy 134.462463 -112.166453) (xy 134.412863 -112.140952) (xy 134.367505 -112.108501) (xy 134.327356 -112.069792)
			(xy 134.29327 -112.025649) (xy 134.265974 -111.977014) (xy 134.246051 -111.924923) (xy 134.233925 -111.870486)
			(xy 134.229854 -111.814864) (xy 131.910453 -111.814864) (xy 131.887105 -111.86467) (xy 131.856332 -111.911183)
			(xy 131.819115 -111.95272) (xy 131.776247 -111.988395) (xy 131.728641 -112.017449) (xy 131.677312 -112.039261)
			(xy 131.623355 -112.053367) (xy 131.567918 -112.059467) (xy 131.512184 -112.05743) (xy 131.457341 -112.0473)
			(xy 131.404557 -112.029293) (xy 131.354957 -112.003792) (xy 131.309599 -111.971341) (xy 131.26945 -111.932632)
			(xy 131.235364 -111.888489) (xy 131.208068 -111.839854) (xy 131.188145 -111.787763) (xy 131.176019 -111.733326)
			(xy 131.171948 -111.677704) (xy 130.64744 -111.677704) (xy 130.64744 -112.652302) (xy 130.647948 -112.658398)
			(xy 130.647948 -112.658906) (xy 130.649405 -112.676657) (xy 130.649408 -112.712275) (xy 130.647948 -112.730026)
			(xy 130.647948 -112.730534) (xy 130.64744 -112.73663) (xy 130.64744 -112.858042) (xy 134.247634 -112.858042)
			(xy 134.251705 -112.80242) (xy 134.263831 -112.747983) (xy 134.283754 -112.695892) (xy 134.31105 -112.647257)
			(xy 134.345136 -112.603114) (xy 134.385285 -112.564405) (xy 134.430643 -112.531954) (xy 134.480243 -112.506453)
			(xy 134.533027 -112.488446) (xy 134.58787 -112.478316) (xy 134.643604 -112.476279) (xy 134.699041 -112.482379)
			(xy 134.752998 -112.496485) (xy 134.804327 -112.518297) (xy 134.807897 -112.520476) (xy 136.813796 -112.520476)
			(xy 136.817867 -112.464854) (xy 136.829993 -112.410417) (xy 136.849916 -112.358326) (xy 136.877212 -112.309691)
			(xy 136.911298 -112.265548) (xy 136.951447 -112.226839) (xy 136.996805 -112.194388) (xy 137.046405 -112.168887)
			(xy 137.099189 -112.15088) (xy 137.154032 -112.14075) (xy 137.209766 -112.138713) (xy 137.265203 -112.144813)
			(xy 137.31916 -112.158919) (xy 137.370489 -112.180731) (xy 137.418095 -112.209785) (xy 137.460963 -112.24546)
			(xy 137.49818 -112.286997) (xy 137.528953 -112.33351) (xy 137.552625 -112.384007) (xy 137.568693 -112.437414)
			(xy 137.576813 -112.49259) (xy 137.577322 -112.520476) (xy 137.577252 -112.524286) (xy 141.085568 -112.524286)
			(xy 141.089639 -112.468664) (xy 141.101765 -112.414227) (xy 141.121688 -112.362136) (xy 141.148984 -112.313501)
			(xy 141.18307 -112.269358) (xy 141.223219 -112.230649) (xy 141.268577 -112.198198) (xy 141.318177 -112.172697)
			(xy 141.370961 -112.15469) (xy 141.425804 -112.14456) (xy 141.481538 -112.142523) (xy 141.536975 -112.148623)
			(xy 141.590932 -112.162729) (xy 141.642261 -112.184541) (xy 141.689867 -112.213595) (xy 141.732735 -112.24927)
			(xy 141.769952 -112.290807) (xy 141.800725 -112.33732) (xy 141.824397 -112.387817) (xy 141.840465 -112.441224)
			(xy 141.848585 -112.4964) (xy 141.849094 -112.524286) (xy 141.848585 -112.552172) (xy 141.840465 -112.607348)
			(xy 141.824397 -112.660755) (xy 141.800725 -112.711252) (xy 141.769952 -112.757765) (xy 141.732735 -112.799302)
			(xy 141.689867 -112.834977) (xy 141.642261 -112.864031) (xy 141.590932 -112.885843) (xy 141.536975 -112.899949)
			(xy 141.481538 -112.906049) (xy 141.425804 -112.904012) (xy 141.370961 -112.893882) (xy 141.318177 -112.875875)
			(xy 141.268577 -112.850374) (xy 141.223219 -112.817923) (xy 141.18307 -112.779214) (xy 141.148984 -112.735071)
			(xy 141.121688 -112.686436) (xy 141.101765 -112.634345) (xy 141.089639 -112.579908) (xy 141.085568 -112.524286)
			(xy 137.577252 -112.524286) (xy 137.576813 -112.548362) (xy 137.568693 -112.603538) (xy 137.552625 -112.656945)
			(xy 137.528953 -112.707442) (xy 137.49818 -112.753955) (xy 137.460963 -112.795492) (xy 137.418095 -112.831167)
			(xy 137.370489 -112.860221) (xy 137.31916 -112.882033) (xy 137.265203 -112.896139) (xy 137.209766 -112.902239)
			(xy 137.154032 -112.900202) (xy 137.099189 -112.890072) (xy 137.046405 -112.872065) (xy 136.996805 -112.846564)
			(xy 136.951447 -112.814113) (xy 136.911298 -112.775404) (xy 136.877212 -112.731261) (xy 136.849916 -112.682626)
			(xy 136.829993 -112.630535) (xy 136.817867 -112.576098) (xy 136.813796 -112.520476) (xy 134.807897 -112.520476)
			(xy 134.851933 -112.547351) (xy 134.894801 -112.583026) (xy 134.932018 -112.624563) (xy 134.962791 -112.671076)
			(xy 134.986463 -112.721573) (xy 135.002531 -112.77498) (xy 135.010651 -112.830156) (xy 135.01116 -112.858042)
			(xy 135.010651 -112.885928) (xy 135.002531 -112.941104) (xy 134.986463 -112.994511) (xy 134.962791 -113.045008)
			(xy 134.954739 -113.057178) (xy 138.399518 -113.057178) (xy 138.403589 -113.001556) (xy 138.415715 -112.947119)
			(xy 138.435638 -112.895028) (xy 138.462934 -112.846393) (xy 138.49702 -112.80225) (xy 138.537169 -112.763541)
			(xy 138.582527 -112.73109) (xy 138.632127 -112.705589) (xy 138.684911 -112.687582) (xy 138.739754 -112.677452)
			(xy 138.795488 -112.675415) (xy 138.850925 -112.681515) (xy 138.904882 -112.695621) (xy 138.956211 -112.717433)
			(xy 139.003817 -112.746487) (xy 139.046685 -112.782162) (xy 139.083902 -112.823699) (xy 139.114675 -112.870212)
			(xy 139.138347 -112.920709) (xy 139.154415 -112.974116) (xy 139.162535 -113.029292) (xy 139.163044 -113.057178)
			(xy 139.162535 -113.085064) (xy 139.154415 -113.14024) (xy 139.138347 -113.193647) (xy 139.121115 -113.230406)
			(xy 139.607542 -113.230406) (xy 139.611613 -113.174784) (xy 139.623739 -113.120347) (xy 139.643662 -113.068256)
			(xy 139.670958 -113.019621) (xy 139.705044 -112.975478) (xy 139.745193 -112.936769) (xy 139.790551 -112.904318)
			(xy 139.840151 -112.878817) (xy 139.892935 -112.86081) (xy 139.947778 -112.85068) (xy 140.003512 -112.848643)
			(xy 140.058949 -112.854743) (xy 140.112906 -112.868849) (xy 140.164235 -112.890661) (xy 140.211841 -112.919715)
			(xy 140.254709 -112.95539) (xy 140.291926 -112.996927) (xy 140.322699 -113.04344) (xy 140.346371 -113.093937)
			(xy 140.362439 -113.147344) (xy 140.370559 -113.20252) (xy 140.371068 -113.230406) (xy 140.370559 -113.258292)
			(xy 140.362439 -113.313468) (xy 140.346371 -113.366875) (xy 140.322699 -113.417372) (xy 140.291926 -113.463885)
			(xy 140.254709 -113.505422) (xy 140.211841 -113.541097) (xy 140.164235 -113.570151) (xy 140.112906 -113.591963)
			(xy 140.058949 -113.606069) (xy 140.003512 -113.612169) (xy 139.947778 -113.610132) (xy 139.892935 -113.600002)
			(xy 139.840151 -113.581995) (xy 139.790551 -113.556494) (xy 139.745193 -113.524043) (xy 139.705044 -113.485334)
			(xy 139.670958 -113.441191) (xy 139.643662 -113.392556) (xy 139.623739 -113.340465) (xy 139.611613 -113.286028)
			(xy 139.607542 -113.230406) (xy 139.121115 -113.230406) (xy 139.114675 -113.244144) (xy 139.083902 -113.290657)
			(xy 139.046685 -113.332194) (xy 139.003817 -113.367869) (xy 138.956211 -113.396923) (xy 138.904882 -113.418735)
			(xy 138.850925 -113.432841) (xy 138.795488 -113.438941) (xy 138.739754 -113.436904) (xy 138.684911 -113.426774)
			(xy 138.632127 -113.408767) (xy 138.582527 -113.383266) (xy 138.537169 -113.350815) (xy 138.49702 -113.312106)
			(xy 138.462934 -113.267963) (xy 138.435638 -113.219328) (xy 138.415715 -113.167237) (xy 138.403589 -113.1128)
			(xy 138.399518 -113.057178) (xy 134.954739 -113.057178) (xy 134.932018 -113.091521) (xy 134.894801 -113.133058)
			(xy 134.851933 -113.168733) (xy 134.804327 -113.197787) (xy 134.752998 -113.219599) (xy 134.699041 -113.233705)
			(xy 134.643604 -113.239805) (xy 134.58787 -113.237768) (xy 134.533027 -113.227638) (xy 134.480243 -113.209631)
			(xy 134.430643 -113.18413) (xy 134.385285 -113.151679) (xy 134.345136 -113.11297) (xy 134.31105 -113.068827)
			(xy 134.283754 -113.020192) (xy 134.263831 -112.968101) (xy 134.251705 -112.913664) (xy 134.247634 -112.858042)
			(xy 130.64744 -112.858042) (xy 130.64744 -113.900712) (xy 137.636756 -113.900712) (xy 137.640827 -113.84509)
			(xy 137.652953 -113.790653) (xy 137.672876 -113.738562) (xy 137.700172 -113.689927) (xy 137.734258 -113.645784)
			(xy 137.774407 -113.607075) (xy 137.819765 -113.574624) (xy 137.869365 -113.549123) (xy 137.922149 -113.531116)
			(xy 137.976992 -113.520986) (xy 138.032726 -113.518949) (xy 138.088163 -113.525049) (xy 138.14212 -113.539155)
			(xy 138.193449 -113.560967) (xy 138.241055 -113.590021) (xy 138.283923 -113.625696) (xy 138.32114 -113.667233)
			(xy 138.351913 -113.713746) (xy 138.375585 -113.764243) (xy 138.391653 -113.81765) (xy 138.399773 -113.872826)
			(xy 138.400282 -113.900712) (xy 138.399773 -113.928598) (xy 138.391653 -113.983774) (xy 138.375585 -114.037181)
			(xy 138.351913 -114.087678) (xy 138.32114 -114.134191) (xy 138.283923 -114.175728) (xy 138.241055 -114.211403)
			(xy 138.193449 -114.240457) (xy 138.14212 -114.262269) (xy 138.088163 -114.276375) (xy 138.032726 -114.282475)
			(xy 137.976992 -114.280438) (xy 137.922149 -114.270308) (xy 137.869365 -114.252301) (xy 137.819765 -114.2268)
			(xy 137.774407 -114.194349) (xy 137.734258 -114.15564) (xy 137.700172 -114.111497) (xy 137.672876 -114.062862)
			(xy 137.652953 -114.010771) (xy 137.640827 -113.956334) (xy 137.636756 -113.900712) (xy 130.64744 -113.900712)
			(xy 130.64744 -114.20729) (xy 130.647934 -114.223944) (xy 130.656554 -114.256116) (xy 130.673209 -114.28496)
			(xy 130.696763 -114.308509) (xy 130.725612 -114.325158) (xy 130.757786 -114.33377) (xy 130.77444 -114.33429)
			(xy 136.791192 -114.33429) (xy 136.948672 -114.491516) (xy 136.948672 -114.902742) (xy 138.679934 -114.902742)
			(xy 138.684005 -114.84712) (xy 138.696131 -114.792683) (xy 138.716054 -114.740592) (xy 138.74335 -114.691957)
			(xy 138.777436 -114.647814) (xy 138.817585 -114.609105) (xy 138.862943 -114.576654) (xy 138.912543 -114.551153)
			(xy 138.965327 -114.533146) (xy 139.02017 -114.523016) (xy 139.075904 -114.520979) (xy 139.131341 -114.527079)
			(xy 139.185298 -114.541185) (xy 139.236627 -114.562997) (xy 139.284233 -114.592051) (xy 139.327101 -114.627726)
			(xy 139.364318 -114.669263) (xy 139.395091 -114.715776) (xy 139.418763 -114.766273) (xy 139.434831 -114.81968)
			(xy 139.442951 -114.874856) (xy 139.44346 -114.902742) (xy 139.442951 -114.930628) (xy 139.434831 -114.985804)
			(xy 139.418763 -115.039211) (xy 139.395091 -115.089708) (xy 139.364318 -115.136221) (xy 139.327101 -115.177758)
			(xy 139.284233 -115.213433) (xy 139.236627 -115.242487) (xy 139.185298 -115.264299) (xy 139.131341 -115.278405)
			(xy 139.075904 -115.284505) (xy 139.02017 -115.282468) (xy 138.965327 -115.272338) (xy 138.912543 -115.254331)
			(xy 138.862943 -115.22883) (xy 138.817585 -115.196379) (xy 138.777436 -115.15767) (xy 138.74335 -115.113527)
			(xy 138.716054 -115.064892) (xy 138.696131 -115.012801) (xy 138.684005 -114.958364) (xy 138.679934 -114.902742)
			(xy 136.948672 -114.902742) (xy 136.948672 -115.764477) (xy 137.473749 -115.764477) (xy 137.479927 -115.709153)
			(xy 137.494079 -115.655315) (xy 137.515905 -115.604105) (xy 137.544942 -115.556611) (xy 137.580572 -115.51384)
			(xy 137.62204 -115.476702) (xy 137.668465 -115.445985) (xy 137.718861 -115.42234) (xy 137.772159 -115.40627)
			(xy 137.827225 -115.398116) (xy 137.882893 -115.398052) (xy 137.937978 -115.406078) (xy 137.991313 -115.422025)
			(xy 138.041763 -115.445552) (xy 138.088259 -115.476163) (xy 138.129813 -115.513205) (xy 138.165543 -115.555892)
			(xy 138.194689 -115.60332) (xy 138.216634 -115.654479) (xy 138.22426 -115.681252) (xy 138.230806 -115.703943)
			(xy 138.25112 -115.746572) (xy 138.278964 -115.784711) (xy 138.313378 -115.817046) (xy 138.353176 -115.842462)
			(xy 138.396985 -115.860085) (xy 138.443298 -115.869307) (xy 138.490517 -115.869809) (xy 138.537015 -115.861574)
			(xy 138.559286 -115.853718) (xy 138.585497 -115.84432) (xy 138.639909 -115.832485) (xy 138.695463 -115.828684)
			(xy 138.75098 -115.832997) (xy 138.80528 -115.845334) (xy 138.852542 -115.863624) (xy 141.037816 -115.863624)
			(xy 141.041887 -115.808002) (xy 141.054013 -115.753565) (xy 141.073936 -115.701474) (xy 141.101232 -115.652839)
			(xy 141.135318 -115.608696) (xy 141.175467 -115.569987) (xy 141.220825 -115.537536) (xy 141.270425 -115.512035)
			(xy 141.323209 -115.494028) (xy 141.378052 -115.483898) (xy 141.433786 -115.481861) (xy 141.489223 -115.487961)
			(xy 141.54318 -115.502067) (xy 141.594509 -115.523879) (xy 141.642115 -115.552933) (xy 141.684983 -115.588608)
			(xy 141.7222 -115.630145) (xy 141.752973 -115.676658) (xy 141.776645 -115.727155) (xy 141.792713 -115.780562)
			(xy 141.800833 -115.835738) (xy 141.801342 -115.863624) (xy 141.800833 -115.89151) (xy 141.792713 -115.946686)
			(xy 141.776645 -116.000093) (xy 141.752973 -116.05059) (xy 141.7222 -116.097103) (xy 141.684983 -116.13864)
			(xy 141.642115 -116.174315) (xy 141.594509 -116.203369) (xy 141.54318 -116.225181) (xy 141.489223 -116.239287)
			(xy 141.433786 -116.245387) (xy 141.378052 -116.24335) (xy 141.323209 -116.23322) (xy 141.270425 -116.215213)
			(xy 141.220825 -116.189712) (xy 141.175467 -116.157261) (xy 141.135318 -116.118552) (xy 141.101232 -116.074409)
			(xy 141.073936 -116.025774) (xy 141.054013 -115.973683) (xy 141.041887 -115.919246) (xy 141.037816 -115.863624)
			(xy 138.852542 -115.863624) (xy 138.857211 -115.865431) (xy 138.905669 -115.892862) (xy 138.949627 -115.927044)
			(xy 138.988149 -115.967253) (xy 139.020419 -116.012633) (xy 139.045751 -116.062221) (xy 139.063607 -116.114965)
			(xy 139.073608 -116.169743) (xy 139.075541 -116.225393) (xy 139.069366 -116.280734) (xy 139.055213 -116.334589)
			(xy 139.033384 -116.385816) (xy 139.004341 -116.433326) (xy 138.968702 -116.476111) (xy 138.927223 -116.513262)
			(xy 138.880784 -116.543989) (xy 138.830374 -116.567642) (xy 138.77706 -116.583717) (xy 138.721977 -116.591872)
			(xy 138.666293 -116.591936) (xy 138.611191 -116.583906) (xy 138.557841 -116.567953) (xy 138.507377 -116.544415)
			(xy 138.460868 -116.513794) (xy 138.419305 -116.476738) (xy 138.383568 -116.434034) (xy 138.354416 -116.386591)
			(xy 138.33247 -116.335414) (xy 138.324844 -116.308632) (xy 138.318303 -116.28594) (xy 138.297986 -116.243312)
			(xy 138.270141 -116.205175) (xy 138.235726 -116.172841) (xy 138.195928 -116.147424) (xy 138.152119 -116.129802)
			(xy 138.105806 -116.12058) (xy 138.058588 -116.120077) (xy 138.01209 -116.128311) (xy 137.989818 -116.136166)
			(xy 137.963598 -116.145519) (xy 137.9092 -116.157338) (xy 137.853662 -116.161127) (xy 137.798163 -116.156804)
			(xy 137.743881 -116.144462) (xy 137.69197 -116.124362) (xy 137.64353 -116.096931) (xy 137.599591 -116.062752)
			(xy 137.561086 -116.02255) (xy 137.528831 -115.97718) (xy 137.503513 -115.927603) (xy 137.485668 -115.874874)
			(xy 137.475676 -115.820111) (xy 137.473749 -115.764477) (xy 136.948672 -115.764477) (xy 136.948672 -116.98605)
			(xy 136.969246 -117.006624) (xy 141.088616 -117.006624) (xy 141.092687 -116.951002) (xy 141.104813 -116.896565)
			(xy 141.124736 -116.844474) (xy 141.152032 -116.795839) (xy 141.186118 -116.751696) (xy 141.226267 -116.712987)
			(xy 141.271625 -116.680536) (xy 141.321225 -116.655035) (xy 141.374009 -116.637028) (xy 141.428852 -116.626898)
			(xy 141.484586 -116.624861) (xy 141.540023 -116.630961) (xy 141.59398 -116.645067) (xy 141.645309 -116.666879)
			(xy 141.692915 -116.695933) (xy 141.735783 -116.731608) (xy 141.773 -116.773145) (xy 141.803773 -116.819658)
			(xy 141.827445 -116.870155) (xy 141.843513 -116.923562) (xy 141.851633 -116.978738) (xy 141.852142 -117.006624)
			(xy 141.851633 -117.03451) (xy 141.843513 -117.089686) (xy 141.827445 -117.143093) (xy 141.803773 -117.19359)
			(xy 141.773 -117.240103) (xy 141.735783 -117.28164) (xy 141.692915 -117.317315) (xy 141.645309 -117.346369)
			(xy 141.59398 -117.368181) (xy 141.540023 -117.382287) (xy 141.484586 -117.388387) (xy 141.428852 -117.38635)
			(xy 141.374009 -117.37622) (xy 141.321225 -117.358213) (xy 141.271625 -117.332712) (xy 141.226267 -117.300261)
			(xy 141.186118 -117.261552) (xy 141.152032 -117.217409) (xy 141.124736 -117.168774) (xy 141.104813 -117.116683)
			(xy 141.092687 -117.062246) (xy 141.088616 -117.006624) (xy 136.969246 -117.006624) (xy 137.279126 -117.316504)
			(xy 137.295881 -117.332538) (xy 137.33407 -117.358839) (xy 137.376398 -117.377773) (xy 137.421459 -117.388711)
			(xy 137.467757 -117.391289) (xy 137.513754 -117.385423) (xy 137.557923 -117.371307) (xy 137.598797 -117.34941)
			(xy 137.6172 -117.3353) (xy 137.639362 -117.318203) (xy 137.687714 -117.290006) (xy 137.739667 -117.26918)
			(xy 137.794107 -117.256171) (xy 137.849863 -117.251261) (xy 137.905738 -117.254553) (xy 137.960532 -117.265977)
			(xy 138.013068 -117.285288) (xy 138.062216 -117.312072) (xy 138.106921 -117.345752) (xy 138.146223 -117.385605)
			(xy 138.179277 -117.430775) (xy 138.205374 -117.480291) (xy 138.223951 -117.533091) (xy 138.234612 -117.588038)
			(xy 138.236452 -117.61597) (xy 138.237894 -117.637458) (xy 138.247098 -117.679526) (xy 138.263263 -117.71944)
			(xy 138.285927 -117.756057) (xy 138.31444 -117.788327) (xy 138.347987 -117.815328) (xy 138.385606 -117.836286)
			(xy 138.42622 -117.850601) (xy 138.468666 -117.857862) (xy 138.490198 -117.858286)
		)
		(stroke
			(width 0)
			(type solid)
		)
		(fill yes)
		(layer "In7.Cu")
		(net "P3V3_CLK_NODE1")
	)
	(gr_poly
		(pts
			(xy 153.146506 -87.472774) (xy 153.934414 -87.472774) (xy 153.994866 -87.436452) (xy 154.011376 -87.40521)
			(xy 154.024711 -87.381077) (xy 154.057268 -87.336579) (xy 154.095893 -87.297232) (xy 154.139781 -87.263857)
			(xy 154.188016 -87.237148) (xy 154.239595 -87.217663) (xy 154.293441 -87.205807) (xy 154.348434 -87.201827)
			(xy 154.403427 -87.205807) (xy 154.457273 -87.217663) (xy 154.508852 -87.237148) (xy 154.557087 -87.263857)
			(xy 154.600975 -87.297232) (xy 154.6396 -87.336579) (xy 154.672157 -87.381077) (xy 154.685492 -87.40521)
			(xy 154.702002 -87.436452) (xy 154.762454 -87.472774) (xy 159.133794 -87.472774) (xy 159.194246 -87.436452)
			(xy 159.210756 -87.40521) (xy 159.224091 -87.381077) (xy 159.256648 -87.336579) (xy 159.295273 -87.297232)
			(xy 159.339161 -87.263857) (xy 159.387396 -87.237148) (xy 159.438975 -87.217663) (xy 159.492821 -87.205807)
			(xy 159.547814 -87.201827) (xy 159.602807 -87.205807) (xy 159.656653 -87.217663) (xy 159.708232 -87.237148)
			(xy 159.756467 -87.263857) (xy 159.800355 -87.297232) (xy 159.83898 -87.336579) (xy 159.871537 -87.381077)
			(xy 159.884872 -87.40521) (xy 159.893436 -87.420186) (xy 159.917129 -87.445244) (xy 159.946669 -87.463038)
			(xy 159.979897 -87.472267) (xy 159.99714 -87.472774) (xy 167.07104 -87.472774) (xy 168.56964 -85.974174)
			(xy 168.56964 -79.132176) (xy 168.569094 -79.115528) (xy 168.560473 -79.083367) (xy 168.543824 -79.054531)
			(xy 168.520281 -79.030986) (xy 168.491448 -79.014333) (xy 168.459288 -79.005708) (xy 168.44264 -79.005176)
			(xy 168.376854 -79.005176) (xy 168.252394 -79.127858) (xy 168.24706 -79.1718) (xy 168.243172 -79.199159)
			(xy 168.228529 -79.252443) (xy 168.206355 -79.303058) (xy 168.177112 -79.349945) (xy 168.141412 -79.392124)
			(xy 168.100002 -79.428714) (xy 168.053748 -79.458948) (xy 168.003617 -79.482195) (xy 167.950657 -79.497968)
			(xy 167.895976 -79.505938) (xy 167.840716 -79.505938) (xy 167.786035 -79.497968) (xy 167.733075 -79.482195)
			(xy 167.682944 -79.458948) (xy 167.63669 -79.428714) (xy 167.59528 -79.392124) (xy 167.55958 -79.349945)
			(xy 167.530337 -79.303058) (xy 167.508163 -79.252443) (xy 167.49352 -79.199159) (xy 167.489632 -79.1718)
			(xy 167.484298 -79.127858) (xy 167.359838 -79.005176) (xy 165.584632 -79.005176) (xy 163.5252 -76.945744)
			(xy 158.854394 -76.945744) (xy 158.23692 -77.563218) (xy 158.23692 -79.266885) (xy 162.222378 -79.266885)
			(xy 162.222379 -79.2113) (xy 162.230446 -79.156303) (xy 162.246408 -79.10306) (xy 162.269928 -79.052696)
			(xy 162.300507 -79.006278) (xy 162.337498 -78.964789) (xy 162.380119 -78.929107) (xy 162.427466 -78.899988)
			(xy 162.478537 -78.878047) (xy 162.532252 -78.86375) (xy 162.587473 -78.857398) (xy 162.643031 -78.859127)
			(xy 162.69775 -78.8689) (xy 162.750471 -78.88651) (xy 162.80008 -78.911583) (xy 162.845524 -78.943591)
			(xy 162.885843 -78.981854) (xy 162.903408 -79.003398) (xy 162.918007 -79.021163) (xy 162.952464 -79.051603)
			(xy 162.991835 -79.075348) (xy 163.034836 -79.091622) (xy 163.080063 -79.099894) (xy 163.126041 -79.099894)
			(xy 163.171268 -79.091622) (xy 163.214269 -79.075348) (xy 163.25364 -79.051603) (xy 163.288097 -79.021163)
			(xy 163.302696 -79.003398) (xy 163.320251 -78.981846) (xy 163.360571 -78.943582) (xy 163.406017 -78.911574)
			(xy 163.455627 -78.8865) (xy 163.50835 -78.86889) (xy 163.56307 -78.859118) (xy 163.618629 -78.857389)
			(xy 163.673851 -78.863741) (xy 163.727567 -78.878039) (xy 163.77864 -78.89998) (xy 163.825988 -78.9291)
			(xy 163.868609 -78.964783) (xy 163.9056 -79.006273) (xy 163.93618 -79.052692) (xy 163.9597 -79.103057)
			(xy 163.975663 -79.156301) (xy 163.98373 -79.211299) (xy 163.983732 -79.266885) (xy 163.975667 -79.321883)
			(xy 163.959706 -79.375129) (xy 163.936188 -79.425494) (xy 163.90561 -79.471914) (xy 163.86862 -79.513406)
			(xy 163.826 -79.54909) (xy 163.778654 -79.578213) (xy 163.727582 -79.600156) (xy 163.673867 -79.614456)
			(xy 163.618645 -79.62081) (xy 163.563086 -79.619084) (xy 163.508365 -79.609313) (xy 163.455641 -79.591706)
			(xy 163.406031 -79.566634) (xy 163.360584 -79.534628) (xy 163.320262 -79.496366) (xy 163.302696 -79.474822)
			(xy 163.288097 -79.457057) (xy 163.25364 -79.426617) (xy 163.214269 -79.402872) (xy 163.171268 -79.386598)
			(xy 163.126041 -79.378326) (xy 163.080063 -79.378326) (xy 163.034836 -79.386598) (xy 162.991835 -79.402872)
			(xy 162.952464 -79.426617) (xy 162.918007 -79.457057) (xy 162.903408 -79.474822) (xy 162.885833 -79.496358)
			(xy 162.845512 -79.534619) (xy 162.800066 -79.566625) (xy 162.750457 -79.591697) (xy 162.697734 -79.609304)
			(xy 162.643015 -79.619075) (xy 162.587457 -79.620801) (xy 162.532236 -79.614447) (xy 162.478522 -79.600148)
			(xy 162.427452 -79.578205) (xy 162.380106 -79.549083) (xy 162.337487 -79.5134) (xy 162.300498 -79.471909)
			(xy 162.26992 -79.42549) (xy 162.246403 -79.375126) (xy 162.230443 -79.321881) (xy 162.222378 -79.266885)
			(xy 158.23692 -79.266885) (xy 158.23692 -80.31607) (xy 157.679885 -80.873105) (xy 164.759148 -80.873105)
			(xy 164.763036 -80.818742) (xy 164.774622 -80.765487) (xy 164.793669 -80.714422) (xy 164.81979 -80.666588)
			(xy 164.852453 -80.622959) (xy 164.890994 -80.584424) (xy 164.934627 -80.551765) (xy 164.982464 -80.52565)
			(xy 165.033531 -80.506609) (xy 165.086788 -80.49503) (xy 165.141151 -80.491148) (xy 165.195512 -80.495044)
			(xy 165.248766 -80.506637) (xy 165.299828 -80.525692) (xy 165.347658 -80.55182) (xy 165.369748 -80.567784)
			(xy 165.38876 -80.58138) (xy 165.430643 -80.602112) (xy 165.475611 -80.614838) (xy 165.522148 -80.619128)
			(xy 165.568685 -80.614838) (xy 165.613653 -80.602112) (xy 165.655536 -80.58138) (xy 165.674548 -80.567784)
			(xy 165.69963 -80.549729) (xy 165.754389 -80.521088) (xy 165.813042 -80.501628) (xy 165.843458 -80.496156)
			(xy 165.865516 -80.492151) (xy 165.907884 -80.477511) (xy 165.947027 -80.455666) (xy 165.98173 -80.427292)
			(xy 166.010918 -80.393271) (xy 166.033684 -80.354656) (xy 166.049323 -80.312647) (xy 166.057349 -80.268545)
			(xy 166.057514 -80.22372) (xy 166.049812 -80.17956) (xy 166.042594 -80.158336) (xy 166.033671 -80.132279)
			(xy 166.022469 -80.078356) (xy 166.019135 -80.023383) (xy 166.023739 -79.968502) (xy 166.036185 -79.914852)
			(xy 166.056214 -79.86355) (xy 166.083412 -79.815659) (xy 166.117211 -79.772176) (xy 166.156911 -79.734004)
			(xy 166.201685 -79.701936) (xy 166.250606 -79.676638) (xy 166.302654 -79.658636) (xy 166.356751 -79.648304)
			(xy 166.41177 -79.645856) (xy 166.46657 -79.651343) (xy 166.520012 -79.664652) (xy 166.570986 -79.685505)
			(xy 166.618432 -79.71347) (xy 166.661365 -79.747965) (xy 166.698892 -79.788275) (xy 166.730235 -79.83356)
			(xy 166.754742 -79.882882) (xy 166.771903 -79.935214) (xy 166.781363 -79.989469) (xy 166.782924 -80.044521)
			(xy 166.776555 -80.099226) (xy 166.762387 -80.152447) (xy 166.740716 -80.203078) (xy 166.71199 -80.250067)
			(xy 166.676808 -80.292439) (xy 166.635899 -80.329312) (xy 166.590114 -80.359921) (xy 166.540405 -80.38363)
			(xy 166.487803 -80.399947) (xy 166.460678 -80.404716) (xy 166.438619 -80.408713) (xy 166.396256 -80.42336)
			(xy 166.357118 -80.44521) (xy 166.322419 -80.473586) (xy 166.293235 -80.507608) (xy 166.270471 -80.546222)
			(xy 166.254832 -80.588229) (xy 166.246803 -80.632329) (xy 166.246633 -80.677153) (xy 166.254328 -80.721311)
			(xy 166.261542 -80.742536) (xy 166.270284 -80.768258) (xy 166.281445 -80.82142) (xy 166.28495 -80.875627)
			(xy 166.280728 -80.929783) (xy 166.268864 -80.982793) (xy 166.249599 -81.033582) (xy 166.223321 -81.081124)
			(xy 166.190564 -81.124457) (xy 166.15199 -81.162703) (xy 166.108379 -81.195088) (xy 166.060614 -81.220958)
			(xy 166.009661 -81.239788) (xy 165.956553 -81.251199) (xy 165.902362 -81.254958) (xy 165.848187 -81.250989)
			(xy 165.795122 -81.239374) (xy 165.744243 -81.220347) (xy 165.696578 -81.194293) (xy 165.674548 -81.1784)
			(xy 165.655536 -81.164804) (xy 165.613653 -81.144072) (xy 165.568685 -81.131346) (xy 165.522148 -81.127056)
			(xy 165.475611 -81.131346) (xy 165.430643 -81.144072) (xy 165.38876 -81.164804) (xy 165.369748 -81.1784)
			(xy 165.347666 -81.194375) (xy 165.299837 -81.220504) (xy 165.248776 -81.23956) (xy 165.195522 -81.251155)
			(xy 165.14116 -81.255052) (xy 165.086797 -81.251172) (xy 165.03354 -81.239594) (xy 164.982473 -81.220554)
			(xy 164.934635 -81.19444) (xy 164.891001 -81.161783) (xy 164.85246 -81.123248) (xy 164.819795 -81.07962)
			(xy 164.793673 -81.031787) (xy 164.774624 -80.980722) (xy 164.763037 -80.927467) (xy 164.759148 -80.873105)
			(xy 157.679885 -80.873105) (xy 156.272661 -82.280329) (xy 165.06144 -82.280329) (xy 165.065324 -82.225967)
			(xy 165.076906 -82.172711) (xy 165.095949 -82.121646) (xy 165.122066 -82.073811) (xy 165.154725 -82.03018)
			(xy 165.193261 -81.991641) (xy 165.23689 -81.958979) (xy 165.284724 -81.932859) (xy 165.335787 -81.913813)
			(xy 165.389042 -81.902228) (xy 165.443404 -81.89834) (xy 165.497765 -81.902229) (xy 165.55102 -81.913815)
			(xy 165.602083 -81.932862) (xy 165.649916 -81.958983) (xy 165.672008 -81.974944) (xy 165.69102 -81.98854)
			(xy 165.732903 -82.009272) (xy 165.777871 -82.021998) (xy 165.824408 -82.026288) (xy 165.870945 -82.021998)
			(xy 165.915913 -82.009272) (xy 165.957796 -81.98854) (xy 165.976808 -81.974944) (xy 165.998941 -81.959049)
			(xy 166.046763 -81.932936) (xy 166.097815 -81.913895) (xy 166.151057 -81.902313) (xy 166.205405 -81.898427)
			(xy 166.259754 -81.902315) (xy 166.312995 -81.913898) (xy 166.364047 -81.932941) (xy 166.411868 -81.959055)
			(xy 166.455486 -81.99171) (xy 166.494012 -82.03024) (xy 166.526663 -82.073861) (xy 166.552773 -82.121684)
			(xy 166.571812 -82.172737) (xy 166.58339 -82.22598) (xy 166.587273 -82.280329) (xy 166.583382 -82.334677)
			(xy 166.571795 -82.387918) (xy 166.55275 -82.438968) (xy 166.526632 -82.486788) (xy 166.493975 -82.530404)
			(xy 166.455442 -82.568928) (xy 166.411819 -82.601576) (xy 166.363994 -82.627683) (xy 166.31294 -82.646718)
			(xy 166.259697 -82.658294) (xy 166.205348 -82.662173) (xy 166.151 -82.658279) (xy 166.09776 -82.646689)
			(xy 166.046711 -82.62764) (xy 165.998893 -82.601519) (xy 165.976808 -82.58556) (xy 165.957796 -82.571964)
			(xy 165.915913 -82.551232) (xy 165.870945 -82.538506) (xy 165.824408 -82.534216) (xy 165.777871 -82.538506)
			(xy 165.732903 -82.551232) (xy 165.69102 -82.571964) (xy 165.672008 -82.58556) (xy 165.649965 -82.601585)
			(xy 165.602136 -82.627714) (xy 165.551075 -82.646769) (xy 165.497822 -82.658363) (xy 165.443461 -82.66226)
			(xy 165.389099 -82.65838) (xy 165.335843 -82.646803) (xy 165.284776 -82.627765) (xy 165.236939 -82.601652)
			(xy 165.193305 -82.568996) (xy 165.154763 -82.530463) (xy 165.122097 -82.486837) (xy 165.095973 -82.439006)
			(xy 165.076922 -82.387944) (xy 165.065333 -82.33469) (xy 165.06144 -82.280329) (xy 156.272661 -82.280329)
			(xy 155.73248 -82.82051) (xy 154.893772 -82.82051) (xy 154.88539 -82.820764) (xy 153.276554 -82.820764)
			(xy 153.260219 -82.821271) (xy 153.228622 -82.829572) (xy 153.200166 -82.84562) (xy 153.176713 -82.868364)
			(xy 153.1598 -82.896314) (xy 153.150533 -82.927642) (xy 153.149554 -82.943954) (xy 153.148274 -82.971964)
			(xy 153.138517 -83.027178) (xy 153.120781 -83.080369) (xy 153.095449 -83.13039) (xy 153.063066 -83.176163)
			(xy 153.024331 -83.216702) (xy 152.980078 -83.251133) (xy 152.931261 -83.278713) (xy 152.878932 -83.29885)
			(xy 152.824218 -83.311108) (xy 152.7683 -83.315224) (xy 152.712382 -83.311108) (xy 152.657668 -83.29885)
			(xy 152.605339 -83.278713) (xy 152.556522 -83.251133) (xy 152.512269 -83.216702) (xy 152.473534 -83.176163)
			(xy 152.441151 -83.13039) (xy 152.415819 -83.080369) (xy 152.398083 -83.027178) (xy 152.388326 -82.971964)
			(xy 152.387046 -82.943954) (xy 152.386061 -82.927634) (xy 152.376826 -82.896282) (xy 152.359926 -82.868305)
			(xy 152.336472 -82.845543) (xy 152.308003 -82.829488) (xy 152.276388 -82.821195) (xy 152.260046 -82.820764)
			(xy 150.694644 -82.820764) (xy 150.692866 -82.82051) (xy 149.527006 -82.82051) (xy 149.525228 -82.820764)
			(xy 149.424644 -82.820764) (xy 149.422866 -82.82051) (xy 148.257006 -82.82051) (xy 148.255228 -82.820764)
			(xy 131.98221 -82.820764) (xy 131.973828 -82.82051) (xy 131.824222 -82.82051) (xy 131.717288 -82.713576)
			(xy 131.712462 -82.70875) (xy 131.712208 -82.70875) (xy 128.817116 -79.813404) (xy 128.817116 -72.511158)
			(xy 128.759966 -72.441308) (xy 128.715262 -72.432164) (xy 128.673249 -72.423151) (xy 128.590944 -72.398453)
			(xy 128.511235 -72.366347) (xy 128.434788 -72.327102) (xy 128.362242 -72.281045) (xy 128.294201 -72.22856)
			(xy 128.231233 -72.170085) (xy 128.173863 -72.106109) (xy 128.122571 -72.037165) (xy 128.077784 -71.963827)
			(xy 128.039876 -71.886709) (xy 128.009163 -71.806454) (xy 127.985901 -71.72373) (xy 127.970285 -71.639229)
			(xy 127.962444 -71.553656) (xy 127.962445 -71.467725) (xy 127.970287 -71.382152) (xy 127.985905 -71.297651)
			(xy 128.009169 -71.214928) (xy 128.039883 -71.134673) (xy 128.077793 -71.057556) (xy 128.122582 -70.98422)
			(xy 128.173876 -70.915276) (xy 128.231246 -70.851301) (xy 128.294216 -70.792828) (xy 128.362258 -70.740344)
			(xy 128.434805 -70.694288) (xy 128.511252 -70.655045) (xy 128.590962 -70.622941) (xy 128.673268 -70.598244)
			(xy 128.715262 -70.58914) (xy 128.73226 -70.58515) (xy 128.763324 -70.569233) (xy 128.788917 -70.545501)
			(xy 128.80713 -70.515726) (xy 128.816601 -70.482132) (xy 128.817116 -70.46468) (xy 128.817116 -62.036452)
			(xy 129.41808 -61.435234) (xy 129.745232 -61.108082) (xy 133.672072 -61.108082) (xy 134.134352 -60.645802)
			(xy 135.791194 -60.645802) (xy 135.806425 -60.64539) (xy 135.836031 -60.638223) (xy 135.863085 -60.624227)
			(xy 135.886039 -60.604203) (xy 135.903577 -60.579298) (xy 135.909558 -60.565284) (xy 135.909558 -60.56503)
			(xy 135.920212 -60.539161) (xy 135.947997 -60.490602) (xy 135.982576 -60.446621) (xy 136.023207 -60.408163)
			(xy 136.06902 -60.376051) (xy 136.119032 -60.350975) (xy 136.17217 -60.333472) (xy 136.227294 -60.323917)
			(xy 136.283222 -60.322516) (xy 136.338756 -60.329298) (xy 136.392704 -60.344119) (xy 136.443908 -60.366659)
			(xy 136.46785 -60.381134) (xy 136.478012 -60.387636) (xy 136.497586 -60.401742) (xy 136.506966 -60.409328)
			(xy 136.526297 -60.425736) (xy 136.560882 -60.462816) (xy 136.590257 -60.504145) (xy 136.613905 -60.548998)
			(xy 136.623044 -60.57265) (xy 136.632696 -60.599066) (xy 136.839452 -60.805822) (xy 139.862814 -60.805822)
			(xy 140.60678 -60.061856) (xy 140.60678 -58.236358) (xy 140.274548 -57.903872) (xy 139.371832 -57.903872)
			(xy 138.819382 -58.456576) (xy 136.854184 -58.456576) (xy 136.734804 -58.337196) (xy 136.733788 -58.337196)
			(xy 136.67359 -58.277252) (xy 135.857742 -58.277252) (xy 135.839962 -58.259472) (xy 135.781542 -58.240676)
			(xy 135.751316 -58.245756) (xy 135.723726 -58.249823) (xy 135.667967 -58.250854) (xy 135.612653 -58.243757)
			(xy 135.558961 -58.228682) (xy 135.508036 -58.20595) (xy 135.460963 -58.176046) (xy 135.418746 -58.139608)
			(xy 135.382284 -58.097411) (xy 135.352353 -58.050356) (xy 135.329592 -57.999444) (xy 135.314487 -57.945761)
			(xy 135.307358 -57.89045) (xy 135.308357 -57.834692) (xy 135.312404 -57.807098) (xy 135.317484 -57.776618)
			(xy 135.298688 -57.718198) (xy 135.193532 -57.613042) (xy 132.605272 -57.613042) (xy 131.982972 -58.235342)
			(xy 131.545584 -58.235342) (xy 131.560157 -58.259373) (xy 131.582855 -58.310786) (xy 131.59777 -58.364971)
			(xy 131.604578 -58.420757) (xy 131.603134 -58.476939) (xy 131.593468 -58.532302) (xy 131.580684 -58.570876)
			(xy 133.756652 -58.570876) (xy 133.760723 -58.515254) (xy 133.772849 -58.460817) (xy 133.792772 -58.408726)
			(xy 133.820068 -58.360091) (xy 133.854154 -58.315948) (xy 133.894303 -58.277239) (xy 133.939661 -58.244788)
			(xy 133.989261 -58.219287) (xy 134.042045 -58.20128) (xy 134.096888 -58.19115) (xy 134.152622 -58.189113)
			(xy 134.208059 -58.195213) (xy 134.262016 -58.209319) (xy 134.313345 -58.231131) (xy 134.360951 -58.260185)
			(xy 134.403819 -58.29586) (xy 134.441036 -58.337397) (xy 134.471809 -58.38391) (xy 134.495481 -58.434407)
			(xy 134.511549 -58.487814) (xy 134.519669 -58.54299) (xy 134.520178 -58.570876) (xy 134.519669 -58.598762)
			(xy 134.511549 -58.653938) (xy 134.495481 -58.707345) (xy 134.471809 -58.757842) (xy 134.441036 -58.804355)
			(xy 134.403819 -58.845892) (xy 134.360951 -58.881567) (xy 134.313345 -58.910621) (xy 134.262016 -58.932433)
			(xy 134.208059 -58.946539) (xy 134.152622 -58.952639) (xy 134.096888 -58.950602) (xy 134.042045 -58.940472)
			(xy 133.989261 -58.922465) (xy 133.939661 -58.896964) (xy 133.894303 -58.864513) (xy 133.854154 -58.825804)
			(xy 133.820068 -58.781661) (xy 133.792772 -58.733026) (xy 133.772849 -58.680935) (xy 133.760723 -58.626498)
			(xy 133.756652 -58.570876) (xy 131.580684 -58.570876) (xy 131.575788 -58.585649) (xy 131.550478 -58.635828)
			(xy 131.518085 -58.681753) (xy 131.479308 -58.722432) (xy 131.434985 -58.756987) (xy 131.386075 -58.784669)
			(xy 131.333635 -58.804881) (xy 131.278798 -58.817185) (xy 131.22275 -58.821316) (xy 131.166702 -58.817185)
			(xy 131.111865 -58.804881) (xy 131.059425 -58.784669) (xy 131.010515 -58.756987) (xy 130.966192 -58.722432)
			(xy 130.927415 -58.681753) (xy 130.895022 -58.635828) (xy 130.869712 -58.585649) (xy 130.852032 -58.532302)
			(xy 130.842366 -58.476939) (xy 130.840922 -58.420757) (xy 130.84773 -58.364971) (xy 130.862645 -58.310786)
			(xy 130.885343 -58.259373) (xy 130.899916 -58.235342) (xy 128.569212 -58.235342) (xy 128.46431 -58.340244)
			(xy 125.363224 -58.340244) (xy 125.339901 -58.340777) (xy 125.29404 -58.349297) (xy 125.250502 -58.366039)
			(xy 125.210747 -58.390439) (xy 125.176109 -58.421681) (xy 125.147749 -58.458716) (xy 125.126619 -58.500301)
			(xy 125.113428 -58.545043) (xy 125.108617 -58.59144) (xy 125.112348 -58.637937) (xy 125.124496 -58.682973)
			(xy 125.134116 -58.704226) (xy 125.146601 -58.729464) (xy 125.164835 -58.782736) (xy 125.175043 -58.838109)
			(xy 125.177001 -58.894382) (xy 125.170669 -58.950331) (xy 125.156182 -59.004741) (xy 125.133857 -59.056432)
			(xy 125.104177 -59.104281) (xy 125.067788 -59.147249) (xy 125.025479 -59.184402) (xy 124.97817 -59.214934)
			(xy 124.926887 -59.238181) (xy 124.872744 -59.25364) (xy 124.816918 -59.260973) (xy 124.760619 -59.260023)
			(xy 124.705072 -59.250809) (xy 124.651482 -59.233532) (xy 124.601013 -59.208567) (xy 124.577602 -59.192922)
			(xy 124.555949 -59.177325) (xy 124.516804 -59.141057) (xy 124.483089 -59.099692) (xy 124.46889 -59.077098)
			(xy 124.461016 -59.06389) (xy 124.450094 -59.052968) (xy 124.437923 -59.041615) (xy 124.409084 -59.025026)
			(xy 124.37694 -59.016441) (xy 124.34367 -59.016441) (xy 124.311526 -59.025026) (xy 124.282687 -59.041615)
			(xy 124.270516 -59.052968) (xy 124.18314 -59.140344) (xy 124.18314 -59.295039) (xy 125.633225 -59.295039)
			(xy 125.639328 -59.239565) (xy 125.653444 -59.185572) (xy 125.675271 -59.134209) (xy 125.704344 -59.086571)
			(xy 125.740043 -59.043675) (xy 125.781607 -59.006433) (xy 125.828151 -58.975639) (xy 125.878682 -58.951951)
			(xy 125.932124 -58.935873) (xy 125.987338 -58.927747) (xy 126.015242 -58.927238) (xy 126.043146 -58.927747)
			(xy 126.09836 -58.935873) (xy 126.151802 -58.951951) (xy 126.202333 -58.975639) (xy 126.248877 -59.006433)
			(xy 126.290441 -59.043675) (xy 126.32614 -59.086571) (xy 126.355213 -59.134209) (xy 126.37704 -59.185572)
			(xy 126.391156 -59.239565) (xy 126.397259 -59.295039) (xy 126.395221 -59.35081) (xy 126.385084 -59.405689)
			(xy 126.367065 -59.458509) (xy 126.341547 -59.508141) (xy 126.309075 -59.553529) (xy 126.27034 -59.593706)
			(xy 126.226168 -59.627814) (xy 126.1775 -59.655128) (xy 126.125374 -59.675064) (xy 126.070901 -59.687199)
			(xy 126.015242 -59.691273) (xy 125.959583 -59.687199) (xy 125.90511 -59.675064) (xy 125.852984 -59.655128)
			(xy 125.804316 -59.627814) (xy 125.760144 -59.593706) (xy 125.721409 -59.553529) (xy 125.688937 -59.508141)
			(xy 125.663419 -59.458509) (xy 125.6454 -59.405689) (xy 125.635263 -59.35081) (xy 125.633225 -59.295039)
			(xy 124.18314 -59.295039) (xy 124.18314 -59.822089) (xy 126.383033 -59.822089) (xy 126.389136 -59.766615)
			(xy 126.403252 -59.712622) (xy 126.425079 -59.661259) (xy 126.454152 -59.613621) (xy 126.489851 -59.570725)
			(xy 126.531415 -59.533483) (xy 126.577959 -59.502689) (xy 126.62849 -59.479001) (xy 126.681932 -59.462923)
			(xy 126.737146 -59.454797) (xy 126.76505 -59.454288) (xy 126.792954 -59.454797) (xy 126.848168 -59.462923)
			(xy 126.90161 -59.479001) (xy 126.952141 -59.502689) (xy 126.998685 -59.533483) (xy 127.031648 -59.563018)
			(xy 130.599687 -59.563018) (xy 130.605787 -59.507581) (xy 130.619893 -59.453624) (xy 130.641705 -59.402295)
			(xy 130.670759 -59.354689) (xy 130.706434 -59.311821) (xy 130.747971 -59.274604) (xy 130.794484 -59.243831)
			(xy 130.844981 -59.220159) (xy 130.898388 -59.204091) (xy 130.953564 -59.195971) (xy 130.98145 -59.195462)
			(xy 131.009336 -59.195971) (xy 131.064512 -59.204091) (xy 131.117919 -59.220159) (xy 131.168416 -59.243831)
			(xy 131.214929 -59.274604) (xy 131.256466 -59.311821) (xy 131.292141 -59.354689) (xy 131.321195 -59.402295)
			(xy 131.343007 -59.453624) (xy 131.357113 -59.507581) (xy 131.363213 -59.563018) (xy 131.361254 -59.616612)
			(xy 132.885687 -59.616612) (xy 132.891787 -59.561175) (xy 132.905893 -59.507218) (xy 132.927705 -59.455889)
			(xy 132.956759 -59.408283) (xy 132.992434 -59.365415) (xy 133.033971 -59.328198) (xy 133.080484 -59.297425)
			(xy 133.130981 -59.273753) (xy 133.184388 -59.257685) (xy 133.239564 -59.249565) (xy 133.26745 -59.249056)
			(xy 133.295336 -59.249565) (xy 133.350512 -59.257685) (xy 133.403919 -59.273753) (xy 133.454416 -59.297425)
			(xy 133.500929 -59.328198) (xy 133.542466 -59.365415) (xy 133.578141 -59.408283) (xy 133.607195 -59.455889)
			(xy 133.629007 -59.507218) (xy 133.643113 -59.561175) (xy 133.649213 -59.616612) (xy 133.647176 -59.672346)
			(xy 133.644244 -59.688222) (xy 135.933686 -59.688222) (xy 135.937757 -59.6326) (xy 135.949883 -59.578163)
			(xy 135.969806 -59.526072) (xy 135.997102 -59.477437) (xy 136.031188 -59.433294) (xy 136.071337 -59.394585)
			(xy 136.116695 -59.362134) (xy 136.166295 -59.336633) (xy 136.219079 -59.318626) (xy 136.273922 -59.308496)
			(xy 136.329656 -59.306459) (xy 136.385093 -59.312559) (xy 136.43905 -59.326665) (xy 136.490379 -59.348477)
			(xy 136.537985 -59.377531) (xy 136.580853 -59.413206) (xy 136.61807 -59.454743) (xy 136.648843 -59.501256)
			(xy 136.672515 -59.551753) (xy 136.688583 -59.60516) (xy 136.696703 -59.660336) (xy 136.697212 -59.688222)
			(xy 136.696703 -59.716108) (xy 136.688583 -59.771284) (xy 136.672515 -59.824691) (xy 136.648843 -59.875188)
			(xy 136.61807 -59.921701) (xy 136.580853 -59.963238) (xy 136.537985 -59.998913) (xy 136.508516 -60.016898)
			(xy 138.297156 -60.016898) (xy 138.301227 -59.961276) (xy 138.313353 -59.906839) (xy 138.333276 -59.854748)
			(xy 138.360572 -59.806113) (xy 138.394658 -59.76197) (xy 138.434807 -59.723261) (xy 138.480165 -59.69081)
			(xy 138.529765 -59.665309) (xy 138.582549 -59.647302) (xy 138.637392 -59.637172) (xy 138.693126 -59.635135)
			(xy 138.748563 -59.641235) (xy 138.80252 -59.655341) (xy 138.853849 -59.677153) (xy 138.901455 -59.706207)
			(xy 138.944323 -59.741882) (xy 138.98154 -59.783419) (xy 139.012313 -59.829932) (xy 139.035985 -59.880429)
			(xy 139.052053 -59.933836) (xy 139.060173 -59.989012) (xy 139.060682 -60.016898) (xy 139.060173 -60.044784)
			(xy 139.052053 -60.09996) (xy 139.035985 -60.153367) (xy 139.012313 -60.203864) (xy 138.98154 -60.250377)
			(xy 138.944323 -60.291914) (xy 138.901455 -60.327589) (xy 138.853849 -60.356643) (xy 138.80252 -60.378455)
			(xy 138.748563 -60.392561) (xy 138.693126 -60.398661) (xy 138.637392 -60.396624) (xy 138.582549 -60.386494)
			(xy 138.529765 -60.368487) (xy 138.480165 -60.342986) (xy 138.434807 -60.310535) (xy 138.394658 -60.271826)
			(xy 138.360572 -60.227683) (xy 138.333276 -60.179048) (xy 138.313353 -60.126957) (xy 138.301227 -60.07252)
			(xy 138.297156 -60.016898) (xy 136.508516 -60.016898) (xy 136.490379 -60.027967) (xy 136.43905 -60.049779)
			(xy 136.385093 -60.063885) (xy 136.329656 -60.069985) (xy 136.273922 -60.067948) (xy 136.219079 -60.057818)
			(xy 136.166295 -60.039811) (xy 136.116695 -60.01431) (xy 136.071337 -59.981859) (xy 136.031188 -59.94315)
			(xy 135.997102 -59.899007) (xy 135.969806 -59.850372) (xy 135.949883 -59.798281) (xy 135.937757 -59.743844)
			(xy 135.933686 -59.688222) (xy 133.644244 -59.688222) (xy 133.637046 -59.727189) (xy 133.619039 -59.779973)
			(xy 133.593538 -59.829573) (xy 133.561087 -59.874931) (xy 133.522378 -59.91508) (xy 133.478235 -59.949166)
			(xy 133.4296 -59.976462) (xy 133.377509 -59.996385) (xy 133.323072 -60.008511) (xy 133.26745 -60.012582)
			(xy 133.211828 -60.008511) (xy 133.157391 -59.996385) (xy 133.1053 -59.976462) (xy 133.056665 -59.949166)
			(xy 133.012522 -59.91508) (xy 132.973813 -59.874931) (xy 132.941362 -59.829573) (xy 132.915861 -59.779973)
			(xy 132.897854 -59.727189) (xy 132.887724 -59.672346) (xy 132.885687 -59.616612) (xy 131.361254 -59.616612)
			(xy 131.361176 -59.618752) (xy 131.351046 -59.673595) (xy 131.333039 -59.726379) (xy 131.307538 -59.775979)
			(xy 131.275087 -59.821337) (xy 131.236378 -59.861486) (xy 131.192235 -59.895572) (xy 131.1436 -59.922868)
			(xy 131.091509 -59.942791) (xy 131.037072 -59.954917) (xy 130.98145 -59.958988) (xy 130.925828 -59.954917)
			(xy 130.871391 -59.942791) (xy 130.8193 -59.922868) (xy 130.770665 -59.895572) (xy 130.726522 -59.861486)
			(xy 130.687813 -59.821337) (xy 130.655362 -59.775979) (xy 130.629861 -59.726379) (xy 130.611854 -59.673595)
			(xy 130.601724 -59.618752) (xy 130.599687 -59.563018) (xy 127.031648 -59.563018) (xy 127.040249 -59.570725)
			(xy 127.075948 -59.613621) (xy 127.105021 -59.661259) (xy 127.126848 -59.712622) (xy 127.140964 -59.766615)
			(xy 127.147067 -59.822089) (xy 127.145029 -59.87786) (xy 127.134892 -59.932739) (xy 127.116873 -59.985559)
			(xy 127.091355 -60.035191) (xy 127.058883 -60.080579) (xy 127.020148 -60.120756) (xy 126.975976 -60.154864)
			(xy 126.927308 -60.182178) (xy 126.875182 -60.202114) (xy 126.820709 -60.214249) (xy 126.76505 -60.218323)
			(xy 126.709391 -60.214249) (xy 126.654918 -60.202114) (xy 126.602792 -60.182178) (xy 126.554124 -60.154864)
			(xy 126.509952 -60.120756) (xy 126.471217 -60.080579) (xy 126.438745 -60.035191) (xy 126.413227 -59.985559)
			(xy 126.395208 -59.932739) (xy 126.385071 -59.87786) (xy 126.383033 -59.822089) (xy 124.18314 -59.822089)
			(xy 124.18314 -60.706) (xy 128.395728 -60.706) (xy 128.399801 -60.650341) (xy 128.411936 -60.595868)
			(xy 128.431872 -60.543742) (xy 128.459186 -60.495074) (xy 128.493294 -60.450902) (xy 128.533471 -60.412167)
			(xy 128.578859 -60.379695) (xy 128.628491 -60.354177) (xy 128.681311 -60.336158) (xy 128.73619 -60.326021)
			(xy 128.791961 -60.323983) (xy 128.847435 -60.330086) (xy 128.901428 -60.344202) (xy 128.952791 -60.366029)
			(xy 129.000429 -60.395102) (xy 129.043325 -60.430801) (xy 129.080567 -60.472365) (xy 129.111361 -60.518909)
			(xy 129.135049 -60.56944) (xy 129.151127 -60.622882) (xy 129.159253 -60.678096) (xy 129.159762 -60.706)
			(xy 129.159253 -60.733904) (xy 129.151127 -60.789118) (xy 129.135049 -60.84256) (xy 129.111361 -60.893091)
			(xy 129.080567 -60.939635) (xy 129.043325 -60.981199) (xy 129.000429 -61.016898) (xy 128.952791 -61.045971)
			(xy 128.901428 -61.067798) (xy 128.847435 -61.081914) (xy 128.791961 -61.088017) (xy 128.73619 -61.085979)
			(xy 128.681311 -61.075842) (xy 128.628491 -61.057823) (xy 128.578859 -61.032305) (xy 128.533471 -60.999833)
			(xy 128.493294 -60.961098) (xy 128.459186 -60.916926) (xy 128.431872 -60.868258) (xy 128.411936 -60.816132)
			(xy 128.399801 -60.761659) (xy 128.395728 -60.706) (xy 124.18314 -60.706) (xy 124.18314 -61.246766)
			(xy 124.23267 -61.314076) (xy 124.272548 -61.326522) (xy 124.298111 -61.334953) (xy 124.346755 -61.358)
			(xy 124.391676 -61.387655) (xy 124.431982 -61.423331) (xy 124.466873 -61.464318) (xy 124.495656 -61.509803)
			(xy 124.517759 -61.558883) (xy 124.532744 -61.610582) (xy 124.540312 -61.663874) (xy 124.540312 -61.676806)
			(xy 126.467107 -61.676806) (xy 126.473207 -61.621369) (xy 126.487313 -61.567412) (xy 126.509125 -61.516083)
			(xy 126.538179 -61.468477) (xy 126.573854 -61.425609) (xy 126.615391 -61.388392) (xy 126.661904 -61.357619)
			(xy 126.712401 -61.333947) (xy 126.765808 -61.317879) (xy 126.820984 -61.309759) (xy 126.84887 -61.30925)
			(xy 126.876756 -61.309759) (xy 126.931932 -61.317879) (xy 126.985339 -61.333947) (xy 127.035836 -61.357619)
			(xy 127.082349 -61.388392) (xy 127.123886 -61.425609) (xy 127.159561 -61.468477) (xy 127.188615 -61.516083)
			(xy 127.210427 -61.567412) (xy 127.224533 -61.621369) (xy 127.230633 -61.676806) (xy 127.228596 -61.73254)
			(xy 127.218466 -61.787383) (xy 127.200459 -61.840167) (xy 127.174958 -61.889767) (xy 127.142507 -61.935125)
			(xy 127.103798 -61.975274) (xy 127.059655 -62.00936) (xy 127.01102 -62.036656) (xy 126.958929 -62.056579)
			(xy 126.904492 -62.068705) (xy 126.84887 -62.072776) (xy 126.793248 -62.068705) (xy 126.738811 -62.056579)
			(xy 126.68672 -62.036656) (xy 126.638085 -62.00936) (xy 126.593942 -61.975274) (xy 126.555233 -61.935125)
			(xy 126.522782 -61.889767) (xy 126.497281 -61.840167) (xy 126.479274 -61.787383) (xy 126.469144 -61.73254)
			(xy 126.467107 -61.676806) (xy 124.540312 -61.676806) (xy 124.540314 -61.717701) (xy 124.532749 -61.770994)
			(xy 124.517768 -61.822694) (xy 124.495668 -61.871775) (xy 124.466888 -61.917262) (xy 124.432 -61.958252)
			(xy 124.391696 -61.99393) (xy 124.346776 -62.023588) (xy 124.298134 -62.046638) (xy 124.272548 -62.054994)
			(xy 124.25724 -62.06023) (xy 124.229738 -62.077252) (xy 124.207408 -62.100651) (xy 124.19169 -62.128919)
			(xy 124.183597 -62.160233) (xy 124.18314 -62.176406) (xy 124.18314 -64.918336) (xy 127.674622 -64.918336)
			(xy 127.678693 -64.862714) (xy 127.690819 -64.808277) (xy 127.710742 -64.756186) (xy 127.738038 -64.707551)
			(xy 127.772124 -64.663408) (xy 127.812273 -64.624699) (xy 127.857631 -64.592248) (xy 127.907231 -64.566747)
			(xy 127.960015 -64.54874) (xy 128.014858 -64.53861) (xy 128.070592 -64.536573) (xy 128.126029 -64.542673)
			(xy 128.179986 -64.556779) (xy 128.231315 -64.578591) (xy 128.278921 -64.607645) (xy 128.321789 -64.64332)
			(xy 128.359006 -64.684857) (xy 128.389779 -64.73137) (xy 128.413451 -64.781867) (xy 128.429519 -64.835274)
			(xy 128.437639 -64.89045) (xy 128.438148 -64.918336) (xy 128.437639 -64.946222) (xy 128.429519 -65.001398)
			(xy 128.413451 -65.054805) (xy 128.389779 -65.105302) (xy 128.359006 -65.151815) (xy 128.321789 -65.193352)
			(xy 128.278921 -65.229027) (xy 128.231315 -65.258081) (xy 128.179986 -65.279893) (xy 128.126029 -65.293999)
			(xy 128.070592 -65.300099) (xy 128.014858 -65.298062) (xy 127.960015 -65.287932) (xy 127.907231 -65.269925)
			(xy 127.857631 -65.244424) (xy 127.812273 -65.211973) (xy 127.772124 -65.173264) (xy 127.738038 -65.129121)
			(xy 127.710742 -65.080486) (xy 127.690819 -65.028395) (xy 127.678693 -64.973958) (xy 127.674622 -64.918336)
			(xy 124.18314 -64.918336) (xy 124.18314 -80.196182) (xy 125.309882 -80.196182) (xy 125.313953 -80.14056)
			(xy 125.326079 -80.086123) (xy 125.346002 -80.034032) (xy 125.373298 -79.985397) (xy 125.407384 -79.941254)
			(xy 125.447533 -79.902545) (xy 125.492891 -79.870094) (xy 125.542491 -79.844593) (xy 125.595275 -79.826586)
			(xy 125.650118 -79.816456) (xy 125.705852 -79.814419) (xy 125.761289 -79.820519) (xy 125.815246 -79.834625)
			(xy 125.866575 -79.856437) (xy 125.914181 -79.885491) (xy 125.957049 -79.921166) (xy 125.994266 -79.962703)
			(xy 126.025039 -80.009216) (xy 126.048711 -80.059713) (xy 126.064779 -80.11312) (xy 126.072899 -80.168296)
			(xy 126.073408 -80.196182) (xy 126.072899 -80.224068) (xy 126.064779 -80.279244) (xy 126.048711 -80.332651)
			(xy 126.025039 -80.383148) (xy 125.994266 -80.429661) (xy 125.957049 -80.471198) (xy 125.914181 -80.506873)
			(xy 125.866575 -80.535927) (xy 125.815246 -80.557739) (xy 125.761289 -80.571845) (xy 125.705852 -80.577945)
			(xy 125.650118 -80.575908) (xy 125.595275 -80.565778) (xy 125.542491 -80.547771) (xy 125.492891 -80.52227)
			(xy 125.447533 -80.489819) (xy 125.407384 -80.45111) (xy 125.373298 -80.406967) (xy 125.346002 -80.358332)
			(xy 125.326079 -80.306241) (xy 125.313953 -80.251804) (xy 125.309882 -80.196182) (xy 124.18314 -80.196182)
			(xy 124.18314 -83.703414) (xy 151.649936 -83.703414) (xy 151.654007 -83.647792) (xy 151.666133 -83.593355)
			(xy 151.686056 -83.541264) (xy 151.713352 -83.492629) (xy 151.747438 -83.448486) (xy 151.787587 -83.409777)
			(xy 151.832945 -83.377326) (xy 151.882545 -83.351825) (xy 151.935329 -83.333818) (xy 151.990172 -83.323688)
			(xy 152.045906 -83.321651) (xy 152.101343 -83.327751) (xy 152.1553 -83.341857) (xy 152.206629 -83.363669)
			(xy 152.254235 -83.392723) (xy 152.297103 -83.428398) (xy 152.33432 -83.469935) (xy 152.365093 -83.516448)
			(xy 152.388765 -83.566945) (xy 152.404833 -83.620352) (xy 152.412953 -83.675528) (xy 152.413462 -83.703414)
			(xy 152.412953 -83.7313) (xy 152.404833 -83.786476) (xy 152.388765 -83.839883) (xy 152.365093 -83.89038)
			(xy 152.33432 -83.936893) (xy 152.297103 -83.97843) (xy 152.254235 -84.014105) (xy 152.206629 -84.043159)
			(xy 152.1553 -84.064971) (xy 152.101343 -84.079077) (xy 152.045906 -84.085177) (xy 151.990172 -84.08314)
			(xy 151.935329 -84.07301) (xy 151.882545 -84.055003) (xy 151.832945 -84.029502) (xy 151.787587 -83.997051)
			(xy 151.747438 -83.958342) (xy 151.713352 -83.914199) (xy 151.686056 -83.865564) (xy 151.666133 -83.813473)
			(xy 151.654007 -83.759036) (xy 151.649936 -83.703414) (xy 124.18314 -83.703414) (xy 124.18314 -83.90255)
			(xy 126.20498 -85.92439) (xy 153.119834 -85.92439) (xy 153.123905 -85.868768) (xy 153.136031 -85.814331)
			(xy 153.155954 -85.76224) (xy 153.18325 -85.713605) (xy 153.217336 -85.669462) (xy 153.257485 -85.630753)
			(xy 153.302843 -85.598302) (xy 153.352443 -85.572801) (xy 153.405227 -85.554794) (xy 153.46007 -85.544664)
			(xy 153.515804 -85.542627) (xy 153.571241 -85.548727) (xy 153.625198 -85.562833) (xy 153.676527 -85.584645)
			(xy 153.692583 -85.594444) (xy 155.482542 -85.594444) (xy 155.486613 -85.538822) (xy 155.498739 -85.484385)
			(xy 155.518662 -85.432294) (xy 155.545958 -85.383659) (xy 155.580044 -85.339516) (xy 155.620193 -85.300807)
			(xy 155.665551 -85.268356) (xy 155.715151 -85.242855) (xy 155.767935 -85.224848) (xy 155.822778 -85.214718)
			(xy 155.878512 -85.212681) (xy 155.933949 -85.218781) (xy 155.987906 -85.232887) (xy 156.039235 -85.254699)
			(xy 156.086841 -85.283753) (xy 156.129709 -85.319428) (xy 156.166926 -85.360965) (xy 156.197699 -85.407478)
			(xy 156.221371 -85.457975) (xy 156.237439 -85.511382) (xy 156.245559 -85.566558) (xy 156.246068 -85.594444)
			(xy 156.245559 -85.62233) (xy 156.237439 -85.677506) (xy 156.221371 -85.730913) (xy 156.197699 -85.78141)
			(xy 156.166926 -85.827923) (xy 156.129709 -85.86946) (xy 156.086841 -85.905135) (xy 156.039235 -85.934189)
			(xy 155.987906 -85.956001) (xy 155.933949 -85.970107) (xy 155.878512 -85.976207) (xy 155.822778 -85.97417)
			(xy 155.767935 -85.96404) (xy 155.715151 -85.946033) (xy 155.665551 -85.920532) (xy 155.620193 -85.888081)
			(xy 155.580044 -85.849372) (xy 155.545958 -85.805229) (xy 155.518662 -85.756594) (xy 155.498739 -85.704503)
			(xy 155.486613 -85.650066) (xy 155.482542 -85.594444) (xy 153.692583 -85.594444) (xy 153.724133 -85.613699)
			(xy 153.767001 -85.649374) (xy 153.804218 -85.690911) (xy 153.834991 -85.737424) (xy 153.858663 -85.787921)
			(xy 153.874731 -85.841328) (xy 153.882851 -85.896504) (xy 153.88336 -85.92439) (xy 153.882851 -85.952276)
			(xy 153.874731 -86.007452) (xy 153.858663 -86.060859) (xy 153.834991 -86.111356) (xy 153.804218 -86.157869)
			(xy 153.767001 -86.199406) (xy 153.724133 -86.235081) (xy 153.676527 -86.264135) (xy 153.625198 -86.285947)
			(xy 153.571241 -86.300053) (xy 153.515804 -86.306153) (xy 153.46007 -86.304116) (xy 153.405227 -86.293986)
			(xy 153.352443 -86.275979) (xy 153.302843 -86.250478) (xy 153.257485 -86.218027) (xy 153.217336 -86.179318)
			(xy 153.18325 -86.135175) (xy 153.155954 -86.08654) (xy 153.136031 -86.034449) (xy 153.123905 -85.980012)
			(xy 153.119834 -85.92439) (xy 126.20498 -85.92439) (xy 126.603506 -86.322916) (xy 162.34232 -86.322916)
			(xy 162.346391 -86.267294) (xy 162.358517 -86.212857) (xy 162.37844 -86.160766) (xy 162.405736 -86.112131)
			(xy 162.439822 -86.067988) (xy 162.479971 -86.029279) (xy 162.525329 -85.996828) (xy 162.574929 -85.971327)
			(xy 162.627713 -85.95332) (xy 162.682556 -85.94319) (xy 162.73829 -85.941153) (xy 162.793727 -85.947253)
			(xy 162.847684 -85.961359) (xy 162.899013 -85.983171) (xy 162.946619 -86.012225) (xy 162.989487 -86.0479)
			(xy 163.026704 -86.089437) (xy 163.057477 -86.13595) (xy 163.081149 -86.186447) (xy 163.097217 -86.239854)
			(xy 163.105337 -86.29503) (xy 163.105846 -86.322916) (xy 163.105337 -86.350802) (xy 163.097217 -86.405978)
			(xy 163.081149 -86.459385) (xy 163.057477 -86.509882) (xy 163.026704 -86.556395) (xy 162.989487 -86.597932)
			(xy 162.946619 -86.633607) (xy 162.899013 -86.662661) (xy 162.847684 -86.684473) (xy 162.793727 -86.698579)
			(xy 162.73829 -86.704679) (xy 162.682556 -86.702642) (xy 162.627713 -86.692512) (xy 162.574929 -86.674505)
			(xy 162.525329 -86.649004) (xy 162.479971 -86.616553) (xy 162.439822 -86.577844) (xy 162.405736 -86.533701)
			(xy 162.37844 -86.485066) (xy 162.358517 -86.432975) (xy 162.346391 -86.378538) (xy 162.34232 -86.322916)
			(xy 126.603506 -86.322916) (xy 127.753364 -87.472774) (xy 127.76962 -87.472774) (xy 128.881632 -88.584786)
			(xy 152.034494 -88.584786)
		)
		(stroke
			(width 0)
			(type solid)
		)
		(fill yes)
		(layer "In7.Cu")
		(net "P1V0_NODE1")
	)
	(gr_poly
		(pts
			(xy 141.6177 -151.65197) (xy 141.6177 -135.897112) (xy 141.169898 -135.44931) (xy 141.157416 -135.437647)
			(xy 141.127699 -135.420823) (xy 141.094584 -135.412489) (xy 141.060444 -135.413242) (xy 141.043914 -135.41756)
			(xy 141.017537 -135.42497) (xy 140.963343 -135.433028) (xy 140.908555 -135.433251) (xy 140.854298 -135.425634)
			(xy 140.801689 -135.410334) (xy 140.751809 -135.387666) (xy 140.705685 -135.358096) (xy 140.664266 -135.322232)
			(xy 140.628402 -135.280812) (xy 140.598832 -135.234687) (xy 140.576165 -135.184807) (xy 140.560865 -135.132198)
			(xy 140.553249 -135.077941) (xy 140.553472 -135.023153) (xy 140.561531 -134.96896) (xy 140.568934 -134.94258)
			(xy 140.579094 -134.909052) (xy 140.561822 -134.841234) (xy 139.972796 -134.252208) (xy 139.891262 -134.239508)
			(xy 139.854432 -134.258558) (xy 139.829028 -134.27107) (xy 139.77541 -134.289283) (xy 139.719689 -134.29937)
			(xy 139.663089 -134.301107) (xy 139.606855 -134.294458) (xy 139.552221 -134.279568) (xy 139.500389 -134.256765)
			(xy 139.452497 -134.226549) (xy 139.409599 -134.189585) (xy 139.372638 -134.146685) (xy 139.342425 -134.098792)
			(xy 139.319624 -134.046958) (xy 139.304738 -133.992323) (xy 139.298092 -133.936088) (xy 139.299833 -133.879488)
			(xy 139.309923 -133.823768) (xy 139.328139 -133.770151) (xy 139.34059 -133.744716) (xy 139.35964 -133.707886)
			(xy 139.34694 -133.626352) (xy 139.051284 -133.330696) (xy 127.8509 -133.330696) (xy 127.834251 -133.331239)
			(xy 127.802089 -133.339857) (xy 127.773253 -133.356505) (xy 127.749708 -133.380049) (xy 127.733058 -133.408885)
			(xy 127.72444 -133.441047) (xy 127.7239 -133.457696) (xy 127.7239 -133.83387) (xy 127.724406 -133.85666)
			(xy 127.732531 -133.90151) (xy 127.748525 -133.944191) (xy 127.771875 -133.983336) (xy 127.801834 -134.017687)
			(xy 127.837438 -134.046144) (xy 127.877548 -134.067794) (xy 127.920876 -134.081943) (xy 127.966033 -134.088137)
			(xy 127.988822 -134.087616) (xy 128.01683 -134.086899) (xy 128.072554 -134.092689) (xy 128.126834 -134.106564)
			(xy 128.178502 -134.128226) (xy 128.226447 -134.157209) (xy 128.269641 -134.19289) (xy 128.307153 -134.234502)
			(xy 128.338179 -134.281152) (xy 128.352421 -134.31139) (xy 130.455922 -134.31139) (xy 130.459993 -134.255768)
			(xy 130.472119 -134.201331) (xy 130.492042 -134.14924) (xy 130.519338 -134.100605) (xy 130.553424 -134.056462)
			(xy 130.593573 -134.017753) (xy 130.638931 -133.985302) (xy 130.688531 -133.959801) (xy 130.741315 -133.941794)
			(xy 130.796158 -133.931664) (xy 130.851892 -133.929627) (xy 130.907329 -133.935727) (xy 130.961286 -133.949833)
			(xy 131.012615 -133.971645) (xy 131.060221 -134.000699) (xy 131.103089 -134.036374) (xy 131.140306 -134.077911)
			(xy 131.171079 -134.124424) (xy 131.194751 -134.174921) (xy 131.210819 -134.228328) (xy 131.218939 -134.283504)
			(xy 131.218962 -134.284781) (xy 132.698507 -134.284781) (xy 132.704041 -134.230432) (xy 132.717271 -134.177429)
			(xy 132.737928 -134.126855) (xy 132.765588 -134.079745) (xy 132.799685 -134.037063) (xy 132.839523 -133.999682)
			(xy 132.884286 -133.968366) (xy 132.933059 -133.943757) (xy 132.984843 -133.926356) (xy 133.03858 -133.916521)
			(xy 133.09317 -133.914453) (xy 133.147498 -133.920194) (xy 133.20045 -133.933626) (xy 133.250945 -133.954474)
			(xy 133.297949 -133.982313) (xy 133.340501 -134.016572) (xy 133.377731 -134.056552) (xy 133.393688 -134.078726)
			(xy 133.407136 -134.097231) (xy 133.439488 -134.129563) (xy 133.477105 -134.155583) (xy 133.518771 -134.17445)
			(xy 133.563142 -134.185555) (xy 133.608783 -134.188539) (xy 133.654222 -134.183306) (xy 133.69799 -134.170024)
			(xy 133.718554 -134.160006) (xy 133.744146 -134.147405) (xy 133.798196 -134.12917) (xy 133.854359 -134.119183)
			(xy 133.911382 -134.117667) (xy 133.967996 -134.124655) (xy 134.022939 -134.139992) (xy 134.074987 -134.163336)
			(xy 134.122981 -134.194167) (xy 134.144766 -134.212584) (xy 134.16228 -134.227287) (xy 134.201506 -134.250784)
			(xy 134.244303 -134.266883) (xy 134.28929 -134.275064) (xy 134.335014 -134.275064) (xy 134.380001 -134.266883)
			(xy 134.422798 -134.250784) (xy 134.462024 -134.227287) (xy 134.479538 -134.212584) (xy 134.500439 -134.194961)
			(xy 134.546251 -134.165129) (xy 134.595851 -134.142142) (xy 134.648224 -134.126468) (xy 134.702298 -134.118429)
			(xy 134.756966 -134.11819) (xy 134.811108 -134.125755) (xy 134.863617 -134.14097) (xy 134.913416 -134.163522)
			(xy 134.959487 -134.192952) (xy 135.000886 -134.228654) (xy 135.036767 -134.2699) (xy 135.066393 -134.315845)
			(xy 135.089159 -134.365547) (xy 135.104599 -134.41799) (xy 135.112397 -134.472099) (xy 135.112392 -134.526767)
			(xy 135.104585 -134.580875) (xy 135.089136 -134.633315) (xy 135.080688 -134.65175) (xy 137.829034 -134.65175)
			(xy 137.833105 -134.596128) (xy 137.845231 -134.541691) (xy 137.865154 -134.4896) (xy 137.89245 -134.440965)
			(xy 137.926536 -134.396822) (xy 137.966685 -134.358113) (xy 138.012043 -134.325662) (xy 138.061643 -134.300161)
			(xy 138.114427 -134.282154) (xy 138.16927 -134.272024) (xy 138.225004 -134.269987) (xy 138.280441 -134.276087)
			(xy 138.334398 -134.290193) (xy 138.385727 -134.312005) (xy 138.433333 -134.341059) (xy 138.476201 -134.376734)
			(xy 138.513418 -134.418271) (xy 138.544191 -134.464784) (xy 138.567863 -134.515281) (xy 138.583931 -134.568688)
			(xy 138.592051 -134.623864) (xy 138.59256 -134.65175) (xy 138.592051 -134.679636) (xy 138.583931 -134.734812)
			(xy 138.567863 -134.788219) (xy 138.544191 -134.838716) (xy 138.513418 -134.885229) (xy 138.476201 -134.926766)
			(xy 138.433333 -134.962441) (xy 138.385727 -134.991495) (xy 138.334398 -135.013307) (xy 138.280441 -135.027413)
			(xy 138.225004 -135.033513) (xy 138.16927 -135.031476) (xy 138.114427 -135.021346) (xy 138.061643 -135.003339)
			(xy 138.012043 -134.977838) (xy 137.966685 -134.945387) (xy 137.926536 -134.906678) (xy 137.89245 -134.862535)
			(xy 137.865154 -134.8139) (xy 137.845231 -134.761809) (xy 137.833105 -134.707372) (xy 137.829034 -134.65175)
			(xy 135.080688 -134.65175) (xy 135.066361 -134.683013) (xy 135.036727 -134.728952) (xy 135.00084 -134.770192)
			(xy 134.959434 -134.805888) (xy 134.913358 -134.835309) (xy 134.863555 -134.857853) (xy 134.811044 -134.873059)
			(xy 134.7569 -134.880615) (xy 134.702232 -134.880366) (xy 134.64816 -134.872318) (xy 134.595789 -134.856635)
			(xy 134.546193 -134.833639) (xy 134.500387 -134.803799) (xy 134.479538 -134.786116) (xy 134.462024 -134.771413)
			(xy 134.422798 -134.747916) (xy 134.380001 -134.731817) (xy 134.335014 -134.723636) (xy 134.28929 -134.723636)
			(xy 134.244303 -134.731817) (xy 134.201506 -134.747916) (xy 134.16228 -134.771413) (xy 134.144766 -134.786116)
			(xy 134.124288 -134.803395) (xy 134.079464 -134.832744) (xy 134.030974 -134.855534) (xy 133.979774 -134.871316)
			(xy 133.926869 -134.879782) (xy 133.8733 -134.880764) (xy 133.820121 -134.874243) (xy 133.768376 -134.860347)
			(xy 133.719084 -134.839349) (xy 133.673214 -134.811663) (xy 133.631668 -134.777833) (xy 133.595262 -134.738523)
			(xy 133.579616 -134.716774) (xy 133.566164 -134.698272) (xy 133.533812 -134.66594) (xy 133.496196 -134.63992)
			(xy 133.454531 -134.621053) (xy 133.410161 -134.609947) (xy 133.36452 -134.606963) (xy 133.319082 -134.612195)
			(xy 133.275314 -134.625476) (xy 133.25475 -134.635494) (xy 133.230216 -134.647514) (xy 133.178566 -134.665307)
			(xy 133.124905 -134.67555) (xy 133.070332 -134.678034) (xy 133.015963 -134.672706) (xy 132.962909 -134.659677)
			(xy 132.912258 -134.639213) (xy 132.865043 -134.611733) (xy 132.822232 -134.577797) (xy 132.784699 -134.538102)
			(xy 132.753214 -134.493459) (xy 132.728419 -134.44478) (xy 132.710822 -134.393062) (xy 132.700783 -134.339363)
			(xy 132.698507 -134.284781) (xy 131.218962 -134.284781) (xy 131.219448 -134.31139) (xy 131.218939 -134.339276)
			(xy 131.210819 -134.394452) (xy 131.194751 -134.447859) (xy 131.171079 -134.498356) (xy 131.140306 -134.544869)
			(xy 131.103089 -134.586406) (xy 131.060221 -134.622081) (xy 131.012615 -134.651135) (xy 130.961286 -134.672947)
			(xy 130.907329 -134.687053) (xy 130.851892 -134.693153) (xy 130.796158 -134.691116) (xy 130.741315 -134.680986)
			(xy 130.688531 -134.662979) (xy 130.638931 -134.637478) (xy 130.593573 -134.605027) (xy 130.553424 -134.566318)
			(xy 130.519338 -134.522175) (xy 130.492042 -134.47354) (xy 130.472119 -134.421449) (xy 130.459993 -134.367012)
			(xy 130.455922 -134.31139) (xy 128.352421 -134.31139) (xy 128.362051 -134.331836) (xy 128.378256 -134.385466)
			(xy 128.386447 -134.440889) (xy 128.386447 -134.496914) (xy 128.378256 -134.552337) (xy 128.36205 -134.605966)
			(xy 128.338177 -134.656651) (xy 128.307151 -134.7033) (xy 128.269639 -134.744912) (xy 128.226445 -134.780593)
			(xy 128.178499 -134.809575) (xy 128.126831 -134.831237) (xy 128.072552 -134.845111) (xy 128.016827 -134.850901)
			(xy 127.988822 -134.850124) (xy 127.966034 -134.849652) (xy 127.920882 -134.855844) (xy 127.877557 -134.86999)
			(xy 127.837451 -134.891635) (xy 127.801847 -134.920085) (xy 127.771888 -134.954429) (xy 127.748534 -134.993565)
			(xy 127.732533 -135.036239) (xy 127.7244 -135.081083) (xy 127.7239 -135.10387) (xy 127.7239 -136.592564)
			(xy 127.72437 -136.614952) (xy 127.73221 -136.659035) (xy 127.747654 -136.701062) (xy 127.770225 -136.739733)
			(xy 127.799222 -136.77385) (xy 127.83375 -136.802357) (xy 127.872739 -136.824372) (xy 127.914983 -136.839214)
			(xy 127.937006 -136.843262) (xy 127.964516 -136.848229) (xy 128.017794 -136.865155) (xy 128.068031 -136.889675)
			(xy 128.114152 -136.921264) (xy 128.155169 -136.959246) (xy 128.190203 -137.002807) (xy 128.218506 -137.051015)
			(xy 128.239469 -137.102837) (xy 128.252645 -137.157164) (xy 128.257752 -137.212832) (xy 128.256792 -137.240772)
			(xy 128.25605 -137.262426) (xy 128.26106 -137.305459) (xy 128.273292 -137.347021) (xy 128.292392 -137.385908)
			(xy 128.317806 -137.420995) (xy 128.3488 -137.451266) (xy 128.384477 -137.475846) (xy 128.423804 -137.494023)
			(xy 128.465643 -137.50527) (xy 128.48717 -137.507726) (xy 128.514503 -137.510716) (xy 128.567967 -137.523547)
			(xy 128.611081 -137.540746) (xy 130.041902 -137.540746) (xy 130.045973 -137.485124) (xy 130.058099 -137.430687)
			(xy 130.078022 -137.378596) (xy 130.105318 -137.329961) (xy 130.139404 -137.285818) (xy 130.179553 -137.247109)
			(xy 130.224911 -137.214658) (xy 130.274511 -137.189157) (xy 130.327295 -137.17115) (xy 130.382138 -137.16102)
			(xy 130.437872 -137.158983) (xy 130.493309 -137.165083) (xy 130.547266 -137.179189) (xy 130.598595 -137.201001)
			(xy 130.646201 -137.230055) (xy 130.682793 -137.260507) (xy 131.428318 -137.260507) (xy 131.433292 -137.206016)
			(xy 131.445998 -137.152795) (xy 131.466177 -137.101935) (xy 131.493415 -137.054479) (xy 131.527152 -137.011401)
			(xy 131.566697 -136.973584) (xy 131.611238 -136.941803) (xy 131.659863 -136.916711) (xy 131.711573 -136.898823)
			(xy 131.765308 -136.888505) (xy 131.819966 -136.885969) (xy 131.874426 -136.891267) (xy 131.927571 -136.90429)
			(xy 131.97831 -136.924771) (xy 132.025603 -136.95229) (xy 132.06848 -136.986283) (xy 132.106061 -137.026052)
			(xy 132.137576 -137.070782) (xy 132.162378 -137.119555) (xy 132.179958 -137.171371) (xy 132.183621 -137.191082)
			(xy 133.053925 -137.191082) (xy 133.058135 -137.13524) (xy 133.070465 -137.080613) (xy 133.090649 -137.028376)
			(xy 133.118255 -136.979652) (xy 133.152688 -136.935488) (xy 133.193208 -136.896832) (xy 133.238944 -136.864517)
			(xy 133.288914 -136.839237) (xy 133.342044 -136.821535) (xy 133.39719 -136.811791) (xy 133.453169 -136.810215)
			(xy 133.508777 -136.816841) (xy 133.562818 -136.831526) (xy 133.614131 -136.853955) (xy 133.661613 -136.883646)
			(xy 133.683248 -136.901428) (xy 133.696154 -136.911655) (xy 133.725841 -136.925866) (xy 133.758177 -136.932007)
			(xy 133.791006 -136.929666) (xy 133.822144 -136.919002) (xy 133.849515 -136.900723) (xy 133.860794 -136.888728)
			(xy 133.880441 -136.867192) (xy 133.925191 -136.829832) (xy 133.975103 -136.799714) (xy 134.029016 -136.777539)
			(xy 134.085674 -136.763822) (xy 134.143759 -136.758882) (xy 134.20192 -136.762836) (xy 134.258802 -136.77559)
			(xy 134.313083 -136.796848) (xy 134.338568 -136.811004) (xy 134.353934 -136.81918) (xy 134.387639 -136.82781)
			(xy 134.422422 -136.827032) (xy 134.455707 -136.816905) (xy 134.48503 -136.798179) (xy 134.497064 -136.785604)
			(xy 134.515898 -136.765192) (xy 134.558453 -136.729506) (xy 134.605733 -136.700367) (xy 134.656739 -136.678391)
			(xy 134.710391 -136.664043) (xy 134.765557 -136.657626) (xy 134.821071 -136.659275) (xy 134.875759 -136.668956)
			(xy 134.928465 -136.686463) (xy 134.978076 -136.711428) (xy 135.023543 -136.743322) (xy 135.063905 -136.781472)
			(xy 135.098309 -136.82507) (xy 135.126028 -136.873197) (xy 135.146476 -136.924833) (xy 135.159222 -136.978889)
			(xy 135.163995 -137.034222) (xy 135.160694 -137.089661) (xy 135.155312 -137.11555) (xy 135.416034 -137.11555)
			(xy 135.420105 -137.059928) (xy 135.432231 -137.005491) (xy 135.452154 -136.9534) (xy 135.47945 -136.904765)
			(xy 135.513536 -136.860622) (xy 135.553685 -136.821913) (xy 135.599043 -136.789462) (xy 135.648643 -136.763961)
			(xy 135.701427 -136.745954) (xy 135.75627 -136.735824) (xy 135.812004 -136.733787) (xy 135.867441 -136.739887)
			(xy 135.921398 -136.753993) (xy 135.972727 -136.775805) (xy 136.020333 -136.804859) (xy 136.063201 -136.840534)
			(xy 136.100418 -136.882071) (xy 136.131191 -136.928584) (xy 136.154863 -136.979081) (xy 136.170931 -137.032488)
			(xy 136.178329 -137.082757) (xy 137.092902 -137.082757) (xy 137.094312 -137.027428) (xy 137.103702 -136.972884)
			(xy 137.120876 -136.920269) (xy 137.145471 -136.870687) (xy 137.176974 -136.82518) (xy 137.214721 -136.784703)
			(xy 137.257921 -136.750105) (xy 137.305667 -136.722112) (xy 137.356957 -136.701313) (xy 137.410714 -136.688143)
			(xy 137.46581 -136.682879) (xy 137.521088 -136.685631) (xy 137.575389 -136.696342) (xy 137.627571 -136.714788)
			(xy 137.676541 -136.74058) (xy 137.72127 -136.773177) (xy 137.76082 -136.811896) (xy 137.777982 -136.83361)
			(xy 137.792115 -136.851399) (xy 137.825642 -136.882056) (xy 137.864086 -136.906263) (xy 137.906222 -136.923247)
			(xy 137.950707 -136.932467) (xy 137.996122 -136.93363) (xy 138.04102 -136.926698) (xy 138.08397 -136.911892)
			(xy 138.123602 -136.889684) (xy 138.158654 -136.860782) (xy 138.173714 -136.84377) (xy 138.191938 -136.82294)
			(xy 138.233408 -136.786287) (xy 138.279739 -136.756011) (xy 138.329959 -136.732747) (xy 138.383013 -136.716984)
			(xy 138.437788 -136.709053) (xy 138.493134 -136.70912) (xy 138.54789 -136.717184) (xy 138.600906 -136.733075)
			(xy 138.651069 -136.75646) (xy 138.697327 -136.786849) (xy 138.738708 -136.823602) (xy 138.774344 -136.865949)
			(xy 138.803487 -136.913001) (xy 138.825525 -136.963771) (xy 138.839995 -137.017192) (xy 138.846595 -137.072143)
			(xy 138.845185 -137.127471) (xy 138.835795 -137.182015) (xy 138.818622 -137.23463) (xy 138.794026 -137.284211)
			(xy 138.762524 -137.329717) (xy 138.724778 -137.370194) (xy 138.681578 -137.404792) (xy 138.633833 -137.432784)
			(xy 138.582543 -137.453584) (xy 138.528787 -137.466754) (xy 138.473692 -137.472018) (xy 138.418414 -137.469266)
			(xy 138.364114 -137.458555) (xy 138.311932 -137.44011) (xy 138.262962 -137.414319) (xy 138.218233 -137.381722)
			(xy 138.178684 -137.343004) (xy 138.161522 -137.32129) (xy 138.147384 -137.303505) (xy 138.113858 -137.272848)
			(xy 138.075415 -137.248641) (xy 138.03328 -137.231657) (xy 137.988796 -137.222436) (xy 137.943381 -137.221273)
			(xy 137.898483 -137.228204) (xy 137.855534 -137.24301) (xy 137.815902 -137.265217) (xy 137.78085 -137.294118)
			(xy 137.76579 -137.31113) (xy 137.747566 -137.33196) (xy 137.706095 -137.368614) (xy 137.659764 -137.398891)
			(xy 137.609544 -137.422155) (xy 137.556489 -137.437918) (xy 137.501714 -137.44585) (xy 137.446367 -137.445783)
			(xy 137.391611 -137.437719) (xy 137.338594 -137.421828) (xy 137.28843 -137.398443) (xy 137.242172 -137.368055)
			(xy 137.200791 -137.331301) (xy 137.165154 -137.288953) (xy 137.136011 -137.241901) (xy 137.113973 -137.191131)
			(xy 137.099502 -137.137709) (xy 137.092902 -137.082757) (xy 136.178329 -137.082757) (xy 136.179051 -137.087664)
			(xy 136.17956 -137.11555) (xy 136.179051 -137.143436) (xy 136.170931 -137.198612) (xy 136.154863 -137.252019)
			(xy 136.131191 -137.302516) (xy 136.100418 -137.349029) (xy 136.063201 -137.390566) (xy 136.020333 -137.426241)
			(xy 135.972727 -137.455295) (xy 135.921398 -137.477107) (xy 135.867441 -137.491213) (xy 135.812004 -137.497313)
			(xy 135.75627 -137.495276) (xy 135.701427 -137.485146) (xy 135.648643 -137.467139) (xy 135.599043 -137.441638)
			(xy 135.553685 -137.409187) (xy 135.513536 -137.370478) (xy 135.47945 -137.326335) (xy 135.452154 -137.2777)
			(xy 135.432231 -137.225609) (xy 135.420105 -137.171172) (xy 135.416034 -137.11555) (xy 135.155312 -137.11555)
			(xy 135.14939 -137.144037) (xy 135.130322 -137.196199) (xy 135.103892 -137.245045) (xy 135.070659 -137.289543)
			(xy 135.031326 -137.328752) (xy 134.986723 -137.361843) (xy 134.937793 -137.388118) (xy 134.885571 -137.407021)
			(xy 134.83116 -137.418152) (xy 134.77571 -137.421276) (xy 134.720393 -137.416328) (xy 134.666377 -137.403411)
			(xy 134.614806 -137.382799) (xy 134.590536 -137.369296) (xy 134.575168 -137.361124) (xy 134.541464 -137.352494)
			(xy 134.506682 -137.35327) (xy 134.473397 -137.363396) (xy 134.444075 -137.382121) (xy 134.43204 -137.394696)
			(xy 134.413775 -137.41441) (xy 134.372743 -137.449112) (xy 134.327249 -137.477715) (xy 134.278192 -137.499654)
			(xy 134.226542 -137.514494) (xy 134.173322 -137.521942) (xy 134.119583 -137.521851) (xy 134.066388 -137.514222)
			(xy 134.014789 -137.499206) (xy 133.965807 -137.477101) (xy 133.92041 -137.448344) (xy 133.899656 -137.431272)
			(xy 133.886747 -137.421049) (xy 133.857061 -137.406837) (xy 133.824726 -137.400697) (xy 133.791897 -137.403036)
			(xy 133.76076 -137.4137) (xy 133.733389 -137.431978) (xy 133.72211 -137.443972) (xy 133.70322 -137.464647)
			(xy 133.660453 -137.5008) (xy 133.61286 -137.530312) (xy 133.561462 -137.552548) (xy 133.507366 -137.56703)
			(xy 133.451734 -137.573447) (xy 133.395762 -137.571661) (xy 133.340652 -137.56171) (xy 133.28759 -137.543808)
			(xy 133.237715 -137.51834) (xy 133.1921 -137.485853) (xy 133.151726 -137.447046) (xy 133.117459 -137.402752)
			(xy 133.090037 -137.353925) (xy 133.07005 -137.301612) (xy 133.057925 -137.24694) (xy 133.053925 -137.191082)
			(xy 132.183621 -137.191082) (xy 132.189956 -137.225167) (xy 132.192167 -137.279839) (xy 132.186545 -137.334266)
			(xy 132.173206 -137.387332) (xy 132.152423 -137.437949) (xy 132.138928 -137.461752) (xy 132.131594 -137.475183)
			(xy 132.122844 -137.504497) (xy 132.121318 -137.53505) (xy 132.127102 -137.56509) (xy 132.139864 -137.592892)
			(xy 132.158873 -137.616861) (xy 132.170678 -137.626598) (xy 132.19201 -137.643735) (xy 132.230061 -137.683054)
			(xy 132.262105 -137.727406) (xy 132.287485 -137.77588) (xy 132.30568 -137.827482) (xy 132.316317 -137.881155)
			(xy 132.319178 -137.935796) (xy 132.314204 -137.990286) (xy 132.301497 -138.043507) (xy 132.281318 -138.094366)
			(xy 132.254081 -138.141821) (xy 132.220344 -138.184899) (xy 132.180799 -138.222716) (xy 132.136258 -138.254495)
			(xy 132.087633 -138.279586) (xy 132.035924 -138.297474) (xy 131.982189 -138.307792) (xy 131.927531 -138.310328)
			(xy 131.873072 -138.305029) (xy 131.819928 -138.292006) (xy 131.769189 -138.271525) (xy 131.721897 -138.244005)
			(xy 131.679021 -138.210013) (xy 131.64144 -138.170244) (xy 131.609926 -138.125514) (xy 131.585125 -138.076741)
			(xy 131.567545 -138.024926) (xy 131.557547 -137.971131) (xy 131.555337 -137.916459) (xy 131.560959 -137.862032)
			(xy 131.574298 -137.808967) (xy 131.595081 -137.758351) (xy 131.608576 -137.734548) (xy 131.615909 -137.721117)
			(xy 131.624658 -137.691803) (xy 131.626185 -137.66125) (xy 131.620401 -137.63121) (xy 131.607639 -137.603408)
			(xy 131.58863 -137.579439) (xy 131.576826 -137.569702) (xy 131.55549 -137.55257) (xy 131.517438 -137.51325)
			(xy 131.485394 -137.468899) (xy 131.460013 -137.420424) (xy 131.441817 -137.368822) (xy 131.43118 -137.315149)
			(xy 131.428318 -137.260507) (xy 130.682793 -137.260507) (xy 130.689069 -137.26573) (xy 130.726286 -137.307267)
			(xy 130.757059 -137.35378) (xy 130.780731 -137.404277) (xy 130.796799 -137.457684) (xy 130.804919 -137.51286)
			(xy 130.805428 -137.540746) (xy 130.804919 -137.568632) (xy 130.796799 -137.623808) (xy 130.780731 -137.677215)
			(xy 130.757059 -137.727712) (xy 130.726286 -137.774225) (xy 130.689069 -137.815762) (xy 130.646201 -137.851437)
			(xy 130.598595 -137.880491) (xy 130.547266 -137.902303) (xy 130.493309 -137.916409) (xy 130.437872 -137.922509)
			(xy 130.382138 -137.920472) (xy 130.327295 -137.910342) (xy 130.274511 -137.892335) (xy 130.224911 -137.866834)
			(xy 130.179553 -137.834383) (xy 130.139404 -137.795674) (xy 130.105318 -137.751531) (xy 130.078022 -137.702896)
			(xy 130.058099 -137.650805) (xy 130.045973 -137.596368) (xy 130.041902 -137.540746) (xy 128.611081 -137.540746)
			(xy 128.619037 -137.54392) (xy 128.666654 -137.571411) (xy 128.709831 -137.605453) (xy 128.747676 -137.645339)
			(xy 128.779404 -137.690244) (xy 128.804358 -137.739238) (xy 128.822022 -137.791306) (xy 128.832029 -137.845371)
			(xy 128.834173 -137.900312) (xy 128.828409 -137.954992) (xy 128.814856 -138.008279) (xy 128.793795 -138.059068)
			(xy 128.765663 -138.106309) (xy 128.731041 -138.149023) (xy 128.690647 -138.186325) (xy 128.645317 -138.217443)
			(xy 128.59599 -138.241733) (xy 128.543687 -138.258691) (xy 128.489493 -138.267967) (xy 128.462024 -138.269218)
			(xy 128.437927 -138.270355) (xy 128.390787 -138.280575) (xy 128.346424 -138.299511) (xy 128.306435 -138.326482)
			(xy 128.272256 -138.360518) (xy 128.245119 -138.400395) (xy 128.225998 -138.444679) (xy 128.220216 -138.4681)
			(xy 128.21351 -138.495856) (xy 128.192973 -138.549133) (xy 128.164727 -138.598756) (xy 128.129405 -138.643618)
			(xy 128.087794 -138.682717) (xy 128.040822 -138.715182) (xy 127.989538 -138.740286) (xy 127.935087 -138.757471)
			(xy 127.878683 -138.766352) (xy 127.850138 -138.767058) (xy 127.833554 -138.767692) (xy 127.801552 -138.776437)
			(xy 127.772887 -138.793136) (xy 127.749495 -138.81666) (xy 127.732959 -138.84542) (xy 127.724396 -138.877471)
			(xy 127.7239 -138.894058) (xy 127.7239 -139.147042) (xy 127.72444 -139.163623) (xy 127.728628 -139.1793)
			(xy 138.152884 -139.1793) (xy 138.156955 -139.123678) (xy 138.169081 -139.069241) (xy 138.189004 -139.01715)
			(xy 138.2163 -138.968515) (xy 138.250386 -138.924372) (xy 138.290535 -138.885663) (xy 138.335893 -138.853212)
			(xy 138.385493 -138.827711) (xy 138.438277 -138.809704) (xy 138.49312 -138.799574) (xy 138.548854 -138.797537)
			(xy 138.604291 -138.803637) (xy 138.658248 -138.817743) (xy 138.709577 -138.839555) (xy 138.757183 -138.868609)
			(xy 138.800051 -138.904284) (xy 138.837268 -138.945821) (xy 138.858749 -138.978289) (xy 139.612918 -138.978289)
			(xy 139.616592 -138.922681) (xy 139.628318 -138.868199) (xy 139.647846 -138.816004) (xy 139.674761 -138.767205)
			(xy 139.70849 -138.722842) (xy 139.748315 -138.683858) (xy 139.793388 -138.651084) (xy 139.84275 -138.625217)
			(xy 139.895351 -138.606808) (xy 139.95007 -138.596248) (xy 140.005744 -138.593762) (xy 140.061187 -138.599404)
			(xy 140.115219 -138.613052) (xy 140.16669 -138.634417) (xy 140.214504 -138.663044) (xy 140.257645 -138.698323)
			(xy 140.295193 -138.739504) (xy 140.32635 -138.78571) (xy 140.350452 -138.835957) (xy 140.366987 -138.889177)
			(xy 140.375602 -138.944236) (xy 140.376114 -138.999963) (xy 140.368512 -139.055171) (xy 140.352958 -139.108686)
			(xy 140.329784 -139.159368) (xy 140.299481 -139.206138) (xy 140.262696 -139.248002) (xy 140.241782 -139.266422)
			(xy 140.224464 -139.281835) (xy 140.195169 -139.31776) (xy 140.17287 -139.3584) (xy 140.158306 -139.402408)
			(xy 140.151958 -139.448326) (xy 140.154038 -139.494635) (xy 140.164476 -139.5398) (xy 140.182927 -139.582325)
			(xy 140.208779 -139.620802) (xy 140.241177 -139.653957) (xy 140.259816 -139.667742) (xy 140.282265 -139.684255)
			(xy 140.322629 -139.722676) (xy 140.356973 -139.76656) (xy 140.384566 -139.814975) (xy 140.404822 -139.866889)
			(xy 140.417308 -139.921198) (xy 140.421759 -139.976746) (xy 140.41808 -140.03235) (xy 140.40635 -140.086827)
			(xy 140.386818 -140.139018) (xy 140.3599 -140.187812) (xy 140.326169 -140.232169) (xy 140.286343 -140.271147)
			(xy 140.241269 -140.303914) (xy 140.191907 -140.329775) (xy 140.139308 -140.348179) (xy 140.084591 -140.358733)
			(xy 140.02892 -140.361213) (xy 139.973481 -140.355567) (xy 139.919454 -140.341914) (xy 139.867988 -140.320545)
			(xy 139.820178 -140.291915) (xy 139.777044 -140.256634) (xy 139.739502 -140.215452) (xy 139.708351 -140.169245)
			(xy 139.684256 -140.118998) (xy 139.667728 -140.06578) (xy 139.659119 -140.010723) (xy 139.658612 -139.955)
			(xy 139.666219 -139.899796) (xy 139.681778 -139.846286) (xy 139.704956 -139.795609) (xy 139.735262 -139.748844)
			(xy 139.772049 -139.706987) (xy 139.792964 -139.68857) (xy 139.810296 -139.67317) (xy 139.839598 -139.637245)
			(xy 139.861901 -139.596604) (xy 139.876469 -139.552593) (xy 139.882817 -139.50667) (xy 139.880736 -139.460358)
			(xy 139.870294 -139.41519) (xy 139.851838 -139.372663) (xy 139.825979 -139.334185) (xy 139.793574 -139.301033)
			(xy 139.77493 -139.28725) (xy 139.752446 -139.270784) (xy 139.712076 -139.232365) (xy 139.677726 -139.188481)
			(xy 139.650127 -139.140066) (xy 139.629866 -139.08815) (xy 139.617374 -139.033839) (xy 139.612918 -138.978289)
			(xy 138.858749 -138.978289) (xy 138.868041 -138.992334) (xy 138.891713 -139.042831) (xy 138.907781 -139.096238)
			(xy 138.915901 -139.151414) (xy 138.91641 -139.1793) (xy 138.915901 -139.207186) (xy 138.907781 -139.262362)
			(xy 138.891713 -139.315769) (xy 138.868041 -139.366266) (xy 138.837268 -139.412779) (xy 138.800051 -139.454316)
			(xy 138.757183 -139.489991) (xy 138.709577 -139.519045) (xy 138.658248 -139.540857) (xy 138.604291 -139.554963)
			(xy 138.548854 -139.561063) (xy 138.49312 -139.559026) (xy 138.438277 -139.548896) (xy 138.385493 -139.530889)
			(xy 138.335893 -139.505388) (xy 138.290535 -139.472937) (xy 138.250386 -139.434228) (xy 138.2163 -139.390085)
			(xy 138.189004 -139.34145) (xy 138.169081 -139.289359) (xy 138.156955 -139.234922) (xy 138.152884 -139.1793)
			(xy 127.728628 -139.1793) (xy 127.733 -139.195663) (xy 127.749531 -139.224413) (xy 127.772914 -139.247929)
			(xy 127.80157 -139.264622) (xy 127.83356 -139.273364) (xy 127.850138 -139.274042) (xy 127.878437 -139.27473)
			(xy 127.93437 -139.283436) (xy 127.988402 -139.300309) (xy 128.039349 -139.32498) (xy 128.086091 -139.356907)
			(xy 128.127605 -139.395389) (xy 128.162977 -139.439581) (xy 128.191432 -139.488515) (xy 128.212346 -139.541116)
			(xy 128.225259 -139.596229) (xy 128.229889 -139.652645) (xy 128.226133 -139.709126) (xy 128.214073 -139.764432)
			(xy 128.193975 -139.81735) (xy 128.16628 -139.866718) (xy 128.131596 -139.911453) (xy 128.111504 -139.931394)
			(xy 128.095567 -139.947288) (xy 128.06901 -139.983624) (xy 128.049271 -140.024071) (xy 128.036967 -140.067363)
			(xy 128.032484 -140.112146) (xy 128.035961 -140.157018) (xy 128.047291 -140.200575) (xy 128.066117 -140.241454)
			(xy 128.091852 -140.278377) (xy 128.10744 -140.294614) (xy 128.306576 -140.493496) (xy 128.367028 -140.493496)
			(xy 128.367028 -140.553948) (xy 128.75514 -140.942314) (xy 128.75514 -141.45895) (xy 130.132834 -141.45895)
			(xy 130.136905 -141.403328) (xy 130.149031 -141.348891) (xy 130.168954 -141.2968) (xy 130.19625 -141.248165)
			(xy 130.230336 -141.204022) (xy 130.270485 -141.165313) (xy 130.315843 -141.132862) (xy 130.365443 -141.107361)
			(xy 130.418227 -141.089354) (xy 130.47307 -141.079224) (xy 130.528804 -141.077187) (xy 130.584241 -141.083287)
			(xy 130.638198 -141.097393) (xy 130.689527 -141.119205) (xy 130.737133 -141.148259) (xy 130.780001 -141.183934)
			(xy 130.817218 -141.225471) (xy 130.847991 -141.271984) (xy 130.871663 -141.322481) (xy 130.887731 -141.375888)
			(xy 130.895851 -141.431064) (xy 130.89636 -141.45895) (xy 130.895851 -141.486836) (xy 130.887731 -141.542012)
			(xy 130.871663 -141.595419) (xy 130.847991 -141.645916) (xy 130.817218 -141.692429) (xy 130.780001 -141.733966)
			(xy 130.737133 -141.769641) (xy 130.689527 -141.798695) (xy 130.638198 -141.820507) (xy 130.584241 -141.834613)
			(xy 130.528804 -141.840713) (xy 130.47307 -141.838676) (xy 130.418227 -141.828546) (xy 130.365443 -141.810539)
			(xy 130.315843 -141.785038) (xy 130.270485 -141.752587) (xy 130.230336 -141.713878) (xy 130.19625 -141.669735)
			(xy 130.168954 -141.6211) (xy 130.149031 -141.569009) (xy 130.136905 -141.514572) (xy 130.132834 -141.45895)
			(xy 128.75514 -141.45895) (xy 128.75514 -142.55115) (xy 139.683234 -142.55115) (xy 139.687305 -142.495528)
			(xy 139.699431 -142.441091) (xy 139.719354 -142.389) (xy 139.74665 -142.340365) (xy 139.780736 -142.296222)
			(xy 139.820885 -142.257513) (xy 139.866243 -142.225062) (xy 139.915843 -142.199561) (xy 139.968627 -142.181554)
			(xy 140.02347 -142.171424) (xy 140.079204 -142.169387) (xy 140.134641 -142.175487) (xy 140.188598 -142.189593)
			(xy 140.239927 -142.211405) (xy 140.287533 -142.240459) (xy 140.330401 -142.276134) (xy 140.367618 -142.317671)
			(xy 140.398391 -142.364184) (xy 140.422063 -142.414681) (xy 140.438131 -142.468088) (xy 140.446251 -142.523264)
			(xy 140.44676 -142.55115) (xy 140.446251 -142.579036) (xy 140.438131 -142.634212) (xy 140.422063 -142.687619)
			(xy 140.398391 -142.738116) (xy 140.367618 -142.784629) (xy 140.330401 -142.826166) (xy 140.287533 -142.861841)
			(xy 140.239927 -142.890895) (xy 140.188598 -142.912707) (xy 140.134641 -142.926813) (xy 140.079204 -142.932913)
			(xy 140.02347 -142.930876) (xy 139.968627 -142.920746) (xy 139.915843 -142.902739) (xy 139.866243 -142.877238)
			(xy 139.820885 -142.844787) (xy 139.780736 -142.806078) (xy 139.74665 -142.761935) (xy 139.719354 -142.7133)
			(xy 139.699431 -142.661209) (xy 139.687305 -142.606772) (xy 139.683234 -142.55115) (xy 128.75514 -142.55115)
			(xy 128.75514 -145.11655) (xy 129.243834 -145.11655) (xy 129.247905 -145.060928) (xy 129.260031 -145.006491)
			(xy 129.279954 -144.9544) (xy 129.30725 -144.905765) (xy 129.341336 -144.861622) (xy 129.381485 -144.822913)
			(xy 129.426843 -144.790462) (xy 129.476443 -144.764961) (xy 129.529227 -144.746954) (xy 129.58407 -144.736824)
			(xy 129.639804 -144.734787) (xy 129.695241 -144.740887) (xy 129.749198 -144.754993) (xy 129.800527 -144.776805)
			(xy 129.848133 -144.805859) (xy 129.891001 -144.841534) (xy 129.928218 -144.883071) (xy 129.958991 -144.929584)
			(xy 129.982663 -144.980081) (xy 129.998731 -145.033488) (xy 130.006851 -145.088664) (xy 130.00736 -145.11655)
			(xy 130.006851 -145.144436) (xy 129.998731 -145.199612) (xy 129.991564 -145.223434) (xy 139.632414 -145.223434)
			(xy 139.635735 -145.167673) (xy 139.647151 -145.112992) (xy 139.66642 -145.060561) (xy 139.693128 -145.0115)
			(xy 139.726706 -144.966858) (xy 139.746228 -144.946878) (xy 139.761681 -144.930985) (xy 139.787316 -144.894825)
			(xy 139.806288 -144.854764) (xy 139.818019 -144.812019) (xy 139.822155 -144.767887) (xy 139.81857 -144.723707)
			(xy 139.807373 -144.680819) (xy 139.788902 -144.640525) (xy 139.776708 -144.622012) (xy 139.761267 -144.598733)
			(xy 139.73658 -144.548623) (xy 139.719465 -144.49545) (xy 139.710287 -144.440348) (xy 139.709243 -144.384498)
			(xy 139.716354 -144.329092) (xy 139.73147 -144.275316) (xy 139.754266 -144.224318) (xy 139.784255 -144.177191)
			(xy 139.820796 -144.13494) (xy 139.863108 -144.09847) (xy 139.910287 -144.068561) (xy 139.961322 -144.045851)
			(xy 140.015124 -144.030826) (xy 140.070542 -144.023808) (xy 140.126391 -144.024947) (xy 140.181476 -144.034218)
			(xy 140.234621 -144.051423) (xy 140.284689 -144.076194) (xy 140.330608 -144.108001) (xy 140.371399 -144.146166)
			(xy 140.406188 -144.189871) (xy 140.434231 -144.238181) (xy 140.45493 -144.290065) (xy 140.467841 -144.344413)
			(xy 140.472688 -144.400063) (xy 140.469368 -144.455824) (xy 140.457952 -144.510506) (xy 140.438684 -144.562938)
			(xy 140.411975 -144.611999) (xy 140.378398 -144.656641) (xy 140.358876 -144.676622) (xy 140.343423 -144.692515)
			(xy 140.317787 -144.728675) (xy 140.298816 -144.768736) (xy 140.287084 -144.811481) (xy 140.282948 -144.855613)
			(xy 140.286533 -144.899793) (xy 140.297731 -144.942681) (xy 140.316201 -144.982975) (xy 140.328396 -145.001488)
			(xy 140.343832 -145.024771) (xy 140.368518 -145.07488) (xy 140.385633 -145.128053) (xy 140.39481 -145.183154)
			(xy 140.395854 -145.239004) (xy 140.388743 -145.29441) (xy 140.373627 -145.348186) (xy 140.350831 -145.399182)
			(xy 140.320841 -145.44631) (xy 140.2843 -145.48856) (xy 140.241988 -145.525029) (xy 140.19481 -145.554938)
			(xy 140.143774 -145.577648) (xy 140.089973 -145.592672) (xy 140.034556 -145.599689) (xy 139.978707 -145.59855)
			(xy 139.923622 -145.589279) (xy 139.870478 -145.572074) (xy 139.820411 -145.547303) (xy 139.774491 -145.515495)
			(xy 139.733701 -145.47733) (xy 139.698913 -145.433626) (xy 139.67087 -145.385315) (xy 139.650172 -145.333431)
			(xy 139.637261 -145.279084) (xy 139.632414 -145.223434) (xy 129.991564 -145.223434) (xy 129.982663 -145.253019)
			(xy 129.958991 -145.303516) (xy 129.928218 -145.350029) (xy 129.891001 -145.391566) (xy 129.848133 -145.427241)
			(xy 129.800527 -145.456295) (xy 129.749198 -145.478107) (xy 129.695241 -145.492213) (xy 129.639804 -145.498313)
			(xy 129.58407 -145.496276) (xy 129.529227 -145.486146) (xy 129.476443 -145.468139) (xy 129.426843 -145.442638)
			(xy 129.381485 -145.410187) (xy 129.341336 -145.371478) (xy 129.30725 -145.327335) (xy 129.279954 -145.2787)
			(xy 129.260031 -145.226609) (xy 129.247905 -145.172172) (xy 129.243834 -145.11655) (xy 128.75514 -145.11655)
			(xy 128.75514 -148.997924) (xy 128.572514 -149.18055) (xy 139.556234 -149.18055) (xy 139.560305 -149.124928)
			(xy 139.572431 -149.070491) (xy 139.592354 -149.0184) (xy 139.61965 -148.969765) (xy 139.653736 -148.925622)
			(xy 139.693885 -148.886913) (xy 139.739243 -148.854462) (xy 139.788843 -148.828961) (xy 139.841627 -148.810954)
			(xy 139.89647 -148.800824) (xy 139.952204 -148.798787) (xy 140.007641 -148.804887) (xy 140.061598 -148.818993)
			(xy 140.112927 -148.840805) (xy 140.160533 -148.869859) (xy 140.203401 -148.905534) (xy 140.240618 -148.947071)
			(xy 140.271391 -148.993584) (xy 140.295063 -149.044081) (xy 140.311131 -149.097488) (xy 140.319251 -149.152664)
			(xy 140.31976 -149.18055) (xy 140.319251 -149.208436) (xy 140.311131 -149.263612) (xy 140.295063 -149.317019)
			(xy 140.271391 -149.367516) (xy 140.240618 -149.414029) (xy 140.203401 -149.455566) (xy 140.160533 -149.491241)
			(xy 140.112927 -149.520295) (xy 140.061598 -149.542107) (xy 140.007641 -149.556213) (xy 139.952204 -149.562313)
			(xy 139.89647 -149.560276) (xy 139.841627 -149.550146) (xy 139.788843 -149.532139) (xy 139.739243 -149.506638)
			(xy 139.693885 -149.474187) (xy 139.653736 -149.435478) (xy 139.61965 -149.391335) (xy 139.592354 -149.3427)
			(xy 139.572431 -149.290609) (xy 139.560305 -149.236172) (xy 139.556234 -149.18055) (xy 128.572514 -149.18055)
			(xy 128.367028 -149.386036) (xy 128.367028 -149.464268) (xy 127.788924 -150.042118) (xy 127.777926 -150.053878)
			(xy 129.756095 -150.053878) (xy 129.762276 -149.999318) (xy 129.776212 -149.946207) (xy 129.797617 -149.895641)
			(xy 129.826048 -149.848666) (xy 129.860919 -149.80625) (xy 129.901508 -149.76927) (xy 129.946979 -149.738489)
			(xy 129.996391 -149.714543) (xy 130.048726 -149.697926) (xy 130.102902 -149.688982) (xy 130.1578 -149.687894)
			(xy 130.212288 -149.694686) (xy 130.26524 -149.709217) (xy 130.315562 -149.731187) (xy 130.362216 -149.760143)
			(xy 130.383534 -149.77745) (xy 130.40215 -149.792449) (xy 130.443833 -149.815847) (xy 130.48916 -149.831029)
			(xy 130.536527 -149.83746) (xy 130.58426 -149.834912) (xy 130.630673 -149.823475) (xy 130.674126 -149.803554)
			(xy 130.693922 -149.79015) (xy 130.71658 -149.774637) (xy 130.765445 -149.749586) (xy 130.817396 -149.731797)
			(xy 130.87136 -149.721637) (xy 130.926223 -149.719317) (xy 130.980852 -149.724883) (xy 131.03412 -149.738221)
			(xy 131.084926 -149.759056) (xy 131.132221 -149.786958) (xy 131.175029 -149.82135) (xy 131.212467 -149.861522)
			(xy 131.24376 -149.906645) (xy 131.261663 -149.94255) (xy 133.638034 -149.94255) (xy 133.642105 -149.886928)
			(xy 133.654231 -149.832491) (xy 133.674154 -149.7804) (xy 133.70145 -149.731765) (xy 133.735536 -149.687622)
			(xy 133.775685 -149.648913) (xy 133.821043 -149.616462) (xy 133.870643 -149.590961) (xy 133.923427 -149.572954)
			(xy 133.97827 -149.562824) (xy 134.034004 -149.560787) (xy 134.089441 -149.566887) (xy 134.143398 -149.580993)
			(xy 134.194727 -149.602805) (xy 134.242333 -149.631859) (xy 134.285201 -149.667534) (xy 134.322418 -149.709071)
			(xy 134.353191 -149.755584) (xy 134.376863 -149.806081) (xy 134.392931 -149.859488) (xy 134.401051 -149.914664)
			(xy 134.40156 -149.94255) (xy 135.009634 -149.94255) (xy 135.013705 -149.886928) (xy 135.025831 -149.832491)
			(xy 135.045754 -149.7804) (xy 135.07305 -149.731765) (xy 135.107136 -149.687622) (xy 135.147285 -149.648913)
			(xy 135.192643 -149.616462) (xy 135.242243 -149.590961) (xy 135.295027 -149.572954) (xy 135.34987 -149.562824)
			(xy 135.405604 -149.560787) (xy 135.461041 -149.566887) (xy 135.514998 -149.580993) (xy 135.566327 -149.602805)
			(xy 135.613933 -149.631859) (xy 135.656801 -149.667534) (xy 135.694018 -149.709071) (xy 135.724791 -149.755584)
			(xy 135.748463 -149.806081) (xy 135.764531 -149.859488) (xy 135.770662 -149.901148) (xy 136.956036 -149.901148)
			(xy 136.960107 -149.845526) (xy 136.972233 -149.791089) (xy 136.992156 -149.738998) (xy 137.019452 -149.690363)
			(xy 137.053538 -149.64622) (xy 137.093687 -149.607511) (xy 137.139045 -149.57506) (xy 137.188645 -149.549559)
			(xy 137.241429 -149.531552) (xy 137.296272 -149.521422) (xy 137.352006 -149.519385) (xy 137.407443 -149.525485)
			(xy 137.4614 -149.539591) (xy 137.512729 -149.561403) (xy 137.560335 -149.590457) (xy 137.603203 -149.626132)
			(xy 137.64042 -149.667669) (xy 137.671193 -149.714182) (xy 137.694865 -149.764679) (xy 137.710933 -149.818086)
			(xy 137.719053 -149.873262) (xy 137.719562 -149.901148) (xy 137.719557 -149.901402) (xy 138.555982 -149.901402)
			(xy 138.560053 -149.84578) (xy 138.572179 -149.791343) (xy 138.592102 -149.739252) (xy 138.619398 -149.690617)
			(xy 138.653484 -149.646474) (xy 138.693633 -149.607765) (xy 138.738991 -149.575314) (xy 138.788591 -149.549813)
			(xy 138.841375 -149.531806) (xy 138.896218 -149.521676) (xy 138.951952 -149.519639) (xy 139.007389 -149.525739)
			(xy 139.061346 -149.539845) (xy 139.112675 -149.561657) (xy 139.160281 -149.590711) (xy 139.203149 -149.626386)
			(xy 139.240366 -149.667923) (xy 139.271139 -149.714436) (xy 139.294811 -149.764933) (xy 139.310879 -149.81834)
			(xy 139.318999 -149.873516) (xy 139.319508 -149.901402) (xy 139.318999 -149.929288) (xy 139.310879 -149.984464)
			(xy 139.294811 -150.037871) (xy 139.271139 -150.088368) (xy 139.240366 -150.134881) (xy 139.203149 -150.176418)
			(xy 139.160281 -150.212093) (xy 139.112675 -150.241147) (xy 139.061346 -150.262959) (xy 139.007389 -150.277065)
			(xy 138.951952 -150.283165) (xy 138.896218 -150.281128) (xy 138.841375 -150.270998) (xy 138.788591 -150.252991)
			(xy 138.738991 -150.22749) (xy 138.693633 -150.195039) (xy 138.653484 -150.15633) (xy 138.619398 -150.112187)
			(xy 138.592102 -150.063552) (xy 138.572179 -150.011461) (xy 138.560053 -149.957024) (xy 138.555982 -149.901402)
			(xy 137.719557 -149.901402) (xy 137.719053 -149.929034) (xy 137.710933 -149.98421) (xy 137.694865 -150.037617)
			(xy 137.671193 -150.088114) (xy 137.64042 -150.134627) (xy 137.603203 -150.176164) (xy 137.560335 -150.211839)
			(xy 137.512729 -150.240893) (xy 137.4614 -150.262705) (xy 137.407443 -150.276811) (xy 137.352006 -150.282911)
			(xy 137.296272 -150.280874) (xy 137.241429 -150.270744) (xy 137.188645 -150.252737) (xy 137.139045 -150.227236)
			(xy 137.093687 -150.194785) (xy 137.053538 -150.156076) (xy 137.019452 -150.111933) (xy 136.992156 -150.063298)
			(xy 136.972233 -150.011207) (xy 136.960107 -149.95677) (xy 136.956036 -149.901148) (xy 135.770662 -149.901148)
			(xy 135.772651 -149.914664) (xy 135.77316 -149.94255) (xy 135.772651 -149.970436) (xy 135.764531 -150.025612)
			(xy 135.748463 -150.079019) (xy 135.724791 -150.129516) (xy 135.694018 -150.176029) (xy 135.656801 -150.217566)
			(xy 135.613933 -150.253241) (xy 135.566327 -150.282295) (xy 135.514998 -150.304107) (xy 135.461041 -150.318213)
			(xy 135.405604 -150.324313) (xy 135.34987 -150.322276) (xy 135.295027 -150.312146) (xy 135.242243 -150.294139)
			(xy 135.192643 -150.268638) (xy 135.147285 -150.236187) (xy 135.107136 -150.197478) (xy 135.07305 -150.153335)
			(xy 135.045754 -150.1047) (xy 135.025831 -150.052609) (xy 135.013705 -149.998172) (xy 135.009634 -149.94255)
			(xy 134.40156 -149.94255) (xy 134.401051 -149.970436) (xy 134.392931 -150.025612) (xy 134.376863 -150.079019)
			(xy 134.353191 -150.129516) (xy 134.322418 -150.176029) (xy 134.285201 -150.217566) (xy 134.242333 -150.253241)
			(xy 134.194727 -150.282295) (xy 134.143398 -150.304107) (xy 134.089441 -150.318213) (xy 134.034004 -150.324313)
			(xy 133.97827 -150.322276) (xy 133.923427 -150.312146) (xy 133.870643 -150.294139) (xy 133.821043 -150.268638)
			(xy 133.775685 -150.236187) (xy 133.735536 -150.197478) (xy 133.70145 -150.153335) (xy 133.674154 -150.1047)
			(xy 133.654231 -150.052609) (xy 133.642105 -149.998172) (xy 133.638034 -149.94255) (xy 131.261663 -149.94255)
			(xy 131.268263 -149.955787) (xy 131.28547 -150.007933) (xy 131.295026 -150.062007) (xy 131.296733 -150.116893)
			(xy 131.290556 -150.171456) (xy 131.276623 -150.224571) (xy 131.255222 -150.275141) (xy 131.226793 -150.322122)
			(xy 131.191925 -150.364543) (xy 131.151337 -150.401529) (xy 131.105867 -150.432315) (xy 131.056454 -150.456268)
			(xy 131.004118 -150.472891) (xy 130.949941 -150.481841) (xy 130.89504 -150.482935) (xy 130.840548 -150.476148)
			(xy 130.787592 -150.461623) (xy 130.737265 -150.439657) (xy 130.690605 -150.410705) (xy 130.669284 -150.3934)
			(xy 130.650656 -150.378418) (xy 130.608974 -150.355024) (xy 130.563651 -150.339842) (xy 130.516287 -150.33341)
			(xy 130.468557 -150.335955) (xy 130.422145 -150.347386) (xy 130.378693 -150.3673) (xy 130.358896 -150.3807)
			(xy 130.336193 -150.396148) (xy 130.28733 -150.421196) (xy 130.235381 -150.438982) (xy 130.181419 -150.449138)
			(xy 130.126559 -150.451456) (xy 130.071932 -150.445887) (xy 130.018668 -150.432547) (xy 129.967866 -150.41171)
			(xy 129.920575 -150.383807) (xy 129.877771 -150.349415) (xy 129.840338 -150.309242) (xy 129.80905 -150.264119)
			(xy 129.784551 -150.214978) (xy 129.767349 -150.162833) (xy 129.757798 -150.108761) (xy 129.756095 -150.053878)
			(xy 127.777926 -150.053878) (xy 127.777566 -150.054263) (xy 127.760957 -150.083056) (xy 127.752346 -150.115161)
			(xy 127.75184 -150.13178) (xy 127.75184 -151.283162) (xy 128.297686 -151.829008) (xy 141.440662 -151.829008)
		)
		(stroke
			(width 0)
			(type solid)
		)
		(fill yes)
		(layer "In7.Cu")
		(net "P1V0_NODE1")
	)
	(gr_poly
		(pts
			(xy 170.294554 -106.862372) (xy 170.307871 -106.856644) (xy 170.335206 -106.846982) (xy 170.349164 -106.843068)
			(xy 170.38193 -106.834432) (xy 170.6118 -106.604562) (xy 170.6118 -104.30383) (xy 170.611335 -104.2816)
			(xy 170.603589 -104.237819) (xy 170.588345 -104.196053) (xy 170.566068 -104.157576) (xy 170.537438 -104.12356)
			(xy 170.503327 -104.095044) (xy 170.464775 -104.072896) (xy 170.422959 -104.057792) (xy 170.379152 -104.050192)
			(xy 170.334692 -104.050328) (xy 170.290933 -104.058197) (xy 170.24921 -104.073557) (xy 170.229784 -104.084374)
			(xy 170.205675 -104.097847) (xy 170.154442 -104.118468) (xy 170.10077 -104.131485) (xy 170.045782 -104.136627)
			(xy 169.990628 -104.133787) (xy 169.936459 -104.123023) (xy 169.884408 -104.104562) (xy 169.835564 -104.078788)
			(xy 169.790946 -104.04624) (xy 169.751488 -104.007598) (xy 169.718014 -103.963671) (xy 169.691224 -103.915377)
			(xy 169.671677 -103.863724) (xy 169.659783 -103.809792) (xy 169.655789 -103.754709) (xy 169.65978 -103.699626)
			(xy 169.671672 -103.645694) (xy 169.691216 -103.59404) (xy 169.718004 -103.545744) (xy 169.751476 -103.501815)
			(xy 169.790932 -103.463172) (xy 169.835548 -103.430622) (xy 169.884392 -103.404846) (xy 169.936441 -103.386381)
			(xy 169.99061 -103.375615) (xy 170.045764 -103.372772) (xy 170.100752 -103.377912) (xy 170.154424 -103.390927)
			(xy 170.205659 -103.411545) (xy 170.229784 -103.42499) (xy 170.24922 -103.435799) (xy 170.290943 -103.451184)
			(xy 170.334706 -103.459072) (xy 170.379175 -103.459222) (xy 170.422991 -103.451631) (xy 170.464817 -103.43653)
			(xy 170.503376 -103.414379) (xy 170.537492 -103.385855) (xy 170.566122 -103.351829) (xy 170.588394 -103.313339)
			(xy 170.603626 -103.271561) (xy 170.611354 -103.227769) (xy 170.6118 -103.205534) (xy 170.6118 -102.87)
			(xy 170.611354 -102.848255) (xy 170.603949 -102.8054) (xy 170.589356 -102.764432) (xy 170.568 -102.726547)
			(xy 170.540505 -102.692851) (xy 170.507674 -102.664329) (xy 170.470466 -102.641814) (xy 170.429968 -102.625962)
			(xy 170.387362 -102.617238) (xy 170.343893 -102.615895) (xy 170.30083 -102.621974) (xy 170.259431 -102.635296)
			(xy 170.239944 -102.644956) (xy 170.214923 -102.657484) (xy 170.162081 -102.675887) (xy 170.107117 -102.686373)
			(xy 170.051211 -102.688718) (xy 169.995563 -102.682871) (xy 169.941365 -102.668957) (xy 169.889782 -102.647275)
			(xy 169.841919 -102.618289) (xy 169.798804 -102.582623) (xy 169.761362 -102.541042) (xy 169.730395 -102.494436)
			(xy 169.70657 -102.443807) (xy 169.690396 -102.390241) (xy 169.68222 -102.334886) (xy 169.682219 -102.278931)
			(xy 169.690392 -102.223576) (xy 169.706564 -102.170009) (xy 169.730387 -102.119378) (xy 169.761351 -102.072772)
			(xy 169.798792 -102.031188) (xy 169.841905 -101.99552) (xy 169.889767 -101.966533) (xy 169.941349 -101.944849)
			(xy 169.995546 -101.930932) (xy 170.051195 -101.925082) (xy 170.107101 -101.927425) (xy 170.162065 -101.937909)
			(xy 170.214908 -101.95631) (xy 170.239944 -101.968808) (xy 170.259416 -101.978504) (xy 170.300819 -101.991829)
			(xy 170.343887 -101.99791) (xy 170.387362 -101.996567) (xy 170.429973 -101.987842) (xy 170.470475 -101.971988)
			(xy 170.507687 -101.949468) (xy 170.54052 -101.920941) (xy 170.568016 -101.887239) (xy 170.589371 -101.849347)
			(xy 170.603962 -101.808372) (xy 170.611362 -101.765512) (xy 170.6118 -101.743764) (xy 170.6118 -100.92563)
			(xy 170.611335 -100.9034) (xy 170.603589 -100.859619) (xy 170.588345 -100.817853) (xy 170.566068 -100.779376)
			(xy 170.537438 -100.74536) (xy 170.503327 -100.716844) (xy 170.464775 -100.694696) (xy 170.422959 -100.679592)
			(xy 170.379152 -100.671992) (xy 170.334692 -100.672128) (xy 170.290933 -100.679997) (xy 170.24921 -100.695357)
			(xy 170.229784 -100.706174) (xy 170.205675 -100.719647) (xy 170.154442 -100.740268) (xy 170.10077 -100.753285)
			(xy 170.045782 -100.758427) (xy 169.990628 -100.755587) (xy 169.936459 -100.744823) (xy 169.884408 -100.726362)
			(xy 169.835564 -100.700588) (xy 169.790946 -100.66804) (xy 169.751488 -100.629398) (xy 169.718014 -100.585471)
			(xy 169.691224 -100.537177) (xy 169.671677 -100.485524) (xy 169.659783 -100.431592) (xy 169.655789 -100.376509)
			(xy 169.65978 -100.321426) (xy 169.671672 -100.267494) (xy 169.691216 -100.21584) (xy 169.718004 -100.167544)
			(xy 169.751476 -100.123615) (xy 169.790932 -100.084972) (xy 169.835548 -100.052422) (xy 169.884392 -100.026646)
			(xy 169.936441 -100.008181) (xy 169.99061 -99.997415) (xy 170.045764 -99.994572) (xy 170.100752 -99.999712)
			(xy 170.154424 -100.012727) (xy 170.205659 -100.033345) (xy 170.229784 -100.04679) (xy 170.24922 -100.057599)
			(xy 170.290943 -100.072984) (xy 170.334706 -100.080872) (xy 170.379175 -100.081022) (xy 170.422991 -100.073431)
			(xy 170.464817 -100.05833) (xy 170.503376 -100.036179) (xy 170.537492 -100.007655) (xy 170.566122 -99.973629)
			(xy 170.588394 -99.935139) (xy 170.603626 -99.893361) (xy 170.611354 -99.849569) (xy 170.6118 -99.827334)
			(xy 170.6118 -98.679) (xy 170.611354 -98.657255) (xy 170.603949 -98.6144) (xy 170.589356 -98.573432)
			(xy 170.568 -98.535547) (xy 170.540505 -98.501851) (xy 170.507674 -98.473329) (xy 170.470466 -98.450814)
			(xy 170.429968 -98.434962) (xy 170.387362 -98.426238) (xy 170.343893 -98.424895) (xy 170.30083 -98.430974)
			(xy 170.259431 -98.444296) (xy 170.239944 -98.453956) (xy 170.214923 -98.466484) (xy 170.162081 -98.484887)
			(xy 170.107117 -98.495373) (xy 170.051211 -98.497718) (xy 169.995563 -98.491871) (xy 169.941365 -98.477957)
			(xy 169.889782 -98.456275) (xy 169.841919 -98.427289) (xy 169.798804 -98.391623) (xy 169.761362 -98.350042)
			(xy 169.730395 -98.303436) (xy 169.70657 -98.252807) (xy 169.690396 -98.199241) (xy 169.68222 -98.143886)
			(xy 169.682219 -98.087931) (xy 169.690392 -98.032576) (xy 169.706564 -97.979009) (xy 169.730387 -97.928378)
			(xy 169.761351 -97.881772) (xy 169.798792 -97.840188) (xy 169.841905 -97.80452) (xy 169.889767 -97.775533)
			(xy 169.941349 -97.753849) (xy 169.995546 -97.739932) (xy 170.051195 -97.734082) (xy 170.107101 -97.736425)
			(xy 170.162065 -97.746909) (xy 170.214908 -97.76531) (xy 170.239944 -97.777808) (xy 170.259416 -97.787504)
			(xy 170.300819 -97.800829) (xy 170.343887 -97.80691) (xy 170.387362 -97.805567) (xy 170.429973 -97.796842)
			(xy 170.470475 -97.780988) (xy 170.507687 -97.758468) (xy 170.54052 -97.729941) (xy 170.568016 -97.696239)
			(xy 170.589371 -97.658347) (xy 170.603962 -97.617372) (xy 170.611362 -97.574512) (xy 170.6118 -97.552764)
			(xy 170.6118 -95.38208) (xy 170.611254 -95.365433) (xy 170.602633 -95.333276) (xy 170.585983 -95.304444)
			(xy 170.56244 -95.280904) (xy 170.533606 -95.264259) (xy 170.501447 -95.255643) (xy 170.4848 -95.25508)
			(xy 168.82745 -95.25508) (xy 168.804456 -95.255573) (xy 168.759217 -95.263841) (xy 168.716205 -95.280117)
			(xy 168.676825 -95.303868) (xy 168.642363 -95.33432) (xy 168.613945 -95.370477) (xy 168.592498 -95.411158)
			(xy 168.578724 -95.455035) (xy 168.573072 -95.500675) (xy 168.575727 -95.546586) (xy 168.586602 -95.59127)
			(xy 168.595548 -95.612458) (xy 168.606643 -95.638611) (xy 168.621839 -95.693349) (xy 168.62875 -95.749736)
			(xy 168.627225 -95.806524) (xy 168.617297 -95.862458) (xy 168.599185 -95.916301) (xy 168.57329 -95.966865)
			(xy 168.540184 -96.01303) (xy 168.500599 -96.053776) (xy 168.455411 -96.088202) (xy 168.405617 -96.115548)
			(xy 168.352319 -96.135209) (xy 168.296696 -96.14675) (xy 168.239976 -96.149916) (xy 168.183413 -96.144637)
			(xy 168.128258 -96.13103) (xy 168.075731 -96.109396) (xy 168.026991 -96.080212) (xy 168.004744 -96.062546)
			(xy 167.980106 -96.040448) (xy 167.967761 -96.029072) (xy 167.938492 -96.012656) (xy 167.905953 -96.004446)
			(xy 167.8724 -96.00501) (xy 167.840155 -96.014309) (xy 167.811454 -96.031699) (xy 167.799512 -96.043496)
			(xy 167.780523 -96.062674) (xy 167.738096 -96.096027) (xy 167.691391 -96.123067) (xy 167.64134 -96.143252)
			(xy 167.588943 -96.156179) (xy 167.535247 -96.161591) (xy 167.481325 -96.159378) (xy 167.428253 -96.149586)
			(xy 167.377091 -96.13241) (xy 167.328862 -96.108193) (xy 167.284528 -96.077419) (xy 167.244976 -96.040702)
			(xy 167.210994 -95.998776) (xy 167.183263 -95.952478) (xy 167.162336 -95.902733) (xy 167.14863 -95.850534)
			(xy 167.14242 -95.796925) (xy 167.142668 -95.769938) (xy 167.143756 -95.743614) (xy 167.152292 -95.691623)
			(xy 167.167919 -95.641308) (xy 167.178736 -95.617284) (xy 167.188162 -95.59604) (xy 167.19998 -95.551096)
			(xy 167.203431 -95.504752) (xy 167.1984 -95.458554) (xy 167.185054 -95.414039) (xy 167.163838 -95.372693)
			(xy 167.135459 -95.335893) (xy 167.100863 -95.304864) (xy 167.061203 -95.280642) (xy 167.017801 -95.264033)
			(xy 166.972102 -95.255591) (xy 166.948866 -95.25508) (xy 166.213536 -95.25508) (xy 166.190094 -95.255614)
			(xy 166.144005 -95.264206) (xy 166.100272 -95.281104) (xy 166.06038 -95.305735) (xy 166.025682 -95.337265)
			(xy 165.997355 -95.374623) (xy 165.976359 -95.416542) (xy 165.963407 -95.461601) (xy 165.958937 -95.508271)
			(xy 165.963103 -95.554969) (xy 165.975761 -95.600111) (xy 165.985698 -95.621348) (xy 165.997459 -95.646374)
			(xy 166.014446 -95.698995) (xy 166.023659 -95.753517) (xy 166.024906 -95.808798) (xy 166.01816 -95.86368)
			(xy 166.003563 -95.917014) (xy 165.981421 -95.967682) (xy 165.952197 -96.014623) (xy 165.916503 -96.056855)
			(xy 165.875087 -96.093492) (xy 165.828816 -96.123767) (xy 165.77866 -96.147046) (xy 165.72567 -96.162842)
			(xy 165.670954 -96.170823) (xy 165.615658 -96.170823) (xy 165.560942 -96.162842) (xy 165.507952 -96.147046)
			(xy 165.457796 -96.123767) (xy 165.411525 -96.093492) (xy 165.370109 -96.056855) (xy 165.334415 -96.014623)
			(xy 165.305191 -95.967682) (xy 165.283049 -95.917014) (xy 165.268452 -95.86368) (xy 165.261706 -95.808798)
			(xy 165.262953 -95.753517) (xy 165.272166 -95.698995) (xy 165.289153 -95.646374) (xy 165.300914 -95.621348)
			(xy 165.31079 -95.600088) (xy 165.323445 -95.554956) (xy 165.327609 -95.50827) (xy 165.323141 -95.461611)
			(xy 165.310192 -95.416563) (xy 165.289201 -95.374654) (xy 165.260881 -95.337305) (xy 165.226192 -95.305782)
			(xy 165.186311 -95.281156) (xy 165.14259 -95.26426) (xy 165.096512 -95.255669) (xy 165.073076 -95.25508)
			(xy 157.978094 -95.25508) (xy 157.961445 -95.255624) (xy 157.929282 -95.264242) (xy 157.900445 -95.280891)
			(xy 157.876899 -95.304434) (xy 157.860248 -95.333269) (xy 157.851626 -95.365431) (xy 157.851094 -95.38208)
			(xy 157.851094 -95.975932) (xy 163.507926 -95.975932) (xy 163.511997 -95.92031) (xy 163.524123 -95.865873)
			(xy 163.544046 -95.813782) (xy 163.571342 -95.765147) (xy 163.605428 -95.721004) (xy 163.645577 -95.682295)
			(xy 163.690935 -95.649844) (xy 163.740535 -95.624343) (xy 163.793319 -95.606336) (xy 163.848162 -95.596206)
			(xy 163.903896 -95.594169) (xy 163.959333 -95.600269) (xy 164.01329 -95.614375) (xy 164.064619 -95.636187)
			(xy 164.112225 -95.665241) (xy 164.155093 -95.700916) (xy 164.19231 -95.742453) (xy 164.223083 -95.788966)
			(xy 164.246755 -95.839463) (xy 164.262823 -95.89287) (xy 164.270943 -95.948046) (xy 164.271452 -95.975932)
			(xy 164.270943 -96.003818) (xy 164.262823 -96.058994) (xy 164.246755 -96.112401) (xy 164.223083 -96.162898)
			(xy 164.19231 -96.209411) (xy 164.155093 -96.250948) (xy 164.112225 -96.286623) (xy 164.064619 -96.315677)
			(xy 164.01329 -96.337489) (xy 163.959333 -96.351595) (xy 163.903896 -96.357695) (xy 163.848162 -96.355658)
			(xy 163.793319 -96.345528) (xy 163.740535 -96.327521) (xy 163.690935 -96.30202) (xy 163.645577 -96.269569)
			(xy 163.605428 -96.23086) (xy 163.571342 -96.186717) (xy 163.544046 -96.138082) (xy 163.524123 -96.085991)
			(xy 163.511997 -96.031554) (xy 163.507926 -95.975932) (xy 157.851094 -95.975932) (xy 157.851094 -96.930464)
			(xy 162.491926 -96.930464) (xy 162.495997 -96.874842) (xy 162.508123 -96.820405) (xy 162.528046 -96.768314)
			(xy 162.555342 -96.719679) (xy 162.589428 -96.675536) (xy 162.629577 -96.636827) (xy 162.674935 -96.604376)
			(xy 162.724535 -96.578875) (xy 162.777319 -96.560868) (xy 162.832162 -96.550738) (xy 162.887896 -96.548701)
			(xy 162.943333 -96.554801) (xy 162.99729 -96.568907) (xy 163.048619 -96.590719) (xy 163.096225 -96.619773)
			(xy 163.139093 -96.655448) (xy 163.17631 -96.696985) (xy 163.207083 -96.743498) (xy 163.230755 -96.793995)
			(xy 163.246823 -96.847402) (xy 163.254943 -96.902578) (xy 163.255452 -96.930464) (xy 163.254943 -96.95835)
			(xy 163.246823 -97.013526) (xy 163.230755 -97.066933) (xy 163.207083 -97.11743) (xy 163.17631 -97.163943)
			(xy 163.139093 -97.20548) (xy 163.096225 -97.241155) (xy 163.048619 -97.270209) (xy 162.99729 -97.292021)
			(xy 162.943333 -97.306127) (xy 162.887896 -97.312227) (xy 162.832162 -97.31019) (xy 162.777319 -97.30006)
			(xy 162.724535 -97.282053) (xy 162.674935 -97.256552) (xy 162.629577 -97.224101) (xy 162.589428 -97.185392)
			(xy 162.555342 -97.141249) (xy 162.528046 -97.092614) (xy 162.508123 -97.040523) (xy 162.495997 -96.986086)
			(xy 162.491926 -96.930464) (xy 157.851094 -96.930464) (xy 157.851094 -97.463102) (xy 158.88157 -97.463102)
			(xy 158.885641 -97.40748) (xy 158.897767 -97.353043) (xy 158.91769 -97.300952) (xy 158.944986 -97.252317)
			(xy 158.979072 -97.208174) (xy 159.019221 -97.169465) (xy 159.064579 -97.137014) (xy 159.114179 -97.111513)
			(xy 159.166963 -97.093506) (xy 159.221806 -97.083376) (xy 159.27754 -97.081339) (xy 159.332977 -97.087439)
			(xy 159.386934 -97.101545) (xy 159.438263 -97.123357) (xy 159.485869 -97.152411) (xy 159.528737 -97.188086)
			(xy 159.565954 -97.229623) (xy 159.596727 -97.276136) (xy 159.620399 -97.326633) (xy 159.636467 -97.38004)
			(xy 159.644587 -97.435216) (xy 159.645096 -97.463102) (xy 159.644587 -97.490988) (xy 159.636467 -97.546164)
			(xy 159.620399 -97.599571) (xy 159.596727 -97.650068) (xy 159.565954 -97.696581) (xy 159.528737 -97.738118)
			(xy 159.485869 -97.773793) (xy 159.438263 -97.802847) (xy 159.386934 -97.824659) (xy 159.332977 -97.838765)
			(xy 159.27754 -97.844865) (xy 159.221806 -97.842828) (xy 159.166963 -97.832698) (xy 159.114179 -97.814691)
			(xy 159.064579 -97.78919) (xy 159.019221 -97.756739) (xy 158.979072 -97.71803) (xy 158.944986 -97.673887)
			(xy 158.91769 -97.625252) (xy 158.897767 -97.573161) (xy 158.885641 -97.518724) (xy 158.88157 -97.463102)
			(xy 157.851094 -97.463102) (xy 157.851094 -98.82919) (xy 160.784251 -98.82919) (xy 160.790621 -98.774251)
			(xy 160.804857 -98.720807) (xy 160.826662 -98.669979) (xy 160.855578 -98.622833) (xy 160.890999 -98.580356)
			(xy 160.932182 -98.543439) (xy 160.978265 -98.512857) (xy 161.028281 -98.489249) (xy 161.081181 -98.473111)
			(xy 161.135858 -98.464782) (xy 161.163508 -98.464116) (xy 161.186659 -98.463419) (xy 161.232143 -98.454704)
			(xy 161.275295 -98.437893) (xy 161.314686 -98.413542) (xy 161.349014 -98.382456) (xy 161.377142 -98.345666)
			(xy 161.398138 -98.304388) (xy 161.411308 -98.25999) (xy 161.416216 -98.213939) (xy 161.414968 -98.190812)
			(xy 161.413321 -98.163196) (xy 161.417124 -98.108004) (xy 161.428859 -98.05394) (xy 161.448277 -98.002137)
			(xy 161.474973 -97.953682) (xy 161.508387 -97.90959) (xy 161.547818 -97.870785) (xy 161.59244 -97.838082)
			(xy 161.641317 -97.812165) (xy 161.693424 -97.793578) (xy 161.747669 -97.782711) (xy 161.802914 -97.779792)
			(xy 161.858003 -97.784882) (xy 161.911778 -97.797873) (xy 161.963114 -97.818495) (xy 162.010934 -97.846314)
			(xy 162.054235 -97.880747) (xy 162.092109 -97.921072) (xy 162.123763 -97.966444) (xy 162.148533 -98.015912)
			(xy 162.1659 -98.068438) (xy 162.175499 -98.122922) (xy 162.17604 -98.141282) (xy 164.067742 -98.141282)
			(xy 164.071813 -98.08566) (xy 164.083939 -98.031223) (xy 164.103862 -97.979132) (xy 164.131158 -97.930497)
			(xy 164.165244 -97.886354) (xy 164.205393 -97.847645) (xy 164.250751 -97.815194) (xy 164.300351 -97.789693)
			(xy 164.353135 -97.771686) (xy 164.407978 -97.761556) (xy 164.463712 -97.759519) (xy 164.519149 -97.765619)
			(xy 164.573106 -97.779725) (xy 164.624435 -97.801537) (xy 164.672041 -97.830591) (xy 164.714909 -97.866266)
			(xy 164.752126 -97.907803) (xy 164.782899 -97.954316) (xy 164.806571 -98.004813) (xy 164.822639 -98.05822)
			(xy 164.830759 -98.113396) (xy 164.830804 -98.115882) (xy 165.820342 -98.115882) (xy 165.824413 -98.06026)
			(xy 165.836539 -98.005823) (xy 165.856462 -97.953732) (xy 165.883758 -97.905097) (xy 165.917844 -97.860954)
			(xy 165.957993 -97.822245) (xy 166.003351 -97.789794) (xy 166.052951 -97.764293) (xy 166.105735 -97.746286)
			(xy 166.160578 -97.736156) (xy 166.216312 -97.734119) (xy 166.271749 -97.740219) (xy 166.325706 -97.754325)
			(xy 166.377035 -97.776137) (xy 166.424641 -97.805191) (xy 166.467509 -97.840866) (xy 166.504726 -97.882403)
			(xy 166.535499 -97.928916) (xy 166.559171 -97.979413) (xy 166.575239 -98.03282) (xy 166.583359 -98.087996)
			(xy 166.583868 -98.115882) (xy 167.547542 -98.115882) (xy 167.551613 -98.06026) (xy 167.563739 -98.005823)
			(xy 167.583662 -97.953732) (xy 167.610958 -97.905097) (xy 167.645044 -97.860954) (xy 167.685193 -97.822245)
			(xy 167.730551 -97.789794) (xy 167.780151 -97.764293) (xy 167.832935 -97.746286) (xy 167.887778 -97.736156)
			(xy 167.943512 -97.734119) (xy 167.998949 -97.740219) (xy 168.052906 -97.754325) (xy 168.104235 -97.776137)
			(xy 168.151841 -97.805191) (xy 168.194709 -97.840866) (xy 168.231926 -97.882403) (xy 168.262699 -97.928916)
			(xy 168.286371 -97.979413) (xy 168.302439 -98.03282) (xy 168.310559 -98.087996) (xy 168.311068 -98.115882)
			(xy 168.310559 -98.143768) (xy 168.302439 -98.198944) (xy 168.286371 -98.252351) (xy 168.262699 -98.302848)
			(xy 168.231926 -98.349361) (xy 168.194709 -98.390898) (xy 168.151841 -98.426573) (xy 168.104235 -98.455627)
			(xy 168.052906 -98.477439) (xy 167.998949 -98.491545) (xy 167.943512 -98.497645) (xy 167.887778 -98.495608)
			(xy 167.832935 -98.485478) (xy 167.780151 -98.467471) (xy 167.730551 -98.44197) (xy 167.685193 -98.409519)
			(xy 167.645044 -98.37081) (xy 167.610958 -98.326667) (xy 167.583662 -98.278032) (xy 167.563739 -98.225941)
			(xy 167.551613 -98.171504) (xy 167.547542 -98.115882) (xy 166.583868 -98.115882) (xy 166.583359 -98.143768)
			(xy 166.575239 -98.198944) (xy 166.559171 -98.252351) (xy 166.535499 -98.302848) (xy 166.504726 -98.349361)
			(xy 166.467509 -98.390898) (xy 166.424641 -98.426573) (xy 166.377035 -98.455627) (xy 166.325706 -98.477439)
			(xy 166.271749 -98.491545) (xy 166.216312 -98.497645) (xy 166.160578 -98.495608) (xy 166.105735 -98.485478)
			(xy 166.052951 -98.467471) (xy 166.003351 -98.44197) (xy 165.957993 -98.409519) (xy 165.917844 -98.37081)
			(xy 165.883758 -98.326667) (xy 165.856462 -98.278032) (xy 165.836539 -98.225941) (xy 165.824413 -98.171504)
			(xy 165.820342 -98.115882) (xy 164.830804 -98.115882) (xy 164.831268 -98.141282) (xy 164.830759 -98.169168)
			(xy 164.822639 -98.224344) (xy 164.806571 -98.277751) (xy 164.782899 -98.328248) (xy 164.752126 -98.374761)
			(xy 164.714909 -98.416298) (xy 164.672041 -98.451973) (xy 164.624435 -98.481027) (xy 164.573106 -98.502839)
			(xy 164.519149 -98.516945) (xy 164.463712 -98.523045) (xy 164.407978 -98.521008) (xy 164.353135 -98.510878)
			(xy 164.300351 -98.492871) (xy 164.250751 -98.46737) (xy 164.205393 -98.434919) (xy 164.165244 -98.39621)
			(xy 164.131158 -98.352067) (xy 164.103862 -98.303432) (xy 164.083939 -98.251341) (xy 164.071813 -98.196904)
			(xy 164.067742 -98.141282) (xy 162.17604 -98.141282) (xy 162.177129 -98.178221) (xy 162.170756 -98.233175)
			(xy 162.156514 -98.286633) (xy 162.134701 -98.337474) (xy 162.105774 -98.384632) (xy 162.070341 -98.427118)
			(xy 162.029143 -98.464042) (xy 161.983046 -98.49463) (xy 161.933014 -98.518239) (xy 161.880097 -98.534376)
			(xy 161.825404 -98.542702) (xy 161.797746 -98.543364) (xy 161.774595 -98.544041) (xy 161.729112 -98.552763)
			(xy 161.685962 -98.569579) (xy 161.646572 -98.593934) (xy 161.612246 -98.625022) (xy 161.584119 -98.661813)
			(xy 161.563122 -98.703091) (xy 161.54995 -98.74749) (xy 161.54504 -98.79354) (xy 161.546286 -98.816668)
			(xy 161.547899 -98.844279) (xy 161.544086 -98.899455) (xy 161.532346 -98.953502) (xy 161.512923 -99.005287)
			(xy 161.486227 -99.053724) (xy 161.452816 -99.097799) (xy 161.41339 -99.136588) (xy 161.368776 -99.169276)
			(xy 161.31991 -99.19518) (xy 161.267815 -99.213755) (xy 161.213584 -99.224614) (xy 161.158354 -99.227527)
			(xy 161.103281 -99.222434) (xy 161.049521 -99.209442) (xy 160.998201 -99.188823) (xy 160.950396 -99.16101)
			(xy 160.907109 -99.126584) (xy 160.869246 -99.086269) (xy 160.837602 -99.040909) (xy 160.812839 -98.991454)
			(xy 160.795478 -98.938942) (xy 160.785882 -98.884474) (xy 160.784251 -98.82919) (xy 157.851094 -98.82919)
			(xy 157.851094 -99.576636) (xy 161.603434 -99.576636) (xy 161.607505 -99.521014) (xy 161.619631 -99.466577)
			(xy 161.639554 -99.414486) (xy 161.66685 -99.365851) (xy 161.700936 -99.321708) (xy 161.741085 -99.282999)
			(xy 161.786443 -99.250548) (xy 161.836043 -99.225047) (xy 161.888827 -99.20704) (xy 161.94367 -99.19691)
			(xy 161.999404 -99.194873) (xy 162.054841 -99.200973) (xy 162.108798 -99.215079) (xy 162.160127 -99.236891)
			(xy 162.207733 -99.265945) (xy 162.250601 -99.30162) (xy 162.287818 -99.343157) (xy 162.318591 -99.38967)
			(xy 162.342263 -99.440167) (xy 162.358331 -99.493574) (xy 162.366451 -99.54875) (xy 162.36696 -99.576636)
			(xy 162.366451 -99.604522) (xy 162.358331 -99.659698) (xy 162.342263 -99.713105) (xy 162.318591 -99.763602)
			(xy 162.287818 -99.810115) (xy 162.250601 -99.851652) (xy 162.207733 -99.887327) (xy 162.196992 -99.893882)
			(xy 164.042342 -99.893882) (xy 164.046413 -99.83826) (xy 164.058539 -99.783823) (xy 164.078462 -99.731732)
			(xy 164.105758 -99.683097) (xy 164.139844 -99.638954) (xy 164.179993 -99.600245) (xy 164.225351 -99.567794)
			(xy 164.274951 -99.542293) (xy 164.327735 -99.524286) (xy 164.382578 -99.514156) (xy 164.438312 -99.512119)
			(xy 164.493749 -99.518219) (xy 164.547706 -99.532325) (xy 164.599035 -99.554137) (xy 164.646641 -99.583191)
			(xy 164.689509 -99.618866) (xy 164.726726 -99.660403) (xy 164.757499 -99.706916) (xy 164.781171 -99.757413)
			(xy 164.797239 -99.81082) (xy 164.805359 -99.865996) (xy 164.805868 -99.893882) (xy 164.805359 -99.921768)
			(xy 164.797239 -99.976944) (xy 164.781171 -100.030351) (xy 164.757499 -100.080848) (xy 164.726726 -100.127361)
			(xy 164.689509 -100.168898) (xy 164.646641 -100.204573) (xy 164.599035 -100.233627) (xy 164.547706 -100.255439)
			(xy 164.493749 -100.269545) (xy 164.438312 -100.275645) (xy 164.382578 -100.273608) (xy 164.327735 -100.263478)
			(xy 164.274951 -100.245471) (xy 164.225351 -100.21997) (xy 164.179993 -100.187519) (xy 164.139844 -100.14881)
			(xy 164.105758 -100.104667) (xy 164.078462 -100.056032) (xy 164.058539 -100.003941) (xy 164.046413 -99.949504)
			(xy 164.042342 -99.893882) (xy 162.196992 -99.893882) (xy 162.160127 -99.916381) (xy 162.108798 -99.938193)
			(xy 162.054841 -99.952299) (xy 161.999404 -99.958399) (xy 161.94367 -99.956362) (xy 161.888827 -99.946232)
			(xy 161.836043 -99.928225) (xy 161.786443 -99.902724) (xy 161.741085 -99.870273) (xy 161.700936 -99.831564)
			(xy 161.66685 -99.787421) (xy 161.639554 -99.738786) (xy 161.619631 -99.686695) (xy 161.607505 -99.632258)
			(xy 161.603434 -99.576636) (xy 157.851094 -99.576636) (xy 157.851094 -100.903786) (xy 161.571938 -100.903786)
			(xy 161.576009 -100.848164) (xy 161.588135 -100.793727) (xy 161.608058 -100.741636) (xy 161.635354 -100.693001)
			(xy 161.66944 -100.648858) (xy 161.709589 -100.610149) (xy 161.754947 -100.577698) (xy 161.804547 -100.552197)
			(xy 161.857331 -100.53419) (xy 161.912174 -100.52406) (xy 161.967908 -100.522023) (xy 162.023345 -100.528123)
			(xy 162.077302 -100.542229) (xy 162.128631 -100.564041) (xy 162.176237 -100.593095) (xy 162.219105 -100.62877)
			(xy 162.256322 -100.670307) (xy 162.287095 -100.71682) (xy 162.310767 -100.767317) (xy 162.326835 -100.820724)
			(xy 162.334955 -100.8759) (xy 162.335464 -100.903786) (xy 162.334955 -100.931672) (xy 162.326835 -100.986848)
			(xy 162.310767 -101.040255) (xy 162.287095 -101.090752) (xy 162.256322 -101.137265) (xy 162.219105 -101.178802)
			(xy 162.176237 -101.214477) (xy 162.128631 -101.243531) (xy 162.077302 -101.265343) (xy 162.023345 -101.279449)
			(xy 161.967908 -101.285549) (xy 161.912174 -101.283512) (xy 161.857331 -101.273382) (xy 161.804547 -101.255375)
			(xy 161.754947 -101.229874) (xy 161.709589 -101.197423) (xy 161.66944 -101.158714) (xy 161.635354 -101.114571)
			(xy 161.608058 -101.065936) (xy 161.588135 -101.013845) (xy 161.576009 -100.959408) (xy 161.571938 -100.903786)
			(xy 157.851094 -100.903786) (xy 157.851094 -101.621082) (xy 164.042342 -101.621082) (xy 164.046413 -101.56546)
			(xy 164.058539 -101.511023) (xy 164.078462 -101.458932) (xy 164.105758 -101.410297) (xy 164.139844 -101.366154)
			(xy 164.179993 -101.327445) (xy 164.225351 -101.294994) (xy 164.274951 -101.269493) (xy 164.327735 -101.251486)
			(xy 164.382578 -101.241356) (xy 164.438312 -101.239319) (xy 164.493749 -101.245419) (xy 164.547706 -101.259525)
			(xy 164.599035 -101.281337) (xy 164.646641 -101.310391) (xy 164.689509 -101.346066) (xy 164.726726 -101.387603)
			(xy 164.757499 -101.434116) (xy 164.781171 -101.484613) (xy 164.797239 -101.53802) (xy 164.805359 -101.593196)
			(xy 164.805868 -101.621082) (xy 164.805359 -101.648968) (xy 164.797239 -101.704144) (xy 164.781171 -101.757551)
			(xy 164.757499 -101.808048) (xy 164.726726 -101.854561) (xy 164.689509 -101.896098) (xy 164.646641 -101.931773)
			(xy 164.599035 -101.960827) (xy 164.547706 -101.982639) (xy 164.493749 -101.996745) (xy 164.438312 -102.002845)
			(xy 164.382578 -102.000808) (xy 164.327735 -101.990678) (xy 164.274951 -101.972671) (xy 164.225351 -101.94717)
			(xy 164.179993 -101.914719) (xy 164.139844 -101.87601) (xy 164.105758 -101.831867) (xy 164.078462 -101.783232)
			(xy 164.058539 -101.731141) (xy 164.046413 -101.676704) (xy 164.042342 -101.621082) (xy 157.851094 -101.621082)
			(xy 157.851094 -102.861997) (xy 159.813507 -102.861997) (xy 159.819019 -102.806401) (xy 159.832579 -102.752203)
			(xy 159.853897 -102.700562) (xy 159.882518 -102.652581) (xy 159.917828 -102.609286) (xy 159.959075 -102.571603)
			(xy 160.005375 -102.540337) (xy 160.05574 -102.516157) (xy 160.109092 -102.499579) (xy 160.164291 -102.490958)
			(xy 160.220158 -102.490478) (xy 160.275497 -102.498149) (xy 160.302448 -102.50551) (xy 160.323827 -102.511218)
			(xy 160.367809 -102.51603) (xy 160.41196 -102.513154) (xy 160.454947 -102.502678) (xy 160.49547 -102.484918)
			(xy 160.532307 -102.46041) (xy 160.564345 -102.429894) (xy 160.590615 -102.394293) (xy 160.600898 -102.3747)
			(xy 160.613724 -102.34988) (xy 160.645561 -102.303971) (xy 160.683753 -102.263196) (xy 160.727482 -102.228425)
			(xy 160.775814 -102.200402) (xy 160.827715 -102.179726) (xy 160.882077 -102.16684) (xy 160.937737 -102.162017)
			(xy 160.993504 -102.165363) (xy 161.048188 -102.176804) (xy 161.10062 -102.196098) (xy 161.149677 -102.22283)
			(xy 161.194312 -102.256429) (xy 161.233571 -102.296179) (xy 161.266614 -102.341228) (xy 161.292735 -102.390613)
			(xy 161.311376 -102.44328) (xy 161.322137 -102.498102) (xy 161.32479 -102.553907) (xy 161.319277 -102.609502)
			(xy 161.305717 -102.6637) (xy 161.284398 -102.71534) (xy 161.255778 -102.763321) (xy 161.220467 -102.806615)
			(xy 161.17922 -102.844297) (xy 161.13292 -102.875562) (xy 161.082555 -102.899742) (xy 161.029203 -102.916319)
			(xy 160.974004 -102.92494) (xy 160.918138 -102.925419) (xy 160.862799 -102.917748) (xy 160.835848 -102.910386)
			(xy 160.81447 -102.904676) (xy 160.770487 -102.899865) (xy 160.726336 -102.902741) (xy 160.68335 -102.913218)
			(xy 160.642826 -102.930978) (xy 160.605989 -102.955486) (xy 160.573952 -102.986002) (xy 160.547681 -103.021603)
			(xy 160.537398 -103.041196) (xy 160.52458 -103.06602) (xy 160.492742 -103.111929) (xy 160.454551 -103.152705)
			(xy 160.410821 -103.187476) (xy 160.362489 -103.2155) (xy 160.310588 -103.236176) (xy 160.256226 -103.249063)
			(xy 160.200566 -103.253885) (xy 160.144798 -103.25054) (xy 160.090114 -103.239099) (xy 160.037682 -103.219806)
			(xy 159.988624 -103.193074) (xy 159.943988 -103.159475) (xy 159.904729 -103.119726) (xy 159.871685 -103.074677)
			(xy 159.845564 -103.025291) (xy 159.826923 -102.972624) (xy 159.81616 -102.917802) (xy 159.813507 -102.861997)
			(xy 157.851094 -102.861997) (xy 157.851094 -103.729282) (xy 164.067742 -103.729282) (xy 164.071813 -103.67366)
			(xy 164.083939 -103.619223) (xy 164.103862 -103.567132) (xy 164.131158 -103.518497) (xy 164.165244 -103.474354)
			(xy 164.205393 -103.435645) (xy 164.250751 -103.403194) (xy 164.300351 -103.377693) (xy 164.353135 -103.359686)
			(xy 164.407978 -103.349556) (xy 164.463712 -103.347519) (xy 164.519149 -103.353619) (xy 164.573106 -103.367725)
			(xy 164.624435 -103.389537) (xy 164.672041 -103.418591) (xy 164.714909 -103.454266) (xy 164.752126 -103.495803)
			(xy 164.782899 -103.542316) (xy 164.806571 -103.592813) (xy 164.822639 -103.64622) (xy 164.830759 -103.701396)
			(xy 164.831268 -103.729282) (xy 164.830804 -103.754682) (xy 165.947342 -103.754682) (xy 165.951413 -103.69906)
			(xy 165.963539 -103.644623) (xy 165.983462 -103.592532) (xy 166.010758 -103.543897) (xy 166.044844 -103.499754)
			(xy 166.084993 -103.461045) (xy 166.130351 -103.428594) (xy 166.179951 -103.403093) (xy 166.232735 -103.385086)
			(xy 166.287578 -103.374956) (xy 166.343312 -103.372919) (xy 166.398749 -103.379019) (xy 166.452706 -103.393125)
			(xy 166.504035 -103.414937) (xy 166.551641 -103.443991) (xy 166.594509 -103.479666) (xy 166.631726 -103.521203)
			(xy 166.662499 -103.567716) (xy 166.686171 -103.618213) (xy 166.702239 -103.67162) (xy 166.710359 -103.726796)
			(xy 166.710404 -103.729282) (xy 167.750742 -103.729282) (xy 167.754813 -103.67366) (xy 167.766939 -103.619223)
			(xy 167.786862 -103.567132) (xy 167.814158 -103.518497) (xy 167.848244 -103.474354) (xy 167.888393 -103.435645)
			(xy 167.933751 -103.403194) (xy 167.983351 -103.377693) (xy 168.036135 -103.359686) (xy 168.090978 -103.349556)
			(xy 168.146712 -103.347519) (xy 168.202149 -103.353619) (xy 168.256106 -103.367725) (xy 168.307435 -103.389537)
			(xy 168.355041 -103.418591) (xy 168.397909 -103.454266) (xy 168.435126 -103.495803) (xy 168.465899 -103.542316)
			(xy 168.489571 -103.592813) (xy 168.505639 -103.64622) (xy 168.513759 -103.701396) (xy 168.514268 -103.729282)
			(xy 168.513759 -103.757168) (xy 168.505639 -103.812344) (xy 168.489571 -103.865751) (xy 168.465899 -103.916248)
			(xy 168.435126 -103.962761) (xy 168.397909 -104.004298) (xy 168.355041 -104.039973) (xy 168.307435 -104.069027)
			(xy 168.256106 -104.090839) (xy 168.202149 -104.104945) (xy 168.146712 -104.111045) (xy 168.090978 -104.109008)
			(xy 168.036135 -104.098878) (xy 167.983351 -104.080871) (xy 167.933751 -104.05537) (xy 167.888393 -104.022919)
			(xy 167.848244 -103.98421) (xy 167.814158 -103.940067) (xy 167.786862 -103.891432) (xy 167.766939 -103.839341)
			(xy 167.754813 -103.784904) (xy 167.750742 -103.729282) (xy 166.710404 -103.729282) (xy 166.710868 -103.754682)
			(xy 166.710359 -103.782568) (xy 166.702239 -103.837744) (xy 166.686171 -103.891151) (xy 166.662499 -103.941648)
			(xy 166.631726 -103.988161) (xy 166.594509 -104.029698) (xy 166.551641 -104.065373) (xy 166.504035 -104.094427)
			(xy 166.452706 -104.116239) (xy 166.398749 -104.130345) (xy 166.343312 -104.136445) (xy 166.287578 -104.134408)
			(xy 166.232735 -104.124278) (xy 166.179951 -104.106271) (xy 166.130351 -104.08077) (xy 166.084993 -104.048319)
			(xy 166.044844 -104.00961) (xy 166.010758 -103.965467) (xy 165.983462 -103.916832) (xy 165.963539 -103.864741)
			(xy 165.951413 -103.810304) (xy 165.947342 -103.754682) (xy 164.830804 -103.754682) (xy 164.830759 -103.757168)
			(xy 164.822639 -103.812344) (xy 164.806571 -103.865751) (xy 164.782899 -103.916248) (xy 164.752126 -103.962761)
			(xy 164.714909 -104.004298) (xy 164.672041 -104.039973) (xy 164.624435 -104.069027) (xy 164.573106 -104.090839)
			(xy 164.519149 -104.104945) (xy 164.463712 -104.111045) (xy 164.407978 -104.109008) (xy 164.353135 -104.098878)
			(xy 164.300351 -104.080871) (xy 164.250751 -104.05537) (xy 164.205393 -104.022919) (xy 164.165244 -103.98421)
			(xy 164.131158 -103.940067) (xy 164.103862 -103.891432) (xy 164.083939 -103.839341) (xy 164.071813 -103.784904)
			(xy 164.067742 -103.729282) (xy 157.851094 -103.729282) (xy 157.851094 -104.128356) (xy 159.813727 -104.128356)
			(xy 159.81968 -104.073316) (xy 159.833525 -104.019715) (xy 159.854971 -103.968678) (xy 159.88357 -103.921276)
			(xy 159.91872 -103.878506) (xy 159.959682 -103.841266) (xy 160.005597 -103.810337) (xy 160.0555 -103.786369)
			(xy 160.108343 -103.769866) (xy 160.163017 -103.761174) (xy 160.218373 -103.760476) (xy 160.273249 -103.767786)
			(xy 160.326491 -103.782951) (xy 160.376983 -103.805653) (xy 160.423663 -103.835414) (xy 160.465552 -103.871609)
			(xy 160.501769 -103.913479) (xy 160.517078 -103.936546) (xy 160.529055 -103.954427) (xy 160.558025 -103.986249)
			(xy 160.59194 -104.01274) (xy 160.62983 -104.033143) (xy 160.670614 -104.046875) (xy 160.713128 -104.053544)
			(xy 160.756159 -104.05296) (xy 160.798476 -104.045139) (xy 160.81883 -104.038146) (xy 160.84309 -104.029682)
			(xy 160.893262 -104.018597) (xy 160.944467 -104.014346) (xy 160.995779 -104.017005) (xy 161.046271 -104.026526)
			(xy 161.095028 -104.042737) (xy 161.141168 -104.065344) (xy 161.162746 -104.079294) (xy 161.18185 -104.091486)
			(xy 161.223372 -104.109632) (xy 161.267452 -104.120133) (xy 161.312696 -104.122656) (xy 161.357671 -104.117121)
			(xy 161.400953 -104.103705) (xy 161.441173 -104.082831) (xy 161.459418 -104.069388) (xy 161.481845 -104.052729)
			(xy 161.530543 -104.025356) (xy 161.582711 -104.005377) (xy 161.637236 -103.993219) (xy 161.692951 -103.989142)
			(xy 161.748665 -103.993234) (xy 161.803186 -104.005406) (xy 161.85535 -104.025399) (xy 161.90404 -104.052785)
			(xy 161.948216 -104.086979) (xy 161.986934 -104.127249) (xy 162.019365 -104.172735) (xy 162.044817 -104.222464)
			(xy 162.062745 -104.275373) (xy 162.072766 -104.33033) (xy 162.074665 -104.386162) (xy 162.068402 -104.441673)
			(xy 162.054111 -104.495678) (xy 162.032098 -104.547022) (xy 162.002832 -104.594606) (xy 161.96694 -104.637414)
			(xy 161.92519 -104.674531) (xy 161.878473 -104.705162) (xy 161.827789 -104.728654) (xy 161.77422 -104.744503)
			(xy 161.718914 -104.752371) (xy 161.663051 -104.75209) (xy 161.607826 -104.743665) (xy 161.55442 -104.727278)
			(xy 161.503974 -104.703277) (xy 161.4805 -104.688132) (xy 161.461371 -104.675981) (xy 161.419856 -104.657829)
			(xy 161.375781 -104.647322) (xy 161.330542 -104.644792) (xy 161.285571 -104.650319) (xy 161.242291 -104.66373)
			(xy 161.202073 -104.684598) (xy 161.183828 -104.698038) (xy 161.160697 -104.715237) (xy 161.11032 -104.743245)
			(xy 161.056304 -104.763355) (xy 160.999877 -104.77511) (xy 160.942323 -104.778242) (xy 160.884953 -104.77268)
			(xy 160.829074 -104.75855) (xy 160.775956 -104.736174) (xy 160.726808 -104.706061) (xy 160.682751 -104.668897)
			(xy 160.644786 -104.625528) (xy 160.628838 -104.601518) (xy 160.616828 -104.583659) (xy 160.587866 -104.551832)
			(xy 160.553959 -104.525337) (xy 160.516073 -104.50493) (xy 160.475293 -104.491195) (xy 160.432782 -104.484523)
			(xy 160.389754 -104.485105) (xy 160.347439 -104.492925) (xy 160.327086 -104.499918) (xy 160.300924 -104.508974)
			(xy 160.246746 -104.520356) (xy 160.191492 -104.523788) (xy 160.136323 -104.519198) (xy 160.082396 -104.506681)
			(xy 160.030844 -104.486502) (xy 159.982751 -104.459083) (xy 159.939125 -104.425001) (xy 159.900884 -104.384972)
			(xy 159.86883 -104.339835) (xy 159.843637 -104.290539) (xy 159.825833 -104.23812) (xy 159.815793 -104.183677)
			(xy 159.813727 -104.128356) (xy 157.851094 -104.128356) (xy 157.851094 -105.760774) (xy 158.068337 -105.978017)
			(xy 164.335165 -105.978017) (xy 164.338541 -105.923381) (xy 164.34969 -105.869789) (xy 164.368384 -105.81834)
			(xy 164.394238 -105.770091) (xy 164.426722 -105.726031) (xy 164.465169 -105.687067) (xy 164.50879 -105.653996)
			(xy 164.556689 -105.627499) (xy 164.607883 -105.608119) (xy 164.661322 -105.596254) (xy 164.715907 -105.592148)
			(xy 164.770519 -105.595885) (xy 164.824036 -105.607388) (xy 164.875361 -105.626421) (xy 164.923438 -105.652593)
			(xy 164.967282 -105.685367) (xy 164.98697 -105.704386) (xy 164.998135 -105.71488) (xy 165.024336 -105.730745)
			(xy 165.053567 -105.739893) (xy 165.084138 -105.741795) (xy 165.114278 -105.73634) (xy 165.142243 -105.723845)
			(xy 165.15461 -105.7148) (xy 165.176305 -105.698553) (xy 165.223357 -105.671654) (xy 165.273742 -105.651683)
			(xy 165.326445 -105.63904) (xy 165.380407 -105.633982) (xy 165.434542 -105.636609) (xy 165.48776 -105.646868)
			(xy 165.538992 -105.664554) (xy 165.587206 -105.689311) (xy 165.631433 -105.720639) (xy 165.651434 -105.73893)
			(xy 165.664428 -105.750366) (xy 165.695019 -105.766525) (xy 165.728826 -105.773876) (xy 165.763365 -105.771881)
			(xy 165.7961 -105.760685) (xy 165.810692 -105.751376) (xy 165.833782 -105.73604) (xy 165.883522 -105.711577)
			(xy 165.936279 -105.694569) (xy 165.990943 -105.685376) (xy 166.046361 -105.684191) (xy 166.101367 -105.691038)
			(xy 166.154803 -105.705773) (xy 166.205544 -105.728087) (xy 166.252522 -105.757509) (xy 166.294747 -105.79342)
			(xy 166.331331 -105.835064) (xy 166.361503 -105.881564) (xy 166.384627 -105.931941) (xy 166.400218 -105.985134)
			(xy 166.407946 -106.040023) (xy 166.4077 -106.086148) (xy 166.824912 -106.086148) (xy 166.828983 -106.030526)
			(xy 166.841109 -105.976089) (xy 166.861032 -105.923998) (xy 166.888328 -105.875363) (xy 166.922414 -105.83122)
			(xy 166.962563 -105.792511) (xy 167.007921 -105.76006) (xy 167.057521 -105.734559) (xy 167.110305 -105.716552)
			(xy 167.165148 -105.706422) (xy 167.220882 -105.704385) (xy 167.276319 -105.710485) (xy 167.330276 -105.724591)
			(xy 167.381605 -105.746403) (xy 167.429211 -105.775457) (xy 167.472079 -105.811132) (xy 167.509296 -105.852669)
			(xy 167.540069 -105.899182) (xy 167.563741 -105.949679) (xy 167.579809 -106.003086) (xy 167.587929 -106.058262)
			(xy 167.588438 -106.086148) (xy 167.587929 -106.114034) (xy 167.579809 -106.16921) (xy 167.576073 -106.181628)
			(xy 168.191311 -106.181628) (xy 168.193825 -106.126957) (xy 168.204126 -106.073206) (xy 168.222003 -106.021479)
			(xy 168.247087 -105.972837) (xy 168.278865 -105.928278) (xy 168.316683 -105.888718) (xy 168.359767 -105.854968)
			(xy 168.407231 -105.827721) (xy 168.458101 -105.807536) (xy 168.511334 -105.794827) (xy 168.565837 -105.789855)
			(xy 168.620491 -105.792723) (xy 168.674174 -105.80337) (xy 168.725785 -105.82158) (xy 168.774264 -105.846978)
			(xy 168.796716 -105.862628) (xy 168.809389 -105.871282) (xy 168.837812 -105.882831) (xy 168.868172 -105.887248)
			(xy 168.898707 -105.884279) (xy 168.927647 -105.874094) (xy 168.953313 -105.857286) (xy 168.964102 -105.846372)
			(xy 168.982722 -105.827005) (xy 169.024509 -105.793236) (xy 169.07062 -105.765662) (xy 169.120142 -105.744828)
			(xy 169.172096 -105.731145) (xy 169.225456 -105.724883) (xy 169.279167 -105.726167) (xy 169.332167 -105.734972)
			(xy 169.383408 -105.751122) (xy 169.40784 -105.762298) (xy 169.423847 -105.769394) (xy 169.458338 -105.775359)
			(xy 169.493151 -105.771714) (xy 169.525659 -105.758734) (xy 169.553409 -105.737399) (xy 169.564304 -105.72369)
			(xy 169.58132 -105.701695) (xy 169.620739 -105.662472) (xy 169.665435 -105.629387) (xy 169.71446 -105.60314)
			(xy 169.766776 -105.584288) (xy 169.821274 -105.573229) (xy 169.8768 -105.570199) (xy 169.932178 -105.575262)
			(xy 169.986235 -105.588309) (xy 170.037825 -105.609066) (xy 170.085855 -105.637091) (xy 170.129309 -105.671792)
			(xy 170.167265 -105.712433) (xy 170.198919 -105.758153) (xy 170.223601 -105.807984) (xy 170.240789 -105.860871)
			(xy 170.250117 -105.915692) (xy 170.251388 -105.971286) (xy 170.244575 -106.026476) (xy 170.229824 -106.080093)
			(xy 170.207445 -106.131) (xy 170.177914 -106.17812) (xy 170.141855 -106.220453) (xy 170.100033 -106.257104)
			(xy 170.053334 -106.287295) (xy 170.002746 -106.310388) (xy 169.949343 -106.325893) (xy 169.894254 -106.333482)
			(xy 169.838647 -106.332993) (xy 169.7837 -106.324437) (xy 169.730577 -106.307996) (xy 169.705274 -106.29646)
			(xy 169.689268 -106.289359) (xy 169.654775 -106.283388) (xy 169.619959 -106.287032) (xy 169.58745 -106.300014)
			(xy 169.559702 -106.321356) (xy 169.54881 -106.335068) (xy 169.532256 -106.356362) (xy 169.494164 -106.394547)
			(xy 169.451076 -106.426989) (xy 169.40385 -106.453043) (xy 169.353427 -106.47219) (xy 169.300811 -106.484048)
			(xy 169.24705 -106.488381) (xy 169.193214 -106.485104) (xy 169.140375 -106.47428) (xy 169.089586 -106.456127)
			(xy 169.041858 -106.431004) (xy 169.019728 -106.415586) (xy 169.007028 -106.406974) (xy 168.978614 -106.39542)
			(xy 168.948261 -106.390995) (xy 168.917731 -106.393956) (xy 168.888794 -106.404132) (xy 168.86313 -106.420931)
			(xy 168.852342 -106.431842) (xy 168.833349 -106.451547) (xy 168.790705 -106.485851) (xy 168.743596 -106.513708)
			(xy 168.69299 -106.534548) (xy 168.639926 -106.547943) (xy 168.585492 -106.553618) (xy 168.530806 -106.551456)
			(xy 168.47699 -106.541502) (xy 168.425148 -106.52396) (xy 168.376345 -106.49919) (xy 168.331583 -106.467701)
			(xy 168.29178 -106.430138) (xy 168.257752 -106.387273) (xy 168.230199 -106.339986) (xy 168.209686 -106.289247)
			(xy 168.196634 -106.236097) (xy 168.191311 -106.181628) (xy 167.576073 -106.181628) (xy 167.563741 -106.222617)
			(xy 167.540069 -106.273114) (xy 167.509296 -106.319627) (xy 167.472079 -106.361164) (xy 167.429211 -106.396839)
			(xy 167.381605 -106.425893) (xy 167.330276 -106.447705) (xy 167.276319 -106.461811) (xy 167.220882 -106.467911)
			(xy 167.165148 -106.465874) (xy 167.110305 -106.455744) (xy 167.057521 -106.437737) (xy 167.007921 -106.412236)
			(xy 166.962563 -106.379785) (xy 166.922414 -106.341076) (xy 166.888328 -106.296933) (xy 166.861032 -106.248298)
			(xy 166.841109 -106.196207) (xy 166.828983 -106.14177) (xy 166.824912 -106.086148) (xy 166.4077 -106.086148)
			(xy 166.40765 -106.095453) (xy 166.399335 -106.150256) (xy 166.383176 -106.20328) (xy 166.359514 -106.253406)
			(xy 166.328846 -106.29958) (xy 166.291819 -106.34083) (xy 166.249212 -106.376288) (xy 166.201922 -106.405206)
			(xy 166.150945 -106.426975) (xy 166.097355 -106.441138) (xy 166.042278 -106.447397) (xy 165.986876 -106.445618)
			(xy 165.932315 -106.435841) (xy 165.879742 -106.41827) (xy 165.830266 -106.393277) (xy 165.784928 -106.361386)
			(xy 165.764464 -106.342688) (xy 165.751474 -106.33125) (xy 165.720879 -106.315101) (xy 165.687073 -106.307755)
			(xy 165.652535 -106.309749) (xy 165.6198 -106.320938) (xy 165.605206 -106.330242) (xy 165.583091 -106.344811)
			(xy 165.535714 -106.368469) (xy 165.485521 -106.38535) (xy 165.433476 -106.39513) (xy 165.380579 -106.397621)
			(xy 165.327845 -106.392774) (xy 165.276288 -106.380683) (xy 165.226898 -106.361581) (xy 165.180623 -106.335833)
			(xy 165.138351 -106.303936) (xy 165.119304 -106.285538) (xy 165.108161 -106.275021) (xy 165.081952 -106.259166)
			(xy 165.052716 -106.250027) (xy 165.022143 -106.24813) (xy 164.992001 -106.253587) (xy 164.964034 -106.266081)
			(xy 164.951664 -106.275124) (xy 164.929822 -106.291623) (xy 164.882277 -106.31875) (xy 164.831343 -106.338805)
			(xy 164.778066 -106.351374) (xy 164.72354 -106.356201) (xy 164.668883 -106.353186) (xy 164.615219 -106.342392)
			(xy 164.563647 -106.324038) (xy 164.515228 -106.298503) (xy 164.470955 -106.266311) (xy 164.431738 -106.228122)
			(xy 164.39838 -106.184721) (xy 164.371567 -106.136998) (xy 164.351849 -106.085932) (xy 164.339632 -106.032574)
			(xy 164.335165 -105.978017) (xy 158.068337 -105.978017) (xy 158.96336 -106.87304) (xy 170.27017 -106.87304)
		)
		(stroke
			(width 0)
			(type solid)
		)
		(fill yes)
		(layer "In7.Cu")
		(net "P3V3_USB_NODE1")
	)
	(gr_poly
		(pts
			(xy 64.313816 -81.101438) (xy 64.449452 -80.965802) (xy 64.464153 -80.949791) (xy 64.488413 -80.913729)
			(xy 64.506179 -80.874063) (xy 64.516933 -80.831952) (xy 64.520361 -80.788625) (xy 64.516362 -80.745346)
			(xy 64.505054 -80.70338) (xy 64.486767 -80.663952) (xy 64.462035 -80.628212) (xy 64.431579 -80.597205)
			(xy 64.396289 -80.571835) (xy 64.357195 -80.552843) (xy 64.336422 -80.546448) (xy 64.310415 -80.53843)
			(xy 64.260811 -80.516047) (xy 64.214891 -80.486841) (xy 64.193928 -80.469486) (xy 64.176192 -80.454882)
			(xy 64.136545 -80.431675) (xy 64.093371 -80.415978) (xy 64.048077 -80.408303) (xy 64.002141 -80.408899)
			(xy 63.957062 -80.417749) (xy 63.91431 -80.434562) (xy 63.87528 -80.458791) (xy 63.857886 -80.473804)
			(xy 63.837718 -80.491459) (xy 63.793343 -80.521525) (xy 63.745196 -80.545081) (xy 63.694224 -80.561662)
			(xy 63.641432 -80.57094) (xy 63.587861 -80.572734) (xy 63.534567 -80.567008) (xy 63.4826 -80.553875)
			(xy 63.432985 -80.533593) (xy 63.386698 -80.506563) (xy 63.36538 -80.490314) (xy 63.348324 -80.477401)
			(xy 63.31079 -80.456882) (xy 63.270348 -80.442945) (xy 63.228142 -80.435983) (xy 63.185366 -80.436193)
			(xy 63.14323 -80.44357) (xy 63.102927 -80.457904) (xy 63.065597 -80.478791) (xy 63.048642 -80.491838)
			(xy 63.02682 -80.508791) (xy 62.979239 -80.536891) (xy 62.928101 -80.557831) (xy 62.874477 -80.571174)
			(xy 62.819489 -80.57664) (xy 62.764288 -80.574114) (xy 62.710029 -80.563651) (xy 62.657847 -80.545467)
			(xy 62.608835 -80.519945) (xy 62.564018 -80.487618) (xy 62.524335 -80.449163) (xy 62.490616 -80.405385)
			(xy 62.463566 -80.357199) (xy 62.443752 -80.305615) (xy 62.431588 -80.251711) (xy 62.427329 -80.196616)
			(xy 62.431063 -80.141484) (xy 62.442714 -80.087467) (xy 62.462037 -80.035697) (xy 62.488627 -79.987256)
			(xy 62.521929 -79.943159) (xy 62.561245 -79.904328) (xy 62.605752 -79.871576) (xy 62.654519 -79.845589)
			(xy 62.706525 -79.82691) (xy 62.760682 -79.815931) (xy 62.815857 -79.81288) (xy 62.870894 -79.817823)
			(xy 62.924643 -79.830655) (xy 62.975977 -79.851108) (xy 63.023824 -79.878754) (xy 63.045848 -79.895446)
			(xy 63.062905 -79.908362) (xy 63.100442 -79.928888) (xy 63.140888 -79.942834) (xy 63.183099 -79.949805)
			(xy 63.225881 -79.949604) (xy 63.268025 -79.942237) (xy 63.308338 -79.927912) (xy 63.34568 -79.907035)
			(xy 63.362586 -79.893922) (xy 63.383486 -79.877679) (xy 63.428913 -79.850507) (xy 63.477659 -79.829876)
			(xy 63.52879 -79.816182) (xy 63.581322 -79.809689) (xy 63.634248 -79.81052) (xy 63.686551 -79.818661)
			(xy 63.737227 -79.833954) (xy 63.785301 -79.856106) (xy 63.829851 -79.884691) (xy 63.850266 -79.901542)
			(xy 63.868003 -79.916145) (xy 63.907651 -79.939351) (xy 63.950825 -79.955047) (xy 63.996119 -79.962722)
			(xy 64.042054 -79.962126) (xy 64.087133 -79.953279) (xy 64.129886 -79.936467) (xy 64.168919 -79.912241)
			(xy 64.186308 -79.897224) (xy 64.2071 -79.879059) (xy 64.252943 -79.84829) (xy 64.302742 -79.824449)
			(xy 64.355457 -79.808035) (xy 64.409987 -79.799389) (xy 64.465193 -79.798692) (xy 64.519924 -79.805959)
			(xy 64.573036 -79.821037) (xy 64.623421 -79.843613) (xy 64.670026 -79.873215) (xy 64.711878 -79.909225)
			(xy 64.748103 -79.95089) (xy 64.777946 -79.997341) (xy 64.800782 -80.047608) (xy 64.808862 -80.074008)
			(xy 64.815334 -80.094744) (xy 64.834347 -80.1338) (xy 64.859725 -80.169052) (xy 64.890728 -80.199475)
			(xy 64.926455 -80.224182) (xy 64.965862 -80.242452) (xy 65.007803 -80.253754) (xy 65.051055 -80.257758)
			(xy 65.094358 -80.254348) (xy 65.13645 -80.243622) (xy 65.176105 -80.225893) (xy 65.212167 -80.201679)
			(xy 65.228216 -80.187038) (xy 65.551304 -79.86395) (xy 65.566894 -79.846912) (xy 65.592247 -79.808318)
			(xy 65.610207 -79.765777) (xy 65.620182 -79.72069) (xy 65.621844 -79.674543) (xy 65.615137 -79.628855)
			(xy 65.600282 -79.585133) (xy 65.57777 -79.544815) (xy 65.548342 -79.50923) (xy 65.512966 -79.479551)
			(xy 65.493138 -79.46771) (xy 65.469923 -79.453949) (xy 65.42726 -79.420899) (xy 65.389678 -79.38217)
			(xy 65.357924 -79.338535) (xy 65.332631 -79.290862) (xy 65.314305 -79.240102) (xy 65.30331 -79.187268)
			(xy 65.301114 -79.16037) (xy 65.299601 -79.144322) (xy 65.289533 -79.11371) (xy 65.272125 -79.086592)
			(xy 65.248485 -79.064694) (xy 65.220115 -79.049409) (xy 65.204594 -79.045054) (xy 65.178486 -79.038208)
			(xy 65.128375 -79.018159) (xy 65.081592 -78.991243) (xy 65.039073 -78.958) (xy 65.001665 -78.919092)
			(xy 64.970119 -78.875299) (xy 64.945062 -78.827494) (xy 64.926998 -78.776634) (xy 64.916286 -78.723735)
			(xy 64.914272 -78.69682) (xy 64.911122 -78.668509) (xy 64.912253 -78.611559) (xy 64.921836 -78.55541)
			(xy 64.939659 -78.501309) (xy 64.965326 -78.450458) (xy 64.998266 -78.403987) (xy 65.037747 -78.362928)
			(xy 65.082893 -78.328195) (xy 65.1327 -78.300557) (xy 65.186062 -78.28063) (xy 65.241793 -78.268855)
			(xy 65.298655 -78.265496) (xy 65.355385 -78.270626) (xy 65.410722 -78.284131) (xy 65.437258 -78.294484)
			(xy 65.458401 -78.302634) (xy 65.502699 -78.312149) (xy 65.547983 -78.313661) (xy 65.592817 -78.307121)
			(xy 65.635781 -78.292736) (xy 65.675514 -78.270962) (xy 65.710758 -78.242488) (xy 65.740396 -78.208218)
			(xy 65.763489 -78.169236) (xy 65.779305 -78.126778) (xy 65.787343 -78.082188) (xy 65.787778 -78.059534)
			(xy 65.787778 -77.521308) (xy 65.764918 -77.47127) (xy 65.74409 -77.453236) (xy 65.731898 -77.44206)
			(xy 65.71957 -77.431104) (xy 65.690625 -77.415318) (xy 65.658607 -77.40746) (xy 65.625643 -77.408051)
			(xy 65.593926 -77.417054) (xy 65.579498 -77.425042) (xy 65.555462 -77.43879) (xy 65.504297 -77.45996)
			(xy 65.450609 -77.473512) (xy 65.395527 -77.479161) (xy 65.340206 -77.476787) (xy 65.28581 -77.466441)
			(xy 65.23348 -77.44834) (xy 65.184317 -77.422865) (xy 65.139353 -77.39055) (xy 65.099532 -77.352075)
			(xy 65.065692 -77.308247) (xy 65.038543 -77.259988) (xy 65.018656 -77.208311) (xy 65.006448 -77.154302)
			(xy 65.002176 -77.099096) (xy 65.005929 -77.043851) (xy 65.017629 -76.98973) (xy 65.037029 -76.937868)
			(xy 65.063723 -76.889356) (xy 65.09715 -76.845212) (xy 65.136607 -76.806364) (xy 65.181265 -76.773628)
			(xy 65.230187 -76.747692) (xy 65.282344 -76.7291) (xy 65.33664 -76.718243) (xy 65.391936 -76.71535)
			(xy 65.44707 -76.72048) (xy 65.474088 -76.726542) (xy 65.49654 -76.731463) (xy 65.542427 -76.734059)
			(xy 65.588033 -76.72836) (xy 65.631869 -76.714552) (xy 65.672508 -76.693085) (xy 65.708623 -76.664659)
			(xy 65.739037 -76.630202) (xy 65.762758 -76.590836) (xy 65.779013 -76.547846) (xy 65.78727 -76.502634)
			(xy 65.787778 -76.479654) (xy 65.787778 -75.782678) (xy 65.787287 -75.760109) (xy 65.779309 -75.715683)
			(xy 65.763608 -75.673364) (xy 65.740678 -75.634485) (xy 65.71124 -75.600269) (xy 65.67622 -75.571791)
			(xy 65.656714 -75.560428) (xy 65.629091 -75.561997) (xy 65.573901 -75.558106) (xy 65.519852 -75.546285)
			(xy 65.468077 -75.526782) (xy 65.419661 -75.500007) (xy 65.375619 -75.466521) (xy 65.336876 -75.427025)
			(xy 65.304242 -75.382347) (xy 65.278402 -75.333426) (xy 65.259898 -75.281285) (xy 65.249119 -75.227019)
			(xy 65.246289 -75.171765) (xy 65.251468 -75.116681) (xy 65.264548 -75.062923) (xy 65.285255 -75.011618)
			(xy 65.313154 -74.96384) (xy 65.34766 -74.920593) (xy 65.388051 -74.882782) (xy 65.433478 -74.851201)
			(xy 65.48299 -74.826511) (xy 65.50914 -74.817478) (xy 65.524129 -74.812033) (xy 65.551003 -74.794883)
			(xy 65.572783 -74.771604) (xy 65.588109 -74.74365) (xy 65.596023 -74.712768) (xy 65.596516 -74.696828)
			(xy 65.596516 -72.764142) (xy 64.888364 -72.05599) (xy 64.888364 -71.661274) (xy 64.381888 -71.154798)
			(xy 61.300106 -71.154798) (xy 61.21273 -71.242174) (xy 57.807098 -71.242174) (xy 57.783958 -71.242658)
			(xy 57.738437 -71.250993) (xy 57.69518 -71.26744) (xy 57.65562 -71.291455) (xy 57.621068 -71.322243)
			(xy 57.592669 -71.358783) (xy 57.581546 -71.37908) (xy 57.58249 -71.408057) (xy 57.576675 -71.465741)
			(xy 57.562217 -71.521885) (xy 57.55132 -71.548752) (xy 57.538739 -71.576659) (xy 57.506002 -71.628381)
			(xy 57.465409 -71.674196) (xy 57.4421 -71.69404) (xy 57.420537 -71.711094) (xy 57.373457 -71.739479)
			(xy 57.322788 -71.760807) (xy 57.26958 -71.774637) (xy 57.214939 -71.78068) (xy 57.159995 -71.778813)
			(xy 57.10589 -71.769074) (xy 57.053744 -71.751664) (xy 57.00464 -71.726945) (xy 56.981852 -71.711566)
			(xy 56.949086 -71.688706) (xy 56.215026 -71.688706) (xy 55.956454 -71.947278) (xy 55.956454 -72.198992)
			(xy 60.018928 -72.198992) (xy 60.022999 -72.14337) (xy 60.035125 -72.088933) (xy 60.055048 -72.036842)
			(xy 60.082344 -71.988207) (xy 60.11643 -71.944064) (xy 60.156579 -71.905355) (xy 60.201937 -71.872904)
			(xy 60.251537 -71.847403) (xy 60.304321 -71.829396) (xy 60.359164 -71.819266) (xy 60.414898 -71.817229)
			(xy 60.470335 -71.823329) (xy 60.524292 -71.837435) (xy 60.575621 -71.859247) (xy 60.623227 -71.888301)
			(xy 60.666095 -71.923976) (xy 60.703312 -71.965513) (xy 60.734085 -72.012026) (xy 60.757757 -72.062523)
			(xy 60.773825 -72.11593) (xy 60.781945 -72.171106) (xy 60.782454 -72.198992) (xy 61.619128 -72.198992)
			(xy 61.623199 -72.14337) (xy 61.635325 -72.088933) (xy 61.655248 -72.036842) (xy 61.682544 -71.988207)
			(xy 61.71663 -71.944064) (xy 61.756779 -71.905355) (xy 61.802137 -71.872904) (xy 61.851737 -71.847403)
			(xy 61.904521 -71.829396) (xy 61.959364 -71.819266) (xy 62.015098 -71.817229) (xy 62.070535 -71.823329)
			(xy 62.124492 -71.837435) (xy 62.175821 -71.859247) (xy 62.223427 -71.888301) (xy 62.266295 -71.923976)
			(xy 62.303512 -71.965513) (xy 62.334285 -72.012026) (xy 62.357957 -72.062523) (xy 62.374025 -72.11593)
			(xy 62.382145 -72.171106) (xy 62.382654 -72.198992) (xy 63.219328 -72.198992) (xy 63.223399 -72.14337)
			(xy 63.235525 -72.088933) (xy 63.255448 -72.036842) (xy 63.282744 -71.988207) (xy 63.31683 -71.944064)
			(xy 63.356979 -71.905355) (xy 63.402337 -71.872904) (xy 63.451937 -71.847403) (xy 63.504721 -71.829396)
			(xy 63.559564 -71.819266) (xy 63.615298 -71.817229) (xy 63.670735 -71.823329) (xy 63.724692 -71.837435)
			(xy 63.776021 -71.859247) (xy 63.823627 -71.888301) (xy 63.866495 -71.923976) (xy 63.903712 -71.965513)
			(xy 63.934485 -72.012026) (xy 63.958157 -72.062523) (xy 63.974225 -72.11593) (xy 63.982345 -72.171106)
			(xy 63.982854 -72.198992) (xy 63.982345 -72.226878) (xy 63.974225 -72.282054) (xy 63.958157 -72.335461)
			(xy 63.934485 -72.385958) (xy 63.903712 -72.432471) (xy 63.866495 -72.474008) (xy 63.823627 -72.509683)
			(xy 63.776021 -72.538737) (xy 63.724692 -72.560549) (xy 63.670735 -72.574655) (xy 63.615298 -72.580755)
			(xy 63.559564 -72.578718) (xy 63.504721 -72.568588) (xy 63.451937 -72.550581) (xy 63.402337 -72.52508)
			(xy 63.356979 -72.492629) (xy 63.31683 -72.45392) (xy 63.282744 -72.409777) (xy 63.255448 -72.361142)
			(xy 63.235525 -72.309051) (xy 63.223399 -72.254614) (xy 63.219328 -72.198992) (xy 62.382654 -72.198992)
			(xy 62.382145 -72.226878) (xy 62.374025 -72.282054) (xy 62.357957 -72.335461) (xy 62.334285 -72.385958)
			(xy 62.303512 -72.432471) (xy 62.266295 -72.474008) (xy 62.223427 -72.509683) (xy 62.175821 -72.538737)
			(xy 62.124492 -72.560549) (xy 62.070535 -72.574655) (xy 62.015098 -72.580755) (xy 61.959364 -72.578718)
			(xy 61.904521 -72.568588) (xy 61.851737 -72.550581) (xy 61.802137 -72.52508) (xy 61.756779 -72.492629)
			(xy 61.71663 -72.45392) (xy 61.682544 -72.409777) (xy 61.655248 -72.361142) (xy 61.635325 -72.309051)
			(xy 61.623199 -72.254614) (xy 61.619128 -72.198992) (xy 60.782454 -72.198992) (xy 60.781945 -72.226878)
			(xy 60.773825 -72.282054) (xy 60.757757 -72.335461) (xy 60.734085 -72.385958) (xy 60.703312 -72.432471)
			(xy 60.666095 -72.474008) (xy 60.623227 -72.509683) (xy 60.575621 -72.538737) (xy 60.524292 -72.560549)
			(xy 60.470335 -72.574655) (xy 60.414898 -72.580755) (xy 60.359164 -72.578718) (xy 60.304321 -72.568588)
			(xy 60.251537 -72.550581) (xy 60.201937 -72.52508) (xy 60.156579 -72.492629) (xy 60.11643 -72.45392)
			(xy 60.082344 -72.409777) (xy 60.055048 -72.361142) (xy 60.035125 -72.309051) (xy 60.022999 -72.254614)
			(xy 60.018928 -72.198992) (xy 55.956454 -72.198992) (xy 55.956454 -72.781414) (xy 56.044338 -72.869298)
			(xy 56.044338 -72.999092) (xy 56.818528 -72.999092) (xy 56.822599 -72.94347) (xy 56.834725 -72.889033)
			(xy 56.854648 -72.836942) (xy 56.881944 -72.788307) (xy 56.91603 -72.744164) (xy 56.956179 -72.705455)
			(xy 57.001537 -72.673004) (xy 57.051137 -72.647503) (xy 57.103921 -72.629496) (xy 57.158764 -72.619366)
			(xy 57.214498 -72.617329) (xy 57.269935 -72.623429) (xy 57.323892 -72.637535) (xy 57.375221 -72.659347)
			(xy 57.422827 -72.688401) (xy 57.465695 -72.724076) (xy 57.502912 -72.765613) (xy 57.533685 -72.812126)
			(xy 57.557357 -72.862623) (xy 57.573425 -72.91603) (xy 57.581545 -72.971206) (xy 57.582054 -72.999092)
			(xy 58.418728 -72.999092) (xy 58.422799 -72.94347) (xy 58.434925 -72.889033) (xy 58.454848 -72.836942)
			(xy 58.482144 -72.788307) (xy 58.51623 -72.744164) (xy 58.556379 -72.705455) (xy 58.601737 -72.673004)
			(xy 58.651337 -72.647503) (xy 58.704121 -72.629496) (xy 58.758964 -72.619366) (xy 58.814698 -72.617329)
			(xy 58.870135 -72.623429) (xy 58.924092 -72.637535) (xy 58.975421 -72.659347) (xy 59.023027 -72.688401)
			(xy 59.065895 -72.724076) (xy 59.103112 -72.765613) (xy 59.133885 -72.812126) (xy 59.157557 -72.862623)
			(xy 59.173625 -72.91603) (xy 59.181745 -72.971206) (xy 59.182254 -72.999092) (xy 59.181745 -73.026978)
			(xy 59.173625 -73.082154) (xy 59.157557 -73.135561) (xy 59.133885 -73.186058) (xy 59.103112 -73.232571)
			(xy 59.065895 -73.274108) (xy 59.023027 -73.309783) (xy 58.975421 -73.338837) (xy 58.924092 -73.360649)
			(xy 58.870135 -73.374755) (xy 58.814698 -73.380855) (xy 58.758964 -73.378818) (xy 58.704121 -73.368688)
			(xy 58.651337 -73.350681) (xy 58.601737 -73.32518) (xy 58.556379 -73.292729) (xy 58.51623 -73.25402)
			(xy 58.482144 -73.209877) (xy 58.454848 -73.161242) (xy 58.434925 -73.109151) (xy 58.422799 -73.054714)
			(xy 58.418728 -72.999092) (xy 57.582054 -72.999092) (xy 57.581545 -73.026978) (xy 57.573425 -73.082154)
			(xy 57.557357 -73.135561) (xy 57.533685 -73.186058) (xy 57.502912 -73.232571) (xy 57.465695 -73.274108)
			(xy 57.422827 -73.309783) (xy 57.375221 -73.338837) (xy 57.323892 -73.360649) (xy 57.269935 -73.374755)
			(xy 57.214498 -73.380855) (xy 57.158764 -73.378818) (xy 57.103921 -73.368688) (xy 57.051137 -73.350681)
			(xy 57.001537 -73.32518) (xy 56.956179 -73.292729) (xy 56.91603 -73.25402) (xy 56.881944 -73.209877)
			(xy 56.854648 -73.161242) (xy 56.834725 -73.109151) (xy 56.822599 -73.054714) (xy 56.818528 -72.999092)
			(xy 56.044338 -72.999092) (xy 56.044338 -73.19772) (xy 56.04482 -73.219783) (xy 56.052456 -73.263245)
			(xy 56.067476 -73.304736) (xy 56.089432 -73.343014) (xy 56.117664 -73.376928) (xy 56.151324 -73.405461)
			(xy 56.189404 -73.427758) (xy 56.23076 -73.443148) (xy 56.252364 -73.447656) (xy 56.278213 -73.437319)
			(xy 56.332115 -73.423402) (xy 56.387467 -73.417467) (xy 56.443094 -73.419642) (xy 56.497814 -73.429879)
			(xy 56.550465 -73.447962) (xy 56.599927 -73.473507) (xy 56.645152 -73.50597) (xy 56.685177 -73.544662)
			(xy 56.719152 -73.588762) (xy 56.746356 -73.637331) (xy 56.766211 -73.68934) (xy 56.778295 -73.743682)
			(xy 56.782351 -73.799192) (xy 60.018928 -73.799192) (xy 60.022999 -73.74357) (xy 60.035125 -73.689133)
			(xy 60.055048 -73.637042) (xy 60.082344 -73.588407) (xy 60.11643 -73.544264) (xy 60.156579 -73.505555)
			(xy 60.201937 -73.473104) (xy 60.251537 -73.447603) (xy 60.304321 -73.429596) (xy 60.359164 -73.419466)
			(xy 60.414898 -73.417429) (xy 60.470335 -73.423529) (xy 60.524292 -73.437635) (xy 60.575621 -73.459447)
			(xy 60.623227 -73.488501) (xy 60.666095 -73.524176) (xy 60.703312 -73.565713) (xy 60.734085 -73.612226)
			(xy 60.757757 -73.662723) (xy 60.773825 -73.71613) (xy 60.781945 -73.771306) (xy 60.782454 -73.799192)
			(xy 63.219328 -73.799192) (xy 63.223399 -73.74357) (xy 63.235525 -73.689133) (xy 63.255448 -73.637042)
			(xy 63.282744 -73.588407) (xy 63.31683 -73.544264) (xy 63.356979 -73.505555) (xy 63.402337 -73.473104)
			(xy 63.451937 -73.447603) (xy 63.504721 -73.429596) (xy 63.559564 -73.419466) (xy 63.615298 -73.417429)
			(xy 63.670735 -73.423529) (xy 63.724692 -73.437635) (xy 63.776021 -73.459447) (xy 63.823627 -73.488501)
			(xy 63.866495 -73.524176) (xy 63.903712 -73.565713) (xy 63.934485 -73.612226) (xy 63.958157 -73.662723)
			(xy 63.974225 -73.71613) (xy 63.982345 -73.771306) (xy 63.982854 -73.799192) (xy 63.982345 -73.827078)
			(xy 63.974225 -73.882254) (xy 63.958157 -73.935661) (xy 63.934485 -73.986158) (xy 63.903712 -74.032671)
			(xy 63.866495 -74.074208) (xy 63.823627 -74.109883) (xy 63.776021 -74.138937) (xy 63.724692 -74.160749)
			(xy 63.670735 -74.174855) (xy 63.615298 -74.180955) (xy 63.559564 -74.178918) (xy 63.504721 -74.168788)
			(xy 63.451937 -74.150781) (xy 63.402337 -74.12528) (xy 63.356979 -74.092829) (xy 63.31683 -74.05412)
			(xy 63.282744 -74.009977) (xy 63.255448 -73.961342) (xy 63.235525 -73.909251) (xy 63.223399 -73.854814)
			(xy 63.219328 -73.799192) (xy 60.782454 -73.799192) (xy 60.781945 -73.827078) (xy 60.773825 -73.882254)
			(xy 60.757757 -73.935661) (xy 60.734085 -73.986158) (xy 60.703312 -74.032671) (xy 60.666095 -74.074208)
			(xy 60.623227 -74.109883) (xy 60.575621 -74.138937) (xy 60.524292 -74.160749) (xy 60.470335 -74.174855)
			(xy 60.414898 -74.180955) (xy 60.359164 -74.178918) (xy 60.304321 -74.168788) (xy 60.251537 -74.150781)
			(xy 60.201937 -74.12528) (xy 60.156579 -74.092829) (xy 60.11643 -74.05412) (xy 60.082344 -74.009977)
			(xy 60.055048 -73.961342) (xy 60.035125 -73.909251) (xy 60.022999 -73.854814) (xy 60.018928 -73.799192)
			(xy 56.782351 -73.799192) (xy 56.782352 -73.799203) (xy 56.778294 -73.854724) (xy 56.766209 -73.909066)
			(xy 56.746354 -73.961074) (xy 56.719149 -74.009644) (xy 56.685172 -74.053742) (xy 56.645147 -74.092434)
			(xy 56.599922 -74.124896) (xy 56.550459 -74.15044) (xy 56.497808 -74.168522) (xy 56.443088 -74.178759)
			(xy 56.387461 -74.180933) (xy 56.332109 -74.174997) (xy 56.278207 -74.161079) (xy 56.252364 -74.150728)
			(xy 56.230741 -74.15518) (xy 56.189356 -74.170538) (xy 56.15125 -74.192821) (xy 56.117571 -74.221357)
			(xy 56.089333 -74.255286) (xy 56.067387 -74.293587) (xy 56.052395 -74.335106) (xy 56.044807 -74.378592)
			(xy 56.044338 -74.400664) (xy 56.044338 -74.599292) (xy 61.619128 -74.599292) (xy 61.623199 -74.54367)
			(xy 61.635325 -74.489233) (xy 61.655248 -74.437142) (xy 61.682544 -74.388507) (xy 61.71663 -74.344364)
			(xy 61.756779 -74.305655) (xy 61.802137 -74.273204) (xy 61.851737 -74.247703) (xy 61.904521 -74.229696)
			(xy 61.959364 -74.219566) (xy 62.015098 -74.217529) (xy 62.070535 -74.223629) (xy 62.124492 -74.237735)
			(xy 62.175821 -74.259547) (xy 62.223427 -74.288601) (xy 62.266295 -74.324276) (xy 62.303512 -74.365813)
			(xy 62.334285 -74.412326) (xy 62.357957 -74.462823) (xy 62.374025 -74.51623) (xy 62.382145 -74.571406)
			(xy 62.382654 -74.599292) (xy 62.382343 -74.61631) (xy 64.035176 -74.61631) (xy 64.039247 -74.560688)
			(xy 64.051373 -74.506251) (xy 64.071296 -74.45416) (xy 64.098592 -74.405525) (xy 64.132678 -74.361382)
			(xy 64.172827 -74.322673) (xy 64.218185 -74.290222) (xy 64.267785 -74.264721) (xy 64.320569 -74.246714)
			(xy 64.375412 -74.236584) (xy 64.431146 -74.234547) (xy 64.486583 -74.240647) (xy 64.54054 -74.254753)
			(xy 64.591869 -74.276565) (xy 64.639475 -74.305619) (xy 64.682343 -74.341294) (xy 64.71956 -74.382831)
			(xy 64.750333 -74.429344) (xy 64.774005 -74.479841) (xy 64.790073 -74.533248) (xy 64.798193 -74.588424)
			(xy 64.798702 -74.61631) (xy 64.798193 -74.644196) (xy 64.790073 -74.699372) (xy 64.774005 -74.752779)
			(xy 64.750333 -74.803276) (xy 64.71956 -74.849789) (xy 64.682343 -74.891326) (xy 64.639475 -74.927001)
			(xy 64.591869 -74.956055) (xy 64.54054 -74.977867) (xy 64.486583 -74.991973) (xy 64.431146 -74.998073)
			(xy 64.375412 -74.996036) (xy 64.320569 -74.985906) (xy 64.267785 -74.967899) (xy 64.218185 -74.942398)
			(xy 64.172827 -74.909947) (xy 64.132678 -74.871238) (xy 64.098592 -74.827095) (xy 64.071296 -74.77846)
			(xy 64.051373 -74.726369) (xy 64.039247 -74.671932) (xy 64.035176 -74.61631) (xy 62.382343 -74.61631)
			(xy 62.382145 -74.627178) (xy 62.374025 -74.682354) (xy 62.357957 -74.735761) (xy 62.334285 -74.786258)
			(xy 62.303512 -74.832771) (xy 62.266295 -74.874308) (xy 62.223427 -74.909983) (xy 62.175821 -74.939037)
			(xy 62.124492 -74.960849) (xy 62.070535 -74.974955) (xy 62.015098 -74.981055) (xy 61.959364 -74.979018)
			(xy 61.904521 -74.968888) (xy 61.851737 -74.950881) (xy 61.802137 -74.92538) (xy 61.756779 -74.892929)
			(xy 61.71663 -74.85422) (xy 61.682544 -74.810077) (xy 61.655248 -74.761442) (xy 61.635325 -74.709351)
			(xy 61.623199 -74.654914) (xy 61.619128 -74.599292) (xy 56.044338 -74.599292) (xy 56.044338 -76.39812)
			(xy 56.04482 -76.420183) (xy 56.052456 -76.463645) (xy 56.067476 -76.505136) (xy 56.089432 -76.543414)
			(xy 56.117664 -76.577328) (xy 56.151324 -76.605861) (xy 56.189404 -76.628158) (xy 56.23076 -76.643548)
			(xy 56.252364 -76.648056) (xy 56.278818 -76.63749) (xy 56.334018 -76.623435) (xy 56.390695 -76.617747)
			(xy 56.447588 -76.620549) (xy 56.503432 -76.631781) (xy 56.556984 -76.651193) (xy 56.607054 -76.678352)
			(xy 56.652529 -76.712655) (xy 56.692396 -76.753339) (xy 56.709564 -76.776072) (xy 56.731475 -76.783912)
			(xy 56.77723 -76.792381) (xy 56.823762 -76.792381) (xy 56.869517 -76.783912) (xy 56.891428 -76.776072)
			(xy 56.899849 -76.764624) (xy 56.918158 -76.742886) (xy 56.928004 -76.732638) (xy 56.936789 -76.723793)
			(xy 56.955346 -76.707142) (xy 56.965088 -76.699364) (xy 56.977693 -76.688802) (xy 56.997489 -76.662557)
			(xy 57.009922 -76.632125) (xy 57.014164 -76.599526) (xy 57.009935 -76.566925) (xy 56.997515 -76.536488)
			(xy 56.977729 -76.510235) (xy 56.965088 -76.49972) (xy 56.943425 -76.482116) (xy 56.904987 -76.441639)
			(xy 56.872857 -76.395993) (xy 56.847722 -76.346153) (xy 56.830118 -76.293181) (xy 56.82042 -76.23821)
			(xy 56.818836 -76.182413) (xy 56.8254 -76.12698) (xy 56.839971 -76.073096) (xy 56.862238 -76.02191)
			(xy 56.891727 -75.974515) (xy 56.927807 -75.931923) (xy 56.969708 -75.895043) (xy 57.016536 -75.864662)
			(xy 57.067291 -75.841429) (xy 57.12089 -75.82584) (xy 57.176189 -75.818228) (xy 57.204102 -75.817984)
			(xy 57.232231 -75.818745) (xy 57.287811 -75.827522) (xy 57.341499 -75.84437) (xy 57.392129 -75.868922)
			(xy 57.438603 -75.900647) (xy 57.479911 -75.938854) (xy 57.515158 -75.982716) (xy 57.543579 -76.03128)
			(xy 57.564557 -76.083493) (xy 57.577636 -76.138221) (xy 57.582533 -76.194277) (xy 57.579141 -76.250444)
			(xy 57.567535 -76.305503) (xy 57.547965 -76.358259) (xy 57.520857 -76.407569) (xy 57.486799 -76.45236)
			(xy 57.44653 -76.491662) (xy 57.424066 -76.50861) (xy 57.416229 -76.530521) (xy 57.407768 -76.576275)
			(xy 57.407776 -76.622804) (xy 57.416251 -76.668554) (xy 57.424066 -76.690474) (xy 57.446078 -76.706988)
			(xy 57.48557 -76.745307) (xy 57.519148 -76.788902) (xy 57.546114 -76.83687) (xy 57.565908 -76.888214)
			(xy 57.57812 -76.941869) (xy 57.582497 -76.996722) (xy 57.581545 -77.011447) (xy 59.219065 -77.011447)
			(xy 59.221286 -76.956803) (xy 59.231288 -76.903035) (xy 59.248864 -76.851247) (xy 59.273655 -76.802499)
			(xy 59.305153 -76.757791) (xy 59.342712 -76.718038) (xy 59.385562 -76.684056) (xy 59.432826 -76.656541)
			(xy 59.483534 -76.636057) (xy 59.536648 -76.623024) (xy 59.591079 -76.617708) (xy 59.645711 -76.620219)
			(xy 59.699424 -76.630505) (xy 59.751118 -76.648356) (xy 59.799734 -76.673405) (xy 59.844274 -76.70514)
			(xy 59.883827 -76.742909) (xy 59.901074 -76.764134) (xy 59.911636 -76.776733) (xy 59.937878 -76.79652)
			(xy 59.968305 -76.808943) (xy 60.000896 -76.813178) (xy 60.033487 -76.808943) (xy 60.063914 -76.79652)
			(xy 60.090156 -76.776733) (xy 60.100718 -76.764134) (xy 60.104528 -76.759308) (xy 60.117861 -76.742264)
			(xy 60.139037 -76.704527) (xy 60.153514 -76.663748) (xy 60.160873 -76.621105) (xy 60.160902 -76.577833)
			(xy 60.1536 -76.535181) (xy 60.139177 -76.494382) (xy 60.118052 -76.456617) (xy 60.104782 -76.439522)
			(xy 60.087937 -76.417933) (xy 60.059908 -76.370893) (xy 60.038893 -76.320329) (xy 60.025324 -76.26728)
			(xy 60.01948 -76.212835) (xy 60.021482 -76.158114) (xy 60.031287 -76.104242) (xy 60.048695 -76.052326)
			(xy 60.073348 -76.003432) (xy 60.104739 -75.958566) (xy 60.142222 -75.918649) (xy 60.185029 -75.884502)
			(xy 60.232278 -75.856828) (xy 60.282999 -75.836194) (xy 60.336149 -75.823024) (xy 60.390636 -75.81759)
			(xy 60.44534 -75.820003) (xy 60.499137 -75.830213) (xy 60.550921 -75.848011) (xy 60.599628 -75.873031)
			(xy 60.644257 -75.904758) (xy 60.683891 -75.942541) (xy 60.701174 -75.96378) (xy 60.711757 -75.976382)
			(xy 60.738038 -75.996169) (xy 60.7685 -76.008591) (xy 60.801123 -76.012825) (xy 60.833746 -76.008591)
			(xy 60.864208 -75.996169) (xy 60.890489 -75.976382) (xy 60.901072 -75.96378) (xy 60.904628 -75.959208)
			(xy 60.917851 -75.942105) (xy 60.938975 -75.904392) (xy 60.953408 -75.863647) (xy 60.960733 -75.821046)
			(xy 60.960738 -75.77782) (xy 60.953424 -75.735217) (xy 60.939002 -75.694468) (xy 60.917888 -75.656749)
			(xy 60.904628 -75.639676) (xy 60.887743 -75.618156) (xy 60.859716 -75.571182) (xy 60.838683 -75.520687)
			(xy 60.825077 -75.467707) (xy 60.819175 -75.413326) (xy 60.8211 -75.35866) (xy 60.83081 -75.304829)
			(xy 60.848108 -75.252936) (xy 60.872639 -75.204046) (xy 60.9039 -75.159159) (xy 60.941251 -75.119196)
			(xy 60.983925 -75.084976) (xy 61.031048 -75.057201) (xy 61.081655 -75.036439) (xy 61.134707 -75.023116)
			(xy 61.189119 -75.017506) (xy 61.243774 -75.019723) (xy 61.297552 -75.029722) (xy 61.349351 -75.047298)
			(xy 61.39811 -75.07209) (xy 61.442829 -75.103591) (xy 61.482591 -75.141155) (xy 61.516582 -75.184012)
			(xy 61.544105 -75.231283) (xy 61.564595 -75.282) (xy 61.577633 -75.335123) (xy 61.582952 -75.389564)
			(xy 61.582501 -75.399392) (xy 63.219328 -75.399392) (xy 63.223399 -75.34377) (xy 63.235525 -75.289333)
			(xy 63.255448 -75.237242) (xy 63.282744 -75.188607) (xy 63.31683 -75.144464) (xy 63.356979 -75.105755)
			(xy 63.402337 -75.073304) (xy 63.451937 -75.047803) (xy 63.504721 -75.029796) (xy 63.559564 -75.019666)
			(xy 63.615298 -75.017629) (xy 63.670735 -75.023729) (xy 63.724692 -75.037835) (xy 63.776021 -75.059647)
			(xy 63.823627 -75.088701) (xy 63.866495 -75.124376) (xy 63.903712 -75.165913) (xy 63.934485 -75.212426)
			(xy 63.958157 -75.262923) (xy 63.974225 -75.31633) (xy 63.982345 -75.371506) (xy 63.982854 -75.399392)
			(xy 63.982345 -75.427278) (xy 63.974225 -75.482454) (xy 63.958157 -75.535861) (xy 63.934485 -75.586358)
			(xy 63.903712 -75.632871) (xy 63.866495 -75.674408) (xy 63.823627 -75.710083) (xy 63.776021 -75.739137)
			(xy 63.724692 -75.760949) (xy 63.670735 -75.775055) (xy 63.615298 -75.781155) (xy 63.559564 -75.779118)
			(xy 63.504721 -75.768988) (xy 63.451937 -75.750981) (xy 63.402337 -75.72548) (xy 63.356979 -75.693029)
			(xy 63.31683 -75.65432) (xy 63.282744 -75.610177) (xy 63.255448 -75.561542) (xy 63.235525 -75.509451)
			(xy 63.223399 -75.455014) (xy 63.219328 -75.399392) (xy 61.582501 -75.399392) (xy 61.580442 -75.444206)
			(xy 61.570156 -75.49793) (xy 61.552303 -75.549635) (xy 61.527249 -75.59826) (xy 61.495509 -75.64281)
			(xy 61.457733 -75.68237) (xy 61.436504 -75.69962) (xy 61.423863 -75.710136) (xy 61.404079 -75.736389)
			(xy 61.391659 -75.766826) (xy 61.387431 -75.799426) (xy 61.391673 -75.832025) (xy 61.404104 -75.862457)
			(xy 61.4239 -75.888701) (xy 61.436504 -75.899264) (xy 61.44133 -75.903074) (xy 61.458404 -75.916336)
			(xy 61.496124 -75.937455) (xy 61.536875 -75.951882) (xy 61.579481 -75.959201) (xy 61.622711 -75.959201)
			(xy 61.665317 -75.951882) (xy 61.706068 -75.937455) (xy 61.743788 -75.916336) (xy 61.760862 -75.903074)
			(xy 61.782541 -75.886184) (xy 61.829757 -75.858067) (xy 61.880518 -75.837015) (xy 61.933775 -75.823465)
			(xy 61.988425 -75.817696) (xy 62.043337 -75.819828) (xy 62.097375 -75.829816) (xy 62.149421 -75.847455)
			(xy 62.198397 -75.872378) (xy 62.20482 -75.876912) (xy 64.218818 -75.876912) (xy 64.222889 -75.82129)
			(xy 64.235015 -75.766853) (xy 64.254938 -75.714762) (xy 64.282234 -75.666127) (xy 64.31632 -75.621984)
			(xy 64.356469 -75.583275) (xy 64.401827 -75.550824) (xy 64.451427 -75.525323) (xy 64.504211 -75.507316)
			(xy 64.559054 -75.497186) (xy 64.614788 -75.495149) (xy 64.670225 -75.501249) (xy 64.724182 -75.515355)
			(xy 64.775511 -75.537167) (xy 64.823117 -75.566221) (xy 64.865985 -75.601896) (xy 64.903202 -75.643433)
			(xy 64.933975 -75.689946) (xy 64.957647 -75.740443) (xy 64.973715 -75.79385) (xy 64.981835 -75.849026)
			(xy 64.982344 -75.876912) (xy 64.981835 -75.904798) (xy 64.973715 -75.959974) (xy 64.957647 -76.013381)
			(xy 64.933975 -76.063878) (xy 64.903202 -76.110391) (xy 64.865985 -76.151928) (xy 64.823117 -76.187603)
			(xy 64.775511 -76.216657) (xy 64.724182 -76.238469) (xy 64.670225 -76.252575) (xy 64.614788 -76.258675)
			(xy 64.559054 -76.256638) (xy 64.504211 -76.246508) (xy 64.451427 -76.228501) (xy 64.401827 -76.203)
			(xy 64.356469 -76.170549) (xy 64.31632 -76.13184) (xy 64.282234 -76.087697) (xy 64.254938 -76.039062)
			(xy 64.235015 -75.986971) (xy 64.222889 -75.932534) (xy 64.218818 -75.876912) (xy 62.20482 -75.876912)
			(xy 62.243291 -75.904071) (xy 62.283173 -75.941877) (xy 62.317218 -75.985014) (xy 62.344722 -76.03259)
			(xy 62.365115 -76.083619) (xy 62.377975 -76.137047) (xy 62.383036 -76.191767) (xy 62.380194 -76.246647)
			(xy 62.369507 -76.300551) (xy 62.351196 -76.352364) (xy 62.325641 -76.401014) (xy 62.29337 -76.445494)
			(xy 62.255051 -76.484884) (xy 62.233556 -76.502006) (xy 62.220587 -76.512598) (xy 62.200287 -76.539215)
			(xy 62.18761 -76.570198) (xy 62.183429 -76.603411) (xy 62.188032 -76.636568) (xy 62.201102 -76.667387)
			(xy 62.221738 -76.693744) (xy 62.234826 -76.70419) (xy 62.240922 -76.709016) (xy 62.258133 -76.721894)
			(xy 62.295965 -76.742294) (xy 62.33669 -76.756036) (xy 62.379147 -76.762728) (xy 62.422125 -76.762179)
			(xy 62.464397 -76.754406) (xy 62.504759 -76.739629) (xy 62.542058 -76.71827) (xy 62.55893 -76.704952)
			(xy 62.580913 -76.687506) (xy 62.62901 -76.658588) (xy 62.680824 -76.637028) (xy 62.735237 -76.623291)
			(xy 62.791076 -76.617673) (xy 62.847135 -76.620296) (xy 62.902206 -76.631102) (xy 62.955099 -76.649859)
			(xy 63.004674 -76.676163) (xy 63.049861 -76.709444) (xy 63.089685 -76.748987) (xy 63.123286 -76.793936)
			(xy 63.149941 -76.843323) (xy 63.169073 -76.896082) (xy 63.18027 -76.951074) (xy 63.18329 -77.007113)
			(xy 63.178068 -77.062991) (xy 63.164717 -77.1175) (xy 63.143526 -77.169466) (xy 63.11495 -77.217766)
			(xy 63.097664 -77.239876) (xy 63.084361 -77.25692) (xy 63.063243 -77.294646) (xy 63.048818 -77.335404)
			(xy 63.041503 -77.378015) (xy 63.041509 -77.42125) (xy 63.048835 -77.46386) (xy 63.06327 -77.504613)
			(xy 63.084397 -77.542335) (xy 63.097664 -77.559408) (xy 63.114561 -77.58092) (xy 63.142592 -77.627895)
			(xy 63.163628 -77.678392) (xy 63.177238 -77.731375) (xy 63.183142 -77.785759) (xy 63.181219 -77.840428)
			(xy 63.17151 -77.894262) (xy 63.158923 -77.932026) (xy 64.13576 -77.932026) (xy 64.139831 -77.876404)
			(xy 64.151957 -77.821967) (xy 64.17188 -77.769876) (xy 64.199176 -77.721241) (xy 64.233262 -77.677098)
			(xy 64.273411 -77.638389) (xy 64.318769 -77.605938) (xy 64.368369 -77.580437) (xy 64.421153 -77.56243)
			(xy 64.475996 -77.5523) (xy 64.53173 -77.550263) (xy 64.587167 -77.556363) (xy 64.641124 -77.570469)
			(xy 64.692453 -77.592281) (xy 64.740059 -77.621335) (xy 64.782927 -77.65701) (xy 64.820144 -77.698547)
			(xy 64.850917 -77.74506) (xy 64.874589 -77.795557) (xy 64.890657 -77.848964) (xy 64.898777 -77.90414)
			(xy 64.899286 -77.932026) (xy 64.898777 -77.959912) (xy 64.890657 -78.015088) (xy 64.874589 -78.068495)
			(xy 64.850917 -78.118992) (xy 64.820144 -78.165505) (xy 64.782927 -78.207042) (xy 64.740059 -78.242717)
			(xy 64.692453 -78.271771) (xy 64.641124 -78.293583) (xy 64.587167 -78.307689) (xy 64.53173 -78.313789)
			(xy 64.475996 -78.311752) (xy 64.421153 -78.301622) (xy 64.368369 -78.283615) (xy 64.318769 -78.258114)
			(xy 64.273411 -78.225663) (xy 64.233262 -78.186954) (xy 64.199176 -78.142811) (xy 64.17188 -78.094176)
			(xy 64.151957 -78.042085) (xy 64.139831 -77.987648) (xy 64.13576 -77.932026) (xy 63.158923 -77.932026)
			(xy 63.154213 -77.946159) (xy 63.129682 -77.995053) (xy 63.09842 -78.039943) (xy 63.061069 -78.07991)
			(xy 63.018394 -78.114133) (xy 62.971268 -78.141911) (xy 62.920659 -78.162675) (xy 62.867604 -78.175999)
			(xy 62.813189 -78.181611) (xy 62.758531 -78.179395) (xy 62.70475 -78.169396) (xy 62.652947 -78.15182)
			(xy 62.604185 -78.127027) (xy 62.559463 -78.095525) (xy 62.519699 -78.05796) (xy 62.485705 -78.015101)
			(xy 62.458181 -77.967827) (xy 62.437689 -77.917107) (xy 62.42465 -77.863981) (xy 62.419331 -77.809537)
			(xy 62.42184 -77.754891) (xy 62.432128 -77.701164) (xy 62.449982 -77.649457) (xy 62.475037 -77.600829)
			(xy 62.506779 -77.556277) (xy 62.544557 -77.516715) (xy 62.565788 -77.499464) (xy 62.578345 -77.488855)
			(xy 62.598132 -77.462624) (xy 62.610558 -77.432208) (xy 62.614798 -77.399626) (xy 62.610571 -77.367042)
			(xy 62.598157 -77.336621) (xy 62.578382 -77.310382) (xy 62.565788 -77.29982) (xy 62.54941 -77.286643)
			(xy 62.51937 -77.257236) (xy 62.505844 -77.241146) (xy 62.495111 -77.228839) (xy 62.468757 -77.20958)
			(xy 62.438375 -77.197651) (xy 62.405958 -77.193836) (xy 62.373636 -77.198384) (xy 62.343531 -77.210998)
			(xy 62.317621 -77.230848) (xy 62.307216 -77.243432) (xy 62.290275 -77.264398) (xy 62.251563 -77.301902)
			(xy 62.207957 -77.333582) (xy 62.160324 -77.358805) (xy 62.109613 -77.37707) (xy 62.056836 -77.388013)
			(xy 62.003044 -77.391415) (xy 61.949309 -77.387209) (xy 61.896702 -77.375478) (xy 61.846271 -77.356456)
			(xy 61.79902 -77.330523) (xy 61.755892 -77.298195) (xy 61.717746 -77.260116) (xy 61.701172 -77.23886)
			(xy 61.69075 -77.22591) (xy 61.664603 -77.205407) (xy 61.634045 -77.192359) (xy 61.601154 -77.187653)
			(xy 61.568163 -77.191608) (xy 61.537316 -77.203956) (xy 61.510708 -77.223857) (xy 61.500004 -77.236574)
			(xy 61.498226 -77.23886) (xy 61.485169 -77.255704) (xy 61.464333 -77.292879) (xy 61.449991 -77.333009)
			(xy 61.442546 -77.37497) (xy 61.442206 -77.417584) (xy 61.448981 -77.459659) (xy 61.46268 -77.500013)
			(xy 61.482921 -77.537515) (xy 61.495686 -77.554582) (xy 61.512368 -77.576613) (xy 61.539732 -77.624624)
			(xy 61.559883 -77.676081) (xy 61.5724 -77.729907) (xy 61.57702 -77.784975) (xy 61.573648 -77.840134)
			(xy 61.562353 -77.894229) (xy 61.543371 -77.946129) (xy 61.517101 -77.994748) (xy 61.484092 -78.039068)
			(xy 61.445034 -78.078162) (xy 61.400744 -78.111212) (xy 61.35215 -78.137527) (xy 61.300268 -78.156556)
			(xy 61.246183 -78.167901) (xy 61.191027 -78.171324) (xy 61.135955 -78.166754) (xy 61.082117 -78.154287)
			(xy 61.030642 -78.134183) (xy 60.982605 -78.106864) (xy 60.960508 -78.090268) (xy 60.94332 -78.077455)
			(xy 60.905574 -78.057136) (xy 60.86495 -78.043449) (xy 60.822604 -78.036784) (xy 60.779741 -78.03733)
			(xy 60.737578 -78.045072) (xy 60.697317 -78.05979) (xy 60.660101 -78.081064) (xy 60.643262 -78.094332)
			(xy 60.621706 -78.11131) (xy 60.574745 -78.139684) (xy 60.524202 -78.161037) (xy 60.471122 -78.174929)
			(xy 60.4166 -78.181073) (xy 60.361759 -78.179341) (xy 60.307733 -78.169771) (xy 60.255634 -78.15256)
			(xy 60.20654 -78.128062) (xy 60.161461 -78.096782) (xy 60.121329 -78.059368) (xy 60.086971 -78.016589)
			(xy 60.059096 -77.969329) (xy 60.03828 -77.918564) (xy 60.024951 -77.86534) (xy 60.019386 -77.810755)
			(xy 60.021698 -77.755936) (xy 60.03184 -77.702014) (xy 60.049602 -77.650101) (xy 60.074619 -77.601268)
			(xy 60.106374 -77.556524) (xy 60.144212 -77.51679) (xy 60.165488 -77.499464) (xy 60.178045 -77.488855)
			(xy 60.197832 -77.462624) (xy 60.210258 -77.432208) (xy 60.214498 -77.399626) (xy 60.210271 -77.367042)
			(xy 60.197857 -77.336621) (xy 60.178082 -77.310382) (xy 60.165488 -77.29982) (xy 60.160662 -77.29601)
			(xy 60.143588 -77.282748) (xy 60.105868 -77.261629) (xy 60.065117 -77.247202) (xy 60.022511 -77.239883)
			(xy 59.979281 -77.239883) (xy 59.936675 -77.247202) (xy 59.895924 -77.261629) (xy 59.858204 -77.282748)
			(xy 59.84113 -77.29601) (xy 59.819573 -77.312841) (xy 59.772604 -77.340856) (xy 59.722116 -77.361877)
			(xy 59.669143 -77.375474) (xy 59.614772 -77.381366) (xy 59.560117 -77.379435) (xy 59.506297 -77.369719)
			(xy 59.454417 -77.352418) (xy 59.405538 -77.327886) (xy 59.360663 -77.296626) (xy 59.320712 -77.259278)
			(xy 59.286503 -77.216609) (xy 59.258738 -77.169491) (xy 59.237985 -77.118892) (xy 59.22467 -77.065849)
			(xy 59.219065 -77.011447) (xy 57.581545 -77.011447) (xy 57.578947 -77.051634) (xy 57.567545 -77.105467)
			(xy 57.548527 -77.157104) (xy 57.522287 -77.205472) (xy 57.48937 -77.249568) (xy 57.450459 -77.288478)
			(xy 57.406362 -77.321393) (xy 57.357993 -77.347632) (xy 57.306356 -77.366648) (xy 57.252522 -77.378049)
			(xy 57.19761 -77.381597) (xy 57.142757 -77.377219) (xy 57.089102 -77.365005) (xy 57.037759 -77.345209)
			(xy 56.989792 -77.318241) (xy 56.946198 -77.284662) (xy 56.90788 -77.245168) (xy 56.891428 -77.223112)
			(xy 56.869517 -77.215272) (xy 56.823762 -77.206803) (xy 56.77723 -77.206803) (xy 56.731475 -77.215272)
			(xy 56.709564 -77.223112) (xy 56.692188 -77.246226) (xy 56.651618 -77.28743) (xy 56.605294 -77.322037)
			(xy 56.554276 -77.349256) (xy 56.499735 -77.368462) (xy 56.442919 -77.379214) (xy 56.385131 -77.381268)
			(xy 56.327696 -77.374575) (xy 56.271929 -77.359288) (xy 56.219108 -77.33576) (xy 56.194452 -77.320648)
			(xy 56.156606 -77.296518) (xy 56.067706 -77.30617) (xy 55.904638 -77.469238) (xy 55.885588 -77.469238)
			(xy 55.781448 -77.573632) (xy 55.562754 -77.573632) (xy 55.547103 -77.574816) (xy 55.517059 -77.583864)
			(xy 55.490131 -77.599971) (xy 55.467947 -77.622161) (xy 55.451849 -77.649094) (xy 55.44281 -77.679141)
			(xy 55.441596 -77.69479) (xy 55.441596 -78.055216) (xy 55.602124 -78.215744) (xy 55.645812 -78.221078)
			(xy 55.671817 -78.224641) (xy 55.722581 -78.237983) (xy 55.771038 -78.258156) (xy 55.816274 -78.284779)
			(xy 55.857434 -78.31735) (xy 55.893742 -78.355254) (xy 55.909464 -78.376272) (xy 55.931375 -78.384112)
			(xy 55.97713 -78.392581) (xy 56.023662 -78.392581) (xy 56.069417 -78.384112) (xy 56.091328 -78.376272)
			(xy 56.107983 -78.354089) (xy 56.146653 -78.314322) (xy 56.190674 -78.280574) (xy 56.23912 -78.253558)
			(xy 56.290967 -78.233843) (xy 56.345123 -78.221845) (xy 56.400446 -78.217818) (xy 56.455769 -78.221845)
			(xy 56.509925 -78.233843) (xy 56.561772 -78.253558) (xy 56.610218 -78.280574) (xy 56.654239 -78.314322)
			(xy 56.692909 -78.354089) (xy 56.709564 -78.376272) (xy 56.731475 -78.384112) (xy 56.77723 -78.392581)
			(xy 56.823762 -78.392581) (xy 56.869517 -78.384112) (xy 56.891428 -78.376272) (xy 56.907886 -78.354327)
			(xy 56.946067 -78.314943) (xy 56.989496 -78.281434) (xy 57.037277 -78.254492) (xy 57.088424 -78.234672)
			(xy 57.141884 -78.222383) (xy 57.196552 -78.217879) (xy 57.251301 -78.221252) (xy 57.305003 -78.232433)
			(xy 57.35655 -78.251191) (xy 57.404877 -78.27714) (xy 57.448989 -78.309744) (xy 57.487976 -78.34833)
			(xy 57.521034 -78.392104) (xy 57.54748 -78.440161) (xy 57.566769 -78.491511) (xy 57.578504 -78.545095)
			(xy 57.582441 -78.599792) (xy 58.418728 -78.599792) (xy 58.422799 -78.54417) (xy 58.434925 -78.489733)
			(xy 58.454848 -78.437642) (xy 58.482144 -78.389007) (xy 58.51623 -78.344864) (xy 58.556379 -78.306155)
			(xy 58.601737 -78.273704) (xy 58.651337 -78.248203) (xy 58.704121 -78.230196) (xy 58.758964 -78.220066)
			(xy 58.814698 -78.218029) (xy 58.870135 -78.224129) (xy 58.924092 -78.238235) (xy 58.975421 -78.260047)
			(xy 59.023027 -78.289101) (xy 59.065895 -78.324776) (xy 59.103112 -78.366313) (xy 59.133885 -78.412826)
			(xy 59.157557 -78.463323) (xy 59.173625 -78.51673) (xy 59.181745 -78.571906) (xy 59.181971 -78.584298)
			(xy 61.623954 -78.584298) (xy 61.628025 -78.528676) (xy 61.640151 -78.474239) (xy 61.660074 -78.422148)
			(xy 61.68737 -78.373513) (xy 61.721456 -78.32937) (xy 61.761605 -78.290661) (xy 61.806963 -78.25821)
			(xy 61.856563 -78.232709) (xy 61.909347 -78.214702) (xy 61.96419 -78.204572) (xy 62.019924 -78.202535)
			(xy 62.075361 -78.208635) (xy 62.129318 -78.222741) (xy 62.180647 -78.244553) (xy 62.228253 -78.273607)
			(xy 62.271121 -78.309282) (xy 62.308338 -78.350819) (xy 62.339111 -78.397332) (xy 62.362783 -78.447829)
			(xy 62.378851 -78.501236) (xy 62.386971 -78.556412) (xy 62.38748 -78.584298) (xy 62.386971 -78.612184)
			(xy 62.378851 -78.66736) (xy 62.362783 -78.720767) (xy 62.339111 -78.771264) (xy 62.308338 -78.817777)
			(xy 62.271121 -78.859314) (xy 62.228253 -78.894989) (xy 62.180647 -78.924043) (xy 62.129318 -78.945855)
			(xy 62.075361 -78.959961) (xy 62.019924 -78.966061) (xy 61.96419 -78.964024) (xy 61.909347 -78.953894)
			(xy 61.856563 -78.935887) (xy 61.806963 -78.910386) (xy 61.761605 -78.877935) (xy 61.721456 -78.839226)
			(xy 61.68737 -78.795083) (xy 61.660074 -78.746448) (xy 61.640151 -78.694357) (xy 61.628025 -78.63992)
			(xy 61.623954 -78.584298) (xy 59.181971 -78.584298) (xy 59.182254 -78.599792) (xy 59.181745 -78.627678)
			(xy 59.173625 -78.682854) (xy 59.157557 -78.736261) (xy 59.133885 -78.786758) (xy 59.103112 -78.833271)
			(xy 59.065895 -78.874808) (xy 59.023027 -78.910483) (xy 58.975421 -78.939537) (xy 58.924092 -78.961349)
			(xy 58.870135 -78.975455) (xy 58.814698 -78.981555) (xy 58.758964 -78.979518) (xy 58.704121 -78.969388)
			(xy 58.651337 -78.951381) (xy 58.601737 -78.92588) (xy 58.556379 -78.893429) (xy 58.51623 -78.85472)
			(xy 58.482144 -78.810577) (xy 58.454848 -78.761942) (xy 58.434925 -78.709851) (xy 58.422799 -78.655414)
			(xy 58.418728 -78.599792) (xy 57.582441 -78.599792) (xy 57.582442 -78.599806) (xy 57.578502 -78.654518)
			(xy 57.566765 -78.708101) (xy 57.547474 -78.759451) (xy 57.521027 -78.807507) (xy 57.487968 -78.851279)
			(xy 57.44898 -78.889865) (xy 57.404866 -78.922467) (xy 57.356538 -78.948414) (xy 57.304991 -78.967171)
			(xy 57.251289 -78.97835) (xy 57.196539 -78.981721) (xy 57.141871 -78.977215) (xy 57.088412 -78.964924)
			(xy 57.037265 -78.945103) (xy 56.989485 -78.918159) (xy 56.946058 -78.884648) (xy 56.907878 -78.845263)
			(xy 56.891428 -78.823312) (xy 56.869517 -78.815472) (xy 56.823762 -78.807003) (xy 56.77723 -78.807003)
			(xy 56.731475 -78.815472) (xy 56.709564 -78.823312) (xy 56.701144 -78.83476) (xy 56.682834 -78.856498)
			(xy 56.672988 -78.866746) (xy 56.664203 -78.875591) (xy 56.645646 -78.892242) (xy 56.635904 -78.90002)
			(xy 56.623311 -78.910582) (xy 56.603537 -78.936822) (xy 56.591124 -78.967243) (xy 56.586897 -78.999826)
			(xy 56.591137 -79.032408) (xy 56.603562 -79.062824) (xy 56.623347 -79.089055) (xy 56.635904 -79.099664)
			(xy 56.656077 -79.116045) (xy 56.692233 -79.153368) (xy 56.722989 -79.195253) (xy 56.747777 -79.240924)
			(xy 56.766138 -79.289537) (xy 56.777732 -79.340192) (xy 56.782344 -79.391951) (xy 56.779889 -79.443857)
			(xy 56.775604 -79.469488) (xy 56.784217 -79.489001) (xy 56.806982 -79.525066) (xy 56.835452 -79.556822)
			(xy 56.868825 -79.583377) (xy 56.906166 -79.603984) (xy 56.946424 -79.618064) (xy 56.988468 -79.625223)
			(xy 57.009792 -79.625698) (xy 60.039758 -79.625698) (xy 61.067442 -80.653382) (xy 61.079349 -80.664616)
			(xy 61.107592 -80.681147) (xy 61.139117 -80.689926) (xy 61.171838 -80.690373) (xy 61.187838 -80.68691)
			(xy 61.204624 -80.682963) (xy 61.238712 -80.677747) (xy 61.25591 -80.676496) (xy 61.284201 -80.675253)
			(xy 61.340618 -80.680131) (xy 61.395694 -80.693299) (xy 61.448216 -80.714467) (xy 61.497031 -80.74317)
			(xy 61.541064 -80.778775) (xy 61.579349 -80.8205) (xy 61.611041 -80.867429) (xy 61.635446 -80.918528)
			(xy 61.652026 -80.972674) (xy 61.656722 -81.0006) (xy 61.659371 -81.015455) (xy 61.670712 -81.043409)
			(xy 61.688311 -81.06791) (xy 61.711179 -81.087583) (xy 61.738034 -81.101325) (xy 61.767368 -81.108363)
			(xy 61.782452 -81.108804) (xy 64.313816 -81.108804)
		)
		(stroke
			(width 0)
			(type solid)
		)
		(fill yes)
		(layer "In7.Cu")
		(net "P1V05_NODE1")
	)
	(gr_poly
		(pts
			(xy 38.333172 -140.270484) (xy 38.349836 -140.270015) (xy 38.382038 -140.261429) (xy 38.41091 -140.244784)
			(xy 38.434476 -140.221219) (xy 38.451124 -140.192349) (xy 38.459714 -140.160148) (xy 38.460172 -140.143484)
			(xy 38.460172 -136.64692) (xy 38.98392 -136.123426) (xy 38.991794 -136.08685) (xy 38.997888 -136.060765)
			(xy 39.016551 -136.010554) (xy 39.042213 -135.963534) (xy 39.074344 -135.920674) (xy 39.112283 -135.882857)
			(xy 39.155246 -135.850864) (xy 39.202349 -135.825354) (xy 39.25262 -135.806852) (xy 39.305022 -135.795742)
			(xy 39.358475 -135.79225) (xy 39.411877 -135.796451) (xy 39.464127 -135.808256) (xy 39.514148 -135.827422)
			(xy 39.560908 -135.853555) (xy 39.603443 -135.886116) (xy 39.640877 -135.924432) (xy 39.672437 -135.967715)
			(xy 39.697473 -136.015072) (xy 39.715468 -136.065526) (xy 39.721282 -136.091676) (xy 39.728902 -136.129268)
			(xy 39.9415 -136.341866) (xy 39.953618 -136.353305) (xy 39.982457 -136.369981) (xy 40.014632 -136.378613)
			(xy 40.047946 -136.378613) (xy 40.080121 -136.369981) (xy 40.10896 -136.353305) (xy 40.121078 -136.341866)
			(xy 40.12692 -136.336278) (xy 40.131746 -136.329928) (xy 40.151831 -136.305139) (xy 40.198814 -136.261984)
			(xy 40.225218 -136.244076) (xy 40.231817 -136.222812) (xy 40.238306 -136.178768) (xy 40.237008 -136.134268)
			(xy 40.22796 -136.090677) (xy 40.220138 -136.069832) (xy 40.197427 -136.053388) (xy 40.156749 -136.014801)
			(xy 40.12231 -135.970556) (xy 40.094889 -135.92165) (xy 40.075104 -135.869188) (xy 40.063401 -135.814355)
			(xy 40.060046 -135.758386) (xy 40.065113 -135.702547) (xy 40.078489 -135.648097) (xy 40.099871 -135.596266)
			(xy 40.128777 -135.548223) (xy 40.146224 -135.526272) (xy 40.159592 -135.509436) (xy 40.181056 -135.472193)
			(xy 40.19594 -135.431866) (xy 40.203818 -135.389608) (xy 40.204466 -135.346628) (xy 40.197864 -135.304152)
			(xy 40.184203 -135.263395) (xy 40.163871 -135.225521) (xy 40.15105 -135.208264) (xy 40.133431 -135.187109)
			(xy 40.103962 -135.140605) (xy 40.081651 -135.090274) (xy 40.066981 -135.03721) (xy 40.060272 -134.982566)
			(xy 40.061669 -134.92753) (xy 40.071142 -134.873296) (xy 40.088486 -134.821045) (xy 40.100504 -134.796276)
			(xy 40.108841 -134.780241) (xy 40.128179 -134.749707) (xy 40.139112 -134.735316) (xy 40.151775 -134.718063)
			(xy 40.17174 -134.680214) (xy 40.185076 -134.639552) (xy 40.191407 -134.59723) (xy 40.190552 -134.554446)
			(xy 40.182537 -134.512411) (xy 40.167587 -134.472315) (xy 40.146126 -134.435293) (xy 40.132762 -134.418578)
			(xy 40.115133 -134.396574) (xy 40.085869 -134.348383) (xy 40.064016 -134.296411) (xy 40.050048 -134.241788)
			(xy 40.044271 -134.185704) (xy 40.04681 -134.129381) (xy 40.057609 -134.074045) (xy 40.076434 -134.0209)
			(xy 40.102874 -133.971104) (xy 40.136354 -133.925741) (xy 40.176146 -133.885799) (xy 40.221382 -133.852147)
			(xy 40.271077 -133.825518) (xy 40.32415 -133.806493) (xy 40.379445 -133.795484) (xy 40.435758 -133.792732)
			(xy 40.491863 -133.798297) (xy 40.546539 -133.812058) (xy 40.598594 -133.833714) (xy 40.646895 -133.862795)
			(xy 40.668956 -133.880352) (xy 40.686265 -133.893969) (xy 40.724598 -133.915646) (xy 40.766092 -133.930395)
			(xy 40.809506 -133.937773) (xy 40.853543 -133.93756) (xy 40.896884 -133.929763) (xy 40.938234 -133.914615)
			(xy 40.976355 -133.892569) (xy 40.993568 -133.878828) (xy 41.0153 -133.861251) (xy 41.063005 -133.832129)
			(xy 41.114524 -133.810457) (xy 41.168701 -133.79672) (xy 41.224322 -133.791226) (xy 41.28014 -133.794098)
			(xy 41.334903 -133.805273) (xy 41.387384 -133.824499) (xy 41.436406 -133.851346) (xy 41.48087 -133.885211)
			(xy 41.519779 -133.925336) (xy 41.55226 -133.970821) (xy 41.577586 -134.020645) (xy 41.595189 -134.073692)
			(xy 41.604674 -134.128774) (xy 41.605708 -134.156704) (xy 41.605789 -134.183196) (xy 41.599369 -134.23578)
			(xy 41.585563 -134.286925) (xy 41.56465 -134.335598) (xy 41.537052 -134.380817) (xy 41.503326 -134.421669)
			(xy 41.464152 -134.457331) (xy 41.42032 -134.487084) (xy 41.372716 -134.510326) (xy 41.322299 -134.526589)
			(xy 41.270086 -134.535544) (xy 41.217131 -134.537012) (xy 41.164502 -134.530963) (xy 41.113261 -134.517518)
			(xy 41.064442 -134.496949) (xy 41.01903 -134.46967) (xy 40.99814 -134.453376) (xy 40.979655 -134.439768)
			(xy 40.938849 -134.418761) (xy 40.894931 -134.405428) (xy 40.849333 -134.400205) (xy 40.803539 -134.40326)
			(xy 40.759038 -134.414495) (xy 40.717282 -134.433543) (xy 40.679627 -134.459785) (xy 40.663114 -134.475728)
			(xy 40.643048 -134.516622) (xy 40.637082 -134.529746) (xy 40.630608 -134.557832) (xy 40.630618 -134.586654)
			(xy 40.637111 -134.614736) (xy 40.643048 -134.627874) (xy 40.663622 -134.670546) (xy 40.682164 -134.68731)
			(xy 40.703014 -134.70679) (xy 40.739132 -134.750963) (xy 40.768096 -134.800123) (xy 40.78923 -134.853123)
			(xy 40.802041 -134.908725) (xy 40.806229 -134.96563) (xy 40.801697 -135.022508) (xy 40.78855 -135.078031)
			(xy 40.767095 -135.130902) (xy 40.737834 -135.179887) (xy 40.72001 -135.202168) (xy 40.706559 -135.21909)
			(xy 40.685017 -135.256566) (xy 40.670122 -135.297144) (xy 40.662304 -135.339656) (xy 40.661787 -135.382879)
			(xy 40.668587 -135.425566) (xy 40.682508 -135.466489) (xy 40.703149 -135.504468) (xy 40.7162 -135.5217)
			(xy 40.734206 -135.543548) (xy 40.764088 -135.591632) (xy 40.786353 -135.643684) (xy 40.800488 -135.698504)
			(xy 40.806168 -135.754832) (xy 40.803262 -135.81137) (xy 40.791837 -135.866819) (xy 40.772156 -135.919901)
			(xy 40.744671 -135.969395) (xy 40.710017 -136.014162) (xy 40.668988 -136.053172) (xy 40.646096 -136.069832)
			(xy 40.638242 -136.090665) (xy 40.629138 -136.134244) (xy 40.627782 -136.178743) (xy 40.634216 -136.222795)
			(xy 40.640762 -136.244076) (xy 40.665032 -136.260507) (xy 40.708693 -136.299606) (xy 40.745867 -136.344917)
			(xy 40.775679 -136.395377) (xy 40.787066 -136.422384) (xy 40.80002 -136.454388) (xy 40.896032 -136.52881)
			(xy 40.908422 -136.53782) (xy 40.936412 -136.550247) (xy 40.966557 -136.555644) (xy 40.99712 -136.5537)
			(xy 41.026338 -136.544527) (xy 41.052528 -136.528653) (xy 41.063672 -136.518142) (xy 41.377108 -136.204452)
			(xy 41.388496 -136.192319) (xy 41.405165 -136.163534) (xy 41.413832 -136.13142) (xy 41.414446 -136.11479)
			(xy 41.414446 -135.461502) (xy 42.644314 -134.231634) (xy 42.659451 -134.215845) (xy 42.684616 -134.180073)
			(xy 42.703284 -134.14052) (xy 42.714901 -134.098354) (xy 42.719126 -134.054822) (xy 42.715834 -134.011209)
			(xy 42.705121 -133.968805) (xy 42.687304 -133.928861) (xy 42.66291 -133.89256) (xy 42.632659 -133.860972)
			(xy 42.615358 -133.847586) (xy 42.594973 -133.832843) (xy 42.557974 -133.798753) (xy 42.525887 -133.760005)
			(xy 42.512234 -133.738874) (xy 42.49631 -133.71209) (xy 42.472659 -133.654447) (xy 42.458935 -133.593671)
			(xy 42.456608 -133.562598) (xy 42.454865 -133.540185) (xy 42.444486 -133.496449) (xy 42.426582 -133.455218)
			(xy 42.401708 -133.417777) (xy 42.370641 -133.385291) (xy 42.334346 -133.358771) (xy 42.293956 -133.339044)
			(xy 42.272458 -133.332474) (xy 42.245507 -133.324302) (xy 42.194179 -133.301128) (xy 42.146815 -133.27066)
			(xy 42.104446 -133.23356) (xy 42.067992 -133.190633) (xy 42.038245 -133.142813) (xy 42.015853 -133.09114)
			(xy 42.001301 -133.036736) (xy 41.994906 -132.980783) (xy 41.996807 -132.924498) (xy 42.006963 -132.869104)
			(xy 42.025152 -132.815806) (xy 42.05098 -132.765761) (xy 42.083886 -132.720057) (xy 42.123153 -132.679688)
			(xy 42.145204 -132.662168) (xy 42.167666 -132.645666) (xy 42.216422 -132.618664) (xy 42.268589 -132.599044)
			(xy 42.323056 -132.587225) (xy 42.378663 -132.583459) (xy 42.434226 -132.587826) (xy 42.488562 -132.600232)
			(xy 42.540514 -132.620414) (xy 42.588976 -132.647942) (xy 42.632915 -132.682229) (xy 42.671397 -132.722546)
			(xy 42.703602 -132.768035) (xy 42.728843 -132.817725) (xy 42.746585 -132.870561) (xy 42.756448 -132.925415)
			(xy 42.757852 -132.953252) (xy 42.759235 -132.975355) (xy 42.768687 -133.018616) (xy 42.785499 -133.059582)
			(xy 42.809162 -133.097011) (xy 42.838958 -133.129769) (xy 42.873983 -133.156863) (xy 42.913177 -133.177471)
			(xy 42.934128 -133.184646) (xy 42.957919 -133.192097) (xy 43.003411 -133.212489) (xy 43.024806 -133.225286)
			(xy 43.047079 -133.239584) (xy 43.087721 -133.273485) (xy 43.123154 -133.3128) (xy 43.152662 -133.356736)
			(xy 43.175651 -133.404408) (xy 43.184064 -133.429502) (xy 43.193462 -133.458966) (xy 43.215306 -133.48081)
			(xy 43.227438 -133.492271) (xy 43.256317 -133.50898) (xy 43.28854 -133.517631) (xy 43.321904 -133.517631)
			(xy 43.354127 -133.50898) (xy 43.383006 -133.492271) (xy 43.395138 -133.48081) (xy 43.410886 -133.465062)
			(xy 44.04233 -133.465062) (xy 45.750226 -131.757166) (xy 45.750226 -131.210304) (xy 45.727366 -131.177538)
			(xy 45.71154 -131.153939) (xy 45.68646 -131.102954) (xy 45.669411 -131.048753) (xy 45.660788 -130.992592)
			(xy 45.660791 -130.935772) (xy 45.669419 -130.879612) (xy 45.686474 -130.825412) (xy 45.711558 -130.77443)
			(xy 45.727366 -130.750818) (xy 45.750226 -130.718052) (xy 45.750226 -130.521456) (xy 45.749818 -130.506239)
			(xy 45.742656 -130.476663) (xy 45.728658 -130.449643) (xy 45.718984 -130.43789) (xy 45.709078 -130.425952)
			(xy 45.698859 -130.414047) (xy 45.673786 -130.395201) (xy 45.644874 -130.383038) (xy 45.61387 -130.378292)
			(xy 45.582644 -130.381249) (xy 45.553081 -130.39173) (xy 45.526966 -130.409104) (xy 45.516038 -130.420364)
			(xy 45.496566 -130.441033) (xy 45.452583 -130.476949) (xy 45.403763 -130.50595) (xy 45.351184 -130.527394)
			(xy 45.296007 -130.540807) (xy 45.239451 -130.545894) (xy 45.182766 -130.542541) (xy 45.127204 -130.530824)
			(xy 45.073992 -130.511001) (xy 45.024307 -130.483509) (xy 44.979245 -130.448956) (xy 44.939803 -130.408106)
			(xy 44.906851 -130.361861) (xy 44.881118 -130.311243) (xy 44.87164 -130.284474) (xy 44.86336 -130.258075)
			(xy 44.853628 -130.203612) (xy 44.851863 -130.148315) (xy 44.8581 -130.093342) (xy 44.87221 -130.039846)
			(xy 44.893897 -129.988948) (xy 44.922705 -129.941715) (xy 44.958032 -129.899136) (xy 44.999137 -129.862105)
			(xy 45.045158 -129.831397) (xy 45.095131 -129.807656) (xy 45.148008 -129.79138) (xy 45.202682 -129.78291)
			(xy 45.258005 -129.782422) (xy 45.312819 -129.789929) (xy 45.365975 -129.805271) (xy 45.391324 -129.816352)
			(xy 45.412533 -129.825415) (xy 45.457282 -129.836565) (xy 45.503309 -129.839458) (xy 45.549102 -129.834)
			(xy 45.593159 -129.820369) (xy 45.634033 -129.799013) (xy 45.670384 -129.770632) (xy 45.701018 -129.736159)
			(xy 45.724929 -129.696725) (xy 45.741333 -129.653624) (xy 45.749691 -129.60827) (xy 45.750226 -129.585212)
			(xy 45.750226 -129.37236) (xy 46.585886 -128.5367) (xy 50.84953 -128.5367) (xy 53.188108 -130.875278)
			(xy 53.205785 -130.892164) (xy 53.246313 -130.919491) (xy 53.291315 -130.938574) (xy 53.339133 -130.94871)
			(xy 53.388006 -130.949525) (xy 53.436136 -130.940991) (xy 53.459126 -130.932682) (xy 53.478432 -130.912811)
			(xy 53.521592 -130.878074) (xy 53.569162 -130.849676) (xy 53.620219 -130.828169) (xy 53.673771 -130.813971)
			(xy 53.728778 -130.807357) (xy 53.784169 -130.808458) (xy 53.838869 -130.81725) (xy 53.891815 -130.833563)
			(xy 53.941978 -130.857081) (xy 53.988383 -130.887345) (xy 54.030129 -130.923769) (xy 54.04866 -130.944366)
			(xy 54.069702 -130.95295) (xy 54.113939 -130.963331) (xy 54.159319 -130.965661) (xy 54.204387 -130.959867)
			(xy 54.226206 -130.95351) (xy 54.24369 -130.932837) (xy 54.283616 -130.89627) (xy 54.328413 -130.865863)
			(xy 54.377137 -130.842257) (xy 54.428763 -130.825947) (xy 54.482206 -130.817277) (xy 54.53634 -130.81643)
			(xy 54.590028 -130.823422) (xy 54.64214 -130.838108) (xy 54.691579 -130.860178) (xy 54.737305 -130.889168)
			(xy 54.778356 -130.924467) (xy 54.796436 -130.94462) (xy 54.816612 -130.949826) (xy 54.858032 -130.954335)
			(xy 54.899632 -130.952007) (xy 54.940291 -130.942905) (xy 54.959758 -130.935476) (xy 54.977827 -130.910528)
			(xy 55.020675 -130.866277) (xy 55.070091 -130.829505) (xy 55.097172 -130.814826) (xy 55.1216 -130.802692)
			(xy 55.173108 -130.784752) (xy 55.226646 -130.774329) (xy 55.281123 -130.771636) (xy 55.335428 -130.776727)
			(xy 55.388454 -130.7895) (xy 55.439122 -130.809694) (xy 55.486397 -130.836896) (xy 55.529317 -130.870554)
			(xy 55.567008 -130.90998) (xy 55.598699 -130.954371) (xy 55.623747 -131.002823) (xy 55.633112 -131.02844)
			(xy 55.641836 -131.054951) (xy 55.652329 -131.109766) (xy 55.654724 -131.165525) (xy 55.648971 -131.221038)
			(xy 55.635193 -131.275121) (xy 55.613683 -131.32662) (xy 55.5849 -131.374436) (xy 55.54946 -131.417549)
			(xy 55.508117 -131.455039) (xy 55.461753 -131.486107) (xy 55.411358 -131.51009) (xy 55.358008 -131.526476)
			(xy 55.302839 -131.534915) (xy 55.247029 -131.535228) (xy 55.19177 -131.527407) (xy 55.138239 -131.51162)
			(xy 55.087579 -131.488203) (xy 55.04087 -131.457656) (xy 54.99911 -131.420631) (xy 54.98084 -131.399534)
			(xy 54.96079 -131.394048) (xy 54.919541 -131.388932) (xy 54.87801 -131.39061) (xy 54.837308 -131.399037)
			(xy 54.817772 -131.406138) (xy 54.801643 -131.427806) (xy 54.764162 -131.4667) (xy 54.743096 -131.483608)
			(xy 54.721674 -131.499608) (xy 54.675152 -131.525959) (xy 54.625343 -131.545394) (xy 54.573268 -131.557514)
			(xy 54.519996 -131.562071) (xy 54.466619 -131.55897) (xy 54.414232 -131.548276) (xy 54.363911 -131.530208)
			(xy 54.316687 -131.505136) (xy 54.273529 -131.473576) (xy 54.254146 -131.45516) (xy 54.237636 -131.438904)
			(xy 54.202838 -131.42341) (xy 54.187602 -131.417245) (xy 54.155154 -131.412086) (xy 54.122464 -131.415379)
			(xy 54.091697 -131.426907) (xy 54.06489 -131.445905) (xy 54.053994 -131.458208) (xy 54.0461 -131.467546)
			(xy 54.029324 -131.485339) (xy 54.020466 -131.493768) (xy 54.013295 -131.513473) (xy 54.004785 -131.55453)
			(xy 54.003142 -131.596427) (xy 54.008412 -131.638024) (xy 54.020451 -131.678189) (xy 54.03893 -131.715826)
			(xy 54.063348 -131.749912) (xy 54.07787 -131.76504) (xy 55.263267 -132.950437) (xy 56.381894 -132.950437)
			(xy 56.381894 -132.897139) (xy 56.389837 -132.844435) (xy 56.405547 -132.793505) (xy 56.428673 -132.745484)
			(xy 56.458697 -132.701447) (xy 56.494949 -132.662376) (xy 56.53662 -132.629145) (xy 56.582778 -132.602496)
			(xy 56.632392 -132.583024) (xy 56.684354 -132.571164) (xy 56.737504 -132.567181) (xy 56.790654 -132.571164)
			(xy 56.842616 -132.583024) (xy 56.89223 -132.602496) (xy 56.938388 -132.629145) (xy 56.980059 -132.662376)
			(xy 57.016311 -132.701447) (xy 57.046335 -132.745484) (xy 57.069461 -132.793505) (xy 57.085171 -132.844435)
			(xy 57.093114 -132.897139) (xy 57.093612 -132.923788) (xy 57.093114 -132.950437) (xy 57.085171 -133.003141)
			(xy 57.069461 -133.054071) (xy 57.046335 -133.102092) (xy 57.016311 -133.146129) (xy 56.980059 -133.1852)
			(xy 56.938388 -133.218431) (xy 56.89223 -133.24508) (xy 56.842616 -133.264552) (xy 56.790654 -133.276412)
			(xy 56.737504 -133.280396) (xy 56.684354 -133.276412) (xy 56.632392 -133.264552) (xy 56.582778 -133.24508)
			(xy 56.53662 -133.218431) (xy 56.494949 -133.1852) (xy 56.458697 -133.146129) (xy 56.428673 -133.102092)
			(xy 56.405547 -133.054071) (xy 56.389837 -133.003141) (xy 56.381894 -132.950437) (xy 55.263267 -132.950437)
			(xy 56.011318 -133.698488) (xy 57.96915 -133.698488) (xy 57.990866 -133.698034) (xy 58.033662 -133.690631)
			(xy 58.074579 -133.676068) (xy 58.112428 -133.654766) (xy 58.146108 -133.627345) (xy 58.174642 -133.594602)
			(xy 58.1972 -133.557488) (xy 58.213127 -133.517082) (xy 58.221958 -133.474558) (xy 58.22315 -133.45287)
			(xy 58.208868 -133.428545) (xy 58.187005 -133.376548) (xy 58.173227 -133.32185) (xy 58.167851 -133.2657)
			(xy 58.170997 -133.209381) (xy 58.182595 -133.15418) (xy 58.202379 -133.101357) (xy 58.229898 -133.052118)
			(xy 58.264523 -133.007589) (xy 58.305463 -132.968787) (xy 58.328306 -132.952236) (xy 58.336683 -132.92965)
			(xy 58.34574 -132.882342) (xy 58.345733 -132.834176) (xy 58.33666 -132.786872) (xy 58.328306 -132.764276)
			(xy 58.305892 -132.748096) (xy 58.265647 -132.7102) (xy 58.231441 -132.666775) (xy 58.204025 -132.618773)
			(xy 58.184001 -132.567248) (xy 58.171808 -132.513331) (xy 58.167713 -132.458203) (xy 58.171807 -132.403076)
			(xy 58.183999 -132.349158) (xy 58.204022 -132.297633) (xy 58.231437 -132.249631) (xy 58.265642 -132.206205)
			(xy 58.305886 -132.168309) (xy 58.328306 -132.152136) (xy 58.336683 -132.12955) (xy 58.34574 -132.082242)
			(xy 58.345733 -132.034076) (xy 58.33666 -131.986772) (xy 58.328306 -131.964176) (xy 58.307452 -131.949167)
			(xy 58.269679 -131.914336) (xy 58.237049 -131.874647) (xy 58.210181 -131.830851) (xy 58.189584 -131.783779)
			(xy 58.17565 -131.734325) (xy 58.168641 -131.683424) (xy 58.168692 -131.632044) (xy 58.171842 -131.606544)
			(xy 58.17578 -131.581259) (xy 58.189691 -131.532014) (xy 58.210217 -131.485139) (xy 58.236971 -131.441518)
			(xy 58.269449 -131.401974) (xy 58.307039 -131.367252) (xy 58.327798 -131.35229) (xy 58.336246 -131.32969)
			(xy 58.345418 -131.28233) (xy 58.345477 -131.234089) (xy 58.336421 -131.186706) (xy 58.328052 -131.164076)
			(xy 58.311034 -131.121404) (xy 55.676546 -128.486916) (xy 55.676546 -126.031244) (xy 54.196488 -124.551186)
			(xy 54.145688 -124.55017) (xy 54.119304 -124.549071) (xy 54.067198 -124.540502) (xy 54.016771 -124.52483)
			(xy 53.968987 -124.502355) (xy 53.924758 -124.473505) (xy 53.88493 -124.438833) (xy 53.850263 -124.399)
			(xy 53.821419 -124.354767) (xy 53.79895 -124.306979) (xy 53.783285 -124.25655) (xy 53.774724 -124.204443)
			(xy 53.773578 -124.17806) (xy 53.772562 -124.12726) (xy 53.257196 -123.611894) (xy 51.543712 -123.611894)
			(xy 51.521357 -123.612371) (xy 51.477338 -123.620204) (xy 51.435366 -123.635613) (xy 51.396736 -123.658124)
			(xy 51.362637 -123.687042) (xy 51.334119 -123.721477) (xy 51.312062 -123.760368) (xy 51.297144 -123.802516)
			(xy 51.293014 -123.824492) (xy 51.287898 -123.852297) (xy 51.270548 -123.906102) (xy 51.245448 -123.956758)
			(xy 51.213148 -124.003156) (xy 51.174355 -124.04428) (xy 51.129919 -124.079229) (xy 51.080812 -124.107239)
			(xy 51.028109 -124.127696) (xy 50.972965 -124.140152) (xy 50.916586 -124.144334) (xy 50.860207 -124.140152)
			(xy 50.805063 -124.127696) (xy 50.75236 -124.107239) (xy 50.703253 -124.079229) (xy 50.658817 -124.04428)
			(xy 50.620024 -124.003156) (xy 50.587724 -123.956758) (xy 50.562624 -123.906102) (xy 50.545274 -123.852297)
			(xy 50.540158 -123.824492) (xy 50.536055 -123.802504) (xy 50.521166 -123.760331) (xy 50.499123 -123.721416)
			(xy 50.470606 -123.686962) (xy 50.436498 -123.658032) (xy 50.397851 -123.635522) (xy 50.35586 -123.620125)
			(xy 50.311822 -123.612319) (xy 50.28946 -123.611894) (xy 47.815246 -123.611894) (xy 47.793047 -123.612346)
			(xy 47.749323 -123.620054) (xy 47.707603 -123.635242) (xy 47.669158 -123.657449) (xy 47.635156 -123.685999)
			(xy 47.606633 -123.720023) (xy 47.584457 -123.758487) (xy 47.569301 -123.800218) (xy 47.561629 -123.843948)
			(xy 47.561246 -123.866148) (xy 47.560817 -123.893425) (xy 47.553119 -123.947431) (xy 47.537807 -123.999789)
			(xy 47.515194 -124.049433) (xy 47.485739 -124.09535) (xy 47.450046 -124.136604) (xy 47.40884 -124.172353)
			(xy 47.362962 -124.201868) (xy 47.313348 -124.224548) (xy 47.26101 -124.239929) (xy 47.207014 -124.247699)
			(xy 47.152462 -124.247699) (xy 47.098466 -124.239929) (xy 47.046128 -124.224548) (xy 46.996514 -124.201868)
			(xy 46.950636 -124.172353) (xy 46.90943 -124.136604) (xy 46.873737 -124.09535) (xy 46.844282 -124.049433)
			(xy 46.821669 -123.999789) (xy 46.806357 -123.947431) (xy 46.798659 -123.893425) (xy 46.79823 -123.866148)
			(xy 46.797795 -123.843951) (xy 46.790125 -123.800224) (xy 46.774974 -123.758495) (xy 46.752804 -123.720034)
			(xy 46.724288 -123.686009) (xy 46.690294 -123.657456) (xy 46.651857 -123.635243) (xy 46.610145 -123.620047)
			(xy 46.566427 -123.612329) (xy 46.54423 -123.611894) (xy 43.74642 -123.611894) (xy 43.724222 -123.612349)
			(xy 43.680502 -123.620059) (xy 43.638786 -123.63525) (xy 43.600344 -123.657458) (xy 43.566347 -123.686008)
			(xy 43.537827 -123.720032) (xy 43.515654 -123.758493) (xy 43.5005 -123.800222) (xy 43.492829 -123.84395)
			(xy 43.49242 -123.866148) (xy 43.491991 -123.893425) (xy 43.484293 -123.947431) (xy 43.468981 -123.999789)
			(xy 43.446368 -124.049433) (xy 43.416913 -124.09535) (xy 43.38122 -124.136604) (xy 43.340014 -124.172353)
			(xy 43.294136 -124.201868) (xy 43.244522 -124.224548) (xy 43.192184 -124.239929) (xy 43.138188 -124.247699)
			(xy 43.083636 -124.247699) (xy 43.02964 -124.239929) (xy 42.977302 -124.224548) (xy 42.927688 -124.201868)
			(xy 42.88181 -124.172353) (xy 42.840604 -124.136604) (xy 42.804911 -124.09535) (xy 42.775456 -124.049433)
			(xy 42.752843 -123.999789) (xy 42.737531 -123.947431) (xy 42.729833 -123.893425) (xy 42.729404 -123.866148)
			(xy 42.728969 -123.843951) (xy 42.721299 -123.800227) (xy 42.706148 -123.7585) (xy 42.683977 -123.72004)
			(xy 42.65546 -123.686018) (xy 42.621466 -123.657468) (xy 42.583029 -123.635259) (xy 42.541317 -123.620066)
			(xy 42.4976 -123.612352) (xy 42.475404 -123.611894) (xy 36.7792 -123.611894) (xy 36.021264 -124.36983)
			(xy 36.021264 -124.408184) (xy 48.766982 -124.408184) (xy 48.771053 -124.352562) (xy 48.783179 -124.298125)
			(xy 48.803102 -124.246034) (xy 48.830398 -124.197399) (xy 48.864484 -124.153256) (xy 48.904633 -124.114547)
			(xy 48.949991 -124.082096) (xy 48.999591 -124.056595) (xy 49.052375 -124.038588) (xy 49.107218 -124.028458)
			(xy 49.162952 -124.026421) (xy 49.218389 -124.032521) (xy 49.272346 -124.046627) (xy 49.323675 -124.068439)
			(xy 49.371281 -124.097493) (xy 49.414149 -124.133168) (xy 49.451366 -124.174705) (xy 49.482139 -124.221218)
			(xy 49.505811 -124.271715) (xy 49.521879 -124.325122) (xy 49.529999 -124.380298) (xy 49.530508 -124.408184)
			(xy 49.529999 -124.43607) (xy 49.521879 -124.491246) (xy 49.505811 -124.544653) (xy 49.482139 -124.59515)
			(xy 49.451366 -124.641663) (xy 49.414149 -124.6832) (xy 49.371281 -124.718875) (xy 49.323675 -124.747929)
			(xy 49.272346 -124.769741) (xy 49.218389 -124.783847) (xy 49.162952 -124.789947) (xy 49.107218 -124.78791)
			(xy 49.052375 -124.77778) (xy 48.999591 -124.759773) (xy 48.949991 -124.734272) (xy 48.904633 -124.701821)
			(xy 48.864484 -124.663112) (xy 48.830398 -124.618969) (xy 48.803102 -124.570334) (xy 48.783179 -124.518243)
			(xy 48.771053 -124.463806) (xy 48.766982 -124.408184) (xy 36.021264 -124.408184) (xy 36.021264 -125.482858)
			(xy 38.366698 -125.482858) (xy 38.370769 -125.427236) (xy 38.382895 -125.372799) (xy 38.402818 -125.320708)
			(xy 38.430114 -125.272073) (xy 38.4642 -125.22793) (xy 38.504349 -125.189221) (xy 38.549707 -125.15677)
			(xy 38.599307 -125.131269) (xy 38.652091 -125.113262) (xy 38.706934 -125.103132) (xy 38.762668 -125.101095)
			(xy 38.818105 -125.107195) (xy 38.872062 -125.121301) (xy 38.923391 -125.143113) (xy 38.970997 -125.172167)
			(xy 39.013865 -125.207842) (xy 39.051082 -125.249379) (xy 39.081855 -125.295892) (xy 39.105527 -125.346389)
			(xy 39.121595 -125.399796) (xy 39.129715 -125.454972) (xy 39.130224 -125.482858) (xy 39.129715 -125.510744)
			(xy 39.121595 -125.56592) (xy 39.105527 -125.619327) (xy 39.081855 -125.669824) (xy 39.051082 -125.716337)
			(xy 39.013865 -125.757874) (xy 38.970997 -125.793549) (xy 38.923391 -125.822603) (xy 38.872062 -125.844415)
			(xy 38.818105 -125.858521) (xy 38.762668 -125.864621) (xy 38.706934 -125.862584) (xy 38.652091 -125.852454)
			(xy 38.599307 -125.834447) (xy 38.549707 -125.808946) (xy 38.504349 -125.776495) (xy 38.4642 -125.737786)
			(xy 38.430114 -125.693643) (xy 38.402818 -125.645008) (xy 38.382895 -125.592917) (xy 38.370769 -125.53848)
			(xy 38.366698 -125.482858) (xy 36.021264 -125.482858) (xy 36.021264 -127.004064) (xy 39.853106 -127.004064)
			(xy 39.857177 -126.948442) (xy 39.869303 -126.894005) (xy 39.889226 -126.841914) (xy 39.916522 -126.793279)
			(xy 39.950608 -126.749136) (xy 39.990757 -126.710427) (xy 40.036115 -126.677976) (xy 40.085715 -126.652475)
			(xy 40.138499 -126.634468) (xy 40.193342 -126.624338) (xy 40.249076 -126.622301) (xy 40.304513 -126.628401)
			(xy 40.35847 -126.642507) (xy 40.409799 -126.664319) (xy 40.457405 -126.693373) (xy 40.500273 -126.729048)
			(xy 40.53749 -126.770585) (xy 40.568263 -126.817098) (xy 40.591935 -126.867595) (xy 40.608003 -126.921002)
			(xy 40.616123 -126.976178) (xy 40.616632 -127.004064) (xy 40.616123 -127.03195) (xy 40.608003 -127.087126)
			(xy 40.591935 -127.140533) (xy 40.568263 -127.19103) (xy 40.553535 -127.213291) (xy 52.630321 -127.213291)
			(xy 52.634948 -127.157988) (xy 52.647538 -127.103938) (xy 52.667828 -127.052284) (xy 52.695387 -127.004114)
			(xy 52.729635 -126.960446) (xy 52.769849 -126.922201) (xy 52.81518 -126.890187) (xy 52.864672 -126.865078)
			(xy 52.917279 -126.847406) (xy 52.971892 -126.837543) (xy 53.027357 -126.835696) (xy 53.082505 -126.841906)
			(xy 53.136171 -126.856041) (xy 53.187223 -126.877802) (xy 53.234583 -126.906731) (xy 53.277251 -126.942217)
			(xy 53.314327 -126.983511) (xy 53.330094 -127.00635) (xy 53.342764 -127.024538) (xy 53.373319 -127.056644)
			(xy 53.408981 -127.082962) (xy 53.448668 -127.102694) (xy 53.491176 -127.115241) (xy 53.535216 -127.120224)
			(xy 53.579453 -127.117491) (xy 53.601112 -127.112776) (xy 53.628216 -127.106817) (xy 53.68348 -127.101798)
			(xy 53.738888 -127.10484) (xy 53.793271 -127.115879) (xy 53.84548 -127.134681) (xy 53.894414 -127.160849)
			(xy 53.93904 -127.193832) (xy 53.978416 -127.232932) (xy 54.011711 -127.277325) (xy 54.038222 -127.326075)
			(xy 54.057389 -127.378151) (xy 54.068809 -127.432455) (xy 54.07224 -127.48784) (xy 54.067609 -127.543138)
			(xy 54.055015 -127.597182) (xy 54.034723 -127.64883) (xy 54.007162 -127.696993) (xy 53.972912 -127.740654)
			(xy 53.932698 -127.778892) (xy 53.887368 -127.8109) (xy 53.837878 -127.836001) (xy 53.785274 -127.853667)
			(xy 53.730664 -127.863524) (xy 53.675203 -127.865364) (xy 53.620061 -127.859149) (xy 53.566401 -127.845009)
			(xy 53.515356 -127.823244) (xy 53.468004 -127.794312) (xy 53.425343 -127.758824) (xy 53.388275 -127.717529)
			(xy 53.372512 -127.69469) (xy 53.359826 -127.676513) (xy 53.329275 -127.644405) (xy 53.293617 -127.618084)
			(xy 53.253933 -127.59835) (xy 53.211427 -127.585801) (xy 53.167388 -127.580816) (xy 53.123152 -127.583549)
			(xy 53.101494 -127.588264) (xy 53.074411 -127.594317) (xy 53.019142 -127.599339) (xy 52.963729 -127.5963)
			(xy 52.909341 -127.585264) (xy 52.857126 -127.566464) (xy 52.808186 -127.540297) (xy 52.763555 -127.507314)
			(xy 52.724173 -127.468213) (xy 52.690872 -127.423818) (xy 52.664355 -127.375067) (xy 52.645182 -127.322988)
			(xy 52.633757 -127.26868) (xy 52.630321 -127.213291) (xy 40.553535 -127.213291) (xy 40.53749 -127.237543)
			(xy 40.500273 -127.27908) (xy 40.457405 -127.314755) (xy 40.409799 -127.343809) (xy 40.35847 -127.365621)
			(xy 40.304513 -127.379727) (xy 40.249076 -127.385827) (xy 40.193342 -127.38379) (xy 40.138499 -127.37366)
			(xy 40.085715 -127.355653) (xy 40.036115 -127.330152) (xy 39.990757 -127.297701) (xy 39.950608 -127.258992)
			(xy 39.916522 -127.214849) (xy 39.889226 -127.166214) (xy 39.869303 -127.114123) (xy 39.857177 -127.059686)
			(xy 39.853106 -127.004064) (xy 36.021264 -127.004064) (xy 36.021264 -132.251258) (xy 38.674795 -132.251258)
			(xy 38.681325 -132.195368) (xy 38.696183 -132.141095) (xy 38.719032 -132.089672) (xy 38.749352 -132.04227)
			(xy 38.786454 -131.999964) (xy 38.807644 -131.981448) (xy 38.824753 -131.966454) (xy 38.8538 -131.931447)
			(xy 38.876156 -131.891829) (xy 38.891105 -131.848867) (xy 38.898172 -131.80393) (xy 38.89713 -131.758452)
			(xy 38.888013 -131.713886) (xy 38.871111 -131.671653) (xy 38.846965 -131.633102) (xy 38.832028 -131.615942)
			(xy 38.813725 -131.59507) (xy 38.782865 -131.548927) (xy 38.759193 -131.498715) (xy 38.743236 -131.445546)
			(xy 38.735346 -131.390598) (xy 38.735698 -131.335088) (xy 38.744283 -131.280244) (xy 38.760913 -131.227282)
			(xy 38.785219 -131.177374) (xy 38.816661 -131.131626) (xy 38.854545 -131.091051) (xy 38.87597 -131.073398)
			(xy 38.893898 -131.058509) (xy 38.924523 -131.023389) (xy 38.948235 -130.983276) (xy 38.96424 -130.939514)
			(xy 38.972003 -130.893568) (xy 38.971263 -130.846976) (xy 38.962045 -130.8013) (xy 38.944657 -130.758068)
			(xy 38.932612 -130.738118) (xy 38.917424 -130.713124) (xy 38.894202 -130.659449) (xy 38.879647 -130.602807)
			(xy 38.874117 -130.544586) (xy 38.877746 -130.486216) (xy 38.890447 -130.429129) (xy 38.911907 -130.374726)
			(xy 38.926262 -130.349244) (xy 38.933557 -130.335872) (xy 38.942327 -130.306712) (xy 38.943939 -130.276305)
			(xy 38.938302 -130.246382) (xy 38.925737 -130.218646) (xy 38.90696 -130.194675) (xy 38.895274 -130.184906)
			(xy 38.874373 -130.167846) (xy 38.837217 -130.128731) (xy 38.80609 -130.084665) (xy 38.781644 -130.036571)
			(xy 38.76439 -129.985455) (xy 38.754688 -129.932384) (xy 38.752742 -129.878469) (xy 38.758591 -129.824837)
			(xy 38.772114 -129.772609) (xy 38.793028 -129.722878) (xy 38.820896 -129.676682) (xy 38.855134 -129.634989)
			(xy 38.895028 -129.598669) (xy 38.917118 -129.58318) (xy 38.935935 -129.56984) (xy 38.968844 -129.53753)
			(xy 38.995388 -129.499814) (xy 39.014693 -129.457929) (xy 39.026129 -129.41325) (xy 39.029319 -129.36724)
			(xy 39.02416 -129.32141) (xy 39.01082 -129.277262) (xy 38.989736 -129.236243) (xy 38.961601 -129.1997)
			(xy 38.944804 -129.183892) (xy 38.924943 -129.165336) (xy 38.890238 -129.123506) (xy 38.861979 -129.077078)
			(xy 38.840764 -129.027037) (xy 38.827044 -128.974445) (xy 38.82111 -128.920418) (xy 38.823088 -128.866102)
			(xy 38.832935 -128.812649) (xy 38.850443 -128.761194) (xy 38.875241 -128.712828) (xy 38.906802 -128.668578)
			(xy 38.944456 -128.629383) (xy 38.987405 -128.596073) (xy 39.034738 -128.569357) (xy 39.08545 -128.5498)
			(xy 39.138464 -128.537817) (xy 39.192658 -128.533664) (xy 39.246879 -128.537427) (xy 39.299979 -128.549028)
			(xy 39.35083 -128.56822) (xy 39.390566 -128.590273) (xy 41.733968 -128.590273) (xy 41.733968 -128.536975)
			(xy 41.741911 -128.484271) (xy 41.757621 -128.433341) (xy 41.780747 -128.38532) (xy 41.810771 -128.341283)
			(xy 41.847023 -128.302212) (xy 41.888694 -128.268981) (xy 41.934852 -128.242332) (xy 41.984466 -128.22286)
			(xy 42.036428 -128.211) (xy 42.089578 -128.207017) (xy 42.142728 -128.211) (xy 42.19469 -128.22286)
			(xy 42.244304 -128.242332) (xy 42.290462 -128.268981) (xy 42.332133 -128.302212) (xy 42.368385 -128.341283)
			(xy 42.398409 -128.38532) (xy 42.421535 -128.433341) (xy 42.437245 -128.484271) (xy 42.445188 -128.536975)
			(xy 42.445686 -128.563624) (xy 42.445188 -128.590273) (xy 42.437245 -128.642977) (xy 42.421535 -128.693907)
			(xy 42.398409 -128.741928) (xy 42.368385 -128.785965) (xy 42.332133 -128.825036) (xy 42.290462 -128.858267)
			(xy 42.244304 -128.884916) (xy 42.19469 -128.904388) (xy 42.142728 -128.916248) (xy 42.089578 -128.920232)
			(xy 42.036428 -128.916248) (xy 41.984466 -128.904388) (xy 41.934852 -128.884916) (xy 41.888694 -128.858267)
			(xy 41.847023 -128.825036) (xy 41.810771 -128.785965) (xy 41.780747 -128.741928) (xy 41.757621 -128.693907)
			(xy 41.741911 -128.642977) (xy 41.733968 -128.590273) (xy 39.390566 -128.590273) (xy 39.398354 -128.594595)
			(xy 39.441541 -128.627594) (xy 39.479477 -128.666518) (xy 39.511355 -128.71054) (xy 39.5365 -128.758726)
			(xy 39.554378 -128.810053) (xy 39.56461 -128.863434) (xy 39.566978 -128.917734) (xy 39.561433 -128.971803)
			(xy 39.548092 -129.024492) (xy 39.527238 -129.074684) (xy 39.499313 -129.121314) (xy 39.46491 -129.163393)
			(xy 39.42476 -129.200027) (xy 39.402512 -129.215642) (xy 39.383675 -129.228952) (xy 39.350772 -129.261271)
			(xy 39.324236 -129.298992) (xy 39.304936 -129.340881) (xy 39.293505 -129.385562) (xy 39.290318 -129.431572)
			(xy 39.295478 -129.477403) (xy 39.308818 -129.521552) (xy 39.329899 -129.562573) (xy 39.358031 -129.59912)
			(xy 39.374826 -129.61493) (xy 39.395625 -129.634278) (xy 39.431612 -129.678229) (xy 39.446128 -129.702793)
			(xy 43.354488 -129.702793) (xy 43.354488 -129.649495) (xy 43.362431 -129.596791) (xy 43.378141 -129.545861)
			(xy 43.401267 -129.49784) (xy 43.431291 -129.453803) (xy 43.467543 -129.414732) (xy 43.509214 -129.381501)
			(xy 43.555372 -129.354852) (xy 43.604986 -129.33538) (xy 43.656948 -129.32352) (xy 43.710098 -129.319537)
			(xy 43.763248 -129.32352) (xy 43.81521 -129.33538) (xy 43.864824 -129.354852) (xy 43.910982 -129.381501)
			(xy 43.952653 -129.414732) (xy 43.988905 -129.453803) (xy 44.018929 -129.49784) (xy 44.042055 -129.545861)
			(xy 44.057765 -129.596791) (xy 44.065708 -129.649495) (xy 44.066206 -129.676144) (xy 44.065708 -129.702793)
			(xy 44.057765 -129.755497) (xy 44.042055 -129.806427) (xy 44.018929 -129.854448) (xy 43.988905 -129.898485)
			(xy 43.952653 -129.937556) (xy 43.910982 -129.970787) (xy 43.864824 -129.997436) (xy 43.81521 -130.016908)
			(xy 43.763248 -130.028768) (xy 43.710098 -130.032752) (xy 43.656948 -130.028768) (xy 43.604986 -130.016908)
			(xy 43.555372 -129.997436) (xy 43.509214 -129.970787) (xy 43.467543 -129.937556) (xy 43.431291 -129.898485)
			(xy 43.401267 -129.854448) (xy 43.378141 -129.806427) (xy 43.362431 -129.755497) (xy 43.354488 -129.702793)
			(xy 39.446128 -129.702793) (xy 39.460512 -129.727133) (xy 39.481655 -129.779857) (xy 39.494551 -129.835178)
			(xy 39.498902 -129.891816) (xy 39.494607 -129.948458) (xy 39.481765 -130.003792) (xy 39.460674 -130.056537)
			(xy 39.446708 -130.081274) (xy 39.439374 -130.094628) (xy 39.430602 -130.123794) (xy 39.428991 -130.154209)
			(xy 39.434635 -130.184138) (xy 39.437507 -130.190473) (xy 40.87748 -130.190473) (xy 40.87748 -130.137175)
			(xy 40.885423 -130.084471) (xy 40.901133 -130.033541) (xy 40.924259 -129.98552) (xy 40.954283 -129.941483)
			(xy 40.990535 -129.902412) (xy 41.032206 -129.869181) (xy 41.078364 -129.842532) (xy 41.127978 -129.82306)
			(xy 41.17994 -129.8112) (xy 41.23309 -129.807217) (xy 41.28624 -129.8112) (xy 41.338202 -129.82306)
			(xy 41.387816 -129.842532) (xy 41.433974 -129.869181) (xy 41.475645 -129.902412) (xy 41.511897 -129.941483)
			(xy 41.541921 -129.98552) (xy 41.565047 -130.033541) (xy 41.580757 -130.084471) (xy 41.5887 -130.137175)
			(xy 41.589198 -130.163824) (xy 41.5887 -130.190473) (xy 41.580757 -130.243177) (xy 41.565047 -130.294107)
			(xy 41.541921 -130.342128) (xy 41.511897 -130.386165) (xy 41.475645 -130.425236) (xy 41.433974 -130.458467)
			(xy 41.387816 -130.485116) (xy 41.338202 -130.504588) (xy 41.28624 -130.516448) (xy 41.23309 -130.520432)
			(xy 41.17994 -130.516448) (xy 41.127978 -130.504588) (xy 41.078364 -130.485116) (xy 41.032206 -130.458467)
			(xy 40.990535 -130.425236) (xy 40.954283 -130.386165) (xy 40.924259 -130.342128) (xy 40.901133 -130.294107)
			(xy 40.885423 -130.243177) (xy 40.87748 -130.190473) (xy 39.437507 -130.190473) (xy 39.447211 -130.211878)
			(xy 39.466003 -130.235846) (xy 39.477696 -130.245612) (xy 39.499377 -130.263375) (xy 39.53774 -130.304232)
			(xy 39.569551 -130.350375) (xy 39.594092 -130.400761) (xy 39.61081 -130.454255) (xy 39.619327 -130.509649)
			(xy 39.619452 -130.565694) (xy 39.611181 -130.621126) (xy 39.594702 -130.674694) (xy 39.570385 -130.725189)
			(xy 39.53878 -130.771473) (xy 39.500599 -130.812501) (xy 39.478966 -130.83032) (xy 39.461017 -130.845184)
			(xy 39.430398 -130.880311) (xy 39.406692 -130.92043) (xy 39.390691 -130.964195) (xy 39.390479 -130.965448)
			(xy 40.088055 -130.965448) (xy 40.09213 -130.912367) (xy 40.10426 -130.860531) (xy 40.124161 -130.811154)
			(xy 40.151366 -130.765393) (xy 40.185238 -130.724321) (xy 40.224982 -130.688902) (xy 40.269667 -130.659964)
			(xy 40.318246 -130.638186) (xy 40.369579 -130.62408) (xy 40.422465 -130.617974) (xy 40.475663 -130.620013)
			(xy 40.527926 -130.630149) (xy 40.578029 -130.648144) (xy 40.612195 -130.666723) (xy 42.364396 -130.666723)
			(xy 42.364396 -130.613425) (xy 42.372339 -130.560721) (xy 42.388049 -130.509791) (xy 42.411175 -130.46177)
			(xy 42.441199 -130.417733) (xy 42.477451 -130.378662) (xy 42.519122 -130.345431) (xy 42.56528 -130.318782)
			(xy 42.614894 -130.29931) (xy 42.666856 -130.28745) (xy 42.720006 -130.283467) (xy 42.773156 -130.28745)
			(xy 42.825118 -130.29931) (xy 42.874732 -130.318782) (xy 42.92089 -130.345431) (xy 42.962561 -130.378662)
			(xy 42.998813 -130.417733) (xy 43.028837 -130.46177) (xy 43.051963 -130.509791) (xy 43.067673 -130.560721)
			(xy 43.075616 -130.613425) (xy 43.076114 -130.640074) (xy 43.075616 -130.666723) (xy 43.067673 -130.719427)
			(xy 43.051963 -130.770357) (xy 43.028837 -130.818378) (xy 42.998813 -130.862415) (xy 42.962561 -130.901486)
			(xy 42.92089 -130.934717) (xy 42.874732 -130.961366) (xy 42.825118 -130.980838) (xy 42.773156 -130.992698)
			(xy 42.720006 -130.996682) (xy 42.666856 -130.992698) (xy 42.614894 -130.980838) (xy 42.56528 -130.961366)
			(xy 42.519122 -130.934717) (xy 42.477451 -130.901486) (xy 42.441199 -130.862415) (xy 42.411175 -130.818378)
			(xy 42.388049 -130.770357) (xy 42.372339 -130.719427) (xy 42.364396 -130.666723) (xy 40.612195 -130.666723)
			(xy 40.624798 -130.673576) (xy 40.667137 -130.70585) (xy 40.704053 -130.744208) (xy 40.734681 -130.787752)
			(xy 40.758303 -130.835461) (xy 40.774366 -130.886217) (xy 40.782493 -130.93883) (xy 40.783002 -130.965448)
			(xy 40.782493 -130.992066) (xy 40.77931 -131.012671) (xy 43.650398 -131.012671) (xy 43.650398 -130.959373)
			(xy 43.658341 -130.906669) (xy 43.674051 -130.855739) (xy 43.697177 -130.807718) (xy 43.727201 -130.763681)
			(xy 43.763453 -130.72461) (xy 43.805124 -130.691379) (xy 43.851282 -130.66473) (xy 43.900896 -130.645258)
			(xy 43.952858 -130.633398) (xy 44.006008 -130.629415) (xy 44.059158 -130.633398) (xy 44.11112 -130.645258)
			(xy 44.160734 -130.66473) (xy 44.206892 -130.691379) (xy 44.248563 -130.72461) (xy 44.284815 -130.763681)
			(xy 44.314839 -130.807718) (xy 44.337965 -130.855739) (xy 44.353675 -130.906669) (xy 44.361618 -130.959373)
			(xy 44.362116 -130.986022) (xy 44.361618 -131.012671) (xy 44.353675 -131.065375) (xy 44.337965 -131.116305)
			(xy 44.314839 -131.164326) (xy 44.284815 -131.208363) (xy 44.248563 -131.247434) (xy 44.206892 -131.280665)
			(xy 44.160734 -131.307314) (xy 44.11112 -131.326786) (xy 44.059158 -131.338646) (xy 44.006008 -131.34263)
			(xy 43.952858 -131.338646) (xy 43.900896 -131.326786) (xy 43.851282 -131.307314) (xy 43.805124 -131.280665)
			(xy 43.763453 -131.247434) (xy 43.727201 -131.208363) (xy 43.697177 -131.164326) (xy 43.674051 -131.116305)
			(xy 43.658341 -131.065375) (xy 43.650398 -131.012671) (xy 40.77931 -131.012671) (xy 40.774366 -131.044679)
			(xy 40.758303 -131.095435) (xy 40.734681 -131.143144) (xy 40.704053 -131.186688) (xy 40.667137 -131.225046)
			(xy 40.624798 -131.25732) (xy 40.578029 -131.282752) (xy 40.527926 -131.300747) (xy 40.475663 -131.310883)
			(xy 40.422465 -131.312922) (xy 40.369579 -131.306816) (xy 40.318246 -131.29271) (xy 40.269667 -131.270932)
			(xy 40.224982 -131.241994) (xy 40.185238 -131.206575) (xy 40.151366 -131.165503) (xy 40.124161 -131.119742)
			(xy 40.10426 -131.070365) (xy 40.09213 -131.018529) (xy 40.088055 -130.965448) (xy 39.390479 -130.965448)
			(xy 39.382932 -131.010144) (xy 39.383675 -131.056737) (xy 39.392893 -131.102414) (xy 39.41028 -131.145648)
			(xy 39.422324 -131.1656) (xy 39.436221 -131.188484) (xy 39.458123 -131.237335) (xy 39.47281 -131.288816)
			(xy 39.479981 -131.34187) (xy 39.479486 -131.395404) (xy 39.471338 -131.448316) (xy 39.455702 -131.499518)
			(xy 39.432902 -131.547956) (xy 39.403406 -131.592633) (xy 39.367821 -131.632631) (xy 39.347648 -131.650232)
			(xy 39.330558 -131.665246) (xy 39.301511 -131.70025) (xy 39.279156 -131.739864) (xy 39.264205 -131.782823)
			(xy 39.257137 -131.827757) (xy 39.258176 -131.873232) (xy 39.261083 -131.887448) (xy 42.725501 -131.887448)
			(xy 42.72841 -131.83497) (xy 42.738998 -131.783489) (xy 42.757034 -131.734122) (xy 42.782127 -131.687941)
			(xy 42.813733 -131.645948) (xy 42.851166 -131.609054) (xy 42.893613 -131.57806) (xy 42.940153 -131.553639)
			(xy 42.989776 -131.536321) (xy 43.041405 -131.526481) (xy 43.09392 -131.524334) (xy 43.14618 -131.529925)
			(xy 43.197051 -131.543134) (xy 43.24543 -131.563673) (xy 43.290266 -131.591098) (xy 43.330586 -131.624812)
			(xy 43.348402 -131.644136) (xy 43.364018 -131.660902) (xy 43.400106 -131.689123) (xy 43.440663 -131.710427)
			(xy 43.48438 -131.724124) (xy 43.529842 -131.729772) (xy 43.575582 -131.727189) (xy 43.620119 -131.716457)
			(xy 43.641264 -131.707636) (xy 43.665422 -131.697328) (xy 43.716083 -131.683463) (xy 43.768255 -131.677385)
			(xy 43.820747 -131.679233) (xy 43.872362 -131.688964) (xy 43.921923 -131.706357) (xy 43.9683 -131.731016)
			(xy 44.010434 -131.762376) (xy 44.047366 -131.799724) (xy 44.078252 -131.842208) (xy 44.102388 -131.888858)
			(xy 44.119225 -131.938611) (xy 44.128377 -131.990332) (xy 44.129636 -132.042842) (xy 44.122973 -132.094942)
			(xy 44.108541 -132.145445) (xy 44.086668 -132.193198) (xy 44.057853 -132.237113) (xy 44.022754 -132.276188)
			(xy 43.982171 -132.309532) (xy 43.937029 -132.336385) (xy 43.888359 -132.356133) (xy 43.837269 -132.368327)
			(xy 43.784926 -132.372689) (xy 43.732523 -132.369118) (xy 43.681255 -132.357697) (xy 43.632292 -132.338686)
			(xy 43.58675 -132.312518) (xy 43.545668 -132.279791) (xy 43.527472 -132.260848) (xy 43.51156 -132.244357)
			(xy 43.474885 -132.216885) (xy 43.433882 -132.196427) (xy 43.389878 -132.183644) (xy 43.344295 -132.178951)
			(xy 43.298609 -132.182499) (xy 43.254298 -132.194174) (xy 43.23334 -132.203444) (xy 43.20937 -132.214224)
			(xy 43.159018 -132.22929) (xy 43.106998 -132.236796) (xy 43.05444 -132.236577) (xy 43.002485 -132.228639)
			(xy 42.95226 -132.213153) (xy 42.904854 -132.190457) (xy 42.861298 -132.161042) (xy 42.822537 -132.125546)
			(xy 42.789411 -132.084742) (xy 42.762639 -132.039512) (xy 42.742804 -131.990841) (xy 42.730334 -131.939783)
			(xy 42.725501 -131.887448) (xy 39.261083 -131.887448) (xy 39.26729 -131.917796) (xy 39.284187 -131.960027)
			(xy 39.308329 -131.998578) (xy 39.323264 -132.015738) (xy 39.341263 -132.03626) (xy 39.371723 -132.081554)
			(xy 39.395246 -132.130808) (xy 39.411329 -132.182968) (xy 39.419628 -132.236918) (xy 39.419964 -132.2915)
			(xy 39.412331 -132.345547) (xy 39.396891 -132.397902) (xy 39.373977 -132.447442) (xy 39.344077 -132.493108)
			(xy 39.326312 -132.513832) (xy 39.310958 -132.531905) (xy 39.286598 -132.572586) (xy 39.281692 -132.5859)
			(xy 40.084636 -132.5859) (xy 40.084873 -132.532616) (xy 40.093247 -132.479995) (xy 40.109562 -132.42927)
			(xy 40.133434 -132.381632) (xy 40.164303 -132.338201) (xy 40.201445 -132.299995) (xy 40.243987 -132.267912)
			(xy 40.290931 -132.242704) (xy 40.341175 -132.224964) (xy 40.39354 -132.215107) (xy 40.446796 -132.213366)
			(xy 40.499692 -132.21978) (xy 40.550988 -132.2342) (xy 40.599479 -132.256288) (xy 40.644026 -132.285523)
			(xy 40.66413 -132.303012) (xy 40.681666 -132.318185) (xy 40.721168 -132.342469) (xy 40.76442 -132.35918)
			(xy 40.809988 -132.367763) (xy 40.856357 -132.367933) (xy 40.901986 -132.359684) (xy 40.94536 -132.34329)
			(xy 40.985038 -132.319296) (xy 41.002712 -132.304282) (xy 41.022942 -132.286931) (xy 41.067753 -132.258079)
			(xy 41.116445 -132.23641) (xy 41.167876 -132.222435) (xy 41.220839 -132.216482) (xy 41.274089 -132.218689)
			(xy 41.326377 -132.229006) (xy 41.376475 -132.247189) (xy 41.423207 -132.272813) (xy 41.465476 -132.305275)
			(xy 41.502289 -132.343814) (xy 41.532783 -132.387524) (xy 41.556241 -132.43538) (xy 41.572113 -132.486258)
			(xy 41.580025 -132.538964) (xy 41.579793 -132.592259) (xy 41.571421 -132.644893) (xy 41.555107 -132.695631)
			(xy 41.531233 -132.743281) (xy 41.500359 -132.786724) (xy 41.463211 -132.82494) (xy 41.420661 -132.857033)
			(xy 41.373708 -132.882248) (xy 41.323453 -132.899995) (xy 41.271077 -132.909855) (xy 41.21781 -132.911598)
			(xy 41.164901 -132.905183) (xy 41.113594 -132.890761) (xy 41.065092 -132.868669) (xy 41.020535 -132.839427)
			(xy 41.000426 -132.821934) (xy 40.982844 -132.806818) (xy 40.943351 -132.782536) (xy 40.900107 -132.765824)
			(xy 40.854549 -132.757237) (xy 40.808189 -132.75706) (xy 40.762566 -132.765298) (xy 40.719196 -132.781679)
			(xy 40.679519 -132.805658) (xy 40.661844 -132.820664) (xy 40.64157 -132.837956) (xy 40.596764 -132.866794)
			(xy 40.548079 -132.888449) (xy 40.496657 -132.902413) (xy 40.443705 -132.908357) (xy 40.390467 -132.906142)
			(xy 40.338193 -132.89582) (xy 40.288108 -132.877633) (xy 40.24139 -132.852009) (xy 40.199135 -132.819549)
			(xy 40.162334 -132.781014) (xy 40.131852 -132.73731) (xy 40.108405 -132.689462) (xy 40.092542 -132.638594)
			(xy 40.084636 -132.5859) (xy 39.281692 -132.5859) (xy 39.270202 -132.617078) (xy 39.262339 -132.663838)
			(xy 39.263282 -132.711246) (xy 39.272998 -132.757656) (xy 39.29115 -132.801461) (xy 39.317109 -132.841141)
			(xy 39.349974 -132.875321) (xy 39.368984 -132.889498) (xy 39.391463 -132.90611) (xy 39.4318 -132.944802)
			(xy 39.466059 -132.988966) (xy 39.493507 -133.037656) (xy 39.513555 -133.089831) (xy 39.525776 -133.144372)
			(xy 39.529907 -133.200113) (xy 39.52586 -133.25586) (xy 39.513721 -133.31042) (xy 39.493751 -133.362625)
			(xy 39.466376 -133.411356) (xy 39.432183 -133.455571) (xy 39.391905 -133.494324) (xy 39.346402 -133.526784)
			(xy 39.29665 -133.552256) (xy 39.243714 -133.570196) (xy 39.188726 -133.580219) (xy 39.132864 -133.582111)
			(xy 39.077324 -133.575831) (xy 39.023295 -133.561514) (xy 38.971934 -133.539465) (xy 38.92434 -133.510158)
			(xy 38.881531 -133.47422) (xy 38.844426 -133.432419) (xy 38.813817 -133.385651) (xy 38.790361 -133.334918)
			(xy 38.774558 -133.281304) (xy 38.766749 -133.225958) (xy 38.767099 -133.170066) (xy 38.775602 -133.114822)
			(xy 38.792075 -133.061411) (xy 38.816165 -133.010975) (xy 38.847358 -132.964595) (xy 38.86581 -132.9436)
			(xy 38.881363 -132.925703) (xy 38.906232 -132.885341) (xy 38.923189 -132.841069) (xy 38.931648 -132.794421)
			(xy 38.931315 -132.747014) (xy 38.922201 -132.70049) (xy 38.904623 -132.656461) (xy 38.87919 -132.616452)
			(xy 38.846782 -132.58185) (xy 38.827964 -132.567426) (xy 38.805512 -132.550464) (xy 38.765573 -132.510826)
			(xy 38.732047 -132.465633) (xy 38.705697 -132.415914) (xy 38.687121 -132.362799) (xy 38.676742 -132.307494)
			(xy 38.674795 -132.251258) (xy 36.021264 -132.251258) (xy 36.021264 -134.753837) (xy 38.88104 -134.753837)
			(xy 38.88104 -134.700539) (xy 38.888983 -134.647835) (xy 38.904693 -134.596905) (xy 38.927819 -134.548884)
			(xy 38.957843 -134.504847) (xy 38.994095 -134.465776) (xy 39.035766 -134.432545) (xy 39.081924 -134.405896)
			(xy 39.131538 -134.386424) (xy 39.1835 -134.374564) (xy 39.23665 -134.370581) (xy 39.2898 -134.374564)
			(xy 39.341762 -134.386424) (xy 39.391376 -134.405896) (xy 39.437534 -134.432545) (xy 39.479205 -134.465776)
			(xy 39.515457 -134.504847) (xy 39.545481 -134.548884) (xy 39.568607 -134.596905) (xy 39.584317 -134.647835)
			(xy 39.59226 -134.700539) (xy 39.592758 -134.727188) (xy 39.59226 -134.753837) (xy 39.584317 -134.806541)
			(xy 39.568607 -134.857471) (xy 39.545481 -134.905492) (xy 39.515457 -134.949529) (xy 39.479205 -134.9886)
			(xy 39.437534 -135.021831) (xy 39.391376 -135.04848) (xy 39.341762 -135.067952) (xy 39.2898 -135.079812)
			(xy 39.23665 -135.083796) (xy 39.1835 -135.079812) (xy 39.131538 -135.067952) (xy 39.081924 -135.04848)
			(xy 39.035766 -135.021831) (xy 38.994095 -134.9886) (xy 38.957843 -134.949529) (xy 38.927819 -134.905492)
			(xy 38.904693 -134.857471) (xy 38.888983 -134.806541) (xy 38.88104 -134.753837) (xy 36.021264 -134.753837)
			(xy 36.021264 -139.684252) (xy 36.607496 -140.270484)
		)
		(stroke
			(width 0)
			(type solid)
		)
		(fill yes)
		(layer "In7.Cu")
		(net "P0V75_BMC_VTTREF_NODE1")
	)
	(gr_poly
		(pts
			(xy 105.405428 -180.23713) (xy 105.430725 -180.223214) (xy 105.484549 -180.20233) (xy 105.540905 -180.189792)
			(xy 105.598507 -180.185885) (xy 105.65604 -180.190698) (xy 105.712192 -180.204121) (xy 105.765681 -180.225849)
			(xy 105.790746 -180.240178) (xy 105.873042 -180.225954) (xy 107.90428 -178.194716) (xy 107.923584 -178.14417)
			(xy 107.922314 -178.117246) (xy 107.922314 -178.112166) (xy 107.921761 -178.083398) (xy 107.928269 -178.02623)
			(xy 107.943289 -177.970687) (xy 107.966481 -177.918031) (xy 107.997318 -177.869454) (xy 108.0351 -177.826061)
			(xy 108.078972 -177.788834) (xy 108.127937 -177.758618) (xy 108.180884 -177.736098) (xy 108.236613 -177.721787)
			(xy 108.29386 -177.716007) (xy 108.322618 -177.716942) (xy 108.349542 -177.718212) (xy 108.400088 -177.698908)
			(xy 108.603542 -177.495454) (xy 108.603542 -177.390298) (xy 108.333794 -177.12055) (xy 108.259118 -177.103786)
			(xy 108.230743 -177.116201) (xy 108.171051 -177.132715) (xy 108.109478 -177.139393) (xy 108.078524 -177.13833)
			(xy 108.051504 -177.136366) (xy 107.998376 -177.125762) (xy 107.947284 -177.107748) (xy 107.899255 -177.082685)
			(xy 107.855256 -177.051078) (xy 107.816172 -177.013563) (xy 107.782789 -176.970895) (xy 107.75578 -176.923933)
			(xy 107.735688 -176.873621) (xy 107.722917 -176.820973) (xy 107.717725 -176.767047) (xy 107.720216 -176.71293)
			(xy 107.730339 -176.659709) (xy 107.747891 -176.608456) (xy 107.772519 -176.560202) (xy 107.803727 -176.515919)
			(xy 107.840887 -176.476497) (xy 107.883251 -176.442731) (xy 107.929968 -176.415298) (xy 107.954826 -176.404524)
			(xy 107.979645 -176.394809) (xy 108.031267 -176.381553) (xy 108.057696 -176.378108) (xy 108.080249 -176.374576)
			(xy 108.123666 -176.360486) (xy 108.163868 -176.338867) (xy 108.199563 -176.310415) (xy 108.229601 -176.276046)
			(xy 108.253019 -176.236864) (xy 108.269061 -176.19413) (xy 108.277213 -176.149217) (xy 108.27766 -176.126394)
			(xy 108.27766 -176.057306) (xy 108.243878 -176.02327) (xy 108.232431 -176.011756) (xy 108.211322 -175.987083)
			(xy 108.201714 -175.973994) (xy 108.186571 -175.952188) (xy 108.161814 -175.905224) (xy 108.143807 -175.855281)
			(xy 108.132898 -175.803324) (xy 108.129298 -175.750357) (xy 108.133077 -175.697402) (xy 108.14416 -175.645482)
			(xy 108.162335 -175.595601) (xy 108.18725 -175.54872) (xy 108.218424 -175.505747) (xy 108.236512 -175.486314)
			(xy 108.255562 -175.43907) (xy 108.260745 -175.425123) (xy 108.265177 -175.395708) (xy 108.26269 -175.366065)
			(xy 108.253421 -175.337799) (xy 108.23787 -175.312441) (xy 108.227622 -175.301656) (xy 108.22559 -175.299624)
			(xy 108.213187 -175.288019) (xy 108.183669 -175.271236) (xy 108.150771 -175.262829) (xy 108.11682 -175.263394)
			(xy 108.100368 -175.26762) (xy 108.074467 -175.27468) (xy 108.021328 -175.282313) (xy 107.967644 -175.282438)
			(xy 107.91447 -175.275051) (xy 107.888532 -175.268128) (xy 107.860472 -175.259503) (xy 107.807204 -175.234837)
			(xy 107.758344 -175.202302) (xy 107.715044 -175.162667) (xy 107.696254 -175.140112) (xy 107.68124 -175.122252)
			(xy 107.645886 -175.091811) (xy 107.605572 -175.06833) (xy 107.561651 -175.052599) (xy 107.515597 -175.045143)
			(xy 107.468956 -175.046214) (xy 107.423293 -175.055777) (xy 107.380141 -175.073508) (xy 107.340948 -175.098815)
			(xy 107.323636 -175.114458) (xy 107.121452 -175.316388) (xy 106.9594 -175.478694) (xy 106.9594 -175.820324)
			(xy 107.0229 -175.892206) (xy 107.070652 -175.898302) (xy 107.098229 -175.902298) (xy 107.151906 -175.91725)
			(xy 107.202838 -175.93985) (xy 107.249941 -175.969617) (xy 107.292215 -176.005917) (xy 107.32876 -176.04798)
			(xy 107.358799 -176.09491) (xy 107.381694 -176.145709) (xy 107.396958 -176.199299) (xy 107.404266 -176.254538)
			(xy 107.403462 -176.310253) (xy 107.394565 -176.365259) (xy 107.377762 -176.418385) (xy 107.353412 -176.468504)
			(xy 107.322032 -176.514548) (xy 107.284289 -176.555539) (xy 107.26293 -176.573434) (xy 107.241533 -176.590131)
			(xy 107.194929 -176.617944) (xy 107.144853 -176.63887) (xy 107.092316 -176.652487) (xy 107.03838 -176.65852)
			(xy 106.984133 -176.656847) (xy 106.930671 -176.647502) (xy 106.879073 -176.630674) (xy 106.854498 -176.619154)
			(xy 106.842052 -176.613312) (xy 106.811064 -176.605692) (xy 106.795092 -176.602295) (xy 106.762453 -176.602817)
			(xy 106.731009 -176.611584) (xy 106.702808 -176.628024) (xy 106.690922 -176.63922) (xy 105.790238 -177.539904)
			(xy 105.766836 -177.543011) (xy 105.721684 -177.556771) (xy 105.67985 -177.578635) (xy 105.642776 -177.607851)
			(xy 105.611737 -177.643413) (xy 105.587803 -177.684098) (xy 105.571796 -177.728503) (xy 105.564268 -177.775102)
			(xy 105.565478 -177.822289) (xy 105.575385 -177.86844) (xy 105.58399 -177.890424) (xy 105.595208 -177.916244)
			(xy 105.61078 -177.970342) (xy 105.618234 -178.026141) (xy 105.617409 -178.08243) (xy 105.608322 -178.137986)
			(xy 105.591171 -178.191604) (xy 105.566329 -178.242121) (xy 105.534333 -178.288439) (xy 105.495879 -178.329553)
			(xy 105.451802 -178.364572) (xy 105.403058 -178.392733) (xy 105.350705 -178.413428) (xy 105.29588 -178.426205)
			(xy 105.239772 -178.430789) (xy 105.1836 -178.427079) (xy 105.156 -178.421538) (xy 105.12855 -178.415072)
			(xy 105.075793 -178.39515) (xy 105.026543 -178.36768) (xy 104.981872 -178.33326) (xy 104.942753 -178.292641)
			(xy 104.910038 -178.246707) (xy 104.884439 -178.196458) (xy 104.866515 -178.142989) (xy 104.856656 -178.087464)
			(xy 104.855076 -178.031093) (xy 104.861809 -177.975103) (xy 104.876709 -177.920714) (xy 104.899452 -177.86911)
			(xy 104.929542 -177.821416) (xy 104.966324 -177.778669) (xy 104.987344 -177.759868) (xy 105.00455 -177.744331)
			(xy 105.033555 -177.708174) (xy 105.055519 -177.667354) (xy 105.069713 -177.623227) (xy 105.075666 -177.577258)
			(xy 105.073181 -177.530971) (xy 105.062339 -177.485903) (xy 105.043502 -177.443549) (xy 105.017293 -177.405316)
			(xy 105.001314 -177.38852) (xy 104.978976 -177.365365) (xy 104.939714 -177.314394) (xy 104.907194 -177.258879)
			(xy 104.881934 -177.199706) (xy 104.864339 -177.137819) (xy 104.854689 -177.074208) (xy 104.853138 -177.009887)
			(xy 104.859711 -176.945885) (xy 104.874304 -176.883222) (xy 104.896682 -176.8229) (xy 104.911144 -176.79416)
			(xy 104.921036 -176.774219) (xy 104.934448 -176.731778) (xy 104.940262 -176.68765) (xy 104.938299 -176.643184)
			(xy 104.928619 -176.59974) (xy 104.911518 -176.558646) (xy 104.887519 -176.521161) (xy 104.857357 -176.48843)
			(xy 104.821953 -176.461454) (xy 104.782392 -176.441058) (xy 104.761284 -176.433988) (xy 104.737154 -176.42586)
			(xy 104.712835 -176.416298) (xy 104.666855 -176.391468) (xy 104.624694 -176.360595) (xy 104.587142 -176.324256)
			(xy 104.554902 -176.283132) (xy 104.528577 -176.237991) (xy 104.50866 -176.18968) (xy 104.501696 -176.164494)
			(xy 104.49306 -176.13122) (xy 103.86314 -175.5013) (xy 103.86314 -174.448216) (xy 104.068372 -174.243238)
			(xy 104.302306 -174.009304) (xy 104.368092 -174.009304) (xy 104.383803 -174.008101) (xy 104.413958 -173.998991)
			(xy 104.440979 -173.9828) (xy 104.45242 -173.971966) (xy 105.036366 -173.38802) (xy 105.998264 -173.38802)
			(xy 106.935778 -172.450506) (xy 106.946019 -172.439705) (xy 106.961623 -172.414367) (xy 106.970922 -172.3861)
			(xy 106.973409 -172.356447) (xy 106.968949 -172.327026) (xy 106.963718 -172.313092) (xy 106.954048 -172.287876)
			(xy 106.941103 -172.235446) (xy 106.935678 -172.181714) (xy 106.937884 -172.127754) (xy 106.947675 -172.074645)
			(xy 106.964856 -172.023446) (xy 106.989084 -171.975181) (xy 107.019875 -171.930813) (xy 107.056613 -171.89123)
			(xy 107.098565 -171.857222) (xy 107.144892 -171.829468) (xy 107.19467 -171.808523) (xy 107.246904 -171.794805)
			(xy 107.300549 -171.788589) (xy 107.354536 -171.789997) (xy 107.407784 -171.799003) (xy 107.433618 -171.80687)
			(xy 107.443016 -171.809918) (xy 107.461558 -171.816776) (xy 107.486704 -171.821602) (xy 107.501936 -171.823939)
			(xy 107.532687 -171.822116) (xy 107.562111 -171.812992) (xy 107.588499 -171.797097) (xy 107.599734 -171.78655)
			(xy 107.85602 -171.530264) (xy 107.87204 -171.513506) (xy 107.898318 -171.475319) (xy 107.917242 -171.433003)
			(xy 107.928184 -171.387958) (xy 107.930782 -171.341676) (xy 107.924949 -171.295689) (xy 107.91088 -171.251521)
			(xy 107.88904 -171.210633) (xy 107.860151 -171.17438) (xy 107.825172 -171.143963) (xy 107.805474 -171.131738)
			(xy 107.781859 -171.118421) (xy 107.738309 -171.086134) (xy 107.699768 -171.048007) (xy 107.667013 -171.004808)
			(xy 107.640703 -170.957407) (xy 107.621369 -170.906759) (xy 107.6094 -170.853883) (xy 107.605037 -170.799846)
			(xy 107.608368 -170.745735) (xy 107.619325 -170.692641) (xy 107.637689 -170.641632) (xy 107.663089 -170.593738)
			(xy 107.695014 -170.549921) (xy 107.73282 -170.511065) (xy 107.775746 -170.477953) (xy 107.799124 -170.464226)
			(xy 107.824225 -170.450625) (xy 107.87754 -170.430213) (xy 107.933301 -170.417973) (xy 107.990264 -170.414179)
			(xy 108.047156 -170.418916) (xy 108.102706 -170.432077) (xy 108.155676 -170.45337) (xy 108.204881 -170.482318)
			(xy 108.249222 -170.518275) (xy 108.287711 -170.560439) (xy 108.319487 -170.607867) (xy 108.34384 -170.659501)
			(xy 108.360227 -170.714187) (xy 108.368283 -170.770704) (xy 108.368592 -170.799252) (xy 108.368592 -170.80484)
			(xy 108.36914 -170.821485) (xy 108.377764 -170.85364) (xy 108.394415 -170.882467) (xy 108.417958 -170.906004)
			(xy 108.44679 -170.922648) (xy 108.478947 -170.931264) (xy 108.495592 -170.93184) (xy 109.344968 -170.93184)
			(xy 109.417104 -170.859704) (xy 112.538002 -170.859704) (xy 112.610138 -170.93184) (xy 113.186972 -170.93184)
			(xy 113.242852 -170.901868) (xy 113.260632 -170.874944) (xy 113.275849 -170.852754) (xy 113.311525 -170.812479)
			(xy 113.352506 -170.777617) (xy 113.397979 -170.748858) (xy 113.447043 -170.726775) (xy 113.498722 -170.711805)
			(xy 113.551992 -170.704245) (xy 113.605796 -170.704245) (xy 113.659066 -170.711805) (xy 113.710745 -170.726775)
			(xy 113.759809 -170.748858) (xy 113.805282 -170.777617) (xy 113.846263 -170.812479) (xy 113.881939 -170.852754)
			(xy 113.897156 -170.874944) (xy 113.906195 -170.887762) (xy 113.92936 -170.908894) (xy 113.956985 -170.923728)
			(xy 113.987396 -170.931367) (xy 114.003074 -170.93184) (xy 116.30025 -170.93184) (xy 116.332 -170.911266)
			(xy 116.355348 -170.896626) (xy 116.405365 -170.873491) (xy 116.458191 -170.857794) (xy 116.512726 -170.849863)
			(xy 116.567834 -170.849863) (xy 116.622369 -170.857794) (xy 116.675195 -170.873491) (xy 116.725212 -170.896626)
			(xy 116.74856 -170.911266) (xy 116.78031 -170.93184) (xy 119.413528 -170.93184) (xy 119.445786 -170.964098)
			(xy 122.147074 -170.964098) (xy 122.151145 -170.908476) (xy 122.163271 -170.854039) (xy 122.183194 -170.801948)
			(xy 122.21049 -170.753313) (xy 122.244576 -170.70917) (xy 122.284725 -170.670461) (xy 122.330083 -170.63801)
			(xy 122.379683 -170.612509) (xy 122.432467 -170.594502) (xy 122.48731 -170.584372) (xy 122.543044 -170.582335)
			(xy 122.598481 -170.588435) (xy 122.652438 -170.602541) (xy 122.703767 -170.624353) (xy 122.751373 -170.653407)
			(xy 122.794241 -170.689082) (xy 122.831458 -170.730619) (xy 122.862231 -170.777132) (xy 122.885903 -170.827629)
			(xy 122.901971 -170.881036) (xy 122.910091 -170.936212) (xy 122.9106 -170.964098) (xy 122.910091 -170.991984)
			(xy 122.901971 -171.04716) (xy 122.885903 -171.100567) (xy 122.862231 -171.151064) (xy 122.831458 -171.197577)
			(xy 122.794241 -171.239114) (xy 122.751373 -171.274789) (xy 122.703767 -171.303843) (xy 122.652438 -171.325655)
			(xy 122.598481 -171.339761) (xy 122.543044 -171.345861) (xy 122.48731 -171.343824) (xy 122.432467 -171.333694)
			(xy 122.379683 -171.315687) (xy 122.330083 -171.290186) (xy 122.284725 -171.257735) (xy 122.244576 -171.219026)
			(xy 122.21049 -171.174883) (xy 122.183194 -171.126248) (xy 122.163271 -171.074157) (xy 122.151145 -171.01972)
			(xy 122.147074 -170.964098) (xy 119.445786 -170.964098) (xy 119.89054 -171.408852) (xy 119.89054 -171.971716)
			(xy 121.373898 -171.971716) (xy 121.377969 -171.916094) (xy 121.390095 -171.861657) (xy 121.410018 -171.809566)
			(xy 121.437314 -171.760931) (xy 121.4714 -171.716788) (xy 121.511549 -171.678079) (xy 121.556907 -171.645628)
			(xy 121.606507 -171.620127) (xy 121.659291 -171.60212) (xy 121.714134 -171.59199) (xy 121.769868 -171.589953)
			(xy 121.825305 -171.596053) (xy 121.879262 -171.610159) (xy 121.930591 -171.631971) (xy 121.978197 -171.661025)
			(xy 122.021065 -171.6967) (xy 122.058282 -171.738237) (xy 122.089055 -171.78475) (xy 122.112727 -171.835247)
			(xy 122.128795 -171.888654) (xy 122.136915 -171.94383) (xy 122.137424 -171.971716) (xy 122.136915 -171.999602)
			(xy 122.128795 -172.054778) (xy 122.112727 -172.108185) (xy 122.089055 -172.158682) (xy 122.058282 -172.205195)
			(xy 122.021065 -172.246732) (xy 121.978197 -172.282407) (xy 121.930591 -172.311461) (xy 121.879262 -172.333273)
			(xy 121.825305 -172.347379) (xy 121.769868 -172.353479) (xy 121.714134 -172.351442) (xy 121.659291 -172.341312)
			(xy 121.606507 -172.323305) (xy 121.556907 -172.297804) (xy 121.511549 -172.265353) (xy 121.4714 -172.226644)
			(xy 121.437314 -172.182501) (xy 121.410018 -172.133866) (xy 121.390095 -172.081775) (xy 121.377969 -172.027338)
			(xy 121.373898 -171.971716) (xy 119.89054 -171.971716) (xy 119.89054 -172.611796) (xy 119.89108 -172.628413)
			(xy 119.899674 -172.660516) (xy 119.916278 -172.689305) (xy 119.927624 -172.701458) (xy 121.689876 -174.463456)
			(xy 121.790714 -174.463456) (xy 121.807365 -174.46296) (xy 121.839532 -174.454335) (xy 121.86837 -174.437678)
			(xy 121.891914 -174.414124) (xy 121.908558 -174.385279) (xy 121.917167 -174.353108) (xy 121.917714 -174.336456)
			(xy 121.917714 -174.302674) (xy 121.8946 -174.262034) (xy 121.88825 -174.24908) (xy 121.876906 -174.224569)
			(xy 121.860469 -174.173122) (xy 121.851461 -174.11987) (xy 121.85006 -174.065879) (xy 121.856295 -174.012231)
			(xy 121.870041 -173.96) (xy 121.891022 -173.910233) (xy 121.918819 -173.863926) (xy 121.935494 -173.84268)
			(xy 121.953081 -173.821757) (xy 121.99323 -173.784668) (xy 122.038259 -173.753687) (xy 122.087247 -173.729446)
			(xy 122.139193 -173.712443) (xy 122.193033 -173.703024) (xy 122.247666 -173.701382) (xy 122.301975 -173.707551)
			(xy 122.354848 -173.721404) (xy 122.405204 -173.742659) (xy 122.452012 -173.77088) (xy 122.473466 -173.787816)
			(xy 122.495999 -173.806991) (xy 122.535434 -173.851095) (xy 122.567586 -173.90076) (xy 122.591683 -173.954795)
			(xy 122.607148 -174.011902) (xy 122.61361 -174.070712) (xy 122.610912 -174.129814) (xy 122.605546 -174.15891)
			(xy 122.601537 -174.181069) (xy 122.600485 -174.226083) (xy 122.607381 -174.270578) (xy 122.622008 -174.313163)
			(xy 122.643909 -174.352504) (xy 122.672399 -174.387371) (xy 122.706587 -174.416672) (xy 122.745403 -174.439492)
			(xy 122.787632 -174.455116) (xy 122.831953 -174.463055) (xy 122.854466 -174.463456) (xy 122.940318 -174.463456)
			(xy 123.533154 -175.056292) (xy 124.145548 -175.056292) (xy 124.168763 -175.055806) (xy 124.214429 -175.04743)
			(xy 124.257811 -175.030891) (xy 124.297464 -175.006742) (xy 124.332067 -174.975787) (xy 124.360466 -174.939058)
			(xy 124.381715 -174.897778) (xy 124.395106 -174.853323) (xy 124.400193 -174.807174) (xy 124.396806 -174.76087)
			(xy 124.39142 -174.738284) (xy 124.383684 -174.711291) (xy 124.375308 -174.655769) (xy 124.375161 -174.599618)
			(xy 124.383248 -174.544053) (xy 124.399392 -174.490274) (xy 124.423246 -174.439442) (xy 124.454294 -174.392656)
			(xy 124.491865 -174.350927) (xy 124.535147 -174.315156) (xy 124.583205 -174.286117) (xy 124.635001 -174.264437)
			(xy 124.689416 -174.250583) (xy 124.717302 -174.247302) (xy 124.748591 -174.244691) (xy 124.811255 -174.248529)
			(xy 124.87244 -174.262601) (xy 124.901706 -174.273972) (xy 124.922846 -174.282146) (xy 124.967144 -174.29171)
			(xy 125.012437 -174.293267) (xy 125.057288 -174.286767) (xy 125.100275 -174.272417) (xy 125.140036 -174.250672)
			(xy 125.175311 -174.22222) (xy 125.204982 -174.187964) (xy 125.228107 -174.148989) (xy 125.243955 -174.106531)
			(xy 125.252022 -174.061935) (xy 125.25248 -174.039276) (xy 125.25248 -173.222412) (xy 125.252004 -173.199983)
			(xy 125.24413 -173.155822) (xy 125.228625 -173.113729) (xy 125.20597 -173.075012) (xy 125.176869 -173.040875)
			(xy 125.142227 -173.012377) (xy 125.103119 -172.990405) (xy 125.060761 -172.97564) (xy 125.016468 -172.968542)
			(xy 124.971617 -172.96933) (xy 124.927602 -172.977982) (xy 124.906532 -172.985684) (xy 124.88071 -172.995719)
			(xy 124.826944 -173.00907) (xy 124.771813 -173.014505) (xy 124.716476 -173.011909) (xy 124.662096 -173.001337)
			(xy 124.609816 -172.983011) (xy 124.560737 -172.957317) (xy 124.51589 -172.924794) (xy 124.476218 -172.886128)
			(xy 124.442555 -172.84213) (xy 124.41561 -172.793726) (xy 124.395949 -172.741934) (xy 124.383984 -172.687843)
			(xy 124.379969 -172.632591) (xy 124.383987 -172.577339) (xy 124.395954 -172.523248) (xy 124.415618 -172.471457)
			(xy 124.442565 -172.423055) (xy 124.47623 -172.379059) (xy 124.515904 -172.340394) (xy 124.560753 -172.307874)
			(xy 124.609833 -172.282182) (xy 124.662113 -172.263859) (xy 124.716494 -172.253289) (xy 124.771832 -172.250696)
			(xy 124.826962 -172.256133) (xy 124.880727 -172.269486) (xy 124.906532 -172.279564) (xy 124.92761 -172.28724)
			(xy 124.971624 -172.295889) (xy 125.016472 -172.296677) (xy 125.060762 -172.289579) (xy 125.103118 -172.274816)
			(xy 125.142225 -172.252847) (xy 125.176867 -172.224353) (xy 125.205969 -172.190221) (xy 125.228628 -172.151509)
			(xy 125.244138 -172.109421) (xy 125.252019 -172.065263) (xy 125.25248 -172.042836) (xy 125.25248 -172.036994)
			(xy 125.252039 -172.021809) (xy 125.244857 -171.9923) (xy 125.230903 -171.965325) (xy 125.210967 -171.942414)
			(xy 125.186179 -171.924866) (xy 125.172216 -171.918884) (xy 125.071632 -171.87926) (xy 124.983748 -171.90847)
			(xy 124.969016 -171.91863) (xy 124.945719 -171.933956) (xy 124.895582 -171.958369) (xy 124.842425 -171.97522)
			(xy 124.787381 -171.984151) (xy 124.731622 -171.984971) (xy 124.676339 -171.977663) (xy 124.622709 -171.962382)
			(xy 124.571876 -171.939455) (xy 124.524924 -171.909369) (xy 124.482853 -171.872768) (xy 124.446561 -171.83043)
			(xy 124.41682 -171.783258) (xy 124.394266 -171.732258) (xy 124.379379 -171.678518) (xy 124.375418 -171.650914)
			(xy 124.37254 -171.624308) (xy 124.373375 -171.570799) (xy 124.381679 -171.517932) (xy 124.397289 -171.466744)
			(xy 124.419899 -171.41824) (xy 124.449065 -171.373371) (xy 124.484215 -171.333017) (xy 124.524659 -171.297972)
			(xy 124.569603 -171.268922) (xy 124.618166 -171.246437) (xy 124.669394 -171.230959) (xy 124.722282 -171.222792)
			(xy 124.775793 -171.222095) (xy 124.828876 -171.228883) (xy 124.88049 -171.243021) (xy 124.905262 -171.25315)
			(xy 124.926357 -171.260957) (xy 124.970448 -171.269846) (xy 125.015414 -171.270834) (xy 125.059852 -171.263891)
			(xy 125.102374 -171.249233) (xy 125.141651 -171.227319) (xy 125.176458 -171.198833) (xy 125.205706 -171.164664)
			(xy 125.228482 -171.12588) (xy 125.244075 -171.083692) (xy 125.251998 -171.039419) (xy 125.25248 -171.01693)
			(xy 125.25248 -169.439844) (xy 125.137164 -169.315892) (xy 125.095508 -169.308272) (xy 125.067482 -169.302667)
			(xy 125.013399 -169.284187) (xy 124.962675 -169.25785) (xy 124.916445 -169.224245) (xy 124.875742 -169.184123)
			(xy 124.841475 -169.138381) (xy 124.814412 -169.088042) (xy 124.795155 -169.03423) (xy 124.784137 -168.978148)
			(xy 124.782326 -168.949624) (xy 124.780873 -168.92753) (xy 124.771288 -168.884308) (xy 124.754356 -168.843401)
			(xy 124.730591 -168.806048) (xy 124.70071 -168.77338) (xy 124.66562 -168.746385) (xy 124.626382 -168.725881)
			(xy 124.584184 -168.712488) (xy 124.540303 -168.706612) (xy 124.518166 -168.707054) (xy 124.489995 -168.708593)
			(xy 124.433739 -168.704354) (xy 124.37872 -168.691877) (xy 124.326138 -168.671435) (xy 124.277139 -168.643474)
			(xy 124.232791 -168.608602) (xy 124.194062 -168.56758) (xy 124.161795 -168.521303) (xy 124.136693 -168.470778)
			(xy 124.119305 -168.417109) (xy 124.11001 -168.361464) (xy 124.109009 -168.305057) (xy 124.116325 -168.249117)
			(xy 124.131798 -168.194865) (xy 124.15509 -168.143482) (xy 124.185695 -168.096089) (xy 124.203968 -168.074594)
			(xy 124.218314 -168.056152) (xy 124.240718 -168.015157) (xy 124.255258 -167.97076) (xy 124.261447 -167.924454)
			(xy 124.259076 -167.877797) (xy 124.248225 -167.832357) (xy 124.229259 -167.789662) (xy 124.202815 -167.751149)
			(xy 124.186696 -167.734234) (xy 122.898154 -166.445692) (xy 122.684286 -166.445692) (xy 122.575066 -166.510462)
			(xy 122.55881 -166.535608) (xy 122.543091 -166.559012) (xy 122.505868 -166.601354) (xy 122.462819 -166.637758)
			(xy 122.414883 -166.66743) (xy 122.363102 -166.689726) (xy 122.308603 -166.70416) (xy 122.252574 -166.710416)
			(xy 122.196235 -166.70836) (xy 122.140811 -166.698037) (xy 122.087509 -166.679669) (xy 122.037491 -166.653659)
			(xy 121.991844 -166.620571) (xy 121.951564 -166.581127) (xy 121.917526 -166.536185) (xy 121.90349 -166.511732)
			(xy 121.894847 -166.497046) (xy 121.871185 -166.472545) (xy 121.841876 -166.455189) (xy 121.809016 -166.446219)
			(xy 121.791984 -166.445692) (xy 119.517668 -166.445692) (xy 119.393208 -166.570152) (xy 119.388382 -166.614602)
			(xy 119.384969 -166.641373) (xy 119.371571 -166.693652) (xy 119.35094 -166.743521) (xy 119.323489 -166.789985)
			(xy 119.289764 -166.832118) (xy 119.250439 -166.869079) (xy 119.206298 -166.900129) (xy 119.158223 -166.924651)
			(xy 119.107172 -166.942153) (xy 119.054164 -166.952288) (xy 119.000257 -166.954853) (xy 118.946527 -166.949796)
			(xy 118.894045 -166.937219) (xy 118.843858 -166.917373) (xy 118.820184 -166.904416) (xy 118.793693 -166.904427)
			(xy 118.741107 -166.898017) (xy 118.689913 -166.884393) (xy 118.641097 -166.863817) (xy 118.595598 -166.836684)
			(xy 118.554291 -166.803516) (xy 118.51797 -166.764952) (xy 118.487335 -166.721734) (xy 118.462974 -166.674692)
			(xy 118.445357 -166.624732) (xy 118.439692 -166.598854) (xy 118.43131 -166.55796) (xy 118.307612 -166.445692)
			(xy 117.839744 -166.445692) (xy 117.789198 -166.46906) (xy 117.77091 -166.490904) (xy 117.752141 -166.512327)
			(xy 117.709344 -166.549906) (xy 117.661432 -166.580698) (xy 117.609472 -166.604018) (xy 117.55462 -166.619347)
			(xy 117.498098 -166.626344) (xy 117.441163 -166.624852) (xy 117.413024 -166.620444) (xy 117.384914 -166.624834)
			(xy 117.328039 -166.626219) (xy 117.271588 -166.619144) (xy 117.216814 -166.603765) (xy 117.164931 -166.580424)
			(xy 117.117088 -166.549638) (xy 117.074346 -166.51209) (xy 117.055646 -166.49065) (xy 117.043242 -166.476934)
			(xy 117.012295 -166.456717) (xy 116.976848 -166.446232) (xy 116.958364 -166.445692) (xy 114.040666 -166.445692)
			(xy 114.01859 -166.446161) (xy 113.975101 -166.45378) (xy 113.933584 -166.468801) (xy 113.895287 -166.490772)
			(xy 113.861364 -166.519031) (xy 113.832836 -166.552728) (xy 113.810561 -166.590849) (xy 113.795209 -166.632245)
			(xy 113.787244 -166.675672) (xy 113.786904 -166.719822) (xy 113.794199 -166.763367) (xy 113.808911 -166.804995)
			(xy 113.819432 -166.824406) (xy 113.832745 -166.84906) (xy 113.852795 -166.901379) (xy 113.864979 -166.956067)
			(xy 113.869036 -167.011948) (xy 113.864877 -167.067823) (xy 113.852593 -167.122488) (xy 113.832448 -167.17477)
			(xy 113.804874 -167.223544) (xy 113.770464 -167.267762) (xy 113.729959 -167.306473) (xy 113.684228 -167.338845)
			(xy 113.634255 -167.364182) (xy 113.60785 -167.373554) (xy 113.586183 -167.381332) (xy 113.545875 -167.403562)
			(xy 113.510229 -167.432687) (xy 113.480409 -167.467753) (xy 113.465134 -167.494204) (xy 121.259852 -167.494204)
			(xy 121.263923 -167.438582) (xy 121.276049 -167.384145) (xy 121.295972 -167.332054) (xy 121.323268 -167.283419)
			(xy 121.357354 -167.239276) (xy 121.397503 -167.200567) (xy 121.442861 -167.168116) (xy 121.492461 -167.142615)
			(xy 121.545245 -167.124608) (xy 121.600088 -167.114478) (xy 121.655822 -167.112441) (xy 121.711259 -167.118541)
			(xy 121.765216 -167.132647) (xy 121.816545 -167.154459) (xy 121.864151 -167.183513) (xy 121.907019 -167.219188)
			(xy 121.944236 -167.260725) (xy 121.975009 -167.307238) (xy 121.998681 -167.357735) (xy 122.014749 -167.411142)
			(xy 122.022869 -167.466318) (xy 122.023378 -167.494204) (xy 122.022869 -167.52209) (xy 122.014749 -167.577266)
			(xy 121.998681 -167.630673) (xy 121.975009 -167.68117) (xy 121.944236 -167.727683) (xy 121.942008 -167.73017)
			(xy 122.731782 -167.73017) (xy 122.735853 -167.674548) (xy 122.747979 -167.620111) (xy 122.767902 -167.56802)
			(xy 122.795198 -167.519385) (xy 122.829284 -167.475242) (xy 122.869433 -167.436533) (xy 122.914791 -167.404082)
			(xy 122.964391 -167.378581) (xy 123.017175 -167.360574) (xy 123.072018 -167.350444) (xy 123.127752 -167.348407)
			(xy 123.183189 -167.354507) (xy 123.237146 -167.368613) (xy 123.288475 -167.390425) (xy 123.336081 -167.419479)
			(xy 123.378949 -167.455154) (xy 123.416166 -167.496691) (xy 123.446939 -167.543204) (xy 123.470611 -167.593701)
			(xy 123.486679 -167.647108) (xy 123.494799 -167.702284) (xy 123.495308 -167.73017) (xy 123.494799 -167.758056)
			(xy 123.486679 -167.813232) (xy 123.470611 -167.866639) (xy 123.446939 -167.917136) (xy 123.416166 -167.963649)
			(xy 123.378949 -168.005186) (xy 123.336081 -168.040861) (xy 123.288475 -168.069915) (xy 123.237146 -168.091727)
			(xy 123.183189 -168.105833) (xy 123.127752 -168.111933) (xy 123.072018 -168.109896) (xy 123.017175 -168.099766)
			(xy 122.964391 -168.081759) (xy 122.914791 -168.056258) (xy 122.869433 -168.023807) (xy 122.829284 -167.985098)
			(xy 122.795198 -167.940955) (xy 122.767902 -167.89232) (xy 122.747979 -167.840229) (xy 122.735853 -167.785792)
			(xy 122.731782 -167.73017) (xy 121.942008 -167.73017) (xy 121.907019 -167.76922) (xy 121.864151 -167.804895)
			(xy 121.816545 -167.833949) (xy 121.765216 -167.855761) (xy 121.711259 -167.869867) (xy 121.655822 -167.875967)
			(xy 121.600088 -167.87393) (xy 121.545245 -167.8638) (xy 121.492461 -167.845793) (xy 121.442861 -167.820292)
			(xy 121.397503 -167.787841) (xy 121.357354 -167.749132) (xy 121.323268 -167.704989) (xy 121.295972 -167.656354)
			(xy 121.276049 -167.604263) (xy 121.263923 -167.549826) (xy 121.259852 -167.494204) (xy 113.465134 -167.494204)
			(xy 113.45739 -167.507615) (xy 113.441923 -167.55097) (xy 113.434514 -167.596401) (xy 113.435406 -167.642424)
			(xy 113.444569 -167.687534) (xy 113.452656 -167.709088) (xy 113.46249 -167.73488) (xy 113.475468 -167.788532)
			(xy 113.48058 -167.843493) (xy 113.47791 -167.894913) (xy 117.225193 -167.894913) (xy 117.230005 -167.839172)
			(xy 117.242908 -167.784732) (xy 117.263626 -167.732761) (xy 117.291714 -167.684374) (xy 117.32657 -167.64061)
			(xy 117.367445 -167.602408) (xy 117.413463 -167.570587) (xy 117.463636 -167.54583) (xy 117.516888 -167.528669)
			(xy 117.572075 -167.519471) (xy 117.628014 -167.518435) (xy 117.683504 -167.525582) (xy 117.737355 -167.540759)
			(xy 117.78841 -167.563641) (xy 117.835575 -167.593735) (xy 117.877838 -167.630397) (xy 117.91429 -167.67284)
			(xy 117.944152 -167.720154) (xy 117.96678 -167.771322) (xy 117.981691 -167.825247) (xy 117.988564 -167.880771)
			(xy 117.987251 -167.936704) (xy 117.983 -167.964358) (xy 117.980891 -167.979095) (xy 117.982758 -168.008799)
			(xy 117.991462 -168.03726) (xy 118.006526 -168.062928) (xy 118.027131 -168.084403) (xy 118.052154 -168.100517)
			(xy 118.066058 -168.105836) (xy 118.092273 -168.115616) (xy 118.141796 -168.141648) (xy 118.186985 -168.174636)
			(xy 118.22687 -168.213872) (xy 118.260595 -168.258514) (xy 118.287436 -168.307604) (xy 118.306818 -168.360088)
			(xy 118.318324 -168.414841) (xy 118.321707 -168.470687) (xy 118.316896 -168.526428) (xy 118.303993 -168.580869)
			(xy 118.283274 -168.63284) (xy 118.255186 -168.681227) (xy 118.22033 -168.724991) (xy 118.179454 -168.763194)
			(xy 118.133436 -168.795015) (xy 118.083262 -168.819771) (xy 118.030011 -168.836932) (xy 117.974823 -168.846129)
			(xy 117.918884 -168.847165) (xy 117.863394 -168.840018) (xy 117.809543 -168.824841) (xy 117.758487 -168.801959)
			(xy 117.711322 -168.771864) (xy 117.66906 -168.735201) (xy 117.632607 -168.692758) (xy 117.602746 -168.645444)
			(xy 117.580118 -168.594275) (xy 117.565208 -168.54035) (xy 117.558336 -168.484825) (xy 117.559649 -168.428892)
			(xy 117.5639 -168.401238) (xy 117.566013 -168.386501) (xy 117.564145 -168.356798) (xy 117.55544 -168.328336)
			(xy 117.540375 -168.302668) (xy 117.519769 -168.281192) (xy 117.494746 -168.265079) (xy 117.480842 -168.25976)
			(xy 117.454626 -168.249983) (xy 117.405103 -168.223951) (xy 117.359914 -168.190963) (xy 117.32003 -168.151727)
			(xy 117.286305 -168.107085) (xy 117.259464 -168.057996) (xy 117.240083 -168.005512) (xy 117.228577 -167.950759)
			(xy 117.225193 -167.894913) (xy 113.47791 -167.894913) (xy 113.477718 -167.898617) (xy 113.466943 -167.952754)
			(xy 113.44848 -168.004773) (xy 113.422713 -168.053589) (xy 113.390181 -168.098182) (xy 113.351562 -168.137621)
			(xy 113.307663 -168.171085) (xy 113.259401 -168.197873) (xy 113.207782 -168.217427) (xy 113.153884 -168.229339)
			(xy 113.098832 -168.23336) (xy 113.043775 -168.229406) (xy 112.989863 -168.217559) (xy 112.93822 -168.198068)
			(xy 112.889925 -168.171338) (xy 112.845986 -168.137928) (xy 112.807319 -168.098535) (xy 112.774733 -168.053982)
			(xy 112.748907 -168.005198) (xy 112.73038 -167.953201) (xy 112.719539 -167.899077) (xy 112.716611 -167.843956)
			(xy 112.721656 -167.788989) (xy 112.734569 -167.735322) (xy 112.75508 -167.684076) (xy 112.782762 -167.63632)
			(xy 112.817037 -167.593052) (xy 112.857189 -167.555175) (xy 112.90238 -167.523478) (xy 112.951666 -167.498624)
			(xy 112.977676 -167.489378) (xy 112.999343 -167.481599) (xy 113.039651 -167.459366) (xy 113.075297 -167.430241)
			(xy 113.105119 -167.395174) (xy 113.12814 -167.355312) (xy 113.14361 -167.311958) (xy 113.151023 -167.266526)
			(xy 113.150136 -167.220502) (xy 113.140979 -167.17539) (xy 113.13287 -167.153844) (xy 113.122746 -167.127234)
			(xy 113.109606 -167.071839) (xy 113.104844 -167.015106) (xy 113.108564 -166.958296) (xy 113.120685 -166.902669)
			(xy 113.140938 -166.84946) (xy 113.15446 -166.824406) (xy 113.164883 -166.804949) (xy 113.179584 -166.763333)
			(xy 113.186873 -166.719804) (xy 113.186531 -166.675669) (xy 113.178569 -166.632258) (xy 113.163225 -166.590875)
			(xy 113.140961 -166.552766) (xy 113.112447 -166.519077) (xy 113.078542 -166.490822) (xy 113.040264 -166.46885)
			(xy 112.998765 -166.453823) (xy 112.955294 -166.446193) (xy 112.933226 -166.445692) (xy 109.801152 -166.445692)
			(xy 109.779099 -166.44616) (xy 109.735656 -166.453772) (xy 109.694182 -166.468776) (xy 109.655923 -166.490721)
			(xy 109.622032 -166.518946) (xy 109.593528 -166.552603) (xy 109.571268 -166.590678) (xy 109.555922 -166.632027)
			(xy 109.547951 -166.675406) (xy 109.547595 -166.71951) (xy 109.550708 -166.741348) (xy 109.554766 -166.768668)
			(xy 109.555897 -166.823888) (xy 109.549057 -166.878695) (xy 109.534386 -166.931943) (xy 109.512193 -166.982519)
			(xy 109.482941 -167.029369) (xy 109.447241 -167.071511) (xy 109.405838 -167.108068) (xy 109.359598 -167.138273)
			(xy 109.309487 -167.161498) (xy 109.256551 -167.177256) (xy 109.201896 -167.185218) (xy 109.146664 -167.185218)
			(xy 109.092009 -167.177256) (xy 109.039073 -167.161498) (xy 108.988962 -167.138273) (xy 108.942722 -167.108068)
			(xy 108.901319 -167.071511) (xy 108.865619 -167.029369) (xy 108.836367 -166.982519) (xy 108.814174 -166.931943)
			(xy 108.799503 -166.878695) (xy 108.792663 -166.823888) (xy 108.793794 -166.768668) (xy 108.797852 -166.741348)
			(xy 108.801002 -166.719517) (xy 108.800613 -166.675415) (xy 108.792619 -166.632042) (xy 108.777258 -166.590699)
			(xy 108.754993 -166.552628) (xy 108.72649 -166.518971) (xy 108.692607 -166.490739) (xy 108.654359 -166.468778)
			(xy 108.612895 -166.453749) (xy 108.56946 -166.446101) (xy 108.547408 -166.445692) (xy 108.518198 -166.445692)
			(xy 108.501549 -166.446235) (xy 108.469387 -166.454853) (xy 108.440551 -166.471502) (xy 108.417005 -166.495046)
			(xy 108.400356 -166.523881) (xy 108.391736 -166.556043) (xy 108.391198 -166.572692) (xy 108.391198 -166.593012)
			(xy 108.397548 -166.612062) (xy 108.405437 -166.637715) (xy 108.414768 -166.690567) (xy 108.416601 -166.744204)
			(xy 108.410899 -166.79757) (xy 108.397776 -166.84961) (xy 108.377489 -166.899297) (xy 108.350441 -166.945652)
			(xy 108.317163 -166.987758) (xy 108.278313 -167.024787) (xy 108.234658 -167.056005) (xy 108.187059 -167.080799)
			(xy 108.136456 -167.098678) (xy 108.083846 -167.109289) (xy 108.030269 -167.112423) (xy 107.97678 -167.108019)
			(xy 107.950508 -167.102536) (xy 107.924417 -167.096158) (xy 107.874216 -167.077062) (xy 107.827192 -167.051109)
			(xy 107.784276 -167.018814) (xy 107.746317 -166.980814) (xy 107.714068 -166.937863) (xy 107.688165 -166.890811)
			(xy 107.669124 -166.84059) (xy 107.657319 -166.788193) (xy 107.652985 -166.734657) (xy 107.65409 -166.70782)
			(xy 107.654327 -166.685173) (xy 107.647745 -166.640367) (xy 107.633325 -166.597438) (xy 107.611523 -166.557746)
			(xy 107.583029 -166.522547) (xy 107.548747 -166.492957) (xy 107.509762 -166.469914) (xy 107.467309 -166.454146)
			(xy 107.422733 -166.446155) (xy 107.40009 -166.445692) (xy 105.68686 -166.445692) (xy 104.975914 -167.156638)
			(xy 104.960326 -167.172926) (xy 104.934589 -167.209938) (xy 104.915789 -167.250911) (xy 104.904516 -167.29456)
			(xy 104.901125 -167.339512) (xy 104.905721 -167.384358) (xy 104.91816 -167.427688) (xy 104.938053 -167.468142)
			(xy 104.951022 -167.486584) (xy 104.966665 -167.508693) (xy 104.992219 -167.556445) (xy 105.010765 -167.60733)
			(xy 105.02193 -167.660326) (xy 105.02549 -167.714367) (xy 105.021373 -167.76837) (xy 105.009663 -167.821248)
			(xy 104.990594 -167.871939) (xy 104.96455 -167.919425) (xy 104.932053 -167.962751) (xy 104.893757 -168.001048)
			(xy 104.850432 -168.033545) (xy 104.802946 -168.059591) (xy 104.752256 -168.078661) (xy 104.699378 -168.090372)
			(xy 104.645376 -168.09449) (xy 104.591334 -168.090931) (xy 104.538338 -168.079767) (xy 104.487452 -168.061222)
			(xy 104.4397 -168.035669) (xy 104.417622 -168.019984) (xy 104.399169 -168.007046) (xy 104.358709 -167.987206)
			(xy 104.315387 -167.974804) (xy 104.270557 -167.970228) (xy 104.225623 -167.973621) (xy 104.181988 -167.984877)
			(xy 104.141019 -168.003644) (xy 104.103997 -168.029335) (xy 104.087676 -168.044876) (xy 103.829358 -168.303194)
			(xy 103.813425 -168.319838) (xy 103.787257 -168.357754) (xy 103.768352 -168.399766) (xy 103.757327 -168.444498)
			(xy 103.754545 -168.490483) (xy 103.760097 -168.536217) (xy 103.7738 -168.580202) (xy 103.795206 -168.620997)
			(xy 103.823614 -168.657266) (xy 103.858093 -168.687821) (xy 103.897515 -168.711661) (xy 103.940588 -168.728006)
			(xy 103.985901 -168.736321) (xy 104.008936 -168.736772) (xy 104.738932 -168.736772) (xy 104.840532 -168.838372)
			(xy 104.956864 -168.838372) (xy 104.973521 -168.837882) (xy 105.0057 -168.829266) (xy 105.034552 -168.812613)
			(xy 105.058108 -168.789058) (xy 105.074763 -168.760207) (xy 105.083381 -168.728029) (xy 105.083864 -168.711372)
			(xy 105.083864 -168.709086) (xy 105.084255 -168.680974) (xy 105.092289 -168.625329) (xy 105.108401 -168.571466)
			(xy 105.132244 -168.52055) (xy 105.1633 -168.473685) (xy 105.200898 -168.431884) (xy 105.244223 -168.396054)
			(xy 105.292336 -168.366969) (xy 105.344197 -168.34526) (xy 105.398683 -168.331396) (xy 105.454613 -168.325678)
			(xy 105.510776 -168.32823) (xy 105.565957 -168.338996) (xy 105.592626 -168.347898) (xy 105.613591 -168.354804)
			(xy 105.65712 -168.362094) (xy 105.701254 -168.361748) (xy 105.744663 -168.353776) (xy 105.78604 -168.338418)
			(xy 105.824138 -168.316137) (xy 105.85781 -168.287604) (xy 105.87228 -168.270936) (xy 105.890014 -168.2504)
			(xy 105.930303 -168.214059) (xy 105.975333 -168.183792) (xy 106.024198 -168.160209) (xy 106.07591 -168.143786)
			(xy 106.129427 -168.134855) (xy 106.18367 -168.133595) (xy 106.237544 -168.140031) (xy 106.289963 -168.154035)
			(xy 106.33987 -168.175323) (xy 106.386258 -168.203466) (xy 106.428191 -168.237897) (xy 106.464824 -168.27792)
			(xy 106.495418 -168.32273) (xy 106.519355 -168.371422) (xy 106.536153 -168.423013) (xy 106.544552 -168.471179)
			(xy 115.731095 -168.471179) (xy 115.734303 -168.416223) (xy 115.745378 -168.362299) (xy 115.76409 -168.310527)
			(xy 115.79005 -168.261983) (xy 115.822719 -168.217675) (xy 115.861418 -168.178523) (xy 115.905344 -168.145342)
			(xy 115.953583 -168.118819) (xy 116.005134 -168.099507) (xy 116.058925 -168.087806) (xy 116.113841 -168.08396)
			(xy 116.168738 -168.088048) (xy 116.222478 -168.099985) (xy 116.273943 -168.119524) (xy 116.322065 -168.146259)
			(xy 116.365844 -168.179633) (xy 116.404371 -168.218955) (xy 116.436844 -168.263406) (xy 116.46259 -168.312064)
			(xy 116.481074 -168.363918) (xy 116.491912 -168.41789) (xy 116.494878 -168.47286) (xy 116.489911 -168.527685)
			(xy 116.477114 -168.581226) (xy 116.467382 -168.606978) (xy 116.459334 -168.628382) (xy 116.450309 -168.673209)
			(xy 116.449455 -168.718927) (xy 116.456799 -168.76406) (xy 116.472105 -168.807148) (xy 116.494876 -168.846801)
			(xy 116.524379 -168.881736) (xy 116.559659 -168.910826) (xy 116.599576 -168.93313) (xy 116.621052 -168.940988)
			(xy 116.646412 -168.950256) (xy 116.694478 -168.974844) (xy 116.738601 -169.00596) (xy 116.777899 -169.042981)
			(xy 116.81159 -169.085171) (xy 116.839 -169.131686) (xy 116.859582 -169.181599) (xy 116.872927 -169.233914)
			(xy 116.878768 -169.287588) (xy 116.876989 -169.341549) (xy 116.872766 -169.368216) (xy 116.869416 -169.389619)
			(xy 116.869231 -169.42805) (xy 118.231047 -169.42805) (xy 118.235623 -169.373843) (xy 118.247853 -169.320836)
			(xy 118.267489 -169.270103) (xy 118.294133 -169.222675) (xy 118.327244 -169.179512) (xy 118.36615 -169.14149)
			(xy 118.410062 -169.109381) (xy 118.43385 -169.096182) (xy 118.454076 -169.084878) (xy 118.490322 -169.056016)
			(xy 118.520743 -169.021069) (xy 118.544335 -168.981192) (xy 118.560317 -168.937702) (xy 118.568162 -168.892038)
			(xy 118.567609 -168.845708) (xy 118.563644 -168.822878) (xy 118.558846 -168.796103) (xy 118.555999 -168.741784)
			(xy 118.560896 -168.687611) (xy 118.573438 -168.634683) (xy 118.593371 -168.584073) (xy 118.620291 -168.536808)
			(xy 118.653652 -168.493846) (xy 118.692777 -168.456058) (xy 118.736872 -168.42421) (xy 118.785044 -168.398949)
			(xy 118.836316 -168.380786) (xy 118.889648 -168.37009) (xy 118.943959 -168.367079) (xy 118.998146 -168.371812)
			(xy 119.051112 -168.384194) (xy 119.101782 -168.403973) (xy 119.149129 -168.43075) (xy 119.192192 -168.46398)
			(xy 119.230098 -168.50299) (xy 119.262079 -168.546989) (xy 119.287486 -168.595084) (xy 119.305804 -168.646301)
			(xy 119.316662 -168.6996) (xy 119.319838 -168.753901) (xy 119.315269 -168.808103) (xy 119.303048 -168.861106)
			(xy 119.283422 -168.911836) (xy 119.256789 -168.959263) (xy 119.223689 -169.002427) (xy 119.184794 -169.040451)
			(xy 119.140892 -169.072566) (xy 119.11711 -169.085768) (xy 119.096923 -169.097139) (xy 119.060675 -169.125987)
			(xy 119.030249 -169.160921) (xy 119.006652 -169.200786) (xy 118.990663 -169.244266) (xy 118.982811 -169.289921)
			(xy 118.983355 -169.336244) (xy 118.987316 -169.359072) (xy 118.992066 -169.385859) (xy 118.994918 -169.440184)
			(xy 118.990024 -169.494363) (xy 118.977484 -169.547298) (xy 118.957552 -169.597915) (xy 118.930632 -169.645187)
			(xy 118.897269 -169.688155) (xy 118.858141 -169.725948) (xy 118.814041 -169.7578) (xy 118.765864 -169.783065)
			(xy 118.714587 -169.80123) (xy 118.661249 -169.811926) (xy 118.606933 -169.814937) (xy 118.552739 -169.810202)
			(xy 118.499768 -169.797817) (xy 118.449094 -169.778033) (xy 118.401743 -169.751251) (xy 118.358678 -169.718014)
			(xy 118.32077 -169.678997) (xy 118.288789 -169.63499) (xy 118.263384 -169.586887) (xy 118.245069 -169.535663)
			(xy 118.234217 -169.482357) (xy 118.231047 -169.42805) (xy 116.869231 -169.42805) (xy 116.869207 -169.432938)
			(xy 116.876348 -169.475664) (xy 116.89063 -169.516561) (xy 116.911642 -169.554443) (xy 116.938773 -169.588213)
			(xy 116.971238 -169.616893) (xy 117.008097 -169.639652) (xy 117.048281 -169.655831) (xy 117.069362 -169.660824)
			(xy 117.096521 -169.667132) (xy 117.14874 -169.686675) (xy 117.197558 -169.713612) (xy 117.241935 -169.747368)
			(xy 117.280924 -169.787225) (xy 117.313696 -169.832334) (xy 117.327484 -169.858675) (xy 121.373904 -169.858675)
			(xy 121.375446 -169.802583) (xy 121.385186 -169.747322) (xy 121.402915 -169.694083) (xy 121.42825 -169.644015)
			(xy 121.460644 -169.598197) (xy 121.4994 -169.557617) (xy 121.543681 -169.523152) (xy 121.592532 -169.495543)
			(xy 121.6449 -169.475386) (xy 121.699655 -169.463117) (xy 121.755617 -169.458999) (xy 121.811579 -169.463122)
			(xy 121.866333 -169.475396) (xy 121.918699 -169.495558) (xy 121.943368 -169.508932) (xy 121.963153 -169.519573)
			(xy 122.00555 -169.534416) (xy 122.049896 -169.541582) (xy 122.094811 -169.540846) (xy 122.138898 -169.532233)
			(xy 122.180787 -169.51601) (xy 122.219175 -169.492681) (xy 122.252868 -169.462971) (xy 122.267218 -169.445686)
			(xy 122.285002 -169.423981) (xy 122.325924 -169.385588) (xy 122.372028 -169.353602) (xy 122.42232 -169.328714)
			(xy 122.475714 -169.311459) (xy 122.531059 -169.302209) (xy 122.587163 -169.301166) (xy 122.642814 -169.30835)
			(xy 122.696813 -169.323606) (xy 122.747995 -169.346607) (xy 122.795257 -169.376856) (xy 122.837579 -169.4137)
			(xy 122.87405 -169.456345) (xy 122.903881 -169.503871) (xy 122.92643 -169.555254) (xy 122.941211 -169.609386)
			(xy 122.947904 -169.665098) (xy 122.946366 -169.72119) (xy 122.93663 -169.776452) (xy 122.918906 -169.829692)
			(xy 122.893575 -169.879762) (xy 122.861185 -169.925583) (xy 122.822433 -169.966165) (xy 122.778155 -170.000635)
			(xy 122.729307 -170.028249) (xy 122.676941 -170.048411) (xy 122.622187 -170.060686) (xy 122.566226 -170.06481)
			(xy 122.510264 -170.060694) (xy 122.455509 -170.048426) (xy 122.40314 -170.028271) (xy 122.37847 -170.0149)
			(xy 122.358668 -170.004292) (xy 122.316275 -169.989442) (xy 122.271933 -169.982271) (xy 122.227021 -169.983001)
			(xy 122.182936 -169.991609) (xy 122.141048 -170.007829) (xy 122.102661 -170.031155) (xy 122.068969 -170.060862)
			(xy 122.05462 -170.078146) (xy 122.03679 -170.099814) (xy 121.995867 -170.138207) (xy 121.949762 -170.170193)
			(xy 121.899471 -170.195081) (xy 121.846076 -170.212335) (xy 121.79073 -170.221582) (xy 121.734627 -170.222625)
			(xy 121.678975 -170.215439) (xy 121.624977 -170.20018) (xy 121.573795 -170.177177) (xy 121.526534 -170.146927)
			(xy 121.484214 -170.11008) (xy 121.447746 -170.067433) (xy 121.417917 -170.019905) (xy 121.395371 -169.96852)
			(xy 121.380594 -169.914388) (xy 121.373904 -169.858675) (xy 117.327484 -169.858675) (xy 117.339553 -169.881732)
			(xy 117.357942 -169.934369) (xy 117.368473 -169.989122) (xy 117.370921 -170.044824) (xy 117.365234 -170.10029)
			(xy 117.351533 -170.154337) (xy 117.330111 -170.205813) (xy 117.301422 -170.253623) (xy 117.266079 -170.296747)
			(xy 117.224835 -170.334266) (xy 117.178569 -170.365382) (xy 117.128265 -170.389431) (xy 117.074997 -170.4059)
			(xy 117.019898 -170.41444) (xy 116.964144 -170.414867) (xy 116.908921 -170.407174) (xy 116.855406 -170.391523)
			(xy 116.80474 -170.368248) (xy 116.758001 -170.337846) (xy 116.716187 -170.300963) (xy 116.680187 -170.258386)
			(xy 116.650769 -170.211022) (xy 116.628559 -170.15988) (xy 116.614031 -170.10605) (xy 116.607494 -170.050678)
			(xy 116.609088 -169.994944) (xy 116.613432 -169.967402) (xy 116.616765 -169.945996) (xy 116.616976 -169.902679)
			(xy 116.609838 -169.859954) (xy 116.595558 -169.819057) (xy 116.574549 -169.781176) (xy 116.547419 -169.747405)
			(xy 116.514956 -169.718725) (xy 116.478099 -169.695966) (xy 116.437916 -169.679787) (xy 116.416836 -169.674794)
			(xy 116.389925 -169.668493) (xy 116.338137 -169.649187) (xy 116.289679 -169.622608) (xy 116.245563 -169.589313)
			(xy 116.206715 -169.55) (xy 116.173948 -169.505492) (xy 116.147947 -169.456721) (xy 116.129258 -169.404708)
			(xy 116.118271 -169.350541) (xy 116.115217 -169.295357) (xy 116.12016 -169.240309) (xy 116.132996 -169.186551)
			(xy 116.14277 -169.160698) (xy 116.150815 -169.139294) (xy 116.159833 -169.094468) (xy 116.160683 -169.048752)
			(xy 116.153337 -169.003622) (xy 116.138031 -168.960535) (xy 116.115261 -168.920884) (xy 116.085762 -168.885948)
			(xy 116.050487 -168.856857) (xy 116.010574 -168.834549) (xy 115.9891 -168.826688) (xy 115.963237 -168.817254)
			(xy 115.914283 -168.792076) (xy 115.869457 -168.760121) (xy 115.829691 -168.722054) (xy 115.79581 -168.678666)
			(xy 115.768518 -168.630858) (xy 115.748382 -168.579623) (xy 115.735821 -168.526025) (xy 115.731095 -168.471179)
			(xy 106.544552 -168.471179) (xy 106.545474 -168.476464) (xy 106.547128 -168.530696) (xy 106.541083 -168.584616)
			(xy 106.527461 -168.637135) (xy 106.51744 -168.66235) (xy 106.507534 -168.685972) (xy 106.507534 -168.711372)
			(xy 106.508025 -168.728028) (xy 106.516642 -168.760205) (xy 106.533296 -168.789054) (xy 106.556851 -168.812608)
			(xy 106.585701 -168.82926) (xy 106.617878 -168.837875) (xy 106.634534 -168.838372) (xy 106.731308 -168.838372)
			(xy 106.76128 -168.820846) (xy 106.785388 -168.807279) (xy 106.836647 -168.78648) (xy 106.890371 -168.773301)
			(xy 106.945436 -168.768018) (xy 107.000687 -168.770741) (xy 107.054965 -168.781414) (xy 107.107133 -168.799813)
			(xy 107.156098 -168.825552) (xy 107.200833 -168.858092) (xy 107.2404 -168.89675) (xy 107.273971 -168.940717)
			(xy 107.300841 -168.98907) (xy 107.320447 -169.040797) (xy 107.328585 -169.07764) (xy 108.873542 -169.07764)
			(xy 108.877613 -169.022018) (xy 108.889739 -168.967581) (xy 108.909662 -168.91549) (xy 108.936958 -168.866855)
			(xy 108.971044 -168.822712) (xy 109.011193 -168.784003) (xy 109.056551 -168.751552) (xy 109.106151 -168.726051)
			(xy 109.158935 -168.708044) (xy 109.213778 -168.697914) (xy 109.269512 -168.695877) (xy 109.324949 -168.701977)
			(xy 109.378906 -168.716083) (xy 109.430235 -168.737895) (xy 109.477841 -168.766949) (xy 109.520709 -168.802624)
			(xy 109.557926 -168.844161) (xy 109.588699 -168.890674) (xy 109.612371 -168.941171) (xy 109.628439 -168.994578)
			(xy 109.636559 -169.049754) (xy 109.637068 -169.07764) (xy 109.636559 -169.105526) (xy 109.632483 -169.133223)
			(xy 112.496877 -169.133223) (xy 112.504242 -169.077065) (xy 112.519828 -169.022613) (xy 112.543291 -168.971062)
			(xy 112.574116 -168.923546) (xy 112.611626 -168.881108) (xy 112.654996 -168.844681) (xy 112.703275 -168.815064)
			(xy 112.755401 -168.792909) (xy 112.810229 -168.778703) (xy 112.866555 -168.772756) (xy 112.923141 -168.775201)
			(xy 112.978745 -168.785983) (xy 113.005616 -168.794938) (xy 113.027146 -168.802051) (xy 113.071893 -168.809347)
			(xy 113.117225 -168.808585) (xy 113.161702 -168.799789) (xy 113.203911 -168.783238) (xy 113.242512 -168.759458)
			(xy 113.27628 -168.729203) (xy 113.290604 -168.711626) (xy 113.308136 -168.689877) (xy 113.348553 -168.651314)
			(xy 113.394161 -168.619056) (xy 113.443986 -168.593794) (xy 113.496961 -168.576067) (xy 113.551956 -168.566253)
			(xy 113.607793 -168.564564) (xy 113.66328 -168.571034) (xy 113.717231 -168.585526) (xy 113.768492 -168.607729)
			(xy 113.815967 -168.63717) (xy 113.858642 -168.673219) (xy 113.895605 -168.715105) (xy 113.926065 -168.761933)
			(xy 113.949371 -168.812702) (xy 113.965025 -168.866327) (xy 113.972693 -168.921661) (xy 113.97221 -168.977522)
			(xy 113.963588 -169.032716) (xy 113.947009 -169.086062) (xy 113.922829 -169.136421) (xy 113.891565 -169.182716)
			(xy 113.853884 -169.223957) (xy 113.810593 -169.259263) (xy 113.762616 -169.287879) (xy 113.710979 -169.309194)
			(xy 113.656786 -169.322752) (xy 113.601196 -169.328263) (xy 113.545396 -169.325609) (xy 113.490579 -169.314847)
			(xy 113.464086 -169.305986) (xy 113.442558 -169.298867) (xy 113.39781 -169.291569) (xy 113.352477 -169.292331)
			(xy 113.307999 -169.301128) (xy 113.265789 -169.31768) (xy 113.227188 -169.341462) (xy 113.193421 -169.371719)
			(xy 113.179098 -169.389298) (xy 113.16335 -169.408348) (xy 113.148026 -169.426318) (xy 113.123726 -169.46681)
			(xy 113.107317 -169.511092) (xy 113.099362 -169.557641) (xy 113.100135 -169.604858) (xy 113.109608 -169.651122)
			(xy 113.127457 -169.694843) (xy 113.153068 -169.734519) (xy 113.168938 -169.75201) (xy 113.187554 -169.772409)
			(xy 113.219426 -169.817503) (xy 113.244465 -169.866721) (xy 113.262147 -169.919035) (xy 113.272103 -169.973351)
			(xy 113.274126 -170.028535) (xy 113.268172 -170.083434) (xy 113.254367 -170.136901) (xy 113.232998 -170.18782)
			(xy 113.204513 -170.235127) (xy 113.169505 -170.277834) (xy 113.128707 -170.315047) (xy 113.08297 -170.345991)
			(xy 113.033251 -170.370019) (xy 112.980587 -170.386629) (xy 112.926079 -170.395473) (xy 112.870865 -170.396367)
			(xy 112.816099 -170.389293) (xy 112.762925 -170.374398) (xy 112.712453 -170.351993) (xy 112.665739 -170.322547)
			(xy 112.623756 -170.286674) (xy 112.587384 -170.245124) (xy 112.557381 -170.198765) (xy 112.534375 -170.148565)
			(xy 112.518845 -170.095572) (xy 112.511116 -170.040895) (xy 112.51135 -169.985674) (xy 112.519542 -169.931064)
			(xy 112.535521 -169.878205) (xy 112.558952 -169.828202) (xy 112.589347 -169.782099) (xy 112.607344 -169.761154)
			(xy 112.622667 -169.743183) (xy 112.646967 -169.702691) (xy 112.663377 -169.65841) (xy 112.671332 -169.611861)
			(xy 112.67056 -169.564643) (xy 112.661087 -169.518379) (xy 112.643238 -169.474658) (xy 112.617627 -169.434983)
			(xy 112.601756 -169.417492) (xy 112.582606 -169.396623) (xy 112.550096 -169.350244) (xy 112.524798 -169.299568)
			(xy 112.507269 -169.24571) (xy 112.497893 -169.189853) (xy 112.496877 -169.133223) (xy 109.632483 -169.133223)
			(xy 109.628439 -169.160702) (xy 109.612371 -169.214109) (xy 109.588699 -169.264606) (xy 109.557926 -169.311119)
			(xy 109.520709 -169.352656) (xy 109.477841 -169.388331) (xy 109.430235 -169.417385) (xy 109.378906 -169.439197)
			(xy 109.324949 -169.453303) (xy 109.269512 -169.459403) (xy 109.213778 -169.457366) (xy 109.158935 -169.447236)
			(xy 109.106151 -169.429229) (xy 109.056551 -169.403728) (xy 109.011193 -169.371277) (xy 108.971044 -169.332568)
			(xy 108.936958 -169.288425) (xy 108.909662 -169.23979) (xy 108.889739 -169.187699) (xy 108.877613 -169.133262)
			(xy 108.873542 -169.07764) (xy 107.328585 -169.07764) (xy 107.332378 -169.094812) (xy 107.336385 -169.149985)
			(xy 107.332383 -169.205158) (xy 107.320456 -169.259174) (xy 107.300854 -169.310902) (xy 107.273988 -169.359258)
			(xy 107.240421 -169.403227) (xy 107.200856 -169.441889) (xy 107.156124 -169.474432) (xy 107.107161 -169.500175)
			(xy 107.054994 -169.518578) (xy 107.000717 -169.529255) (xy 106.945467 -169.531983) (xy 106.890401 -169.526704)
			(xy 106.836676 -169.513529) (xy 106.785415 -169.492734) (xy 106.76128 -169.479214) (xy 106.731308 -169.461688)
			(xy 104.91724 -169.461688) (xy 104.901426 -169.462165) (xy 104.870771 -169.469952) (xy 104.842981 -169.485055)
			(xy 104.819772 -169.506542) (xy 104.802575 -169.533087) (xy 104.792453 -169.563052) (xy 104.790748 -169.578782)
			(xy 104.788168 -169.605654) (xy 104.776396 -169.658338) (xy 104.757315 -169.708837) (xy 104.731306 -169.756142)
			(xy 104.698889 -169.799308) (xy 104.66071 -169.837473) (xy 104.617533 -169.869876) (xy 104.57022 -169.895869)
			(xy 104.519715 -169.914933) (xy 104.467026 -169.926687) (xy 104.413208 -169.930897) (xy 104.359333 -169.927479)
			(xy 104.306477 -169.9165) (xy 104.255698 -169.898181) (xy 104.208007 -169.872886) (xy 104.164358 -169.841121)
			(xy 104.125623 -169.803521) (xy 104.092575 -169.760836) (xy 104.065873 -169.713919) (xy 104.046052 -169.663706)
			(xy 104.033507 -169.611201) (xy 104.030526 -169.58437) (xy 104.027322 -169.561496) (xy 104.013721 -169.517359)
			(xy 103.992371 -169.476406) (xy 103.963975 -169.439983) (xy 103.929466 -169.409289) (xy 103.889981 -169.385333)
			(xy 103.846817 -169.368905) (xy 103.801396 -169.360543) (xy 103.778304 -169.360088) (xy 103.533702 -169.360088)
			(xy 103.45928 -169.43451) (xy 103.45928 -172.139864) (xy 103.302745 -172.296399) (xy 104.050062 -172.296399)
			(xy 104.056063 -172.24138) (xy 104.069952 -172.187805) (xy 104.091437 -172.1368) (xy 104.120067 -172.089436)
			(xy 104.155241 -172.046705) (xy 104.196221 -172.009506) (xy 104.242146 -171.978619) (xy 104.292052 -171.954693)
			(xy 104.344892 -171.93823) (xy 104.399557 -171.929576) (xy 104.454898 -171.928911) (xy 104.482392 -171.932092)
			(xy 104.505339 -171.934754) (xy 104.551479 -171.93251) (xy 104.596453 -171.921962) (xy 104.638779 -171.903459)
			(xy 104.677063 -171.877608) (xy 104.710043 -171.845263) (xy 104.736633 -171.807488) (xy 104.755956 -171.765529)
			(xy 104.767375 -171.720769) (xy 104.770515 -171.674681) (xy 104.768396 -171.651676) (xy 104.765607 -171.622829)
			(xy 104.76778 -171.564918) (xy 104.772714 -171.53636) (xy 104.776332 -171.51512) (xy 104.77723 -171.472048)
			(xy 104.770849 -171.429441) (xy 104.757371 -171.388522) (xy 104.737183 -171.350463) (xy 104.710863 -171.316356)
			(xy 104.679167 -171.287178) (xy 104.643002 -171.263765) (xy 104.603406 -171.246789) (xy 104.561514 -171.236736)
			(xy 104.54005 -171.234862) (xy 104.512169 -171.232574) (xy 104.45749 -171.220746) (xy 104.405125 -171.20106)
			(xy 104.356195 -171.173939) (xy 104.31175 -171.139965) (xy 104.272742 -171.099865) (xy 104.240007 -171.054498)
			(xy 104.214247 -171.004839) (xy 104.196015 -170.95195) (xy 104.185701 -170.896965) (xy 104.183526 -170.841064)
			(xy 104.189537 -170.785445) (xy 104.203605 -170.731299) (xy 104.225429 -170.679788) (xy 104.25454 -170.632016)
			(xy 104.290314 -170.589006) (xy 104.331986 -170.551681) (xy 104.37866 -170.520841) (xy 104.429338 -170.497146)
			(xy 104.482932 -170.481106) (xy 104.538295 -170.473063) (xy 104.594238 -170.47319) (xy 104.649563 -170.481485)
			(xy 104.703084 -170.497769) (xy 104.753653 -170.521693) (xy 104.800187 -170.552745) (xy 104.841689 -170.590259)
			(xy 104.877267 -170.633431) (xy 104.906161 -170.681335) (xy 104.92775 -170.732945) (xy 104.941572 -170.787154)
			(xy 104.94733 -170.8428) (xy 104.944901 -170.898691) (xy 104.9401 -170.926252) (xy 104.936456 -170.947488)
			(xy 104.935559 -170.990563) (xy 104.941943 -171.033171) (xy 104.955423 -171.074092) (xy 104.975614 -171.112152)
			(xy 105.001937 -171.146261) (xy 105.033636 -171.175439) (xy 105.069804 -171.198851) (xy 105.109403 -171.215826)
			(xy 105.151299 -171.225877) (xy 105.172764 -171.22775) (xy 105.199831 -171.23003) (xy 105.25297 -171.24129)
			(xy 105.303975 -171.25997) (xy 105.351815 -171.285695) (xy 105.395524 -171.317944) (xy 105.434219 -171.356065)
			(xy 105.467116 -171.399288) (xy 105.493553 -171.446738) (xy 105.512993 -171.497459) (xy 105.525045 -171.550423)
			(xy 105.529464 -171.604561) (xy 105.526162 -171.658779) (xy 105.515205 -171.71198) (xy 105.496814 -171.763091)
			(xy 105.471362 -171.811077) (xy 105.439362 -171.854968) (xy 105.401462 -171.893879) (xy 105.358427 -171.927022)
			(xy 105.311127 -171.953727) (xy 105.260518 -171.973456) (xy 105.207623 -171.985808) (xy 105.153511 -171.990536)
			(xy 105.099275 -171.987542) (xy 105.046012 -171.976887) (xy 104.994798 -171.958787) (xy 104.946668 -171.933608)
			(xy 104.924352 -171.918122) (xy 104.910943 -171.908999) (xy 104.880733 -171.897227) (xy 104.84853 -171.893451)
			(xy 104.816416 -171.897917) (xy 104.786466 -171.910336) (xy 104.760614 -171.929904) (xy 104.740531 -171.955358)
			(xy 104.727514 -171.985054) (xy 104.722405 -172.017072) (xy 104.725533 -172.049343) (xy 104.736697 -172.079784)
			(xy 104.745536 -172.093382) (xy 104.758582 -172.112794) (xy 104.780358 -172.154187) (xy 104.78897 -172.175932)
			(xy 104.797561 -172.197392) (xy 104.821336 -172.237028) (xy 104.851889 -172.271709) (xy 104.888214 -172.300288)
			(xy 104.92911 -172.321824) (xy 104.973227 -172.335604) (xy 105.01911 -172.341174) (xy 105.042208 -172.34027)
			(xy 105.070264 -172.339083) (xy 105.126206 -172.343936) (xy 105.180832 -172.356938) (xy 105.232963 -172.377806)
			(xy 105.281472 -172.406089) (xy 105.325311 -172.441178) (xy 105.363533 -172.482314) (xy 105.395313 -172.528608)
			(xy 105.419964 -172.57906) (xy 105.436953 -172.632581) (xy 105.445914 -172.688013) (xy 105.446653 -172.744161)
			(xy 105.439154 -172.79981) (xy 105.423579 -172.853759) (xy 105.400264 -172.904842) (xy 105.369713 -172.951957)
			(xy 105.332586 -172.994084) (xy 105.289686 -173.030314) (xy 105.241938 -173.059864) (xy 105.190374 -173.082097)
			(xy 105.136109 -173.096531) (xy 105.080313 -173.102855) (xy 105.024194 -173.100932) (xy 104.968963 -173.090804)
			(xy 104.915812 -173.07269) (xy 104.865891 -173.046981) (xy 104.820278 -173.014231) (xy 104.779957 -172.97515)
			(xy 104.745801 -172.930581) (xy 104.718546 -172.881486) (xy 104.708198 -172.855382) (xy 104.699628 -172.833913)
			(xy 104.675852 -172.794274) (xy 104.645295 -172.759593) (xy 104.608967 -172.731013) (xy 104.568067 -172.709479)
			(xy 104.523945 -172.695702) (xy 104.478059 -172.690137) (xy 104.45496 -172.691044) (xy 104.427304 -172.692161)
			(xy 104.372155 -172.687502) (xy 104.318258 -172.674923) (xy 104.266745 -172.654687) (xy 104.218697 -172.62722)
			(xy 104.175122 -172.593097) (xy 104.136935 -172.553036) (xy 104.104939 -172.507877) (xy 104.079804 -172.458568)
			(xy 104.062058 -172.406145) (xy 104.052074 -172.351708) (xy 104.050062 -172.296399) (xy 103.302745 -172.296399)
			(xy 103.00716 -172.591984) (xy 103.00716 -176.654714) (xy 103.144828 -176.792636) (xy 103.638604 -177.286412)
			(xy 103.638604 -177.974244) (xy 103.638858 -178.715162) (xy 105.177844 -180.253894) (xy 105.375964 -180.253894)
		)
		(stroke
			(width 0)
			(type solid)
		)
		(fill yes)
		(layer "In7.Cu")
		(net "P3V3_NODE1")
	)
	(gr_poly
		(pts
			(xy 56.087518 -102.554532) (xy 56.110701 -102.554024) (xy 56.156298 -102.545623) (xy 56.199614 -102.529085)
			(xy 56.239207 -102.50496) (xy 56.273765 -102.474048) (xy 56.302137 -102.437378) (xy 56.323382 -102.396166)
			(xy 56.336793 -102.351783) (xy 56.341926 -102.305703) (xy 56.33861 -102.259457) (xy 56.326954 -102.214581)
			(xy 56.317642 -102.193344) (xy 56.306523 -102.168343) (xy 56.290754 -102.115949) (xy 56.28263 -102.06184)
			(xy 56.282318 -102.007126) (xy 56.289824 -101.952927) (xy 56.304994 -101.900357) (xy 56.327517 -101.850492)
			(xy 56.356931 -101.804355) (xy 56.392633 -101.762893) (xy 56.433891 -101.726954) (xy 56.479859 -101.697278)
			(xy 56.529595 -101.67447) (xy 56.582078 -101.659001) (xy 56.636232 -101.651186) (xy 56.690948 -101.651186)
			(xy 56.745102 -101.659001) (xy 56.797585 -101.67447) (xy 56.847321 -101.697278) (xy 56.893289 -101.726954)
			(xy 56.934547 -101.762893) (xy 56.970249 -101.804355) (xy 56.999663 -101.850492) (xy 57.022186 -101.900357)
			(xy 57.037356 -101.952927) (xy 57.044862 -102.007126) (xy 57.04455 -102.06184) (xy 57.036426 -102.115949)
			(xy 57.020657 -102.168343) (xy 57.009538 -102.193344) (xy 57.000226 -102.21457) (xy 56.988616 -102.259438)
			(xy 56.985334 -102.305668) (xy 56.99049 -102.351727) (xy 57.003913 -102.396087) (xy 57.025157 -102.437277)
			(xy 57.053519 -102.473933) (xy 57.088057 -102.504837) (xy 57.127627 -102.528966) (xy 57.170916 -102.54552)
			(xy 57.216489 -102.553949) (xy 57.239662 -102.554532) (xy 57.565036 -102.554532) (xy 58.71464 -101.404928)
			(xy 58.71464 -100.64115) (xy 58.713624 -100.63353) (xy 58.711108 -100.610228) (xy 58.711109 -100.56336)
			(xy 58.713624 -100.540058) (xy 58.71464 -100.532438) (xy 58.71464 -99.867466) (xy 58.66384 -99.799648)
			(xy 58.623454 -99.78771) (xy 58.597727 -99.779683) (xy 58.54866 -99.757393) (xy 58.503218 -99.72842)
			(xy 58.462306 -99.69334) (xy 58.426737 -99.652852) (xy 58.39722 -99.607762) (xy 58.374342 -99.558966)
			(xy 58.358558 -99.507437) (xy 58.350183 -99.454199) (xy 58.349383 -99.400313) (xy 58.356174 -99.34685)
			(xy 58.370422 -99.294874) (xy 58.391841 -99.245421) (xy 58.420007 -99.199475) (xy 58.454358 -99.157949)
			(xy 58.494212 -99.12167) (xy 58.538773 -99.091361) (xy 58.562748 -99.07905) (xy 58.57712 -99.071453)
			(xy 58.601734 -99.050233) (xy 58.620188 -99.023483) (xy 58.631285 -98.992938) (xy 58.634305 -98.96058)
			(xy 58.629052 -98.92851) (xy 58.622946 -98.913442) (xy 58.612452 -98.888563) (xy 58.597785 -98.836597)
			(xy 58.590586 -98.783084) (xy 58.590998 -98.72909) (xy 58.599014 -98.675693) (xy 58.614473 -98.623957)
			(xy 58.637068 -98.574916) (xy 58.666346 -98.529548) (xy 58.683652 -98.50882) (xy 58.71464 -98.473006)
			(xy 58.71464 -97.103946) (xy 58.05043 -96.439736) (xy 54.10073 -96.439736) (xy 50.56759 -92.906596)
			(xy 43.94962 -92.906596) (xy 41.8719 -90.828876) (xy 41.8719 -88.947752) (xy 41.871399 -88.931461)
			(xy 41.863138 -88.899944) (xy 41.847168 -88.871545) (xy 41.824529 -88.848113) (xy 41.796696 -88.831177)
			(xy 41.765481 -88.821838) (xy 41.749218 -88.820752) (xy 41.721321 -88.819314) (xy 41.666367 -88.809292)
			(xy 41.613463 -88.791363) (xy 41.563739 -88.76591) (xy 41.518258 -88.733477) (xy 41.477994 -88.694759)
			(xy 41.443806 -88.650582) (xy 41.416427 -88.601892) (xy 41.396441 -88.54973) (xy 41.384276 -88.49521)
			(xy 41.380192 -88.4395) (xy 41.384276 -88.383789) (xy 41.396441 -88.32927) (xy 41.416427 -88.277108)
			(xy 41.443807 -88.228418) (xy 41.477994 -88.184241) (xy 41.518258 -88.145523) (xy 41.563739 -88.11309)
			(xy 41.613463 -88.087637) (xy 41.666367 -88.069708) (xy 41.721321 -88.059686) (xy 41.749218 -88.058244)
			(xy 41.765492 -88.057204) (xy 41.796734 -88.047891) (xy 41.824591 -88.030958) (xy 41.847242 -88.007512)
			(xy 41.863204 -87.979088) (xy 41.871435 -87.947544) (xy 41.8719 -87.931244) (xy 41.8719 -85.337142)
			(xy 41.861486 -85.313266) (xy 41.851657 -85.289341) (xy 41.837813 -85.239503) (xy 41.830827 -85.188253)
			(xy 41.830828 -85.136529) (xy 41.837816 -85.085279) (xy 41.851663 -85.035442) (xy 41.861486 -85.011514)
			(xy 41.8719 -84.987638) (xy 41.8719 -74.163428) (xy 41.871409 -74.146771) (xy 41.862792 -74.11459)
			(xy 41.846139 -74.085737) (xy 41.822585 -74.062178) (xy 41.793736 -74.045518) (xy 41.761557 -74.036895)
			(xy 41.7449 -74.036428) (xy 41.656 -74.036428) (xy 41.633141 -74.036904) (xy 41.588158 -74.045068)
			(xy 41.545363 -74.061152) (xy 41.506137 -74.084634) (xy 41.471747 -74.114758) (xy 41.443303 -74.15055)
			(xy 41.421724 -74.190855) (xy 41.407708 -74.234371) (xy 41.401705 -74.279693) (xy 41.403911 -74.325358)
			(xy 41.414254 -74.36989) (xy 41.4324 -74.411853) (xy 41.444672 -74.431144) (xy 41.459506 -74.454265)
			(xy 41.483098 -74.503874) (xy 41.499331 -74.556353) (xy 41.507871 -74.610618) (xy 41.508541 -74.665546)
			(xy 41.501326 -74.720003) (xy 41.486376 -74.772862) (xy 41.464 -74.823031) (xy 41.434661 -74.869472)
			(xy 41.398964 -74.911226) (xy 41.357649 -74.947428) (xy 41.311569 -74.977332) (xy 41.261676 -75.000317)
			(xy 41.209003 -75.015911) (xy 41.154638 -75.023788) (xy 41.099706 -75.023788) (xy 41.045341 -75.015911)
			(xy 40.992668 -75.000317) (xy 40.942775 -74.977332) (xy 40.896695 -74.947428) (xy 40.85538 -74.911226)
			(xy 40.819683 -74.869472) (xy 40.790344 -74.823031) (xy 40.767968 -74.772862) (xy 40.753018 -74.720003)
			(xy 40.745803 -74.665546) (xy 40.746473 -74.610618) (xy 40.755013 -74.556353) (xy 40.771246 -74.503874)
			(xy 40.794838 -74.454265) (xy 40.809672 -74.431144) (xy 40.821931 -74.411851) (xy 40.840043 -74.369885)
			(xy 40.850359 -74.325358) (xy 40.852545 -74.279703) (xy 40.846533 -74.234393) (xy 40.832515 -74.190889)
			(xy 40.810943 -74.150592) (xy 40.782514 -74.114803) (xy 40.748143 -74.084674) (xy 40.708938 -74.061177)
			(xy 40.666163 -74.04507) (xy 40.621197 -74.036871) (xy 40.598344 -74.036428) (xy 40.527478 -74.036428)
			(xy 40.509802 -74.036998) (xy 40.475808 -74.046698) (xy 40.445791 -74.06537) (xy 40.433498 -74.078084)
			(xy 40.41366 -74.099093) (xy 40.368772 -74.135476) (xy 40.318911 -74.164675) (xy 40.265218 -74.186021)
			(xy 40.20892 -74.199028) (xy 40.151304 -74.203397) (xy 40.093688 -74.199028) (xy 40.03739 -74.186021)
			(xy 39.983697 -74.164675) (xy 39.933836 -74.135476) (xy 39.888948 -74.099093) (xy 39.86911 -74.078084)
			(xy 39.856801 -74.06539) (xy 39.826781 -74.046734) (xy 39.792802 -74.037003) (xy 39.77513 -74.036428)
			(xy 38.651688 -74.036428) (xy 38.629129 -74.036892) (xy 38.584712 -74.044812) (xy 38.542392 -74.060454)
			(xy 38.503502 -74.083327) (xy 38.469264 -74.11271) (xy 38.440756 -74.147679) (xy 38.418873 -74.187135)
			(xy 38.404305 -74.229836) (xy 38.39751 -74.274439) (xy 38.398701 -74.319541) (xy 38.402768 -74.341736)
			(xy 38.40763 -74.36747) (xy 38.411075 -74.419727) (xy 38.409626 -74.445876) (xy 38.408466 -74.469061)
			(xy 38.413582 -74.515195) (xy 38.426992 -74.559633) (xy 38.448251 -74.600896) (xy 38.476651 -74.637611)
			(xy 38.511247 -74.668556) (xy 38.550889 -74.692703) (xy 38.594257 -74.709247) (xy 38.639909 -74.717639)
			(xy 38.663118 -74.718164) (xy 39.751762 -74.718164) (xy 40.208708 -75.174856) (xy 40.208708 -76.98105)
			(xy 40.811956 -76.98105) (xy 40.816027 -76.925428) (xy 40.828153 -76.870991) (xy 40.848076 -76.8189)
			(xy 40.875372 -76.770265) (xy 40.909458 -76.726122) (xy 40.949607 -76.687413) (xy 40.994965 -76.654962)
			(xy 41.044565 -76.629461) (xy 41.097349 -76.611454) (xy 41.152192 -76.601324) (xy 41.207926 -76.599287)
			(xy 41.263363 -76.605387) (xy 41.31732 -76.619493) (xy 41.368649 -76.641305) (xy 41.416255 -76.670359)
			(xy 41.459123 -76.706034) (xy 41.49634 -76.747571) (xy 41.527113 -76.794084) (xy 41.550785 -76.844581)
			(xy 41.566853 -76.897988) (xy 41.574973 -76.953164) (xy 41.575482 -76.98105) (xy 41.574973 -77.008936)
			(xy 41.566853 -77.064112) (xy 41.550785 -77.117519) (xy 41.527113 -77.168016) (xy 41.49634 -77.214529)
			(xy 41.459123 -77.256066) (xy 41.416255 -77.291741) (xy 41.368649 -77.320795) (xy 41.31732 -77.342607)
			(xy 41.263363 -77.356713) (xy 41.207926 -77.362813) (xy 41.152192 -77.360776) (xy 41.097349 -77.350646)
			(xy 41.044565 -77.332639) (xy 40.994965 -77.307138) (xy 40.949607 -77.274687) (xy 40.909458 -77.235978)
			(xy 40.875372 -77.191835) (xy 40.848076 -77.1432) (xy 40.828153 -77.091109) (xy 40.816027 -77.036672)
			(xy 40.811956 -76.98105) (xy 40.208708 -76.98105) (xy 40.208708 -78.452726) (xy 39.831264 -78.83017)
			(xy 40.68648 -78.83017) (xy 40.690551 -78.774548) (xy 40.702677 -78.720111) (xy 40.7226 -78.66802)
			(xy 40.749896 -78.619385) (xy 40.783982 -78.575242) (xy 40.824131 -78.536533) (xy 40.869489 -78.504082)
			(xy 40.919089 -78.478581) (xy 40.971873 -78.460574) (xy 41.026716 -78.450444) (xy 41.08245 -78.448407)
			(xy 41.137887 -78.454507) (xy 41.191844 -78.468613) (xy 41.243173 -78.490425) (xy 41.290779 -78.519479)
			(xy 41.333647 -78.555154) (xy 41.370864 -78.596691) (xy 41.401637 -78.643204) (xy 41.425309 -78.693701)
			(xy 41.441377 -78.747108) (xy 41.449497 -78.802284) (xy 41.450006 -78.83017) (xy 41.449497 -78.858056)
			(xy 41.441377 -78.913232) (xy 41.425309 -78.966639) (xy 41.401637 -79.017136) (xy 41.370864 -79.063649)
			(xy 41.333647 -79.105186) (xy 41.290779 -79.140861) (xy 41.243173 -79.169915) (xy 41.191844 -79.191727)
			(xy 41.137887 -79.205833) (xy 41.08245 -79.211933) (xy 41.026716 -79.209896) (xy 40.971873 -79.199766)
			(xy 40.919089 -79.181759) (xy 40.869489 -79.156258) (xy 40.824131 -79.123807) (xy 40.783982 -79.085098)
			(xy 40.749896 -79.040955) (xy 40.7226 -78.99232) (xy 40.702677 -78.940229) (xy 40.690551 -78.885792)
			(xy 40.68648 -78.83017) (xy 39.831264 -78.83017) (xy 39.723314 -78.93812) (xy 37.638228 -78.93812)
			(xy 37.616117 -78.938595) (xy 37.572563 -78.946246) (xy 37.530991 -78.961322) (xy 37.492656 -78.983367)
			(xy 37.458717 -79.011716) (xy 37.430199 -79.045512) (xy 37.407962 -79.083736) (xy 37.392678 -79.125232)
			(xy 37.388292 -79.146908) (xy 37.382868 -79.174247) (xy 37.365143 -79.227087) (xy 37.339918 -79.276785)
			(xy 37.307729 -79.322285) (xy 37.269262 -79.362616) (xy 37.225337 -79.39692) (xy 37.176887 -79.424468)
			(xy 37.124944 -79.444673) (xy 37.070615 -79.457104) (xy 37.015054 -79.461498) (xy 36.959446 -79.45776)
			(xy 36.904973 -79.445971) (xy 36.852796 -79.42638) (xy 36.804024 -79.399406) (xy 36.759697 -79.365622)
			(xy 36.720757 -79.325748) (xy 36.688033 -79.280632) (xy 36.662223 -79.231235) (xy 36.643876 -79.178607)
			(xy 36.633381 -79.123871) (xy 36.630963 -79.068189) (xy 36.636673 -79.012748) (xy 36.643056 -78.985618)
			(xy 36.646591 -78.969546) (xy 36.646254 -78.936652) (xy 36.637537 -78.904932) (xy 36.621017 -78.876485)
			(xy 36.609782 -78.86446) (xy 36.213288 -78.46822) (xy 36.213288 -75.04176) (xy 36.537138 -74.718164)
			(xy 37.39515 -74.718164) (xy 37.41835 -74.717636) (xy 37.463975 -74.709195) (xy 37.507314 -74.69262)
			(xy 37.546928 -74.668461) (xy 37.581504 -74.637519) (xy 37.609896 -74.600819) (xy 37.631163 -74.55958)
			(xy 37.644598 -74.515168) (xy 37.649756 -74.469055) (xy 37.648642 -74.445876) (xy 37.647209 -74.419727)
			(xy 37.650651 -74.367471) (xy 37.6555 -74.341736) (xy 37.659571 -74.319549) (xy 37.660728 -74.274459)
			(xy 37.653909 -74.229874) (xy 37.639326 -74.187192) (xy 37.617439 -74.147753) (xy 37.588935 -74.112798)
			(xy 37.554708 -74.083422) (xy 37.515834 -74.060549) (xy 37.473532 -74.044896) (xy 37.429132 -74.036956)
			(xy 37.40658 -74.036428) (xy 36.08197 -74.036428) (xy 36.05927 -74.036905) (xy 36.014584 -74.044924)
			(xy 35.972034 -74.060756) (xy 35.932974 -74.083897) (xy 35.898648 -74.113609) (xy 35.870148 -74.148948)
			(xy 35.84838 -74.188789) (xy 35.834038 -74.231864) (xy 35.827578 -74.276802) (xy 35.829206 -74.322172)
			(xy 35.838869 -74.366532) (xy 35.856261 -74.408468) (xy 35.868102 -74.427842) (xy 35.882485 -74.45109)
			(xy 35.905172 -74.500828) (xy 35.920526 -74.553295) (xy 35.928233 -74.607417) (xy 35.928133 -74.662084)
			(xy 35.920231 -74.716178) (xy 35.904687 -74.768589) (xy 35.881819 -74.818244) (xy 35.852097 -74.864126)
			(xy 35.816129 -74.905295) (xy 35.774652 -74.940907) (xy 35.728516 -74.970233) (xy 35.678666 -74.992672)
			(xy 35.626123 -75.007764) (xy 35.571964 -75.015201) (xy 35.517297 -75.014829) (xy 35.463244 -75.006657)
			(xy 35.410911 -74.990852) (xy 35.361371 -74.967737) (xy 35.315637 -74.937787) (xy 35.274649 -74.901614)
			(xy 35.239244 -74.85996) (xy 35.210148 -74.813679) (xy 35.187958 -74.763717) (xy 35.173127 -74.7111)
			(xy 35.165961 -74.656904) (xy 35.166605 -74.60224) (xy 35.170364 -74.575162) (xy 35.173273 -74.553531)
			(xy 35.172518 -74.509895) (xy 35.164321 -74.46703) (xy 35.148923 -74.426195) (xy 35.126776 -74.388589)
			(xy 35.098532 -74.355319) (xy 35.06502 -74.327362) (xy 35.027226 -74.30554) (xy 34.986259 -74.290494)
			(xy 34.964878 -74.28611) (xy 34.937372 -74.280594) (xy 34.884247 -74.262573) (xy 34.834327 -74.236977)
			(xy 34.811208 -74.221086) (xy 34.79884 -74.212778) (xy 34.771228 -74.201599) (xy 34.741777 -74.19713)
			(xy 34.712092 -74.199615) (xy 34.683794 -74.208918) (xy 34.658425 -74.224531) (xy 34.647632 -74.234802)
			(xy 34.48304 -74.399394) (xy 34.48304 -76.027026) (xy 34.483471 -76.048671) (xy 34.4908 -76.091337)
			(xy 34.505259 -76.132141) (xy 34.526427 -76.169903) (xy 34.553693 -76.203528) (xy 34.586266 -76.232041)
			(xy 34.623203 -76.254618) (xy 34.663434 -76.270604) (xy 34.705793 -76.279536) (xy 34.749053 -76.281154)
			(xy 34.770568 -76.27874) (xy 34.797709 -76.275564) (xy 34.852352 -76.276084) (xy 34.906362 -76.284395)
			(xy 34.958634 -76.300325) (xy 35.008099 -76.32355) (xy 35.053744 -76.353593) (xy 35.094637 -76.389841)
			(xy 35.12994 -76.431552) (xy 35.158932 -76.477873) (xy 35.18102 -76.527855) (xy 35.195751 -76.580478)
			(xy 35.202824 -76.634664) (xy 35.202095 -76.689304) (xy 35.193579 -76.743282) (xy 35.177449 -76.795493)
			(xy 35.154036 -76.844868) (xy 35.123819 -76.890399) (xy 35.087415 -76.931153) (xy 35.04557 -76.966297)
			(xy 34.999139 -76.995112) (xy 34.974276 -77.00645) (xy 34.953238 -77.016233) (xy 34.914834 -77.042255)
			(xy 34.881787 -77.074812) (xy 34.855194 -77.112824) (xy 34.835938 -77.155029) (xy 34.824657 -77.200027)
			(xy 34.821726 -77.246325) (xy 34.827242 -77.292386) (xy 34.841022 -77.336683) (xy 34.862609 -77.377745)
			(xy 34.876486 -77.39634) (xy 34.893221 -77.418354) (xy 34.920836 -77.466261) (xy 34.941245 -77.517653)
			(xy 34.954023 -77.571453) (xy 34.958899 -77.626534) (xy 34.955774 -77.681742) (xy 34.944711 -77.735921)
			(xy 34.925944 -77.787935) (xy 34.899864 -77.836695) (xy 34.867018 -77.88118) (xy 34.828095 -77.920457)
			(xy 34.78391 -77.953703) (xy 34.735388 -77.980223) (xy 34.683545 -77.999461) (xy 34.629469 -78.011014)
			(xy 34.601912 -78.013306) (xy 34.586007 -78.014822) (xy 34.55564 -78.024717) (xy 34.528687 -78.041851)
			(xy 34.506839 -78.065147) (xy 34.491469 -78.093144) (xy 34.483541 -78.124083) (xy 34.48304 -78.140052)
			(xy 34.48304 -79.446628) (xy 34.534856 -79.5147) (xy 34.576512 -79.52613) (xy 34.603007 -79.533922)
			(xy 34.653588 -79.556089) (xy 34.700444 -79.585318) (xy 34.742595 -79.621) (xy 34.779159 -79.662387)
			(xy 34.809372 -79.708615) (xy 34.832602 -79.758717) (xy 34.848364 -79.811645) (xy 34.856327 -79.866293)
			(xy 34.856326 -79.921518) (xy 34.848361 -79.976166) (xy 34.832598 -80.029094) (xy 34.809366 -80.079195)
			(xy 34.779152 -80.125422) (xy 34.742586 -80.166809) (xy 34.700435 -80.202489) (xy 34.653578 -80.231717)
			(xy 34.602996 -80.253882) (xy 34.576512 -80.261714) (xy 34.560643 -80.266617) (xy 34.531968 -80.283351)
			(xy 34.508579 -80.306914) (xy 34.492056 -80.335711) (xy 34.483519 -80.367795) (xy 34.48304 -80.384396)
			(xy 34.48304 -80.476344) (xy 36.595302 -80.476344) (xy 36.599373 -80.420722) (xy 36.611499 -80.366285)
			(xy 36.631422 -80.314194) (xy 36.658718 -80.265559) (xy 36.692804 -80.221416) (xy 36.732953 -80.182707)
			(xy 36.778311 -80.150256) (xy 36.827911 -80.124755) (xy 36.880695 -80.106748) (xy 36.935538 -80.096618)
			(xy 36.991272 -80.094581) (xy 37.046709 -80.100681) (xy 37.100666 -80.114787) (xy 37.151995 -80.136599)
			(xy 37.199601 -80.165653) (xy 37.242469 -80.201328) (xy 37.279686 -80.242865) (xy 37.310459 -80.289378)
			(xy 37.334131 -80.339875) (xy 37.350199 -80.393282) (xy 37.358319 -80.448458) (xy 37.358828 -80.476344)
			(xy 37.358319 -80.50423) (xy 37.350199 -80.559406) (xy 37.334131 -80.612813) (xy 37.310459 -80.66331)
			(xy 37.279686 -80.709823) (xy 37.242469 -80.75136) (xy 37.199601 -80.787035) (xy 37.168467 -80.806036)
			(xy 37.951154 -80.806036) (xy 37.955225 -80.750414) (xy 37.967351 -80.695977) (xy 37.987274 -80.643886)
			(xy 38.01457 -80.595251) (xy 38.048656 -80.551108) (xy 38.088805 -80.512399) (xy 38.134163 -80.479948)
			(xy 38.183763 -80.454447) (xy 38.236547 -80.43644) (xy 38.29139 -80.42631) (xy 38.347124 -80.424273)
			(xy 38.402561 -80.430373) (xy 38.456518 -80.444479) (xy 38.507847 -80.466291) (xy 38.555453 -80.495345)
			(xy 38.598321 -80.53102) (xy 38.6192 -80.554322) (xy 40.642284 -80.554322) (xy 40.646355 -80.4987)
			(xy 40.658481 -80.444263) (xy 40.678404 -80.392172) (xy 40.7057 -80.343537) (xy 40.739786 -80.299394)
			(xy 40.779935 -80.260685) (xy 40.825293 -80.228234) (xy 40.874893 -80.202733) (xy 40.927677 -80.184726)
			(xy 40.98252 -80.174596) (xy 41.038254 -80.172559) (xy 41.093691 -80.178659) (xy 41.147648 -80.192765)
			(xy 41.198977 -80.214577) (xy 41.246583 -80.243631) (xy 41.289451 -80.279306) (xy 41.326668 -80.320843)
			(xy 41.357441 -80.367356) (xy 41.381113 -80.417853) (xy 41.397181 -80.47126) (xy 41.405301 -80.526436)
			(xy 41.40581 -80.554322) (xy 41.405301 -80.582208) (xy 41.397181 -80.637384) (xy 41.381113 -80.690791)
			(xy 41.357441 -80.741288) (xy 41.326668 -80.787801) (xy 41.289451 -80.829338) (xy 41.246583 -80.865013)
			(xy 41.198977 -80.894067) (xy 41.147648 -80.915879) (xy 41.093691 -80.929985) (xy 41.038254 -80.936085)
			(xy 40.98252 -80.934048) (xy 40.927677 -80.923918) (xy 40.874893 -80.905911) (xy 40.825293 -80.88041)
			(xy 40.779935 -80.847959) (xy 40.739786 -80.80925) (xy 40.7057 -80.765107) (xy 40.678404 -80.716472)
			(xy 40.658481 -80.664381) (xy 40.646355 -80.609944) (xy 40.642284 -80.554322) (xy 38.6192 -80.554322)
			(xy 38.635538 -80.572557) (xy 38.666311 -80.61907) (xy 38.689983 -80.669567) (xy 38.706051 -80.722974)
			(xy 38.714171 -80.77815) (xy 38.71468 -80.806036) (xy 38.714171 -80.833922) (xy 38.706051 -80.889098)
			(xy 38.689983 -80.942505) (xy 38.666311 -80.993002) (xy 38.635538 -81.039515) (xy 38.598321 -81.081052)
			(xy 38.555453 -81.116727) (xy 38.507847 -81.145781) (xy 38.456518 -81.167593) (xy 38.402561 -81.181699)
			(xy 38.347124 -81.187799) (xy 38.29139 -81.185762) (xy 38.236547 -81.175632) (xy 38.183763 -81.157625)
			(xy 38.134163 -81.132124) (xy 38.088805 -81.099673) (xy 38.048656 -81.060964) (xy 38.01457 -81.016821)
			(xy 37.987274 -80.968186) (xy 37.967351 -80.916095) (xy 37.955225 -80.861658) (xy 37.951154 -80.806036)
			(xy 37.168467 -80.806036) (xy 37.151995 -80.816089) (xy 37.100666 -80.837901) (xy 37.046709 -80.852007)
			(xy 36.991272 -80.858107) (xy 36.935538 -80.85607) (xy 36.880695 -80.84594) (xy 36.827911 -80.827933)
			(xy 36.778311 -80.802432) (xy 36.732953 -80.769981) (xy 36.692804 -80.731272) (xy 36.658718 -80.687129)
			(xy 36.631422 -80.638494) (xy 36.611499 -80.586403) (xy 36.599373 -80.531966) (xy 36.595302 -80.476344)
			(xy 34.48304 -80.476344) (xy 34.48304 -80.697832) (xy 34.483478 -80.713281) (xy 34.490914 -80.74327)
			(xy 34.505343 -80.770592) (xy 34.515298 -80.782414) (xy 34.533514 -80.803519) (xy 34.564262 -80.85002)
			(xy 34.587914 -80.900501) (xy 34.603967 -80.953888) (xy 34.612079 -81.009042) (xy 34.612077 -81.06479)
			(xy 34.60396 -81.119944) (xy 34.587903 -81.173329) (xy 34.564246 -81.223809) (xy 34.533494 -81.270307)
			(xy 34.515298 -81.29143) (xy 34.505331 -81.303244) (xy 34.4909 -81.330568) (xy 34.483467 -81.360562)
			(xy 34.48304 -81.376012) (xy 34.48304 -81.778348) (xy 34.515552 -81.836006) (xy 34.544254 -81.853532)
			(xy 34.567952 -81.868438) (xy 34.611107 -81.904097) (xy 34.648587 -81.945683) (xy 34.679585 -81.9923)
			(xy 34.703435 -82.042948) (xy 34.719625 -82.096539) (xy 34.727807 -82.15192) (xy 34.727806 -82.179922)
			(xy 36.727382 -82.179922) (xy 36.731453 -82.1243) (xy 36.743579 -82.069863) (xy 36.763502 -82.017772)
			(xy 36.790798 -81.969137) (xy 36.824884 -81.924994) (xy 36.865033 -81.886285) (xy 36.910391 -81.853834)
			(xy 36.959991 -81.828333) (xy 37.012775 -81.810326) (xy 37.067618 -81.800196) (xy 37.123352 -81.798159)
			(xy 37.178789 -81.804259) (xy 37.232746 -81.818365) (xy 37.284075 -81.840177) (xy 37.331681 -81.869231)
			(xy 37.374549 -81.904906) (xy 37.411766 -81.946443) (xy 37.442539 -81.992956) (xy 37.466211 -82.043453)
			(xy 37.482279 -82.09686) (xy 37.490399 -82.152036) (xy 37.490908 -82.179922) (xy 37.490399 -82.207808)
			(xy 37.482279 -82.262984) (xy 37.466211 -82.316391) (xy 37.442539 -82.366888) (xy 37.411766 -82.413401)
			(xy 37.374549 -82.454938) (xy 37.331681 -82.490613) (xy 37.284075 -82.519667) (xy 37.232746 -82.541479)
			(xy 37.178789 -82.555585) (xy 37.123352 -82.561685) (xy 37.067618 -82.559648) (xy 37.012775 -82.549518)
			(xy 36.959991 -82.531511) (xy 36.910391 -82.50601) (xy 36.865033 -82.473559) (xy 36.824884 -82.43485)
			(xy 36.790798 -82.390707) (xy 36.763502 -82.342072) (xy 36.743579 -82.289981) (xy 36.731453 -82.235544)
			(xy 36.727382 -82.179922) (xy 34.727806 -82.179922) (xy 34.727805 -82.207903) (xy 34.71962 -82.263284)
			(xy 34.703426 -82.316873) (xy 34.679573 -82.36752) (xy 34.648573 -82.414135) (xy 34.611091 -82.455718)
			(xy 34.567933 -82.491376) (xy 34.544254 -82.506312) (xy 34.515552 -82.523838) (xy 34.48304 -82.581496)
			(xy 34.48304 -83.326519) (xy 40.147525 -83.326519) (xy 40.149904 -83.271295) (xy 40.160229 -83.216992)
			(xy 40.178284 -83.164748) (xy 40.203692 -83.115657) (xy 40.235919 -83.070748) (xy 40.274291 -83.030961)
			(xy 40.318005 -82.99713) (xy 40.366144 -82.969963) (xy 40.4177 -82.950028) (xy 40.471594 -82.937745)
			(xy 40.526696 -82.933369) (xy 40.581853 -82.936993) (xy 40.635909 -82.948541) (xy 40.687732 -82.96777)
			(xy 40.736237 -82.994278) (xy 40.758618 -83.010502) (xy 40.77267 -83.020342) (xy 40.804583 -83.032892)
			(xy 40.838683 -83.03651) (xy 40.872519 -83.030935) (xy 40.903655 -83.016567) (xy 40.917114 -83.00593)
			(xy 40.932611 -82.993122) (xy 40.965824 -82.970465) (xy 40.983408 -82.960718) (xy 40.996767 -82.953034)
			(xy 41.019599 -82.932343) (xy 41.036807 -82.906785) (xy 41.047389 -82.877847) (xy 41.050729 -82.847217)
			(xy 41.046631 -82.816679) (xy 41.035334 -82.788013) (xy 41.017497 -82.762889) (xy 40.99416 -82.742771)
			(xy 40.980614 -82.73542) (xy 40.956403 -82.722632) (xy 40.911544 -82.691241) (xy 40.871634 -82.653758)
			(xy 40.837494 -82.610954) (xy 40.809824 -82.563709) (xy 40.789193 -82.512993) (xy 40.776026 -82.459848)
			(xy 40.770592 -82.405367) (xy 40.773004 -82.350668) (xy 40.783212 -82.296877) (xy 40.801006 -82.245097)
			(xy 40.82602 -82.196394) (xy 40.857741 -82.151767) (xy 40.895517 -82.112134) (xy 40.938571 -82.07831)
			(xy 40.986019 -82.050989) (xy 41.036886 -82.030732) (xy 41.090126 -82.017957) (xy 41.144646 -82.012925)
			(xy 41.199325 -82.01574) (xy 41.25304 -82.026343) (xy 41.304687 -82.044518) (xy 41.353205 -82.069891)
			(xy 41.397597 -82.101939) (xy 41.43695 -82.140006) (xy 41.470456 -82.183308) (xy 41.497427 -82.230956)
			(xy 41.517309 -82.28197) (xy 41.529692 -82.335303) (xy 41.534322 -82.389859) (xy 41.531104 -82.444516)
			(xy 41.520105 -82.498151) (xy 41.501551 -82.549663) (xy 41.475821 -82.597993) (xy 41.443447 -82.642147)
			(xy 41.424606 -82.662014) (xy 41.409395 -82.67829) (xy 41.384234 -82.715046) (xy 41.365861 -82.755623)
			(xy 41.354837 -82.79878) (xy 41.3515 -82.843197) (xy 41.355951 -82.887517) (xy 41.368055 -82.930384)
			(xy 41.387441 -82.970487) (xy 41.413516 -83.006599) (xy 41.429178 -83.02244) (xy 41.448572 -83.04184)
			(xy 41.48214 -83.085224) (xy 41.509148 -83.132968) (xy 41.529039 -83.184089) (xy 41.541404 -83.237531)
			(xy 41.545988 -83.292194) (xy 41.542695 -83.346949) (xy 41.531594 -83.400668) (xy 41.512914 -83.452244)
			(xy 41.48704 -83.500612) (xy 41.454505 -83.544776) (xy 41.41598 -83.583825) (xy 41.37226 -83.616954)
			(xy 41.324246 -83.64348) (xy 41.272927 -83.662856) (xy 41.219363 -83.674681) (xy 41.164657 -83.678714)
			(xy 41.109938 -83.67487) (xy 41.056333 -83.663228) (xy 41.004948 -83.644029) (xy 40.956843 -83.617669)
			(xy 40.93464 -83.60156) (xy 40.920612 -83.591683) (xy 40.88869 -83.579143) (xy 40.854583 -83.575534)
			(xy 40.820743 -83.581118) (xy 40.789604 -83.595491) (xy 40.776144 -83.606132) (xy 40.754732 -83.623615)
			(xy 40.707868 -83.652926) (xy 40.657263 -83.675166) (xy 40.603978 -83.689868) (xy 40.549129 -83.696725)
			(xy 40.493865 -83.695592) (xy 40.439343 -83.686495) (xy 40.386705 -83.669623) (xy 40.337054 -83.645329)
			(xy 40.291429 -83.614123) (xy 40.250787 -83.576658) (xy 40.215978 -83.533719) (xy 40.187731 -83.486206)
			(xy 40.166639 -83.435112) (xy 40.153143 -83.381509) (xy 40.147525 -83.326519) (xy 34.48304 -83.326519)
			(xy 34.48304 -83.744816) (xy 34.483569 -83.768149) (xy 34.492089 -83.81403) (xy 34.50884 -83.857585)
			(xy 34.51134 -83.861656) (xy 38.030402 -83.861656) (xy 38.034473 -83.806034) (xy 38.046599 -83.751597)
			(xy 38.066522 -83.699506) (xy 38.093818 -83.650871) (xy 38.127904 -83.606728) (xy 38.168053 -83.568019)
			(xy 38.213411 -83.535568) (xy 38.263011 -83.510067) (xy 38.315795 -83.49206) (xy 38.370638 -83.48193)
			(xy 38.426372 -83.479893) (xy 38.481809 -83.485993) (xy 38.535766 -83.500099) (xy 38.587095 -83.521911)
			(xy 38.634701 -83.550965) (xy 38.677569 -83.58664) (xy 38.714786 -83.628177) (xy 38.745559 -83.67469)
			(xy 38.769231 -83.725187) (xy 38.785299 -83.778594) (xy 38.793419 -83.83377) (xy 38.793928 -83.861656)
			(xy 38.793419 -83.889542) (xy 38.785299 -83.944718) (xy 38.769231 -83.998125) (xy 38.745559 -84.048622)
			(xy 38.714786 -84.095135) (xy 38.677569 -84.136672) (xy 38.634701 -84.172347) (xy 38.587095 -84.201401)
			(xy 38.535766 -84.223213) (xy 38.481809 -84.237319) (xy 38.426372 -84.243419) (xy 38.370638 -84.241382)
			(xy 38.315795 -84.231252) (xy 38.263011 -84.213245) (xy 38.213411 -84.187744) (xy 38.168053 -84.155293)
			(xy 38.127904 -84.116584) (xy 38.093818 -84.072441) (xy 38.066522 -84.023806) (xy 38.046599 -83.971715)
			(xy 38.034473 -83.917278) (xy 38.030402 -83.861656) (xy 34.51134 -83.861656) (xy 34.533259 -83.897351)
			(xy 34.564526 -83.931993) (xy 34.60159 -83.960346) (xy 34.643206 -83.981458) (xy 34.687977 -83.99462)
			(xy 34.711132 -83.997546) (xy 34.738973 -84.000878) (xy 34.793323 -84.014663) (xy 34.84507 -84.036257)
			(xy 34.893097 -84.065194) (xy 34.93637 -84.10085) (xy 34.973957 -84.142458) (xy 35.005047 -84.189121)
			(xy 35.02897 -84.239832) (xy 35.045212 -84.2935) (xy 35.05342 -84.348967) (xy 35.05342 -84.405038)
			(xy 35.045211 -84.460505) (xy 35.028969 -84.514172) (xy 35.005045 -84.564883) (xy 34.973954 -84.611545)
			(xy 34.936367 -84.653153) (xy 34.893094 -84.688809) (xy 34.845066 -84.717745) (xy 34.793319 -84.739338)
			(xy 34.738969 -84.753122) (xy 34.711132 -84.756498) (xy 34.687973 -84.759401) (xy 34.643196 -84.772553)
			(xy 34.601574 -84.793663) (xy 34.564507 -84.822018) (xy 34.533242 -84.856666) (xy 34.50883 -84.896441)
			(xy 34.492093 -84.940005) (xy 34.483593 -84.985893) (xy 34.48304 -85.009228) (xy 34.48304 -85.421724)
			(xy 37.847522 -85.421724) (xy 37.851593 -85.366102) (xy 37.863719 -85.311665) (xy 37.883642 -85.259574)
			(xy 37.910938 -85.210939) (xy 37.945024 -85.166796) (xy 37.985173 -85.128087) (xy 38.030531 -85.095636)
			(xy 38.080131 -85.070135) (xy 38.132915 -85.052128) (xy 38.187758 -85.041998) (xy 38.243492 -85.039961)
			(xy 38.298929 -85.046061) (xy 38.352886 -85.060167) (xy 38.404215 -85.081979) (xy 38.451821 -85.111033)
			(xy 38.494689 -85.146708) (xy 38.531906 -85.188245) (xy 38.562679 -85.234758) (xy 38.586351 -85.285255)
			(xy 38.602419 -85.338662) (xy 38.610539 -85.393838) (xy 38.611048 -85.421724) (xy 38.610539 -85.44961)
			(xy 38.602419 -85.504786) (xy 38.594637 -85.530652) (xy 39.356763 -85.530652) (xy 39.356893 -85.475168)
			(xy 39.365059 -85.420289) (xy 39.381089 -85.367171) (xy 39.404645 -85.316936) (xy 39.435231 -85.270644)
			(xy 39.4722 -85.229271) (xy 39.514772 -85.19369) (xy 39.56205 -85.164651) (xy 39.613036 -85.142768)
			(xy 39.666655 -85.128502) (xy 39.721774 -85.122155) (xy 39.777232 -85.123859) (xy 39.831857 -85.13358)
			(xy 39.884498 -85.151111) (xy 39.909496 -85.163152) (xy 39.929502 -85.172665) (xy 39.971924 -85.18541)
			(xy 40.015913 -85.190611) (xy 40.060137 -85.188109) (xy 40.103259 -85.177981) (xy 40.143973 -85.160534)
			(xy 40.181048 -85.136295) (xy 40.197532 -85.121496) (xy 40.218427 -85.102672) (xy 40.264682 -85.070685)
			(xy 40.31513 -85.045833) (xy 40.368681 -85.028656) (xy 40.424172 -85.019525) (xy 40.480402 -85.018637)
			(xy 40.536154 -85.026013) (xy 40.59022 -85.041492) (xy 40.641427 -85.064739) (xy 40.688668 -85.095251)
			(xy 40.730919 -85.132366) (xy 40.749474 -85.1535) (xy 40.764234 -85.170182) (xy 40.798507 -85.198626)
			(xy 40.837212 -85.220661) (xy 40.879167 -85.235612) (xy 40.923085 -85.24302) (xy 40.967622 -85.24266)
			(xy 41.011414 -85.234541) (xy 41.03243 -85.22716) (xy 41.058614 -85.217878) (xy 41.11292 -85.206176)
			(xy 41.16835 -85.202477) (xy 41.22373 -85.206858) (xy 41.277888 -85.219227) (xy 41.329679 -85.239321)
			(xy 41.378008 -85.266716) (xy 41.421851 -85.300832) (xy 41.460281 -85.340947) (xy 41.492485 -85.386213)
			(xy 41.517782 -85.435672) (xy 41.535636 -85.488278) (xy 41.54567 -85.542917) (xy 41.547672 -85.598434)
			(xy 41.541599 -85.653653) (xy 41.527579 -85.707408) (xy 41.50591 -85.75856) (xy 41.477049 -85.806028)
			(xy 41.441608 -85.848807) (xy 41.400335 -85.885992) (xy 41.354105 -85.916796) (xy 41.303896 -85.940568)
			(xy 41.250768 -85.956804) (xy 41.195848 -85.965162) (xy 41.140296 -85.965464) (xy 41.085288 -85.957704)
			(xy 41.031987 -85.942047) (xy 40.981522 -85.918822) (xy 40.934959 -85.888523) (xy 40.893285 -85.851789)
			(xy 40.87495 -85.830918) (xy 40.860168 -85.814256) (xy 40.825901 -85.785809) (xy 40.787199 -85.763772)
			(xy 40.745249 -85.748818) (xy 40.701334 -85.741406) (xy 40.656799 -85.741764) (xy 40.613009 -85.749879)
			(xy 40.591994 -85.757258) (xy 40.567262 -85.765996) (xy 40.516072 -85.777431) (xy 40.463798 -85.781753)
			(xy 40.411424 -85.778881) (xy 40.359937 -85.768869) (xy 40.310304 -85.751905) (xy 40.286686 -85.740494)
			(xy 40.266691 -85.730955) (xy 40.224266 -85.718209) (xy 40.180273 -85.71301) (xy 40.136046 -85.715515)
			(xy 40.092922 -85.725647) (xy 40.052207 -85.743101) (xy 40.015133 -85.767347) (xy 39.99865 -85.78215)
			(xy 39.978066 -85.800755) (xy 39.932512 -85.832429) (xy 39.882849 -85.85717) (xy 39.830127 -85.874456)
			(xy 39.775457 -85.883921) (xy 39.719992 -85.885366) (xy 39.664902 -85.878761) (xy 39.611351 -85.864245)
			(xy 39.560468 -85.842124) (xy 39.513326 -85.812865) (xy 39.47092 -85.777086) (xy 39.434145 -85.73554)
			(xy 39.403776 -85.689105) (xy 39.380455 -85.638761) (xy 39.364673 -85.585569) (xy 39.356763 -85.530652)
			(xy 38.594637 -85.530652) (xy 38.586351 -85.558193) (xy 38.562679 -85.60869) (xy 38.531906 -85.655203)
			(xy 38.494689 -85.69674) (xy 38.451821 -85.732415) (xy 38.404215 -85.761469) (xy 38.352886 -85.783281)
			(xy 38.298929 -85.797387) (xy 38.243492 -85.803487) (xy 38.187758 -85.80145) (xy 38.132915 -85.79132)
			(xy 38.080131 -85.773313) (xy 38.030531 -85.747812) (xy 37.985173 -85.715361) (xy 37.945024 -85.676652)
			(xy 37.910938 -85.632509) (xy 37.883642 -85.583874) (xy 37.863719 -85.531783) (xy 37.851593 -85.477346)
			(xy 37.847522 -85.421724) (xy 34.48304 -85.421724) (xy 34.48304 -86.416388) (xy 34.515044 -86.448392)
			(xy 36.37788 -90.44305) (xy 36.37788 -92.574364) (xy 38.39464 -94.591124) (xy 49.254662 -94.591124)
			(xy 49.258733 -94.535502) (xy 49.270859 -94.481065) (xy 49.290782 -94.428974) (xy 49.318078 -94.380339)
			(xy 49.352164 -94.336196) (xy 49.392313 -94.297487) (xy 49.437671 -94.265036) (xy 49.487271 -94.239535)
			(xy 49.540055 -94.221528) (xy 49.594898 -94.211398) (xy 49.650632 -94.209361) (xy 49.706069 -94.215461)
			(xy 49.760026 -94.229567) (xy 49.811355 -94.251379) (xy 49.858961 -94.280433) (xy 49.901829 -94.316108)
			(xy 49.939046 -94.357645) (xy 49.969819 -94.404158) (xy 49.993491 -94.454655) (xy 50.009559 -94.508062)
			(xy 50.017679 -94.563238) (xy 50.018188 -94.591124) (xy 50.017679 -94.61901) (xy 50.009559 -94.674186)
			(xy 49.993491 -94.727593) (xy 49.969819 -94.77809) (xy 49.939046 -94.824603) (xy 49.901829 -94.86614)
			(xy 49.858961 -94.901815) (xy 49.811355 -94.930869) (xy 49.760026 -94.952681) (xy 49.706069 -94.966787)
			(xy 49.650632 -94.972887) (xy 49.594898 -94.97085) (xy 49.540055 -94.96072) (xy 49.487271 -94.942713)
			(xy 49.437671 -94.917212) (xy 49.392313 -94.884761) (xy 49.352164 -94.846052) (xy 49.318078 -94.801909)
			(xy 49.290782 -94.753274) (xy 49.270859 -94.701183) (xy 49.258733 -94.646746) (xy 49.254662 -94.591124)
			(xy 38.39464 -94.591124) (xy 39.268908 -95.465392) (xy 40.204644 -95.465392) (xy 40.273478 -95.411036)
			(xy 40.283892 -95.36811) (xy 40.291037 -95.340743) (xy 40.312299 -95.288332) (xy 40.341067 -95.239634)
			(xy 40.376708 -95.195717) (xy 40.418442 -95.157543) (xy 40.465355 -95.125949) (xy 40.516418 -95.101627)
			(xy 40.570512 -95.08511) (xy 40.626452 -95.07676) (xy 40.683012 -95.07676) (xy 40.738952 -95.08511)
			(xy 40.793046 -95.101627) (xy 40.844109 -95.125949) (xy 40.891022 -95.157543) (xy 40.932756 -95.195717)
			(xy 40.968397 -95.239634) (xy 40.997165 -95.288332) (xy 41.018427 -95.340743) (xy 41.025572 -95.36811)
			(xy 41.030065 -95.384493) (xy 41.04643 -95.414247) (xy 41.070062 -95.438634) (xy 41.099287 -95.455927)
			(xy 41.132037 -95.464902) (xy 41.149016 -95.465392) (xy 42.24909 -95.465392) (xy 42.314622 -95.419672)
			(xy 42.328338 -95.38208) (xy 42.338182 -95.356493) (xy 42.364157 -95.308214) (xy 42.396774 -95.26415)
			(xy 42.435363 -95.225208) (xy 42.479128 -95.192191) (xy 42.527169 -95.165778) (xy 42.578495 -95.146513)
			(xy 42.63205 -95.134793) (xy 42.686732 -95.130859) (xy 42.741414 -95.134793) (xy 42.794969 -95.146513)
			(xy 42.846295 -95.165778) (xy 42.894336 -95.192191) (xy 42.938101 -95.225208) (xy 42.97669 -95.26415)
			(xy 43.009307 -95.308214) (xy 43.035282 -95.356493) (xy 43.045126 -95.38208) (xy 43.050884 -95.396474)
			(xy 43.06827 -95.42213) (xy 43.091325 -95.442842) (xy 43.118692 -95.457389) (xy 43.148757 -95.464915)
			(xy 43.164252 -95.465392) (xy 44.315634 -95.465392) (xy 44.330169 -95.464998) (xy 44.358484 -95.458414)
			(xy 44.384565 -95.445574) (xy 44.407051 -95.427149) (xy 44.416218 -95.415862) (xy 44.432961 -95.394824)
			(xy 44.471379 -95.357209) (xy 44.514699 -95.325361) (xy 44.562061 -95.299911) (xy 44.612528 -95.281364)
			(xy 44.665098 -95.270086) (xy 44.718732 -95.266302) (xy 44.772366 -95.270086) (xy 44.824936 -95.281364)
			(xy 44.875403 -95.299911) (xy 44.922765 -95.325361) (xy 44.966085 -95.357209) (xy 45.004503 -95.394824)
			(xy 45.021246 -95.415862) (xy 45.030432 -95.427129) (xy 45.052923 -95.445538) (xy 45.078996 -95.458382)
			(xy 45.107298 -95.464995) (xy 45.12183 -95.465392) (xy 46.331124 -95.465392) (xy 46.346573 -95.464955)
			(xy 46.376565 -95.457522) (xy 46.40389 -95.443098) (xy 46.426947 -95.422528) (xy 46.436026 -95.41002)
			(xy 46.452561 -95.386824) (xy 46.491387 -95.345145) (xy 46.535979 -95.309703) (xy 46.585346 -95.281284)
			(xy 46.638388 -95.260522) (xy 46.693929 -95.247876) (xy 46.750732 -95.24363) (xy 46.807535 -95.247876)
			(xy 46.863076 -95.260522) (xy 46.916118 -95.281284) (xy 46.965485 -95.309703) (xy 47.010077 -95.345145)
			(xy 47.048903 -95.386824) (xy 47.065438 -95.41002) (xy 47.074506 -95.422541) (xy 47.097556 -95.443132)
			(xy 47.124885 -95.457567) (xy 47.154886 -95.464999) (xy 47.17034 -95.465392) (xy 47.365666 -95.465392)
			(xy 47.79899 -95.898716) (xy 48.558956 -95.898716) (xy 48.563027 -95.843094) (xy 48.575153 -95.788657)
			(xy 48.595076 -95.736566) (xy 48.622372 -95.687931) (xy 48.656458 -95.643788) (xy 48.696607 -95.605079)
			(xy 48.741965 -95.572628) (xy 48.791565 -95.547127) (xy 48.844349 -95.52912) (xy 48.899192 -95.51899)
			(xy 48.954926 -95.516953) (xy 49.010363 -95.523053) (xy 49.06432 -95.537159) (xy 49.115649 -95.558971)
			(xy 49.163255 -95.588025) (xy 49.206123 -95.6237) (xy 49.24334 -95.665237) (xy 49.274113 -95.71175)
			(xy 49.276624 -95.717106) (xy 49.894234 -95.717106) (xy 49.898305 -95.661484) (xy 49.910431 -95.607047)
			(xy 49.930354 -95.554956) (xy 49.95765 -95.506321) (xy 49.991736 -95.462178) (xy 50.031885 -95.423469)
			(xy 50.077243 -95.391018) (xy 50.126843 -95.365517) (xy 50.179627 -95.34751) (xy 50.23447 -95.33738)
			(xy 50.290204 -95.335343) (xy 50.345641 -95.341443) (xy 50.399598 -95.355549) (xy 50.450927 -95.377361)
			(xy 50.498533 -95.406415) (xy 50.541401 -95.44209) (xy 50.578618 -95.483627) (xy 50.609391 -95.53014)
			(xy 50.633063 -95.580637) (xy 50.649131 -95.634044) (xy 50.657251 -95.68922) (xy 50.65776 -95.717106)
			(xy 50.657375 -95.738188) (xy 51.135024 -95.738188) (xy 51.139095 -95.682566) (xy 51.151221 -95.628129)
			(xy 51.171144 -95.576038) (xy 51.19844 -95.527403) (xy 51.232526 -95.48326) (xy 51.272675 -95.444551)
			(xy 51.318033 -95.4121) (xy 51.367633 -95.386599) (xy 51.420417 -95.368592) (xy 51.47526 -95.358462)
			(xy 51.530994 -95.356425) (xy 51.586431 -95.362525) (xy 51.640388 -95.376631) (xy 51.691717 -95.398443)
			(xy 51.739323 -95.427497) (xy 51.782191 -95.463172) (xy 51.819408 -95.504709) (xy 51.850181 -95.551222)
			(xy 51.873853 -95.601719) (xy 51.889921 -95.655126) (xy 51.898041 -95.710302) (xy 51.89855 -95.738188)
			(xy 51.898041 -95.766074) (xy 51.889921 -95.82125) (xy 51.873853 -95.874657) (xy 51.850181 -95.925154)
			(xy 51.819408 -95.971667) (xy 51.782191 -96.013204) (xy 51.739323 -96.048879) (xy 51.691717 -96.077933)
			(xy 51.640388 -96.099745) (xy 51.586431 -96.113851) (xy 51.530994 -96.119951) (xy 51.47526 -96.117914)
			(xy 51.420417 -96.107784) (xy 51.367633 -96.089777) (xy 51.318033 -96.064276) (xy 51.272675 -96.031825)
			(xy 51.232526 -95.993116) (xy 51.19844 -95.948973) (xy 51.171144 -95.900338) (xy 51.151221 -95.848247)
			(xy 51.139095 -95.79381) (xy 51.135024 -95.738188) (xy 50.657375 -95.738188) (xy 50.657251 -95.744992)
			(xy 50.649131 -95.800168) (xy 50.633063 -95.853575) (xy 50.609391 -95.904072) (xy 50.578618 -95.950585)
			(xy 50.541401 -95.992122) (xy 50.498533 -96.027797) (xy 50.450927 -96.056851) (xy 50.399598 -96.078663)
			(xy 50.345641 -96.092769) (xy 50.290204 -96.098869) (xy 50.23447 -96.096832) (xy 50.179627 -96.086702)
			(xy 50.126843 -96.068695) (xy 50.077243 -96.043194) (xy 50.031885 -96.010743) (xy 49.991736 -95.972034)
			(xy 49.95765 -95.927891) (xy 49.930354 -95.879256) (xy 49.910431 -95.827165) (xy 49.898305 -95.772728)
			(xy 49.894234 -95.717106) (xy 49.276624 -95.717106) (xy 49.297785 -95.762247) (xy 49.313853 -95.815654)
			(xy 49.321973 -95.87083) (xy 49.322482 -95.898716) (xy 49.321973 -95.926602) (xy 49.313853 -95.981778)
			(xy 49.297785 -96.035185) (xy 49.274113 -96.085682) (xy 49.24334 -96.132195) (xy 49.206123 -96.173732)
			(xy 49.163255 -96.209407) (xy 49.115649 -96.238461) (xy 49.06432 -96.260273) (xy 49.010363 -96.274379)
			(xy 48.954926 -96.280479) (xy 48.899192 -96.278442) (xy 48.844349 -96.268312) (xy 48.791565 -96.250305)
			(xy 48.741965 -96.224804) (xy 48.696607 -96.192353) (xy 48.656458 -96.153644) (xy 48.622372 -96.109501)
			(xy 48.595076 -96.060866) (xy 48.575153 -96.008775) (xy 48.563027 -95.954338) (xy 48.558956 -95.898716)
			(xy 47.79899 -95.898716) (xy 48.896016 -96.995742) (xy 48.906743 -97.005904) (xy 48.931853 -97.021463)
			(xy 48.959873 -97.030817) (xy 48.989295 -97.03346) (xy 49.018533 -97.029252) (xy 49.032414 -97.02419)
			(xy 49.058343 -97.014534) (xy 49.112224 -97.001957) (xy 49.167356 -96.997294) (xy 49.222583 -97.000644)
			(xy 49.276748 -97.011936) (xy 49.328713 -97.030934) (xy 49.377389 -97.057239) (xy 49.421755 -97.090299)
			(xy 49.46088 -97.12942) (xy 49.493944 -97.173783) (xy 49.520253 -97.222457) (xy 49.539255 -97.274421)
			(xy 49.550552 -97.328584) (xy 49.553906 -97.383811) (xy 49.549248 -97.438944) (xy 49.536676 -97.492825)
			(xy 49.526952 -97.518728) (xy 49.521948 -97.532623) (xy 49.517759 -97.561848) (xy 49.520406 -97.591254)
			(xy 49.529746 -97.619262) (xy 49.545278 -97.64437) (xy 49.5554 -97.655126) (xy 49.58334 -97.683066)
			(xy 49.58334 -97.859088) (xy 51.403502 -97.859088) (xy 51.407573 -97.803466) (xy 51.419699 -97.749029)
			(xy 51.439622 -97.696938) (xy 51.466918 -97.648303) (xy 51.501004 -97.60416) (xy 51.541153 -97.565451)
			(xy 51.586511 -97.533) (xy 51.636111 -97.507499) (xy 51.688895 -97.489492) (xy 51.743738 -97.479362)
			(xy 51.799472 -97.477325) (xy 51.854909 -97.483425) (xy 51.908866 -97.497531) (xy 51.960195 -97.519343)
			(xy 52.007801 -97.548397) (xy 52.050669 -97.584072) (xy 52.087886 -97.625609) (xy 52.118659 -97.672122)
			(xy 52.142331 -97.722619) (xy 52.158399 -97.776026) (xy 52.166519 -97.831202) (xy 52.166869 -97.85036)
			(xy 53.976578 -97.85036) (xy 53.97799 -97.794265) (xy 53.987606 -97.738982) (xy 54.005217 -97.685705)
			(xy 54.030443 -97.635582) (xy 54.062741 -97.589696) (xy 54.101412 -97.549038) (xy 54.145624 -97.514483)
			(xy 54.19442 -97.486779) (xy 54.246749 -97.466523) (xy 54.301481 -97.454151) (xy 54.357435 -97.449932)
			(xy 54.413403 -97.453957) (xy 54.468178 -97.466137) (xy 54.520577 -97.486211) (xy 54.56947 -97.513745)
			(xy 54.613801 -97.548145) (xy 54.652614 -97.588669) (xy 54.685071 -97.634442) (xy 54.710472 -97.684477)
			(xy 54.728268 -97.737693) (xy 54.738076 -97.792941) (xy 54.739684 -97.849031) (xy 54.733057 -97.904751)
			(xy 54.718337 -97.958899) (xy 54.695844 -98.010306) (xy 54.681374 -98.034348) (xy 54.670098 -98.053329)
			(xy 54.653494 -98.09423) (xy 54.644211 -98.137387) (xy 54.642528 -98.181498) (xy 54.648497 -98.225236)
			(xy 54.661938 -98.267283) (xy 54.682446 -98.306374) (xy 54.709403 -98.341331) (xy 54.741997 -98.3711)
			(xy 54.760368 -98.383344) (xy 54.783774 -98.398829) (xy 54.826198 -98.435565) (xy 54.862783 -98.47812)
			(xy 54.892738 -98.525576) (xy 54.915417 -98.576909) (xy 54.93033 -98.63101) (xy 54.937156 -98.686713)
			(xy 54.935747 -98.742814) (xy 54.926134 -98.798104) (xy 54.908524 -98.851389) (xy 54.883297 -98.901519)
			(xy 54.850998 -98.947412) (xy 54.812324 -98.988077) (xy 54.768109 -99.022637) (xy 54.719308 -99.050347)
			(xy 54.666973 -99.070607) (xy 54.612235 -99.082982) (xy 54.556275 -99.087203) (xy 54.5003 -99.08318)
			(xy 54.445519 -99.070999) (xy 54.393113 -99.050923) (xy 54.344214 -99.023386) (xy 54.299877 -98.988983)
			(xy 54.26106 -98.948454) (xy 54.228599 -98.902676) (xy 54.203195 -98.852635) (xy 54.185397 -98.799413)
			(xy 54.175588 -98.744158) (xy 54.173981 -98.688061) (xy 54.18061 -98.632335) (xy 54.195332 -98.578181)
			(xy 54.21783 -98.526769) (xy 54.232302 -98.502724) (xy 54.243586 -98.483749) (xy 54.260181 -98.442845)
			(xy 54.269457 -98.399689) (xy 54.271135 -98.355579) (xy 54.265164 -98.311842) (xy 54.251723 -98.269796)
			(xy 54.231218 -98.230706) (xy 54.204265 -98.195748) (xy 54.171676 -98.165974) (xy 54.153308 -98.153728)
			(xy 54.12992 -98.138222) (xy 54.087503 -98.101487) (xy 54.050927 -98.058934) (xy 54.020979 -98.011481)
			(xy 53.998307 -97.960152) (xy 53.983399 -97.906056) (xy 53.976578 -97.85036) (xy 52.166869 -97.85036)
			(xy 52.167028 -97.859088) (xy 52.166519 -97.886974) (xy 52.158399 -97.94215) (xy 52.142331 -97.995557)
			(xy 52.118659 -98.046054) (xy 52.087886 -98.092567) (xy 52.050669 -98.134104) (xy 52.007801 -98.169779)
			(xy 51.960195 -98.198833) (xy 51.908866 -98.220645) (xy 51.854909 -98.234751) (xy 51.799472 -98.240851)
			(xy 51.743738 -98.238814) (xy 51.688895 -98.228684) (xy 51.636111 -98.210677) (xy 51.586511 -98.185176)
			(xy 51.541153 -98.152725) (xy 51.501004 -98.114016) (xy 51.466918 -98.069873) (xy 51.439622 -98.021238)
			(xy 51.419699 -97.969147) (xy 51.407573 -97.91471) (xy 51.403502 -97.859088) (xy 49.58334 -97.859088)
			(xy 49.58334 -98.785172) (xy 49.583794 -98.80086) (xy 49.591457 -98.831284) (xy 49.606347 -98.8589)
			(xy 49.616614 -98.87077) (xy 49.63525 -98.891965) (xy 49.666714 -98.938815) (xy 49.690932 -98.98979)
			(xy 49.707377 -99.043776) (xy 49.715689 -99.099596) (xy 49.715689 -99.102672) (xy 50.529488 -99.102672)
			(xy 50.533559 -99.04705) (xy 50.545685 -98.992613) (xy 50.565608 -98.940522) (xy 50.592904 -98.891887)
			(xy 50.62699 -98.847744) (xy 50.667139 -98.809035) (xy 50.712497 -98.776584) (xy 50.762097 -98.751083)
			(xy 50.814881 -98.733076) (xy 50.869724 -98.722946) (xy 50.925458 -98.720909) (xy 50.980895 -98.727009)
			(xy 51.034852 -98.741115) (xy 51.086181 -98.762927) (xy 51.133787 -98.791981) (xy 51.176655 -98.827656)
			(xy 51.213872 -98.869193) (xy 51.244645 -98.915706) (xy 51.268317 -98.966203) (xy 51.284385 -99.01961)
			(xy 51.292505 -99.074786) (xy 51.293014 -99.102672) (xy 51.292505 -99.130558) (xy 51.284385 -99.185734)
			(xy 51.268317 -99.239141) (xy 51.246613 -99.28544) (xy 55.012797 -99.28544) (xy 55.016868 -99.230576)
			(xy 55.028777 -99.176866) (xy 55.048278 -99.125423) (xy 55.074966 -99.077315) (xy 55.108288 -99.03354)
			(xy 55.147551 -98.995005) (xy 55.191944 -98.962509) (xy 55.240543 -98.936727) (xy 55.292342 -98.918193)
			(xy 55.346266 -98.907292) (xy 55.401196 -98.90425) (xy 55.455994 -98.90913) (xy 55.509523 -98.92183)
			(xy 55.560672 -98.942088) (xy 55.608381 -98.969483) (xy 55.630318 -98.986086) (xy 55.648996 -99.000121)
			(xy 55.690411 -99.021738) (xy 55.735078 -99.035422) (xy 55.781494 -99.040714) (xy 55.828096 -99.037434)
			(xy 55.873313 -99.025694) (xy 55.915624 -99.005889) (xy 55.953604 -98.978686) (xy 55.97017 -98.96221)
			(xy 55.989767 -98.942485) (xy 56.033694 -98.908397) (xy 56.082107 -98.88105) (xy 56.133977 -98.861024)
			(xy 56.188206 -98.848743) (xy 56.243644 -98.844469) (xy 56.271414 -98.845878) (xy 56.292889 -98.846901)
			(xy 56.335659 -98.842567) (xy 56.37709 -98.831096) (xy 56.416 -98.812816) (xy 56.451278 -98.788249)
			(xy 56.481919 -98.758096) (xy 56.507048 -98.723216) (xy 56.525949 -98.684604) (xy 56.538082 -98.643362)
			(xy 56.543101 -98.600667) (xy 56.542432 -98.579178) (xy 56.541421 -98.547218) (xy 56.54882 -98.483706)
			(xy 56.566687 -98.422313) (xy 56.580024 -98.39325) (xy 56.589646 -98.37224) (xy 56.601921 -98.327693)
			(xy 56.605943 -98.281661) (xy 56.601581 -98.23566) (xy 56.588978 -98.191205) (xy 56.568549 -98.149759)
			(xy 56.540967 -98.112687) (xy 56.524398 -98.096578) (xy 56.504242 -98.07704) (xy 56.469231 -98.033164)
			(xy 56.441029 -97.984631) (xy 56.420243 -97.932488) (xy 56.407324 -97.877863) (xy 56.40255 -97.821934)
			(xy 56.406025 -97.765909) (xy 56.417672 -97.710998) (xy 56.437241 -97.658388) (xy 56.46431 -97.609213)
			(xy 56.498293 -97.564536) (xy 56.538456 -97.525322) (xy 56.583933 -97.492418) (xy 56.633741 -97.466534)
			(xy 56.686805 -97.448229) (xy 56.741979 -97.437899) (xy 56.798071 -97.435766) (xy 56.853869 -97.441876)
			(xy 56.90817 -97.456099) (xy 56.9598 -97.478125) (xy 57.007645 -97.507481) (xy 57.05067 -97.543532)
			(xy 57.087948 -97.585499) (xy 57.118673 -97.632476) (xy 57.142181 -97.683448) (xy 57.157965 -97.737316)
			(xy 57.165684 -97.792915) (xy 57.165171 -97.849045) (xy 57.156437 -97.904494) (xy 57.139672 -97.958064)
			(xy 57.127902 -97.983548) (xy 57.1183 -98.004566) (xy 57.106029 -98.04911) (xy 57.102008 -98.095139)
			(xy 57.106368 -98.141137) (xy 57.118967 -98.18559) (xy 57.139389 -98.227035) (xy 57.166963 -98.264109)
			(xy 57.183528 -98.28022) (xy 57.20347 -98.299327) (xy 57.238013 -98.342424) (xy 57.265981 -98.390051)
			(xy 57.28679 -98.441213) (xy 57.300005 -98.49484) (xy 57.305349 -98.549813) (xy 57.302711 -98.604982)
			(xy 57.292147 -98.659193) (xy 57.273877 -98.711316) (xy 57.248282 -98.760259) (xy 57.215898 -98.805001)
			(xy 57.177401 -98.844606) (xy 57.133597 -98.878246) (xy 57.085399 -98.905219) (xy 57.033816 -98.924961)
			(xy 56.979926 -98.93706) (xy 56.924854 -98.941262) (xy 56.89727 -98.939858) (xy 56.875796 -98.938781)
			(xy 56.833021 -98.943119) (xy 56.791586 -98.954594) (xy 56.752673 -98.972879) (xy 56.717393 -98.997452)
			(xy 56.686751 -99.027612) (xy 56.661623 -99.062499) (xy 56.642724 -99.101117) (xy 56.630594 -99.142365)
			(xy 56.62558 -99.185067) (xy 56.626252 -99.206558) (xy 56.627128 -99.233837) (xy 56.62217 -99.288187)
			(xy 56.609518 -99.341276) (xy 56.58943 -99.39202) (xy 56.562316 -99.439383) (xy 56.528729 -99.4824)
			(xy 56.489354 -99.520191) (xy 56.444996 -99.551985) (xy 56.396561 -99.577134) (xy 56.345035 -99.595124)
			(xy 56.291472 -99.605587) (xy 56.236965 -99.608311) (xy 56.182625 -99.60324) (xy 56.129563 -99.590477)
			(xy 56.078861 -99.570283) (xy 56.031554 -99.54307) (xy 56.009794 -99.526598) (xy 55.991106 -99.512577)
			(xy 55.949694 -99.490962) (xy 55.905028 -99.477277) (xy 55.858614 -99.471984) (xy 55.812015 -99.475262)
			(xy 55.766799 -99.486999) (xy 55.724488 -99.506801) (xy 55.686509 -99.534) (xy 55.669942 -99.550474)
			(xy 55.650533 -99.569973) (xy 55.607119 -99.603764) (xy 55.559302 -99.630969) (xy 55.508073 -99.651023)
			(xy 55.454494 -99.66351) (xy 55.399677 -99.668172) (xy 55.344759 -99.664912) (xy 55.290879 -99.653796)
			(xy 55.239154 -99.635056) (xy 55.190658 -99.609081) (xy 55.146395 -99.576409) (xy 55.107285 -99.537718)
			(xy 55.074138 -99.493811) (xy 55.047641 -99.445597) (xy 55.028345 -99.394077) (xy 55.01665 -99.34032)
			(xy 55.012797 -99.28544) (xy 51.246613 -99.28544) (xy 51.244645 -99.289638) (xy 51.213872 -99.336151)
			(xy 51.176655 -99.377688) (xy 51.133787 -99.413363) (xy 51.086181 -99.442417) (xy 51.034852 -99.464229)
			(xy 50.980895 -99.478335) (xy 50.925458 -99.484435) (xy 50.869724 -99.482398) (xy 50.814881 -99.472268)
			(xy 50.762097 -99.454261) (xy 50.712497 -99.42876) (xy 50.667139 -99.396309) (xy 50.62699 -99.3576)
			(xy 50.592904 -99.313457) (xy 50.565608 -99.264822) (xy 50.545685 -99.212731) (xy 50.533559 -99.158294)
			(xy 50.529488 -99.102672) (xy 49.715689 -99.102672) (xy 49.715687 -99.156031) (xy 49.707371 -99.21185)
			(xy 49.690923 -99.265835) (xy 49.6667 -99.316808) (xy 49.635233 -99.363656) (xy 49.616614 -99.384866)
			(xy 49.606391 -99.396763) (xy 49.591542 -99.424383) (xy 49.583857 -99.454786) (xy 49.58334 -99.470464)
			(xy 49.58334 -100.32365) (xy 49.583908 -100.34081) (xy 49.593064 -100.373885) (xy 49.6107 -100.403327)
			(xy 49.62271 -100.415598) (xy 49.641632 -100.434236) (xy 49.674659 -100.475831) (xy 49.701597 -100.521605)
			(xy 49.721926 -100.570673) (xy 49.735253 -100.622086) (xy 49.74132 -100.674851) (xy 49.740898 -100.69195)
			(xy 50.541934 -100.69195) (xy 50.546005 -100.636328) (xy 50.558131 -100.581891) (xy 50.578054 -100.5298)
			(xy 50.60535 -100.481165) (xy 50.639436 -100.437022) (xy 50.679585 -100.398313) (xy 50.724943 -100.365862)
			(xy 50.774543 -100.340361) (xy 50.827327 -100.322354) (xy 50.88217 -100.312224) (xy 50.937904 -100.310187)
			(xy 50.993341 -100.316287) (xy 51.047298 -100.330393) (xy 51.098627 -100.352205) (xy 51.146233 -100.381259)
			(xy 51.189101 -100.416934) (xy 51.226318 -100.458471) (xy 51.231899 -100.466906) (xy 54.077106 -100.466906)
			(xy 54.081177 -100.411284) (xy 54.093303 -100.356847) (xy 54.113226 -100.304756) (xy 54.140522 -100.256121)
			(xy 54.174608 -100.211978) (xy 54.214757 -100.173269) (xy 54.260115 -100.140818) (xy 54.309715 -100.115317)
			(xy 54.362499 -100.09731) (xy 54.417342 -100.08718) (xy 54.473076 -100.085143) (xy 54.528513 -100.091243)
			(xy 54.58247 -100.105349) (xy 54.633799 -100.127161) (xy 54.681405 -100.156215) (xy 54.724273 -100.19189)
			(xy 54.76149 -100.233427) (xy 54.792263 -100.27994) (xy 54.815935 -100.330437) (xy 54.832003 -100.383844)
			(xy 54.840123 -100.43902) (xy 54.840632 -100.466906) (xy 54.840123 -100.494792) (xy 54.832003 -100.549968)
			(xy 54.815935 -100.603375) (xy 54.792263 -100.653872) (xy 54.76149 -100.700385) (xy 54.724273 -100.741922)
			(xy 54.681405 -100.777597) (xy 54.633799 -100.806651) (xy 54.58247 -100.828463) (xy 54.528513 -100.842569)
			(xy 54.473076 -100.848669) (xy 54.417342 -100.846632) (xy 54.362499 -100.836502) (xy 54.309715 -100.818495)
			(xy 54.260115 -100.792994) (xy 54.214757 -100.760543) (xy 54.174608 -100.721834) (xy 54.140522 -100.677691)
			(xy 54.113226 -100.629056) (xy 54.093303 -100.576965) (xy 54.081177 -100.522528) (xy 54.077106 -100.466906)
			(xy 51.231899 -100.466906) (xy 51.257091 -100.504984) (xy 51.280763 -100.555481) (xy 51.296831 -100.608888)
			(xy 51.304951 -100.664064) (xy 51.30546 -100.69195) (xy 51.304951 -100.719836) (xy 51.296831 -100.775012)
			(xy 51.280763 -100.828419) (xy 51.257091 -100.878916) (xy 51.226318 -100.925429) (xy 51.189101 -100.966966)
			(xy 51.146233 -101.002641) (xy 51.098627 -101.031695) (xy 51.047298 -101.053507) (xy 50.993341 -101.067613)
			(xy 50.937904 -101.073713) (xy 50.88217 -101.071676) (xy 50.827327 -101.061546) (xy 50.774543 -101.043539)
			(xy 50.724943 -101.018038) (xy 50.679585 -100.985587) (xy 50.639436 -100.946878) (xy 50.60535 -100.902735)
			(xy 50.578054 -100.8541) (xy 50.558131 -100.802009) (xy 50.546005 -100.747572) (xy 50.541934 -100.69195)
			(xy 49.740898 -100.69195) (xy 49.74001 -100.727947) (xy 49.731349 -100.780348) (xy 49.715503 -100.831042)
			(xy 49.692779 -100.879047) (xy 49.67859 -100.9015) (xy 49.669508 -100.916339) (xy 49.659006 -100.949494)
			(xy 49.657843 -100.984254) (xy 49.666107 -101.018037) (xy 49.683184 -101.048335) (xy 49.6951 -101.061012)
			(xy 50.146204 -101.512116) (xy 54.258462 -101.512116) (xy 54.262533 -101.456494) (xy 54.274659 -101.402057)
			(xy 54.294582 -101.349966) (xy 54.321878 -101.301331) (xy 54.355964 -101.257188) (xy 54.396113 -101.218479)
			(xy 54.441471 -101.186028) (xy 54.491071 -101.160527) (xy 54.543855 -101.14252) (xy 54.598698 -101.13239)
			(xy 54.654432 -101.130353) (xy 54.709869 -101.136453) (xy 54.763826 -101.150559) (xy 54.815155 -101.172371)
			(xy 54.862761 -101.201425) (xy 54.905629 -101.2371) (xy 54.942846 -101.278637) (xy 54.973619 -101.32515)
			(xy 54.997291 -101.375647) (xy 55.013359 -101.429054) (xy 55.021479 -101.48423) (xy 55.021988 -101.512116)
			(xy 55.021479 -101.540002) (xy 55.013359 -101.595178) (xy 54.997291 -101.648585) (xy 54.973619 -101.699082)
			(xy 54.942846 -101.745595) (xy 54.905629 -101.787132) (xy 54.862761 -101.822807) (xy 54.815155 -101.851861)
			(xy 54.763826 -101.873673) (xy 54.709869 -101.887779) (xy 54.654432 -101.893879) (xy 54.598698 -101.891842)
			(xy 54.543855 -101.881712) (xy 54.491071 -101.863705) (xy 54.441471 -101.838204) (xy 54.396113 -101.805753)
			(xy 54.355964 -101.767044) (xy 54.321878 -101.722901) (xy 54.294582 -101.674266) (xy 54.274659 -101.622175)
			(xy 54.262533 -101.567738) (xy 54.258462 -101.512116) (xy 50.146204 -101.512116) (xy 50.775108 -102.14102)
			(xy 50.866802 -102.149148) (xy 50.904648 -102.122986) (xy 50.9275 -102.107749) (xy 50.976674 -102.083288)
			(xy 51.028848 -102.066131) (xy 51.082943 -102.056632) (xy 51.137841 -102.054988) (xy 51.192407 -102.061232)
			(xy 51.245515 -102.075236) (xy 51.296065 -102.09671) (xy 51.343014 -102.125211) (xy 51.385392 -102.160148)
			(xy 51.422321 -102.200801) (xy 51.453041 -102.24633) (xy 51.476914 -102.295792) (xy 51.493449 -102.348167)
			(xy 51.502303 -102.402371) (xy 51.503326 -102.429818) (xy 51.504145 -102.446263) (xy 51.513147 -102.477923)
			(xy 51.529952 -102.506225) (xy 51.553441 -102.529284) (xy 51.582048 -102.545563) (xy 51.613868 -102.55398)
			(xy 51.630326 -102.554532)
		)
		(stroke
			(width 0)
			(type solid)
		)
		(fill yes)
		(layer "In7.Cu")
		(net "P1V8_NODE1")
	)
	(gr_poly
		(pts
			(xy 19.412204 -71.961502) (xy 23.355808 -71.961502) (xy 24.57704 -70.74027) (xy 24.57704 -64.215772)
			(xy 24.533046 -64.170864) (xy 24.450118 -64.076362) (xy 24.373268 -63.976855) (xy 24.302796 -63.872733)
			(xy 24.23898 -63.764404) (xy 24.182069 -63.652293) (xy 24.132286 -63.53684) (xy 24.089828 -63.418497)
			(xy 24.05486 -63.297729) (xy 24.027519 -63.175009) (xy 24.007914 -63.050818) (xy 23.996119 -62.925644)
			(xy 23.992183 -62.799977) (xy 23.99612 -62.67431) (xy 24.007914 -62.549136) (xy 24.02752 -62.424945)
			(xy 24.054861 -62.302226) (xy 24.08983 -62.181458) (xy 24.132289 -62.063115) (xy 24.182071 -61.947662)
			(xy 24.238982 -61.835551) (xy 24.302799 -61.727223) (xy 24.373271 -61.623101) (xy 24.450122 -61.523594)
			(xy 24.53305 -61.429092) (xy 24.57704 -61.38418) (xy 24.57704 -59.370976) (xy 24.421084 -59.21502)
			(xy 24.378158 -59.209432) (xy 24.349941 -59.205278) (xy 24.295084 -59.189682) (xy 24.243158 -59.166094)
			(xy 24.195323 -59.13504) (xy 24.152643 -59.097211) (xy 24.116069 -59.05345) (xy 24.086417 -59.004733)
			(xy 24.064347 -58.952145) (xy 24.050351 -58.896857) (xy 24.044741 -58.840102) (xy 24.047641 -58.783144)
			(xy 24.058988 -58.727252) (xy 24.078528 -58.673673) (xy 24.091646 -58.648346) (xy 24.10714 -58.619898)
			(xy 24.10714 -56.248554) (xy 24.67864 -55.677054) (xy 24.67864 -41.145968) (xy 23.196042 -39.66337)
			(xy 20.637246 -39.66337) (xy 20.613685 -39.663881) (xy 20.56737 -39.67256) (xy 20.523448 -39.689628)
			(xy 20.483426 -39.7145) (xy 20.448675 -39.746325) (xy 20.420387 -39.78401) (xy 20.399531 -39.826265)
			(xy 20.386822 -39.87164) (xy 20.382696 -39.91858) (xy 20.387294 -39.965477) (xy 20.393406 -39.988236)
			(xy 20.400758 -40.014389) (xy 20.408842 -40.068109) (xy 20.409227 -40.122433) (xy 20.401904 -40.176262)
			(xy 20.387021 -40.228509) (xy 20.364879 -40.278117) (xy 20.335926 -40.324083) (xy 20.300747 -40.365479)
			(xy 20.260053 -40.401468) (xy 20.214666 -40.431322) (xy 20.165504 -40.454437) (xy 20.113561 -40.470348)
			(xy 20.059887 -40.478731) (xy 20.005566 -40.479417) (xy 19.951697 -40.472393) (xy 19.899369 -40.457801)
			(xy 19.849638 -40.435935) (xy 19.803512 -40.407238) (xy 19.761921 -40.372289) (xy 19.725707 -40.331795)
			(xy 19.695601 -40.286575) (xy 19.672213 -40.237543) (xy 19.663664 -40.211756) (xy 19.656394 -40.190424)
			(xy 19.635419 -40.15054) (xy 19.60774 -40.114981) (xy 19.574223 -40.084859) (xy 19.535921 -40.061119)
			(xy 19.494032 -40.044506) (xy 19.449871 -40.035539) (xy 19.40482 -40.0345) (xy 19.382486 -40.037512)
			(xy 19.354002 -40.042357) (xy 19.296262 -40.04441) (xy 19.238873 -40.037731) (xy 19.183147 -40.022474)
			(xy 19.13036 -39.998988) (xy 19.081718 -39.96781) (xy 19.038334 -39.929652) (xy 19.001201 -39.885389)
			(xy 18.985738 -39.860982) (xy 18.975879 -39.844361) (xy 18.959205 -39.809497) (xy 18.952464 -39.791386)
			(xy 18.940018 -39.756588) (xy 18.819368 -39.66337) (xy 11.020552 -39.66337) (xy 10.956036 -39.707312)
			(xy 10.941558 -39.743888) (xy 10.927897 -39.777286) (xy 10.894077 -39.84103) (xy 10.853254 -39.900532)
			(xy 10.805952 -39.955026) (xy 10.752781 -40.003811) (xy 10.694425 -40.046258) (xy 10.631637 -40.081821)
			(xy 10.565224 -40.110041) (xy 10.496041 -40.130556) (xy 10.42498 -40.143102) (xy 10.352955 -40.147516)
			(xy 10.280893 -40.143742) (xy 10.209723 -40.131828) (xy 10.140361 -40.111928) (xy 10.0737 -40.084299)
			(xy 10.010598 -40.049296) (xy 9.951868 -40.007369) (xy 9.898266 -39.959058) (xy 9.873996 -39.932356)
			(xy 9.786874 -40.019478) (xy 9.744964 -40.061388) (xy 9.271 -40.535606) (xy 9.271 -40.989504) (xy 14.766542 -40.989504)
			(xy 14.770613 -40.933882) (xy 14.782739 -40.879445) (xy 14.802662 -40.827354) (xy 14.829958 -40.778719)
			(xy 14.864044 -40.734576) (xy 14.904193 -40.695867) (xy 14.949551 -40.663416) (xy 14.999151 -40.637915)
			(xy 15.051935 -40.619908) (xy 15.106778 -40.609778) (xy 15.162512 -40.607741) (xy 15.217949 -40.613841)
			(xy 15.271906 -40.627947) (xy 15.323235 -40.649759) (xy 15.370841 -40.678813) (xy 15.413709 -40.714488)
			(xy 15.450926 -40.756025) (xy 15.481699 -40.802538) (xy 15.505371 -40.853035) (xy 15.521439 -40.906442)
			(xy 15.529559 -40.961618) (xy 15.530068 -40.989504) (xy 15.529559 -41.01739) (xy 15.521439 -41.072566)
			(xy 15.505371 -41.125973) (xy 15.481699 -41.17647) (xy 15.450926 -41.222983) (xy 15.413709 -41.26452)
			(xy 15.370841 -41.300195) (xy 15.323235 -41.329249) (xy 15.271906 -41.351061) (xy 15.217949 -41.365167)
			(xy 15.162512 -41.371267) (xy 15.106778 -41.36923) (xy 15.051935 -41.3591) (xy 14.999151 -41.341093)
			(xy 14.949551 -41.315592) (xy 14.904193 -41.283141) (xy 14.864044 -41.244432) (xy 14.829958 -41.200289)
			(xy 14.802662 -41.151654) (xy 14.782739 -41.099563) (xy 14.770613 -41.045126) (xy 14.766542 -40.989504)
			(xy 9.271 -40.989504) (xy 9.271 -42.857987) (xy 9.994378 -42.857987) (xy 9.994378 -42.762365) (xy 10.002274 -42.667069)
			(xy 10.018013 -42.572751) (xy 10.041487 -42.480054) (xy 10.072536 -42.389613) (xy 10.110947 -42.302045)
			(xy 10.156458 -42.217947) (xy 10.208758 -42.137895) (xy 10.267491 -42.062436) (xy 10.332254 -41.992084)
			(xy 10.402606 -41.927321) (xy 10.478065 -41.868588) (xy 10.558117 -41.816288) (xy 10.642215 -41.770777)
			(xy 10.729783 -41.732366) (xy 10.820224 -41.701317) (xy 10.912921 -41.677843) (xy 11.007239 -41.662104)
			(xy 11.102535 -41.654208) (xy 11.198157 -41.654208) (xy 11.293453 -41.662104) (xy 11.387771 -41.677843)
			(xy 11.480468 -41.701317) (xy 11.570909 -41.732366) (xy 11.658477 -41.770777) (xy 11.703593 -41.795192)
			(xy 17.781522 -41.795192) (xy 17.785593 -41.73957) (xy 17.797719 -41.685133) (xy 17.817642 -41.633042)
			(xy 17.844938 -41.584407) (xy 17.879024 -41.540264) (xy 17.919173 -41.501555) (xy 17.964531 -41.469104)
			(xy 18.014131 -41.443603) (xy 18.066915 -41.425596) (xy 18.121758 -41.415466) (xy 18.177492 -41.413429)
			(xy 18.232929 -41.419529) (xy 18.286886 -41.433635) (xy 18.338215 -41.455447) (xy 18.385821 -41.484501)
			(xy 18.428689 -41.520176) (xy 18.465906 -41.561713) (xy 18.496679 -41.608226) (xy 18.520351 -41.658723)
			(xy 18.536419 -41.71213) (xy 18.544539 -41.767306) (xy 18.545048 -41.795192) (xy 18.544539 -41.823078)
			(xy 18.536419 -41.878254) (xy 18.520351 -41.931661) (xy 18.496679 -41.982158) (xy 18.465906 -42.028671)
			(xy 18.428689 -42.070208) (xy 18.385821 -42.105883) (xy 18.338215 -42.134937) (xy 18.286886 -42.156749)
			(xy 18.232929 -42.170855) (xy 18.177492 -42.176955) (xy 18.121758 -42.174918) (xy 18.066915 -42.164788)
			(xy 18.014131 -42.146781) (xy 17.964531 -42.12128) (xy 17.919173 -42.088829) (xy 17.879024 -42.05012)
			(xy 17.844938 -42.005977) (xy 17.817642 -41.957342) (xy 17.797719 -41.905251) (xy 17.785593 -41.850814)
			(xy 17.781522 -41.795192) (xy 11.703593 -41.795192) (xy 11.742575 -41.816288) (xy 11.822627 -41.868588)
			(xy 11.898086 -41.927321) (xy 11.968438 -41.992084) (xy 12.033201 -42.062436) (xy 12.091934 -42.137895)
			(xy 12.144234 -42.217947) (xy 12.189745 -42.302045) (xy 12.228156 -42.389613) (xy 12.259205 -42.480054)
			(xy 12.282679 -42.572751) (xy 12.286313 -42.59453) (xy 17.082006 -42.59453) (xy 17.086077 -42.538908)
			(xy 17.098203 -42.484471) (xy 17.118126 -42.43238) (xy 17.145422 -42.383745) (xy 17.179508 -42.339602)
			(xy 17.219657 -42.300893) (xy 17.265015 -42.268442) (xy 17.314615 -42.242941) (xy 17.367399 -42.224934)
			(xy 17.422242 -42.214804) (xy 17.477976 -42.212767) (xy 17.533413 -42.218867) (xy 17.58737 -42.232973)
			(xy 17.638699 -42.254785) (xy 17.686305 -42.283839) (xy 17.729173 -42.319514) (xy 17.76639 -42.361051)
			(xy 17.797163 -42.407564) (xy 17.820835 -42.458061) (xy 17.836903 -42.511468) (xy 17.845023 -42.566644)
			(xy 17.845532 -42.59453) (xy 17.845023 -42.622416) (xy 17.836903 -42.677592) (xy 17.820835 -42.730999)
			(xy 17.797163 -42.781496) (xy 17.76639 -42.828009) (xy 17.729173 -42.869546) (xy 17.686305 -42.905221)
			(xy 17.638699 -42.934275) (xy 17.58737 -42.956087) (xy 17.533413 -42.970193) (xy 17.477976 -42.976293)
			(xy 17.422242 -42.974256) (xy 17.367399 -42.964126) (xy 17.314615 -42.946119) (xy 17.265015 -42.920618)
			(xy 17.219657 -42.888167) (xy 17.179508 -42.849458) (xy 17.145422 -42.805315) (xy 17.118126 -42.75668)
			(xy 17.098203 -42.704589) (xy 17.086077 -42.650152) (xy 17.082006 -42.59453) (xy 12.286313 -42.59453)
			(xy 12.298418 -42.667069) (xy 12.306314 -42.762365) (xy 12.306808 -42.810176) (xy 12.306314 -42.857987)
			(xy 12.298418 -42.953283) (xy 12.282679 -43.047601) (xy 12.259205 -43.140298) (xy 12.243308 -43.186604)
			(xy 13.890242 -43.186604) (xy 13.894313 -43.130982) (xy 13.906439 -43.076545) (xy 13.926362 -43.024454)
			(xy 13.953658 -42.975819) (xy 13.987744 -42.931676) (xy 14.027893 -42.892967) (xy 14.073251 -42.860516)
			(xy 14.122851 -42.835015) (xy 14.175635 -42.817008) (xy 14.230478 -42.806878) (xy 14.286212 -42.804841)
			(xy 14.341649 -42.810941) (xy 14.395606 -42.825047) (xy 14.446935 -42.846859) (xy 14.494541 -42.875913)
			(xy 14.537409 -42.911588) (xy 14.574626 -42.953125) (xy 14.605399 -42.999638) (xy 14.629071 -43.050135)
			(xy 14.645139 -43.103542) (xy 14.653259 -43.158718) (xy 14.653768 -43.186604) (xy 14.653259 -43.21449)
			(xy 14.645139 -43.269666) (xy 14.629071 -43.323073) (xy 14.605399 -43.37357) (xy 14.574626 -43.420083)
			(xy 14.537409 -43.46162) (xy 14.494541 -43.497295) (xy 14.446935 -43.526349) (xy 14.395606 -43.548161)
			(xy 14.341649 -43.562267) (xy 14.286212 -43.568367) (xy 14.230478 -43.56633) (xy 14.175635 -43.5562)
			(xy 14.122851 -43.538193) (xy 14.073251 -43.512692) (xy 14.027893 -43.480241) (xy 13.987744 -43.441532)
			(xy 13.953658 -43.397389) (xy 13.926362 -43.348754) (xy 13.906439 -43.296663) (xy 13.894313 -43.242226)
			(xy 13.890242 -43.186604) (xy 12.243308 -43.186604) (xy 12.228156 -43.230739) (xy 12.189745 -43.318307)
			(xy 12.144234 -43.402405) (xy 12.091934 -43.482457) (xy 12.033201 -43.557916) (xy 11.968438 -43.628268)
			(xy 11.898086 -43.693031) (xy 11.822627 -43.751764) (xy 11.742575 -43.804064) (xy 11.673084 -43.84167)
			(xy 20.199602 -43.84167) (xy 20.203673 -43.786048) (xy 20.215799 -43.731611) (xy 20.235722 -43.67952)
			(xy 20.263018 -43.630885) (xy 20.297104 -43.586742) (xy 20.337253 -43.548033) (xy 20.382611 -43.515582)
			(xy 20.432211 -43.490081) (xy 20.484995 -43.472074) (xy 20.539838 -43.461944) (xy 20.595572 -43.459907)
			(xy 20.651009 -43.466007) (xy 20.704966 -43.480113) (xy 20.756295 -43.501925) (xy 20.803901 -43.530979)
			(xy 20.846769 -43.566654) (xy 20.883986 -43.608191) (xy 20.914759 -43.654704) (xy 20.938431 -43.705201)
			(xy 20.954499 -43.758608) (xy 20.962619 -43.813784) (xy 20.963128 -43.84167) (xy 20.962619 -43.869556)
			(xy 20.954499 -43.924732) (xy 20.938431 -43.978139) (xy 20.914759 -44.028636) (xy 20.883986 -44.075149)
			(xy 20.846769 -44.116686) (xy 20.803901 -44.152361) (xy 20.756295 -44.181415) (xy 20.704966 -44.203227)
			(xy 20.651009 -44.217333) (xy 20.595572 -44.223433) (xy 20.539838 -44.221396) (xy 20.484995 -44.211266)
			(xy 20.432211 -44.193259) (xy 20.382611 -44.167758) (xy 20.337253 -44.135307) (xy 20.297104 -44.096598)
			(xy 20.263018 -44.052455) (xy 20.235722 -44.00382) (xy 20.215799 -43.951729) (xy 20.203673 -43.897292)
			(xy 20.199602 -43.84167) (xy 11.673084 -43.84167) (xy 11.658477 -43.849575) (xy 11.570909 -43.887986)
			(xy 11.480468 -43.919035) (xy 11.387771 -43.942509) (xy 11.293453 -43.958248) (xy 11.198157 -43.966144)
			(xy 11.102535 -43.966144) (xy 11.007239 -43.958248) (xy 10.912921 -43.942509) (xy 10.820224 -43.919035)
			(xy 10.729783 -43.887986) (xy 10.642215 -43.849575) (xy 10.558117 -43.804064) (xy 10.478065 -43.751764)
			(xy 10.402606 -43.693031) (xy 10.332254 -43.628268) (xy 10.267491 -43.557916) (xy 10.208758 -43.482457)
			(xy 10.156458 -43.402405) (xy 10.110947 -43.318307) (xy 10.072536 -43.230739) (xy 10.041487 -43.140298)
			(xy 10.018013 -43.047601) (xy 10.002274 -42.953283) (xy 9.994378 -42.857987) (xy 9.271 -42.857987)
			(xy 9.271 -45.284898) (xy 9.320276 -45.351954) (xy 9.3599 -45.3644) (xy 9.396513 -45.376459) (xy 9.467055 -45.40755)
			(xy 9.533746 -45.446215) (xy 9.595778 -45.491984) (xy 9.652397 -45.544301) (xy 9.702914 -45.602531)
			(xy 9.746717 -45.665967) (xy 9.783274 -45.733837) (xy 9.81214 -45.805318) (xy 9.832965 -45.879541)
			(xy 9.845496 -45.955605) (xy 9.848088 -45.994066) (xy 9.849598 -46.032409) (xy 9.845245 -46.109022)
			(xy 9.832531 -46.184699) (xy 9.811609 -46.25853) (xy 9.782731 -46.329626) (xy 9.746243 -46.397133)
			(xy 9.702584 -46.460241) (xy 9.652279 -46.518189) (xy 9.595933 -46.570283) (xy 9.565386 -46.593506)
			(xy 9.547407 -46.608103) (xy 9.516572 -46.642649) (xy 9.492505 -46.682209) (xy 9.476003 -46.725475)
			(xy 9.467614 -46.771015) (xy 9.467613 -46.81732) (xy 9.476002 -46.86286) (xy 9.492503 -46.906126)
			(xy 9.516569 -46.945687) (xy 9.547404 -46.980233) (xy 9.565386 -46.994826) (xy 9.596002 -47.018088)
			(xy 9.652471 -47.07028) (xy 9.702871 -47.128353) (xy 9.746593 -47.191607) (xy 9.78311 -47.259277)
			(xy 9.81198 -47.330546) (xy 9.832854 -47.404553) (xy 9.84548 -47.480403) (xy 9.849706 -47.557181)
			(xy 9.84548 -47.633959) (xy 9.832853 -47.70981) (xy 9.811979 -47.783816) (xy 9.783109 -47.855085)
			(xy 9.746592 -47.922755) (xy 9.702869 -47.986008) (xy 9.652469 -48.044082) (xy 9.596 -48.096273)
			(xy 9.565386 -48.119538) (xy 9.547408 -48.134136) (xy 9.516574 -48.168682) (xy 9.492508 -48.208242)
			(xy 9.476008 -48.251507) (xy 9.467619 -48.297046) (xy 9.467619 -48.320199) (xy 9.950721 -48.320199)
			(xy 9.954888 -48.243962) (xy 9.96734 -48.168634) (xy 9.987927 -48.095112) (xy 10.016405 -48.024271)
			(xy 10.052434 -47.956956) (xy 10.095585 -47.89397) (xy 10.145344 -47.836061) (xy 10.201118 -47.783921)
			(xy 10.231374 -47.760636) (xy 10.249989 -47.746099) (xy 10.281934 -47.711313) (xy 10.306905 -47.671227)
			(xy 10.324045 -47.627219) (xy 10.332764 -47.580803) (xy 10.332762 -47.533575) (xy 10.324039 -47.48716)
			(xy 10.306895 -47.443153) (xy 10.281921 -47.403069) (xy 10.249973 -47.368287) (xy 10.231374 -47.353728)
			(xy 10.201115 -47.330448) (xy 10.145342 -47.278306) (xy 10.095585 -47.220397) (xy 10.052435 -47.157409)
			(xy 10.016408 -47.090094) (xy 9.987931 -47.019254) (xy 9.967345 -46.945732) (xy 9.954894 -46.870404)
			(xy 9.950728 -46.794168) (xy 9.954895 -46.717932) (xy 9.967346 -46.642604) (xy 9.987933 -46.569082)
			(xy 10.01641 -46.498241) (xy 10.052438 -46.430926) (xy 10.095588 -46.367939) (xy 10.145346 -46.31003)
			(xy 10.201119 -46.257889) (xy 10.231374 -46.234604) (xy 10.249974 -46.220047) (xy 10.281921 -46.185266)
			(xy 10.306896 -46.145183) (xy 10.324039 -46.101178) (xy 10.332761 -46.054763) (xy 10.332761 -46.007537)
			(xy 10.324039 -45.961122) (xy 10.306896 -45.917117) (xy 10.281921 -45.877034) (xy 10.249974 -45.842253)
			(xy 10.231374 -45.827696) (xy 10.20191 -45.805026) (xy 10.147455 -45.754409) (xy 10.098682 -45.698297)
			(xy 10.056139 -45.637326) (xy 10.020308 -45.572184) (xy 9.991594 -45.503606) (xy 9.970321 -45.432369)
			(xy 9.95673 -45.359275) (xy 9.950974 -45.285152) (xy 9.953117 -45.210837) (xy 9.963137 -45.137169)
			(xy 9.980919 -45.064981) (xy 10.006263 -44.995088) (xy 10.038882 -44.928279) (xy 10.078408 -44.865311)
			(xy 10.124395 -44.806893) (xy 10.176322 -44.753687) (xy 10.233603 -44.706293) (xy 10.295592 -44.665246)
			(xy 10.361586 -44.631011) (xy 10.430842 -44.603974) (xy 10.502576 -44.584441) (xy 10.575979 -44.572632)
			(xy 10.65022 -44.56868) (xy 10.724461 -44.572632) (xy 10.797864 -44.584441) (xy 10.853557 -44.599606)
			(xy 17.065242 -44.599606) (xy 17.069313 -44.543984) (xy 17.081439 -44.489547) (xy 17.101362 -44.437456)
			(xy 17.128658 -44.388821) (xy 17.162744 -44.344678) (xy 17.202893 -44.305969) (xy 17.248251 -44.273518)
			(xy 17.297851 -44.248017) (xy 17.350635 -44.23001) (xy 17.405478 -44.21988) (xy 17.461212 -44.217843)
			(xy 17.516649 -44.223943) (xy 17.570606 -44.238049) (xy 17.621935 -44.259861) (xy 17.669541 -44.288915)
			(xy 17.712409 -44.32459) (xy 17.749626 -44.366127) (xy 17.780399 -44.41264) (xy 17.804071 -44.463137)
			(xy 17.820139 -44.516544) (xy 17.828259 -44.57172) (xy 17.828768 -44.599606) (xy 17.828259 -44.627492)
			(xy 17.820139 -44.682668) (xy 17.804071 -44.736075) (xy 17.780399 -44.786572) (xy 17.749626 -44.833085)
			(xy 17.712409 -44.874622) (xy 17.669541 -44.910297) (xy 17.621935 -44.939351) (xy 17.570606 -44.961163)
			(xy 17.516649 -44.975269) (xy 17.461212 -44.981369) (xy 17.405478 -44.979332) (xy 17.350635 -44.969202)
			(xy 17.297851 -44.951195) (xy 17.248251 -44.925694) (xy 17.202893 -44.893243) (xy 17.162744 -44.854534)
			(xy 17.128658 -44.810391) (xy 17.101362 -44.761756) (xy 17.081439 -44.709665) (xy 17.069313 -44.655228)
			(xy 17.065242 -44.599606) (xy 10.853557 -44.599606) (xy 10.869598 -44.603974) (xy 10.938854 -44.631011)
			(xy 11.004848 -44.665246) (xy 11.066837 -44.706293) (xy 11.124118 -44.753687) (xy 11.176045 -44.806893)
			(xy 11.222032 -44.865311) (xy 11.261558 -44.928279) (xy 11.294177 -44.995088) (xy 11.319521 -45.064981)
			(xy 11.337303 -45.137169) (xy 11.346341 -45.203618) (xy 22.700994 -45.203618) (xy 22.705065 -45.147996)
			(xy 22.717191 -45.093559) (xy 22.737114 -45.041468) (xy 22.76441 -44.992833) (xy 22.798496 -44.94869)
			(xy 22.838645 -44.909981) (xy 22.884003 -44.87753) (xy 22.933603 -44.852029) (xy 22.986387 -44.834022)
			(xy 23.04123 -44.823892) (xy 23.096964 -44.821855) (xy 23.152401 -44.827955) (xy 23.206358 -44.842061)
			(xy 23.257687 -44.863873) (xy 23.305293 -44.892927) (xy 23.348161 -44.928602) (xy 23.385378 -44.970139)
			(xy 23.416151 -45.016652) (xy 23.439823 -45.067149) (xy 23.455891 -45.120556) (xy 23.464011 -45.175732)
			(xy 23.46452 -45.203618) (xy 23.464011 -45.231504) (xy 23.455891 -45.28668) (xy 23.439823 -45.340087)
			(xy 23.416151 -45.390584) (xy 23.385378 -45.437097) (xy 23.348161 -45.478634) (xy 23.305293 -45.514309)
			(xy 23.257687 -45.543363) (xy 23.206358 -45.565175) (xy 23.152401 -45.579281) (xy 23.096964 -45.585381)
			(xy 23.04123 -45.583344) (xy 22.986387 -45.573214) (xy 22.933603 -45.555207) (xy 22.884003 -45.529706)
			(xy 22.838645 -45.497255) (xy 22.798496 -45.458546) (xy 22.76441 -45.414403) (xy 22.737114 -45.365768)
			(xy 22.717191 -45.313677) (xy 22.705065 -45.25924) (xy 22.700994 -45.203618) (xy 11.346341 -45.203618)
			(xy 11.347323 -45.210837) (xy 11.349466 -45.285152) (xy 11.34371 -45.359275) (xy 11.330119 -45.432369)
			(xy 11.308846 -45.503606) (xy 11.280132 -45.572184) (xy 11.244301 -45.637326) (xy 11.201758 -45.698297)
			(xy 11.152985 -45.754409) (xy 11.09853 -45.805026) (xy 11.069066 -45.827696) (xy 11.050466 -45.842253)
			(xy 11.018519 -45.877034) (xy 11.003681 -45.900848) (xy 14.16126 -45.900848) (xy 14.165331 -45.845226)
			(xy 14.177457 -45.790789) (xy 14.19738 -45.738698) (xy 14.224676 -45.690063) (xy 14.258762 -45.64592)
			(xy 14.298911 -45.607211) (xy 14.344269 -45.57476) (xy 14.393869 -45.549259) (xy 14.446653 -45.531252)
			(xy 14.501496 -45.521122) (xy 14.55723 -45.519085) (xy 14.612667 -45.525185) (xy 14.666624 -45.539291)
			(xy 14.717953 -45.561103) (xy 14.765559 -45.590157) (xy 14.808427 -45.625832) (xy 14.845644 -45.667369)
			(xy 14.876417 -45.713882) (xy 14.900089 -45.764379) (xy 14.916157 -45.817786) (xy 14.924277 -45.872962)
			(xy 14.924786 -45.900848) (xy 14.924638 -45.908976) (xy 16.852644 -45.908976) (xy 16.856715 -45.853354)
			(xy 16.868841 -45.798917) (xy 16.888764 -45.746826) (xy 16.91606 -45.698191) (xy 16.950146 -45.654048)
			(xy 16.990295 -45.615339) (xy 17.035653 -45.582888) (xy 17.085253 -45.557387) (xy 17.138037 -45.53938)
			(xy 17.19288 -45.52925) (xy 17.248614 -45.527213) (xy 17.304051 -45.533313) (xy 17.358008 -45.547419)
			(xy 17.409337 -45.569231) (xy 17.456943 -45.598285) (xy 17.499811 -45.63396) (xy 17.537028 -45.675497)
			(xy 17.567801 -45.72201) (xy 17.591473 -45.772507) (xy 17.607541 -45.825914) (xy 17.615661 -45.88109)
			(xy 17.61617 -45.908976) (xy 17.615661 -45.936862) (xy 17.607541 -45.992038) (xy 17.591473 -46.045445)
			(xy 17.567801 -46.095942) (xy 17.537028 -46.142455) (xy 17.499811 -46.183992) (xy 17.456943 -46.219667)
			(xy 17.409337 -46.248721) (xy 17.358008 -46.270533) (xy 17.304051 -46.284639) (xy 17.248614 -46.290739)
			(xy 17.19288 -46.288702) (xy 17.138037 -46.278572) (xy 17.085253 -46.260565) (xy 17.035653 -46.235064)
			(xy 16.990295 -46.202613) (xy 16.950146 -46.163904) (xy 16.91606 -46.119761) (xy 16.888764 -46.071126)
			(xy 16.868841 -46.019035) (xy 16.856715 -45.964598) (xy 16.852644 -45.908976) (xy 14.924638 -45.908976)
			(xy 14.924277 -45.928734) (xy 14.916157 -45.98391) (xy 14.900089 -46.037317) (xy 14.876417 -46.087814)
			(xy 14.845644 -46.134327) (xy 14.808427 -46.175864) (xy 14.765559 -46.211539) (xy 14.717953 -46.240593)
			(xy 14.666624 -46.262405) (xy 14.612667 -46.276511) (xy 14.55723 -46.282611) (xy 14.501496 -46.280574)
			(xy 14.446653 -46.270444) (xy 14.393869 -46.252437) (xy 14.344269 -46.226936) (xy 14.298911 -46.194485)
			(xy 14.258762 -46.155776) (xy 14.224676 -46.111633) (xy 14.19738 -46.062998) (xy 14.177457 -46.010907)
			(xy 14.165331 -45.95647) (xy 14.16126 -45.900848) (xy 11.003681 -45.900848) (xy 10.993544 -45.917117)
			(xy 10.976401 -45.961122) (xy 10.967679 -46.007537) (xy 10.967679 -46.054763) (xy 10.976401 -46.101178)
			(xy 10.993544 -46.145183) (xy 11.018519 -46.185266) (xy 11.050466 -46.220047) (xy 11.069066 -46.234604)
			(xy 11.099317 -46.257894) (xy 11.15509 -46.310035) (xy 11.204847 -46.367943) (xy 11.247997 -46.43093)
			(xy 11.284025 -46.498244) (xy 11.312501 -46.569084) (xy 11.333088 -46.642605) (xy 11.345539 -46.717932)
			(xy 11.349706 -46.794168) (xy 11.345539 -46.870403) (xy 11.333089 -46.94573) (xy 11.312503 -47.019252)
			(xy 11.284027 -47.090092) (xy 11.247999 -47.157406) (xy 11.20485 -47.220393) (xy 11.155093 -47.278302)
			(xy 11.099321 -47.330443) (xy 11.069066 -47.353728) (xy 11.050484 -47.368307) (xy 11.018535 -47.403084)
			(xy 10.993559 -47.443163) (xy 10.976415 -47.487165) (xy 10.967691 -47.533577) (xy 10.967689 -47.580801)
			(xy 10.976409 -47.627214) (xy 10.99355 -47.671218) (xy 11.018522 -47.711299) (xy 11.050468 -47.746079)
			(xy 11.069066 -47.760636) (xy 11.099319 -47.783924) (xy 11.155089 -47.836066) (xy 11.204845 -47.893975)
			(xy 11.247994 -47.956962) (xy 11.284021 -48.024276) (xy 11.312496 -48.095116) (xy 11.333082 -48.168637)
			(xy 11.345533 -48.243964) (xy 11.346173 -48.255682) (xy 16.526762 -48.255682) (xy 16.530833 -48.20006)
			(xy 16.542959 -48.145623) (xy 16.562882 -48.093532) (xy 16.590178 -48.044897) (xy 16.624264 -48.000754)
			(xy 16.664413 -47.962045) (xy 16.709771 -47.929594) (xy 16.759371 -47.904093) (xy 16.812155 -47.886086)
			(xy 16.866998 -47.875956) (xy 16.922732 -47.873919) (xy 16.978169 -47.880019) (xy 17.032126 -47.894125)
			(xy 17.083455 -47.915937) (xy 17.131061 -47.944991) (xy 17.173929 -47.980666) (xy 17.184339 -47.992284)
			(xy 18.727926 -47.992284) (xy 18.731997 -47.936662) (xy 18.744123 -47.882225) (xy 18.764046 -47.830134)
			(xy 18.791342 -47.781499) (xy 18.825428 -47.737356) (xy 18.865577 -47.698647) (xy 18.910935 -47.666196)
			(xy 18.960535 -47.640695) (xy 19.013319 -47.622688) (xy 19.068162 -47.612558) (xy 19.123896 -47.610521)
			(xy 19.179333 -47.616621) (xy 19.23329 -47.630727) (xy 19.284619 -47.652539) (xy 19.332225 -47.681593)
			(xy 19.375093 -47.717268) (xy 19.41231 -47.758805) (xy 19.443083 -47.805318) (xy 19.466755 -47.855815)
			(xy 19.482823 -47.909222) (xy 19.490943 -47.964398) (xy 19.491452 -47.992284) (xy 19.490943 -48.02017)
			(xy 19.482823 -48.075346) (xy 19.466755 -48.128753) (xy 19.443083 -48.17925) (xy 19.41231 -48.225763)
			(xy 19.375093 -48.2673) (xy 19.332225 -48.302975) (xy 19.284619 -48.332029) (xy 19.23329 -48.353841)
			(xy 19.179333 -48.367947) (xy 19.123896 -48.374047) (xy 19.068162 -48.37201) (xy 19.013319 -48.36188)
			(xy 18.960535 -48.343873) (xy 18.910935 -48.318372) (xy 18.865577 -48.285921) (xy 18.825428 -48.247212)
			(xy 18.791342 -48.203069) (xy 18.764046 -48.154434) (xy 18.744123 -48.102343) (xy 18.731997 -48.047906)
			(xy 18.727926 -47.992284) (xy 17.184339 -47.992284) (xy 17.211146 -48.022203) (xy 17.241919 -48.068716)
			(xy 17.265591 -48.119213) (xy 17.281659 -48.17262) (xy 17.289779 -48.227796) (xy 17.290288 -48.255682)
			(xy 17.289779 -48.283568) (xy 17.281659 -48.338744) (xy 17.265591 -48.392151) (xy 17.241919 -48.442648)
			(xy 17.211146 -48.489161) (xy 17.173929 -48.530698) (xy 17.131061 -48.566373) (xy 17.083455 -48.595427)
			(xy 17.032126 -48.617239) (xy 16.978169 -48.631345) (xy 16.922732 -48.637445) (xy 16.866998 -48.635408)
			(xy 16.812155 -48.625278) (xy 16.759371 -48.607271) (xy 16.709771 -48.58177) (xy 16.664413 -48.549319)
			(xy 16.624264 -48.51061) (xy 16.590178 -48.466467) (xy 16.562882 -48.417832) (xy 16.542959 -48.365741)
			(xy 16.530833 -48.311304) (xy 16.526762 -48.255682) (xy 11.346173 -48.255682) (xy 11.349699 -48.320199)
			(xy 11.345533 -48.396434) (xy 11.333083 -48.471761) (xy 11.312497 -48.545282) (xy 11.284022 -48.616122)
			(xy 11.247995 -48.683436) (xy 11.236523 -48.700182) (xy 20.453602 -48.700182) (xy 20.457673 -48.64456)
			(xy 20.469799 -48.590123) (xy 20.489722 -48.538032) (xy 20.517018 -48.489397) (xy 20.551104 -48.445254)
			(xy 20.591253 -48.406545) (xy 20.636611 -48.374094) (xy 20.686211 -48.348593) (xy 20.738995 -48.330586)
			(xy 20.793838 -48.320456) (xy 20.849572 -48.318419) (xy 20.905009 -48.324519) (xy 20.958966 -48.338625)
			(xy 21.010295 -48.360437) (xy 21.057901 -48.389491) (xy 21.100769 -48.425166) (xy 21.137986 -48.466703)
			(xy 21.168759 -48.513216) (xy 21.192431 -48.563713) (xy 21.208499 -48.61712) (xy 21.216619 -48.672296)
			(xy 21.217128 -48.700182) (xy 21.216619 -48.728068) (xy 21.208499 -48.783244) (xy 21.192431 -48.836651)
			(xy 21.168759 -48.887148) (xy 21.137986 -48.933661) (xy 21.100769 -48.975198) (xy 21.057901 -49.010873)
			(xy 21.010295 -49.039927) (xy 20.958966 -49.061739) (xy 20.905009 -49.075845) (xy 20.849572 -49.081945)
			(xy 20.793838 -49.079908) (xy 20.738995 -49.069778) (xy 20.686211 -49.051771) (xy 20.636611 -49.02627)
			(xy 20.591253 -48.993819) (xy 20.551104 -48.95511) (xy 20.517018 -48.910967) (xy 20.489722 -48.862332)
			(xy 20.469799 -48.810241) (xy 20.457673 -48.755804) (xy 20.453602 -48.700182) (xy 11.236523 -48.700182)
			(xy 11.204847 -48.746423) (xy 11.155091 -48.804333) (xy 11.09932 -48.856474) (xy 11.069066 -48.87976)
			(xy 11.050452 -48.8943) (xy 11.018503 -48.929083) (xy 10.993527 -48.969168) (xy 10.976384 -49.013177)
			(xy 10.967664 -49.059594) (xy 10.967665 -49.106823) (xy 10.976389 -49.15324) (xy 10.993535 -49.197247)
			(xy 11.018513 -49.23733) (xy 11.050464 -49.272111) (xy 11.069066 -49.286668) (xy 11.099321 -49.309953)
			(xy 11.155094 -49.362094) (xy 11.204851 -49.420003) (xy 11.248001 -49.48299) (xy 11.284028 -49.550305)
			(xy 11.312505 -49.621145) (xy 11.333091 -49.694667) (xy 11.345542 -49.769994) (xy 11.349709 -49.84623)
			(xy 11.345542 -49.922466) (xy 11.333091 -49.997793) (xy 11.312505 -50.071315) (xy 11.306191 -50.087022)
			(xy 17.126202 -50.087022) (xy 17.130273 -50.0314) (xy 17.142399 -49.976963) (xy 17.162322 -49.924872)
			(xy 17.189618 -49.876237) (xy 17.223704 -49.832094) (xy 17.263853 -49.793385) (xy 17.309211 -49.760934)
			(xy 17.358811 -49.735433) (xy 17.411595 -49.717426) (xy 17.466438 -49.707296) (xy 17.522172 -49.705259)
			(xy 17.577609 -49.711359) (xy 17.631566 -49.725465) (xy 17.682895 -49.747277) (xy 17.730501 -49.776331)
			(xy 17.773369 -49.812006) (xy 17.810586 -49.853543) (xy 17.841359 -49.900056) (xy 17.865031 -49.950553)
			(xy 17.881099 -50.00396) (xy 17.889219 -50.059136) (xy 17.889728 -50.087022) (xy 17.889219 -50.114908)
			(xy 17.881099 -50.170084) (xy 17.865031 -50.223491) (xy 17.841359 -50.273988) (xy 17.810586 -50.320501)
			(xy 17.773369 -50.362038) (xy 17.730501 -50.397713) (xy 17.682895 -50.426767) (xy 17.631566 -50.448579)
			(xy 17.577609 -50.462685) (xy 17.522172 -50.468785) (xy 17.466438 -50.466748) (xy 17.411595 -50.456618)
			(xy 17.358811 -50.438611) (xy 17.309211 -50.41311) (xy 17.263853 -50.380659) (xy 17.223704 -50.34195)
			(xy 17.189618 -50.297807) (xy 17.162322 -50.249172) (xy 17.142399 -50.197081) (xy 17.130273 -50.142644)
			(xy 17.126202 -50.087022) (xy 11.306191 -50.087022) (xy 11.284028 -50.142155) (xy 11.248001 -50.20947)
			(xy 11.204851 -50.272457) (xy 11.155094 -50.330366) (xy 11.099321 -50.382507) (xy 11.069066 -50.405792)
			(xy 11.05047 -50.420354) (xy 11.018523 -50.455134) (xy 10.993548 -50.495216) (xy 10.976405 -50.539221)
			(xy 10.967683 -50.585635) (xy 10.967682 -50.632861) (xy 10.976403 -50.679275) (xy 10.98039 -50.68951)
			(xy 13.832584 -50.68951) (xy 13.836655 -50.633888) (xy 13.848781 -50.579451) (xy 13.868704 -50.52736)
			(xy 13.896 -50.478725) (xy 13.930086 -50.434582) (xy 13.970235 -50.395873) (xy 14.015593 -50.363422)
			(xy 14.065193 -50.337921) (xy 14.117977 -50.319914) (xy 14.17282 -50.309784) (xy 14.228554 -50.307747)
			(xy 14.283991 -50.313847) (xy 14.337948 -50.327953) (xy 14.389277 -50.349765) (xy 14.436883 -50.378819)
			(xy 14.479751 -50.414494) (xy 14.516968 -50.456031) (xy 14.547741 -50.502544) (xy 14.571413 -50.553041)
			(xy 14.587481 -50.606448) (xy 14.595601 -50.661624) (xy 14.59611 -50.68951) (xy 14.595601 -50.717396)
			(xy 14.587481 -50.772572) (xy 14.571413 -50.825979) (xy 14.547741 -50.876476) (xy 14.516968 -50.922989)
			(xy 14.479751 -50.964526) (xy 14.436883 -51.000201) (xy 14.389277 -51.029255) (xy 14.337948 -51.051067)
			(xy 14.283991 -51.065173) (xy 14.228554 -51.071273) (xy 14.17282 -51.069236) (xy 14.117977 -51.059106)
			(xy 14.065193 -51.041099) (xy 14.015593 -51.015598) (xy 13.970235 -50.983147) (xy 13.930086 -50.944438)
			(xy 13.896 -50.900295) (xy 13.868704 -50.85166) (xy 13.848781 -50.799569) (xy 13.836655 -50.745132)
			(xy 13.832584 -50.68951) (xy 10.98039 -50.68951) (xy 10.993546 -50.72328) (xy 11.01852 -50.763362)
			(xy 11.050467 -50.798143) (xy 11.069066 -50.8127) (xy 11.099323 -50.835983) (xy 11.155096 -50.888124)
			(xy 11.204853 -50.946033) (xy 11.248003 -51.00902) (xy 11.28403 -51.076335) (xy 11.286181 -51.081686)
			(xy 18.759168 -51.081686) (xy 18.763239 -51.026064) (xy 18.775365 -50.971627) (xy 18.795288 -50.919536)
			(xy 18.822584 -50.870901) (xy 18.85667 -50.826758) (xy 18.896819 -50.788049) (xy 18.942177 -50.755598)
			(xy 18.991777 -50.730097) (xy 19.044561 -50.71209) (xy 19.099404 -50.70196) (xy 19.155138 -50.699923)
			(xy 19.210575 -50.706023) (xy 19.264532 -50.720129) (xy 19.315861 -50.741941) (xy 19.363467 -50.770995)
			(xy 19.406335 -50.80667) (xy 19.443552 -50.848207) (xy 19.474325 -50.89472) (xy 19.497997 -50.945217)
			(xy 19.514065 -50.998624) (xy 19.522185 -51.0538) (xy 19.522694 -51.081686) (xy 19.522185 -51.109572)
			(xy 19.514065 -51.164748) (xy 19.497997 -51.218155) (xy 19.474325 -51.268652) (xy 19.443552 -51.315165)
			(xy 19.406335 -51.356702) (xy 19.363467 -51.392377) (xy 19.315861 -51.421431) (xy 19.264532 -51.443243)
			(xy 19.210575 -51.457349) (xy 19.155138 -51.463449) (xy 19.099404 -51.461412) (xy 19.044561 -51.451282)
			(xy 18.991777 -51.433275) (xy 18.942177 -51.407774) (xy 18.896819 -51.375323) (xy 18.85667 -51.336614)
			(xy 18.822584 -51.292471) (xy 18.795288 -51.243836) (xy 18.775365 -51.191745) (xy 18.763239 -51.137308)
			(xy 18.759168 -51.081686) (xy 11.286181 -51.081686) (xy 11.312507 -51.147176) (xy 11.333093 -51.220698)
			(xy 11.345544 -51.296025) (xy 11.349711 -51.372261) (xy 11.345544 -51.448497) (xy 11.333093 -51.523825)
			(xy 11.312506 -51.597347) (xy 11.284029 -51.668187) (xy 11.248001 -51.735502) (xy 11.204852 -51.798489)
			(xy 11.155094 -51.856398) (xy 11.109734 -51.898804) (xy 14.286228 -51.898804) (xy 14.290299 -51.843182)
			(xy 14.302425 -51.788745) (xy 14.322348 -51.736654) (xy 14.349644 -51.688019) (xy 14.38373 -51.643876)
			(xy 14.423879 -51.605167) (xy 14.469237 -51.572716) (xy 14.518837 -51.547215) (xy 14.571621 -51.529208)
			(xy 14.626464 -51.519078) (xy 14.682198 -51.517041) (xy 14.737635 -51.523141) (xy 14.791592 -51.537247)
			(xy 14.842921 -51.559059) (xy 14.890527 -51.588113) (xy 14.933395 -51.623788) (xy 14.970612 -51.665325)
			(xy 15.001385 -51.711838) (xy 15.025057 -51.762335) (xy 15.041125 -51.815742) (xy 15.049245 -51.870918)
			(xy 15.049754 -51.898804) (xy 15.049245 -51.92669) (xy 15.041125 -51.981866) (xy 15.025057 -52.035273)
			(xy 15.001385 -52.08577) (xy 14.970612 -52.132283) (xy 14.933395 -52.17382) (xy 14.890527 -52.209495)
			(xy 14.842921 -52.238549) (xy 14.791592 -52.260361) (xy 14.783288 -52.262532) (xy 18.380962 -52.262532)
			(xy 18.385033 -52.20691) (xy 18.397159 -52.152473) (xy 18.417082 -52.100382) (xy 18.444378 -52.051747)
			(xy 18.478464 -52.007604) (xy 18.518613 -51.968895) (xy 18.563971 -51.936444) (xy 18.613571 -51.910943)
			(xy 18.666355 -51.892936) (xy 18.721198 -51.882806) (xy 18.776932 -51.880769) (xy 18.832369 -51.886869)
			(xy 18.886326 -51.900975) (xy 18.937655 -51.922787) (xy 18.985261 -51.951841) (xy 19.028129 -51.987516)
			(xy 19.065346 -52.029053) (xy 19.096119 -52.075566) (xy 19.119791 -52.126063) (xy 19.135859 -52.17947)
			(xy 19.143979 -52.234646) (xy 19.144488 -52.262532) (xy 19.144052 -52.286408) (xy 21.604222 -52.286408)
			(xy 21.608293 -52.230786) (xy 21.620419 -52.176349) (xy 21.640342 -52.124258) (xy 21.667638 -52.075623)
			(xy 21.701724 -52.03148) (xy 21.741873 -51.992771) (xy 21.787231 -51.96032) (xy 21.836831 -51.934819)
			(xy 21.889615 -51.916812) (xy 21.944458 -51.906682) (xy 22.000192 -51.904645) (xy 22.055629 -51.910745)
			(xy 22.109586 -51.924851) (xy 22.160915 -51.946663) (xy 22.208521 -51.975717) (xy 22.251389 -52.011392)
			(xy 22.288606 -52.052929) (xy 22.319379 -52.099442) (xy 22.343051 -52.149939) (xy 22.359119 -52.203346)
			(xy 22.367239 -52.258522) (xy 22.367748 -52.286408) (xy 22.367239 -52.314294) (xy 22.359119 -52.36947)
			(xy 22.343051 -52.422877) (xy 22.319379 -52.473374) (xy 22.288606 -52.519887) (xy 22.251389 -52.561424)
			(xy 22.208521 -52.597099) (xy 22.160915 -52.626153) (xy 22.109586 -52.647965) (xy 22.055629 -52.662071)
			(xy 22.000192 -52.668171) (xy 21.944458 -52.666134) (xy 21.889615 -52.656004) (xy 21.836831 -52.637997)
			(xy 21.787231 -52.612496) (xy 21.741873 -52.580045) (xy 21.701724 -52.541336) (xy 21.667638 -52.497193)
			(xy 21.640342 -52.448558) (xy 21.620419 -52.396467) (xy 21.608293 -52.34203) (xy 21.604222 -52.286408)
			(xy 19.144052 -52.286408) (xy 19.143979 -52.290418) (xy 19.135859 -52.345594) (xy 19.119791 -52.399001)
			(xy 19.096119 -52.449498) (xy 19.065346 -52.496011) (xy 19.028129 -52.537548) (xy 18.985261 -52.573223)
			(xy 18.937655 -52.602277) (xy 18.886326 -52.624089) (xy 18.832369 -52.638195) (xy 18.776932 -52.644295)
			(xy 18.721198 -52.642258) (xy 18.666355 -52.632128) (xy 18.613571 -52.614121) (xy 18.563971 -52.58862)
			(xy 18.518613 -52.556169) (xy 18.478464 -52.51746) (xy 18.444378 -52.473317) (xy 18.417082 -52.424682)
			(xy 18.397159 -52.372591) (xy 18.385033 -52.318154) (xy 18.380962 -52.262532) (xy 14.783288 -52.262532)
			(xy 14.737635 -52.274467) (xy 14.682198 -52.280567) (xy 14.626464 -52.27853) (xy 14.571621 -52.2684)
			(xy 14.518837 -52.250393) (xy 14.469237 -52.224892) (xy 14.423879 -52.192441) (xy 14.38373 -52.153732)
			(xy 14.349644 -52.109589) (xy 14.322348 -52.060954) (xy 14.302425 -52.008863) (xy 14.290299 -51.954426)
			(xy 14.286228 -51.898804) (xy 11.109734 -51.898804) (xy 11.099321 -51.908539) (xy 11.069066 -51.931824)
			(xy 11.050514 -51.946395) (xy 11.018659 -51.981181) (xy 10.993761 -52.021243) (xy 10.976673 -52.065206)
			(xy 10.96798 -52.111567) (xy 10.96798 -52.158735) (xy 10.976674 -52.205095) (xy 10.993762 -52.249059)
			(xy 11.01866 -52.28912) (xy 11.050515 -52.323906) (xy 11.069066 -52.338478) (xy 11.099321 -52.361763)
			(xy 11.155094 -52.413904) (xy 11.204851 -52.471813) (xy 11.248001 -52.5348) (xy 11.284028 -52.602115)
			(xy 11.312505 -52.672955) (xy 11.333091 -52.746477) (xy 11.345542 -52.821804) (xy 11.349709 -52.89804)
			(xy 11.345542 -52.974276) (xy 11.333091 -53.049603) (xy 11.312505 -53.123125) (xy 11.284028 -53.193965)
			(xy 11.248001 -53.26128) (xy 11.204851 -53.324267) (xy 11.155094 -53.382176) (xy 11.099321 -53.434317)
			(xy 11.069066 -53.457602) (xy 11.05047 -53.472164) (xy 11.018523 -53.506944) (xy 10.993548 -53.547026)
			(xy 10.976405 -53.591031) (xy 10.967683 -53.637445) (xy 10.967682 -53.684671) (xy 10.976403 -53.731085)
			(xy 10.993546 -53.77509) (xy 11.01852 -53.815172) (xy 11.050467 -53.849953) (xy 11.069066 -53.86451)
			(xy 11.099323 -53.887793) (xy 11.155096 -53.939934) (xy 11.204853 -53.997843) (xy 11.248003 -54.06083)
			(xy 11.28403 -54.128145) (xy 11.312507 -54.198986) (xy 11.333093 -54.272508) (xy 11.345544 -54.347835)
			(xy 11.349711 -54.424071) (xy 11.345544 -54.500307) (xy 11.333093 -54.575635) (xy 11.312506 -54.649157)
			(xy 11.284029 -54.719997) (xy 11.248001 -54.787312) (xy 11.227308 -54.817518) (xy 17.100802 -54.817518)
			(xy 17.104873 -54.761896) (xy 17.116999 -54.707459) (xy 17.136922 -54.655368) (xy 17.164218 -54.606733)
			(xy 17.198304 -54.56259) (xy 17.238453 -54.523881) (xy 17.283811 -54.49143) (xy 17.333411 -54.465929)
			(xy 17.386195 -54.447922) (xy 17.441038 -54.437792) (xy 17.496772 -54.435755) (xy 17.552209 -54.441855)
			(xy 17.606166 -54.455961) (xy 17.657495 -54.477773) (xy 17.705101 -54.506827) (xy 17.71981 -54.519068)
			(xy 19.478242 -54.519068) (xy 19.482313 -54.463446) (xy 19.494439 -54.409009) (xy 19.514362 -54.356918)
			(xy 19.541658 -54.308283) (xy 19.575744 -54.26414) (xy 19.615893 -54.225431) (xy 19.661251 -54.19298)
			(xy 19.710851 -54.167479) (xy 19.763635 -54.149472) (xy 19.818478 -54.139342) (xy 19.874212 -54.137305)
			(xy 19.929649 -54.143405) (xy 19.983606 -54.157511) (xy 20.034935 -54.179323) (xy 20.082541 -54.208377)
			(xy 20.125409 -54.244052) (xy 20.162626 -54.285589) (xy 20.193399 -54.332102) (xy 20.217071 -54.382599)
			(xy 20.233139 -54.436006) (xy 20.241259 -54.491182) (xy 20.241768 -54.519068) (xy 20.241259 -54.546954)
			(xy 20.233139 -54.60213) (xy 20.217071 -54.655537) (xy 20.193399 -54.706034) (xy 20.162626 -54.752547)
			(xy 20.125409 -54.794084) (xy 20.082541 -54.829759) (xy 20.034935 -54.858813) (xy 19.983606 -54.880625)
			(xy 19.929649 -54.894731) (xy 19.874212 -54.900831) (xy 19.818478 -54.898794) (xy 19.763635 -54.888664)
			(xy 19.710851 -54.870657) (xy 19.661251 -54.845156) (xy 19.615893 -54.812705) (xy 19.575744 -54.773996)
			(xy 19.541658 -54.729853) (xy 19.514362 -54.681218) (xy 19.494439 -54.629127) (xy 19.482313 -54.57469)
			(xy 19.478242 -54.519068) (xy 17.71981 -54.519068) (xy 17.747969 -54.542502) (xy 17.785186 -54.584039)
			(xy 17.815959 -54.630552) (xy 17.839631 -54.681049) (xy 17.855699 -54.734456) (xy 17.863819 -54.789632)
			(xy 17.864328 -54.817518) (xy 17.863819 -54.845404) (xy 17.855699 -54.90058) (xy 17.839631 -54.953987)
			(xy 17.815959 -55.004484) (xy 17.785186 -55.050997) (xy 17.747969 -55.092534) (xy 17.705101 -55.128209)
			(xy 17.657495 -55.157263) (xy 17.606166 -55.179075) (xy 17.552209 -55.193181) (xy 17.496772 -55.199281)
			(xy 17.441038 -55.197244) (xy 17.386195 -55.187114) (xy 17.333411 -55.169107) (xy 17.283811 -55.143606)
			(xy 17.238453 -55.111155) (xy 17.198304 -55.072446) (xy 17.164218 -55.028303) (xy 17.136922 -54.979668)
			(xy 17.116999 -54.927577) (xy 17.104873 -54.87314) (xy 17.100802 -54.817518) (xy 11.227308 -54.817518)
			(xy 11.204852 -54.850299) (xy 11.155094 -54.908208) (xy 11.099321 -54.960349) (xy 11.069066 -54.983634)
			(xy 11.050478 -54.998205) (xy 11.018529 -55.032984) (xy 10.993553 -55.073064) (xy 10.976409 -55.117067)
			(xy 10.967686 -55.16348) (xy 10.967684 -55.210706) (xy 10.976405 -55.257119) (xy 10.993547 -55.301123)
			(xy 11.01852 -55.341205) (xy 11.050467 -55.375985) (xy 11.069066 -55.390542) (xy 11.09853 -55.413212)
			(xy 11.152985 -55.463829) (xy 11.193049 -55.509922) (xy 13.939264 -55.509922) (xy 13.943335 -55.4543)
			(xy 13.955461 -55.399863) (xy 13.975384 -55.347772) (xy 14.00268 -55.299137) (xy 14.036766 -55.254994)
			(xy 14.076915 -55.216285) (xy 14.122273 -55.183834) (xy 14.171873 -55.158333) (xy 14.224657 -55.140326)
			(xy 14.2795 -55.130196) (xy 14.335234 -55.128159) (xy 14.390671 -55.134259) (xy 14.444628 -55.148365)
			(xy 14.495957 -55.170177) (xy 14.543563 -55.199231) (xy 14.586431 -55.234906) (xy 14.623648 -55.276443)
			(xy 14.654421 -55.322956) (xy 14.678093 -55.373453) (xy 14.694161 -55.42686) (xy 14.702281 -55.482036)
			(xy 14.702651 -55.502302) (xy 18.810222 -55.502302) (xy 18.814293 -55.44668) (xy 18.826419 -55.392243)
			(xy 18.846342 -55.340152) (xy 18.873638 -55.291517) (xy 18.907724 -55.247374) (xy 18.947873 -55.208665)
			(xy 18.993231 -55.176214) (xy 19.042831 -55.150713) (xy 19.095615 -55.132706) (xy 19.150458 -55.122576)
			(xy 19.206192 -55.120539) (xy 19.261629 -55.126639) (xy 19.315586 -55.140745) (xy 19.366915 -55.162557)
			(xy 19.414521 -55.191611) (xy 19.457389 -55.227286) (xy 19.494606 -55.268823) (xy 19.525379 -55.315336)
			(xy 19.549051 -55.365833) (xy 19.565119 -55.41924) (xy 19.573239 -55.474416) (xy 19.573748 -55.502302)
			(xy 19.573239 -55.530188) (xy 19.565119 -55.585364) (xy 19.557555 -55.610506) (xy 21.430486 -55.610506)
			(xy 21.434557 -55.554884) (xy 21.446683 -55.500447) (xy 21.466606 -55.448356) (xy 21.493902 -55.399721)
			(xy 21.527988 -55.355578) (xy 21.568137 -55.316869) (xy 21.613495 -55.284418) (xy 21.663095 -55.258917)
			(xy 21.715879 -55.24091) (xy 21.770722 -55.23078) (xy 21.826456 -55.228743) (xy 21.881893 -55.234843)
			(xy 21.93585 -55.248949) (xy 21.987179 -55.270761) (xy 22.034785 -55.299815) (xy 22.077653 -55.33549)
			(xy 22.11487 -55.377027) (xy 22.145643 -55.42354) (xy 22.169315 -55.474037) (xy 22.185383 -55.527444)
			(xy 22.193503 -55.58262) (xy 22.194012 -55.610506) (xy 22.193503 -55.638392) (xy 22.185383 -55.693568)
			(xy 22.169315 -55.746975) (xy 22.145643 -55.797472) (xy 22.11487 -55.843985) (xy 22.077653 -55.885522)
			(xy 22.034785 -55.921197) (xy 21.987179 -55.950251) (xy 21.93585 -55.972063) (xy 21.881893 -55.986169)
			(xy 21.826456 -55.992269) (xy 21.770722 -55.990232) (xy 21.715879 -55.980102) (xy 21.663095 -55.962095)
			(xy 21.613495 -55.936594) (xy 21.568137 -55.904143) (xy 21.527988 -55.865434) (xy 21.493902 -55.821291)
			(xy 21.466606 -55.772656) (xy 21.446683 -55.720565) (xy 21.434557 -55.666128) (xy 21.430486 -55.610506)
			(xy 19.557555 -55.610506) (xy 19.549051 -55.638771) (xy 19.525379 -55.689268) (xy 19.494606 -55.735781)
			(xy 19.457389 -55.777318) (xy 19.414521 -55.812993) (xy 19.366915 -55.842047) (xy 19.315586 -55.863859)
			(xy 19.261629 -55.877965) (xy 19.206192 -55.884065) (xy 19.150458 -55.882028) (xy 19.095615 -55.871898)
			(xy 19.042831 -55.853891) (xy 18.993231 -55.82839) (xy 18.947873 -55.795939) (xy 18.907724 -55.75723)
			(xy 18.873638 -55.713087) (xy 18.846342 -55.664452) (xy 18.826419 -55.612361) (xy 18.814293 -55.557924)
			(xy 18.810222 -55.502302) (xy 14.702651 -55.502302) (xy 14.70279 -55.509922) (xy 14.702281 -55.537808)
			(xy 14.694161 -55.592984) (xy 14.678093 -55.646391) (xy 14.654421 -55.696888) (xy 14.623648 -55.743401)
			(xy 14.586431 -55.784938) (xy 14.543563 -55.820613) (xy 14.495957 -55.849667) (xy 14.444628 -55.871479)
			(xy 14.390671 -55.885585) (xy 14.335234 -55.891685) (xy 14.2795 -55.889648) (xy 14.224657 -55.879518)
			(xy 14.171873 -55.861511) (xy 14.122273 -55.83601) (xy 14.076915 -55.803559) (xy 14.036766 -55.76485)
			(xy 14.00268 -55.720707) (xy 13.975384 -55.672072) (xy 13.955461 -55.619981) (xy 13.943335 -55.565544)
			(xy 13.939264 -55.509922) (xy 11.193049 -55.509922) (xy 11.201758 -55.519941) (xy 11.244301 -55.580912)
			(xy 11.280132 -55.646054) (xy 11.308846 -55.714632) (xy 11.330119 -55.785869) (xy 11.34371 -55.858963)
			(xy 11.349466 -55.933086) (xy 11.347323 -56.007401) (xy 11.337303 -56.081069) (xy 11.319521 -56.153257)
			(xy 11.294177 -56.22315) (xy 11.261558 -56.289959) (xy 11.222032 -56.352927) (xy 11.176045 -56.411345)
			(xy 11.124118 -56.464551) (xy 11.066837 -56.511945) (xy 11.004848 -56.552992) (xy 10.938854 -56.587227)
			(xy 10.869598 -56.614264) (xy 10.797864 -56.633797) (xy 10.724461 -56.645606) (xy 10.65022 -56.649558)
			(xy 10.575979 -56.645606) (xy 10.502576 -56.633797) (xy 10.430842 -56.614264) (xy 10.361586 -56.587227)
			(xy 10.295592 -56.552992) (xy 10.233603 -56.511945) (xy 10.176322 -56.464551) (xy 10.124395 -56.411345)
			(xy 10.078408 -56.352927) (xy 10.038882 -56.289959) (xy 10.006263 -56.22315) (xy 9.980919 -56.153257)
			(xy 9.963137 -56.081069) (xy 9.953117 -56.007401) (xy 9.950974 -55.933086) (xy 9.95673 -55.858963)
			(xy 9.970321 -55.785869) (xy 9.991594 -55.714632) (xy 10.020308 -55.646054) (xy 10.056139 -55.580912)
			(xy 10.098682 -55.519941) (xy 10.147455 -55.463829) (xy 10.20191 -55.413212) (xy 10.231374 -55.390542)
			(xy 10.249984 -55.375998) (xy 10.281928 -55.341213) (xy 10.306899 -55.301128) (xy 10.32404 -55.257121)
			(xy 10.332759 -55.210706) (xy 10.332758 -55.163479) (xy 10.324036 -55.117065) (xy 10.306893 -55.073059)
			(xy 10.281919 -55.032975) (xy 10.249973 -54.998193) (xy 10.231374 -54.983634) (xy 10.201121 -54.960346)
			(xy 10.145348 -54.908206) (xy 10.095591 -54.850297) (xy 10.052441 -54.78731) (xy 10.016414 -54.719996)
			(xy 9.987937 -54.649156) (xy 9.96735 -54.575634) (xy 9.9549 -54.500307) (xy 9.950733 -54.424071)
			(xy 9.954899 -54.347836) (xy 9.96735 -54.272508) (xy 9.987936 -54.198987) (xy 10.016413 -54.128147)
			(xy 10.05244 -54.060832) (xy 10.09559 -53.997845) (xy 10.145347 -53.939936) (xy 10.201119 -53.887795)
			(xy 10.231374 -53.86451) (xy 10.249978 -53.849957) (xy 10.281925 -53.815176) (xy 10.3069 -53.775092)
			(xy 10.324043 -53.731086) (xy 10.332764 -53.684671) (xy 10.332764 -53.637444) (xy 10.324041 -53.591029)
			(xy 10.306898 -53.547023) (xy 10.281922 -53.50694) (xy 10.249974 -53.472159) (xy 10.231374 -53.457602)
			(xy 10.201119 -53.434317) (xy 10.145346 -53.382176) (xy 10.095589 -53.324267) (xy 10.052439 -53.26128)
			(xy 10.016412 -53.193965) (xy 9.987935 -53.123125) (xy 9.967349 -53.049603) (xy 9.954898 -52.974276)
			(xy 9.950731 -52.89804) (xy 9.954898 -52.821804) (xy 9.967349 -52.746477) (xy 9.987935 -52.672955)
			(xy 10.016412 -52.602115) (xy 10.052439 -52.5348) (xy 10.095589 -52.471813) (xy 10.145346 -52.413904)
			(xy 10.201119 -52.361763) (xy 10.231374 -52.338478) (xy 10.249955 -52.323925) (xy 10.281871 -52.289161)
			(xy 10.306821 -52.249103) (xy 10.323946 -52.205128) (xy 10.332659 -52.158747) (xy 10.332659 -52.111554)
			(xy 10.323946 -52.065173) (xy 10.306821 -52.021198) (xy 10.281872 -51.98114) (xy 10.249956 -51.946376)
			(xy 10.231374 -51.931824) (xy 10.201121 -51.908536) (xy 10.145348 -51.856396) (xy 10.095591 -51.798487)
			(xy 10.052441 -51.7355) (xy 10.016414 -51.668186) (xy 9.987937 -51.597346) (xy 9.96735 -51.523824)
			(xy 9.9549 -51.448497) (xy 9.950733 -51.372261) (xy 9.954899 -51.296026) (xy 9.96735 -51.220698)
			(xy 9.987936 -51.147177) (xy 10.016413 -51.076337) (xy 10.05244 -51.009022) (xy 10.09559 -50.946035)
			(xy 10.145347 -50.888126) (xy 10.201119 -50.835985) (xy 10.231374 -50.8127) (xy 10.249978 -50.798147)
			(xy 10.281925 -50.763366) (xy 10.3069 -50.723282) (xy 10.324043 -50.679276) (xy 10.332764 -50.632861)
			(xy 10.332764 -50.585634) (xy 10.324041 -50.539219) (xy 10.306898 -50.495213) (xy 10.281922 -50.45513)
			(xy 10.249974 -50.420349) (xy 10.231374 -50.405792) (xy 10.201119 -50.382507) (xy 10.145346 -50.330366)
			(xy 10.095589 -50.272457) (xy 10.052439 -50.20947) (xy 10.016412 -50.142155) (xy 9.987935 -50.071315)
			(xy 9.967349 -49.997793) (xy 9.954898 -49.922466) (xy 9.950731 -49.84623) (xy 9.954898 -49.769994)
			(xy 9.967349 -49.694667) (xy 9.987935 -49.621145) (xy 10.016412 -49.550305) (xy 10.052439 -49.48299)
			(xy 10.095589 -49.420003) (xy 10.145346 -49.362094) (xy 10.201119 -49.309953) (xy 10.231374 -49.286668)
			(xy 10.249958 -49.272093) (xy 10.281902 -49.237313) (xy 10.306874 -49.197233) (xy 10.324015 -49.153231)
			(xy 10.332737 -49.10682) (xy 10.332738 -49.059597) (xy 10.32402 -49.013185) (xy 10.306881 -48.969182)
			(xy 10.281912 -48.9291) (xy 10.24997 -48.894318) (xy 10.231374 -48.87976) (xy 10.201116 -48.856478)
			(xy 10.145342 -48.804337) (xy 10.095583 -48.746429) (xy 10.052432 -48.683441) (xy 10.016404 -48.616127)
			(xy 9.987926 -48.545286) (xy 9.967339 -48.471764) (xy 9.954888 -48.396435) (xy 9.950721 -48.320199)
			(xy 9.467619 -48.320199) (xy 9.467619 -48.343351) (xy 9.476007 -48.38889) (xy 9.492507 -48.432156)
			(xy 9.516572 -48.471716) (xy 9.547406 -48.506262) (xy 9.565386 -48.520858) (xy 9.596001 -48.54412)
			(xy 9.65247 -48.596312) (xy 9.70287 -48.654385) (xy 9.746593 -48.717639) (xy 9.783109 -48.785309)
			(xy 9.811979 -48.856578) (xy 9.832853 -48.930584) (xy 9.845478 -49.006435) (xy 9.849704 -49.083212)
			(xy 9.845478 -49.15999) (xy 9.832851 -49.23584) (xy 9.811977 -49.309847) (xy 9.783107 -49.381115)
			(xy 9.74659 -49.448785) (xy 9.702867 -49.512038) (xy 9.652467 -49.570111) (xy 9.595998 -49.622303)
			(xy 9.565386 -49.64557) (xy 9.547408 -49.660167) (xy 9.516573 -49.694713) (xy 9.492507 -49.734273)
			(xy 9.476006 -49.777538) (xy 9.467617 -49.823077) (xy 9.467617 -49.869383) (xy 9.476006 -49.914922)
			(xy 9.492507 -49.958187) (xy 9.516573 -49.997747) (xy 9.547408 -50.032293) (xy 9.565386 -50.04689)
			(xy 9.59523 -50.069539) (xy 9.650395 -50.12024) (xy 9.699822 -50.176549) (xy 9.742943 -50.237821)
			(xy 9.779265 -50.303353) (xy 9.80837 -50.372394) (xy 9.829925 -50.444152) (xy 9.843682 -50.517802)
			(xy 9.849484 -50.592502) (xy 9.847264 -50.667394) (xy 9.837048 -50.741619) (xy 9.818952 -50.814326)
			(xy 9.793185 -50.884681) (xy 9.760042 -50.951876) (xy 9.719903 -51.015142) (xy 9.673228 -51.073752)
			(xy 9.620553 -51.127035) (xy 9.562482 -51.174379) (xy 9.53135 -51.195224) (xy 9.520174 -51.20259)
			(xy 9.16305 -51.559714) (xy 8.775192 -51.559714) (xy 8.553958 -51.780948) (xy 8.553958 -52.533296)
			(xy 8.756142 -52.73548) (xy 9.271 -52.73548) (xy 9.271 -52.914804) (xy 9.320276 -52.98186) (xy 9.3599 -52.994306)
			(xy 9.396513 -53.006365) (xy 9.467054 -53.037456) (xy 9.533745 -53.076121) (xy 9.595777 -53.121891)
			(xy 9.652395 -53.174208) (xy 9.702912 -53.232438) (xy 9.746715 -53.295873) (xy 9.783271 -53.363743)
			(xy 9.812136 -53.435224) (xy 9.832961 -53.509447) (xy 9.845491 -53.585511) (xy 9.848088 -53.623972)
			(xy 9.849598 -53.662314) (xy 9.845244 -53.738928) (xy 9.83253 -53.814604) (xy 9.811607 -53.888434)
			(xy 9.782728 -53.95953) (xy 9.74624 -54.027037) (xy 9.702581 -54.090144) (xy 9.652276 -54.148092)
			(xy 9.59593 -54.200185) (xy 9.565386 -54.223412) (xy 9.547408 -54.238009) (xy 9.516573 -54.272555)
			(xy 9.492507 -54.312115) (xy 9.476007 -54.35538) (xy 9.467618 -54.400919) (xy 9.467618 -54.447224)
			(xy 9.476008 -54.492762) (xy 9.492508 -54.536028) (xy 9.516575 -54.575587) (xy 9.54741 -54.610132)
			(xy 9.565386 -54.624732) (xy 9.593761 -54.646242) (xy 9.646441 -54.694153) (xy 9.693978 -54.747169)
			(xy 9.735882 -54.804743) (xy 9.771717 -54.866277) (xy 9.801113 -54.931134) (xy 9.823765 -54.998643)
			(xy 9.839439 -55.068104) (xy 9.847973 -55.138799) (xy 9.849104 -55.174388) (xy 9.849257 -55.214522)
			(xy 9.841483 -55.294406) (xy 9.824611 -55.372875) (xy 9.798865 -55.448895) (xy 9.764582 -55.521466)
			(xy 9.722214 -55.589634) (xy 9.69772 -55.621428) (xy 9.673738 -55.65089) (xy 9.620382 -55.704968)
			(xy 9.561475 -55.752941) (xy 9.497715 -55.794245) (xy 9.429851 -55.828391) (xy 9.394444 -55.842154)
			(xy 9.35863 -55.855362) (xy 9.271 -55.974996) (xy 9.271 -56.881776) (xy 14.079726 -56.881776) (xy 14.083797 -56.826154)
			(xy 14.095923 -56.771717) (xy 14.115846 -56.719626) (xy 14.143142 -56.670991) (xy 14.177228 -56.626848)
			(xy 14.217377 -56.588139) (xy 14.262735 -56.555688) (xy 14.312335 -56.530187) (xy 14.365119 -56.51218)
			(xy 14.419962 -56.50205) (xy 14.475696 -56.500013) (xy 14.531133 -56.506113) (xy 14.58509 -56.520219)
			(xy 14.636419 -56.542031) (xy 14.684025 -56.571085) (xy 14.726893 -56.60676) (xy 14.76411 -56.648297)
			(xy 14.794883 -56.69481) (xy 14.818555 -56.745307) (xy 14.834623 -56.798714) (xy 14.842743 -56.85389)
			(xy 14.843252 -56.881776) (xy 14.842743 -56.909662) (xy 14.834623 -56.964838) (xy 14.818555 -57.018245)
			(xy 14.794883 -57.068742) (xy 14.76411 -57.115255) (xy 14.726893 -57.156792) (xy 14.689883 -57.187592)
			(xy 17.944082 -57.187592) (xy 17.948153 -57.13197) (xy 17.960279 -57.077533) (xy 17.980202 -57.025442)
			(xy 18.007498 -56.976807) (xy 18.041584 -56.932664) (xy 18.081733 -56.893955) (xy 18.127091 -56.861504)
			(xy 18.176691 -56.836003) (xy 18.229475 -56.817996) (xy 18.284318 -56.807866) (xy 18.340052 -56.805829)
			(xy 18.395489 -56.811929) (xy 18.449446 -56.826035) (xy 18.500775 -56.847847) (xy 18.548381 -56.876901)
			(xy 18.591249 -56.912576) (xy 18.628466 -56.954113) (xy 18.659239 -57.000626) (xy 18.682911 -57.051123)
			(xy 18.698979 -57.10453) (xy 18.707099 -57.159706) (xy 18.707608 -57.187592) (xy 18.707099 -57.215478)
			(xy 18.698979 -57.270654) (xy 18.682911 -57.324061) (xy 18.659239 -57.374558) (xy 18.628466 -57.421071)
			(xy 18.591249 -57.462608) (xy 18.548381 -57.498283) (xy 18.500775 -57.527337) (xy 18.449446 -57.549149)
			(xy 18.395489 -57.563255) (xy 18.340052 -57.569355) (xy 18.284318 -57.567318) (xy 18.229475 -57.557188)
			(xy 18.176691 -57.539181) (xy 18.127091 -57.51368) (xy 18.081733 -57.481229) (xy 18.041584 -57.44252)
			(xy 18.007498 -57.398377) (xy 17.980202 -57.349742) (xy 17.960279 -57.297651) (xy 17.948153 -57.243214)
			(xy 17.944082 -57.187592) (xy 14.689883 -57.187592) (xy 14.684025 -57.192467) (xy 14.636419 -57.221521)
			(xy 14.58509 -57.243333) (xy 14.531133 -57.257439) (xy 14.475696 -57.263539) (xy 14.419962 -57.261502)
			(xy 14.365119 -57.251372) (xy 14.312335 -57.233365) (xy 14.262735 -57.207864) (xy 14.217377 -57.175413)
			(xy 14.177228 -57.136704) (xy 14.143142 -57.092561) (xy 14.115846 -57.043926) (xy 14.095923 -56.991835)
			(xy 14.083797 -56.937398) (xy 14.079726 -56.881776) (xy 9.271 -56.881776) (xy 9.271 -58.837889) (xy 9.994378 -58.837889)
			(xy 9.994378 -58.742267) (xy 10.002274 -58.646971) (xy 10.018013 -58.552653) (xy 10.041487 -58.459956)
			(xy 10.072536 -58.369515) (xy 10.110947 -58.281947) (xy 10.156458 -58.197849) (xy 10.208758 -58.117797)
			(xy 10.267491 -58.042338) (xy 10.332254 -57.971986) (xy 10.402606 -57.907223) (xy 10.478065 -57.84849)
			(xy 10.558117 -57.79619) (xy 10.642215 -57.750679) (xy 10.729783 -57.712268) (xy 10.820224 -57.681219)
			(xy 10.912921 -57.657745) (xy 11.007239 -57.642006) (xy 11.102535 -57.63411) (xy 11.198157 -57.63411)
			(xy 11.293453 -57.642006) (xy 11.387771 -57.657745) (xy 11.480468 -57.681219) (xy 11.570909 -57.712268)
			(xy 11.658477 -57.750679) (xy 11.742575 -57.79619) (xy 11.822627 -57.84849) (xy 11.898086 -57.907223)
			(xy 11.968438 -57.971986) (xy 12.033201 -58.042338) (xy 12.066782 -58.085482) (xy 15.802862 -58.085482)
			(xy 15.806933 -58.02986) (xy 15.819059 -57.975423) (xy 15.838982 -57.923332) (xy 15.866278 -57.874697)
			(xy 15.900364 -57.830554) (xy 15.940513 -57.791845) (xy 15.985871 -57.759394) (xy 16.035471 -57.733893)
			(xy 16.088255 -57.715886) (xy 16.143098 -57.705756) (xy 16.198832 -57.703719) (xy 16.254269 -57.709819)
			(xy 16.308226 -57.723925) (xy 16.359555 -57.745737) (xy 16.407161 -57.774791) (xy 16.450029 -57.810466)
			(xy 16.487246 -57.852003) (xy 16.518019 -57.898516) (xy 16.541691 -57.949013) (xy 16.557759 -58.00242)
			(xy 16.565879 -58.057596) (xy 16.566388 -58.085482) (xy 16.565879 -58.113368) (xy 16.557759 -58.168544)
			(xy 16.541691 -58.221951) (xy 16.518019 -58.272448) (xy 16.487246 -58.318961) (xy 16.450029 -58.360498)
			(xy 16.407161 -58.396173) (xy 16.363779 -58.422649) (xy 19.586611 -58.422649) (xy 19.587227 -58.368134)
			(xy 19.595598 -58.314263) (xy 19.611554 -58.262131) (xy 19.634768 -58.212802) (xy 19.664768 -58.16728)
			(xy 19.700943 -58.126493) (xy 19.742557 -58.091271) (xy 19.78876 -58.062332) (xy 19.838613 -58.040266)
			(xy 19.8911 -58.025521) (xy 19.945151 -58.018399) (xy 19.999666 -58.019044) (xy 20.053533 -58.027443)
			(xy 20.105656 -58.043426) (xy 20.154973 -58.066666) (xy 20.200479 -58.09669) (xy 20.241247 -58.132887)
			(xy 20.276447 -58.174519) (xy 20.305362 -58.220738) (xy 20.327402 -58.270603) (xy 20.342119 -58.323097)
			(xy 20.349213 -58.377152) (xy 20.348539 -58.431666) (xy 20.340111 -58.485529) (xy 20.324101 -58.537644)
			(xy 20.312888 -58.562494) (xy 20.303335 -58.583842) (xy 20.291396 -58.629056) (xy 20.287938 -58.675692)
			(xy 20.293078 -58.722173) (xy 20.306642 -58.766927) (xy 20.328172 -58.80844) (xy 20.356939 -58.845309)
			(xy 20.374102 -58.861198) (xy 20.394154 -58.879666) (xy 20.429388 -58.921259) (xy 20.458343 -58.967444)
			(xy 20.480427 -59.017281) (xy 20.495192 -59.069754) (xy 20.502336 -59.123795) (xy 20.501713 -59.178303)
			(xy 20.493338 -59.232166) (xy 20.477379 -59.284289) (xy 20.454162 -59.333608) (xy 20.424161 -59.379121)
			(xy 20.387986 -59.419898) (xy 20.346374 -59.45511) (xy 20.300173 -59.48404) (xy 20.250324 -59.506097)
			(xy 20.197843 -59.520833) (xy 20.143798 -59.527948) (xy 20.089291 -59.527296) (xy 20.035432 -59.518891)
			(xy 19.983318 -59.502904) (xy 19.934011 -59.479661) (xy 19.888515 -59.449635) (xy 19.847757 -59.413438)
			(xy 19.812568 -59.371807) (xy 19.783663 -59.32559) (xy 19.761633 -59.275729) (xy 19.746925 -59.22324)
			(xy 19.73984 -59.169192) (xy 19.740521 -59.114685) (xy 19.748955 -59.06083) (xy 19.76497 -59.008725)
			(xy 19.776186 -58.98388) (xy 19.785772 -58.962546) (xy 19.797709 -58.917327) (xy 19.801164 -58.870687)
			(xy 19.796019 -58.824202) (xy 19.782449 -58.779446) (xy 19.760913 -58.737932) (xy 19.732138 -58.701064)
			(xy 19.714972 -58.685176) (xy 19.694833 -58.6668) (xy 19.65959 -58.625206) (xy 19.630627 -58.579017)
			(xy 19.608534 -58.529176) (xy 19.593762 -58.476697) (xy 19.586611 -58.422649) (xy 16.363779 -58.422649)
			(xy 16.359555 -58.425227) (xy 16.308226 -58.447039) (xy 16.254269 -58.461145) (xy 16.198832 -58.467245)
			(xy 16.143098 -58.465208) (xy 16.088255 -58.455078) (xy 16.035471 -58.437071) (xy 15.985871 -58.41157)
			(xy 15.940513 -58.379119) (xy 15.900364 -58.34041) (xy 15.866278 -58.296267) (xy 15.838982 -58.247632)
			(xy 15.819059 -58.195541) (xy 15.806933 -58.141104) (xy 15.802862 -58.085482) (xy 12.066782 -58.085482)
			(xy 12.091934 -58.117797) (xy 12.144234 -58.197849) (xy 12.189745 -58.281947) (xy 12.228156 -58.369515)
			(xy 12.259205 -58.459956) (xy 12.282679 -58.552653) (xy 12.298418 -58.646971) (xy 12.306314 -58.742267)
			(xy 12.306808 -58.790078) (xy 12.306314 -58.837889) (xy 12.298418 -58.933185) (xy 12.282679 -59.027503)
			(xy 12.259205 -59.1202) (xy 12.228156 -59.210641) (xy 12.189745 -59.298209) (xy 12.144234 -59.382307)
			(xy 12.091934 -59.462359) (xy 12.033201 -59.537818) (xy 11.968438 -59.60817) (xy 11.898086 -59.672933)
			(xy 11.822627 -59.731666) (xy 11.742575 -59.783966) (xy 11.658477 -59.829477) (xy 11.570909 -59.867888)
			(xy 11.480468 -59.898937) (xy 11.387771 -59.922411) (xy 11.293453 -59.93815) (xy 11.198157 -59.946046)
			(xy 11.102535 -59.946046) (xy 11.007239 -59.93815) (xy 10.912921 -59.922411) (xy 10.820224 -59.898937)
			(xy 10.729783 -59.867888) (xy 10.642215 -59.829477) (xy 10.558117 -59.783966) (xy 10.478065 -59.731666)
			(xy 10.402606 -59.672933) (xy 10.332254 -59.60817) (xy 10.267491 -59.537818) (xy 10.208758 -59.462359)
			(xy 10.156458 -59.382307) (xy 10.110947 -59.298209) (xy 10.072536 -59.210641) (xy 10.041487 -59.1202)
			(xy 10.018013 -59.027503) (xy 10.002274 -58.933185) (xy 9.994378 -58.837889) (xy 9.271 -58.837889)
			(xy 9.271 -60.71362) (xy 15.802354 -60.71362) (xy 15.806425 -60.657998) (xy 15.818551 -60.603561)
			(xy 15.838474 -60.55147) (xy 15.86577 -60.502835) (xy 15.899856 -60.458692) (xy 15.940005 -60.419983)
			(xy 15.985363 -60.387532) (xy 16.034963 -60.362031) (xy 16.087747 -60.344024) (xy 16.14259 -60.333894)
			(xy 16.198324 -60.331857) (xy 16.253761 -60.337957) (xy 16.307718 -60.352063) (xy 16.359047 -60.373875)
			(xy 16.406653 -60.402929) (xy 16.449521 -60.438604) (xy 16.486738 -60.480141) (xy 16.517511 -60.526654)
			(xy 16.541183 -60.577151) (xy 16.557251 -60.630558) (xy 16.565371 -60.685734) (xy 16.56588 -60.71362)
			(xy 16.565371 -60.741506) (xy 16.557251 -60.796682) (xy 16.541183 -60.850089) (xy 16.517511 -60.900586)
			(xy 16.486738 -60.947099) (xy 16.449521 -60.988636) (xy 16.406653 -61.024311) (xy 16.359047 -61.053365)
			(xy 16.307718 -61.075177) (xy 16.253761 -61.089283) (xy 16.198324 -61.095383) (xy 16.14259 -61.093346)
			(xy 16.087747 -61.083216) (xy 16.034963 -61.065209) (xy 15.985363 -61.039708) (xy 15.940005 -61.007257)
			(xy 15.899856 -60.968548) (xy 15.86577 -60.924405) (xy 15.838474 -60.87577) (xy 15.818551 -60.823679)
			(xy 15.806425 -60.769242) (xy 15.802354 -60.71362) (xy 9.271 -60.71362) (xy 9.271 -64.501776) (xy 9.714992 -64.501776)
			(xy 9.714992 -62.088776) (xy 9.715492 -62.053129) (xy 9.723474 -61.982283) (xy 9.739338 -61.912777)
			(xy 9.762885 -61.845483) (xy 9.793819 -61.78125) (xy 9.83175 -61.720883) (xy 9.876201 -61.665143)
			(xy 9.926613 -61.614731) (xy 9.982353 -61.57028) (xy 10.04272 -61.532349) (xy 10.106953 -61.501415)
			(xy 10.174247 -61.477868) (xy 10.243753 -61.462004) (xy 10.314599 -61.454022) (xy 10.385893 -61.454022)
			(xy 10.456739 -61.462004) (xy 10.526245 -61.477868) (xy 10.593539 -61.501415) (xy 10.657772 -61.532349)
			(xy 10.718139 -61.57028) (xy 10.773879 -61.614731) (xy 10.824291 -61.665143) (xy 10.868742 -61.720883)
			(xy 10.906673 -61.78125) (xy 10.937607 -61.845483) (xy 10.961154 -61.912777) (xy 10.977018 -61.982283)
			(xy 10.977483 -61.986414) (xy 22.071328 -61.986414) (xy 22.075399 -61.930792) (xy 22.087525 -61.876355)
			(xy 22.107448 -61.824264) (xy 22.134744 -61.775629) (xy 22.16883 -61.731486) (xy 22.208979 -61.692777)
			(xy 22.254337 -61.660326) (xy 22.303937 -61.634825) (xy 22.356721 -61.616818) (xy 22.411564 -61.606688)
			(xy 22.467298 -61.604651) (xy 22.522735 -61.610751) (xy 22.576692 -61.624857) (xy 22.628021 -61.646669)
			(xy 22.675627 -61.675723) (xy 22.718495 -61.711398) (xy 22.755712 -61.752935) (xy 22.786485 -61.799448)
			(xy 22.810157 -61.849945) (xy 22.826225 -61.903352) (xy 22.834345 -61.958528) (xy 22.834854 -61.986414)
			(xy 22.834345 -62.0143) (xy 22.826225 -62.069476) (xy 22.810157 -62.122883) (xy 22.786485 -62.17338)
			(xy 22.755712 -62.219893) (xy 22.718495 -62.26143) (xy 22.675627 -62.297105) (xy 22.628021 -62.326159)
			(xy 22.576692 -62.347971) (xy 22.522735 -62.362077) (xy 22.467298 -62.368177) (xy 22.411564 -62.36614)
			(xy 22.356721 -62.35601) (xy 22.303937 -62.338003) (xy 22.254337 -62.312502) (xy 22.208979 -62.280051)
			(xy 22.16883 -62.241342) (xy 22.134744 -62.197199) (xy 22.107448 -62.148564) (xy 22.087525 -62.096473)
			(xy 22.075399 -62.042036) (xy 22.071328 -61.986414) (xy 10.977483 -61.986414) (xy 10.985 -62.053129)
			(xy 10.9855 -62.088776) (xy 10.9855 -63.311786) (xy 21.583648 -63.311786) (xy 21.587719 -63.256164)
			(xy 21.599845 -63.201727) (xy 21.619768 -63.149636) (xy 21.647064 -63.101001) (xy 21.68115 -63.056858)
			(xy 21.721299 -63.018149) (xy 21.766657 -62.985698) (xy 21.816257 -62.960197) (xy 21.869041 -62.94219)
			(xy 21.923884 -62.93206) (xy 21.979618 -62.930023) (xy 22.035055 -62.936123) (xy 22.089012 -62.950229)
			(xy 22.140341 -62.972041) (xy 22.187947 -63.001095) (xy 22.230815 -63.03677) (xy 22.268032 -63.078307)
			(xy 22.298805 -63.12482) (xy 22.322477 -63.175317) (xy 22.338545 -63.228724) (xy 22.346665 -63.2839)
			(xy 22.347174 -63.311786) (xy 22.346665 -63.339672) (xy 22.338545 -63.394848) (xy 22.322477 -63.448255)
			(xy 22.298805 -63.498752) (xy 22.268032 -63.545265) (xy 22.230815 -63.586802) (xy 22.187947 -63.622477)
			(xy 22.140341 -63.651531) (xy 22.089012 -63.673343) (xy 22.035055 -63.687449) (xy 21.979618 -63.693549)
			(xy 21.923884 -63.691512) (xy 21.869041 -63.681382) (xy 21.816257 -63.663375) (xy 21.766657 -63.637874)
			(xy 21.721299 -63.605423) (xy 21.68115 -63.566714) (xy 21.647064 -63.522571) (xy 21.619768 -63.473936)
			(xy 21.599845 -63.421845) (xy 21.587719 -63.367408) (xy 21.583648 -63.311786) (xy 10.9855 -63.311786)
			(xy 10.9855 -64.501776) (xy 10.985 -64.537423) (xy 10.977018 -64.608269) (xy 10.961154 -64.677775)
			(xy 10.937607 -64.745069) (xy 10.906673 -64.809302) (xy 10.868742 -64.869669) (xy 10.824291 -64.925409)
			(xy 10.773879 -64.975821) (xy 10.718139 -65.020272) (xy 10.657772 -65.058203) (xy 10.593539 -65.089137)
			(xy 10.526245 -65.112684) (xy 10.456739 -65.128548) (xy 10.385893 -65.13653) (xy 10.314599 -65.13653)
			(xy 10.243753 -65.128548) (xy 10.174247 -65.112684) (xy 10.106953 -65.089137) (xy 10.04272 -65.058203)
			(xy 9.982353 -65.020272) (xy 9.926613 -64.975821) (xy 9.876201 -64.925409) (xy 9.83175 -64.869669)
			(xy 9.793819 -64.809302) (xy 9.762885 -64.745069) (xy 9.739338 -64.677775) (xy 9.723474 -64.608269)
			(xy 9.715492 -64.537423) (xy 9.714992 -64.501776) (xy 9.271 -64.501776) (xy 9.271 -65.290446) (xy 13.34973 -65.290446)
			(xy 13.353801 -65.234824) (xy 13.365927 -65.180387) (xy 13.38585 -65.128296) (xy 13.413146 -65.079661)
			(xy 13.447232 -65.035518) (xy 13.487381 -64.996809) (xy 13.532739 -64.964358) (xy 13.582339 -64.938857)
			(xy 13.635123 -64.92085) (xy 13.689966 -64.91072) (xy 13.7457 -64.908683) (xy 13.801137 -64.914783)
			(xy 13.855094 -64.928889) (xy 13.906423 -64.950701) (xy 13.954029 -64.979755) (xy 13.996897 -65.01543)
			(xy 14.034114 -65.056967) (xy 14.064887 -65.10348) (xy 14.088559 -65.153977) (xy 14.104627 -65.207384)
			(xy 14.112747 -65.26256) (xy 14.113256 -65.290446) (xy 14.112747 -65.318332) (xy 14.104627 -65.373508)
			(xy 14.088559 -65.426915) (xy 14.068034 -65.470699) (xy 20.234185 -65.470699) (xy 20.236623 -65.415708)
			(xy 20.24694 -65.361639) (xy 20.264921 -65.309615) (xy 20.290193 -65.260714) (xy 20.322231 -65.215954)
			(xy 20.36037 -65.176264) (xy 20.403818 -65.142467) (xy 20.451672 -65.115267) (xy 20.502939 -65.095226)
			(xy 20.556554 -65.082763) (xy 20.611404 -65.078135) (xy 20.666349 -65.081439) (xy 20.720249 -65.092605)
			(xy 20.771984 -65.111403) (xy 20.82048 -65.137442) (xy 20.864731 -65.170181) (xy 20.903816 -65.20894)
			(xy 20.936924 -65.252914) (xy 20.963368 -65.301191) (xy 20.982599 -65.352767) (xy 20.994216 -65.406571)
			(xy 20.99798 -65.461487) (xy 20.993812 -65.516374) (xy 20.981798 -65.570091) (xy 20.962188 -65.621524)
			(xy 20.935389 -65.669604) (xy 20.901957 -65.713334) (xy 20.88261 -65.732914) (xy 20.866611 -65.749233)
			(xy 20.84018 -65.786511) (xy 20.820841 -65.827914) (xy 20.809216 -65.872108) (xy 20.805681 -65.917668)
			(xy 20.810349 -65.963126) (xy 20.82307 -66.007016) (xy 20.843434 -66.047925) (xy 20.870784 -66.084534)
			(xy 20.887182 -66.100452) (xy 20.906997 -66.11956) (xy 20.941474 -66.16247) (xy 20.969425 -66.209891)
			(xy 20.99027 -66.260836) (xy 21.003577 -66.314249) (xy 21.009068 -66.369019) (xy 21.00663 -66.42401)
			(xy 20.996313 -66.47808) (xy 20.978332 -66.530105) (xy 20.95306 -66.579006) (xy 20.921022 -66.623767)
			(xy 20.882882 -66.663458) (xy 20.839434 -66.697255) (xy 20.79158 -66.724456) (xy 20.740312 -66.744496)
			(xy 20.686697 -66.75696) (xy 20.631846 -66.761588) (xy 20.576901 -66.758284) (xy 20.523 -66.747117)
			(xy 20.471264 -66.728319) (xy 20.422767 -66.70228) (xy 20.378517 -66.669541) (xy 20.339432 -66.630781)
			(xy 20.306323 -66.586806) (xy 20.279879 -66.538529) (xy 20.260648 -66.486952) (xy 20.24903 -66.433147)
			(xy 20.245267 -66.378231) (xy 20.249436 -66.323344) (xy 20.26145 -66.269626) (xy 20.281061 -66.218192)
			(xy 20.30786 -66.170112) (xy 20.341292 -66.126382) (xy 20.36064 -66.106802) (xy 20.37662 -66.090466)
			(xy 20.403046 -66.05319) (xy 20.422382 -66.011789) (xy 20.434005 -65.9676) (xy 20.437542 -65.922044)
			(xy 20.432877 -65.876589) (xy 20.420161 -65.832701) (xy 20.399804 -65.791793) (xy 20.372462 -65.755184)
			(xy 20.356068 -65.739264) (xy 20.336254 -65.720156) (xy 20.301777 -65.677246) (xy 20.273827 -65.629826)
			(xy 20.252982 -65.578881) (xy 20.239676 -65.525469) (xy 20.234185 -65.470699) (xy 14.068034 -65.470699)
			(xy 14.064887 -65.477412) (xy 14.034114 -65.523925) (xy 13.996897 -65.565462) (xy 13.954029 -65.601137)
			(xy 13.906423 -65.630191) (xy 13.855094 -65.652003) (xy 13.801137 -65.666109) (xy 13.7457 -65.672209)
			(xy 13.689966 -65.670172) (xy 13.635123 -65.660042) (xy 13.582339 -65.642035) (xy 13.532739 -65.616534)
			(xy 13.487381 -65.584083) (xy 13.447232 -65.545374) (xy 13.413146 -65.501231) (xy 13.38585 -65.452596)
			(xy 13.365927 -65.400505) (xy 13.353801 -65.346068) (xy 13.34973 -65.290446) (xy 9.271 -65.290446)
			(xy 9.271 -66.246756) (xy 19.236688 -66.246756) (xy 19.240759 -66.191134) (xy 19.252885 -66.136697)
			(xy 19.272808 -66.084606) (xy 19.300104 -66.035971) (xy 19.33419 -65.991828) (xy 19.374339 -65.953119)
			(xy 19.419697 -65.920668) (xy 19.469297 -65.895167) (xy 19.522081 -65.87716) (xy 19.576924 -65.86703)
			(xy 19.632658 -65.864993) (xy 19.688095 -65.871093) (xy 19.742052 -65.885199) (xy 19.793381 -65.907011)
			(xy 19.840987 -65.936065) (xy 19.883855 -65.97174) (xy 19.921072 -66.013277) (xy 19.951845 -66.05979)
			(xy 19.975517 -66.110287) (xy 19.991585 -66.163694) (xy 19.999705 -66.21887) (xy 20.000214 -66.246756)
			(xy 19.999705 -66.274642) (xy 19.991585 -66.329818) (xy 19.975517 -66.383225) (xy 19.951845 -66.433722)
			(xy 19.921072 -66.480235) (xy 19.883855 -66.521772) (xy 19.840987 -66.557447) (xy 19.793381 -66.586501)
			(xy 19.742052 -66.608313) (xy 19.688095 -66.622419) (xy 19.632658 -66.628519) (xy 19.576924 -66.626482)
			(xy 19.522081 -66.616352) (xy 19.469297 -66.598345) (xy 19.419697 -66.572844) (xy 19.374339 -66.540393)
			(xy 19.33419 -66.501684) (xy 19.300104 -66.457541) (xy 19.272808 -66.408906) (xy 19.252885 -66.356815)
			(xy 19.240759 -66.302378) (xy 19.236688 -66.246756) (xy 9.271 -66.246756) (xy 9.271 -67.965066) (xy 19.822158 -67.965066)
			(xy 19.826229 -67.909444) (xy 19.838355 -67.855007) (xy 19.858278 -67.802916) (xy 19.885574 -67.754281)
			(xy 19.91966 -67.710138) (xy 19.959809 -67.671429) (xy 20.005167 -67.638978) (xy 20.054767 -67.613477)
			(xy 20.107551 -67.59547) (xy 20.162394 -67.58534) (xy 20.218128 -67.583303) (xy 20.273565 -67.589403)
			(xy 20.327522 -67.603509) (xy 20.378851 -67.625321) (xy 20.426457 -67.654375) (xy 20.469325 -67.69005)
			(xy 20.506542 -67.731587) (xy 20.537315 -67.7781) (xy 20.560987 -67.828597) (xy 20.577055 -67.882004)
			(xy 20.585175 -67.93718) (xy 20.585684 -67.965066) (xy 20.585175 -67.992952) (xy 20.577055 -68.048128)
			(xy 20.560987 -68.101535) (xy 20.537315 -68.152032) (xy 20.506542 -68.198545) (xy 20.469325 -68.240082)
			(xy 20.426457 -68.275757) (xy 20.378851 -68.304811) (xy 20.327522 -68.326623) (xy 20.273565 -68.340729)
			(xy 20.218128 -68.346829) (xy 20.162394 -68.344792) (xy 20.107551 -68.334662) (xy 20.054767 -68.316655)
			(xy 20.005167 -68.291154) (xy 19.959809 -68.258703) (xy 19.91966 -68.219994) (xy 19.885574 -68.175851)
			(xy 19.858278 -68.127216) (xy 19.838355 -68.075125) (xy 19.826229 -68.020688) (xy 19.822158 -67.965066)
			(xy 9.271 -67.965066) (xy 9.271 -69.42328) (xy 11.942826 -72.095106) (xy 19.2786 -72.095106)
		)
		(stroke
			(width 0)
			(type solid)
		)
		(fill yes)
		(layer "In7.Cu")
		(net "P5V_CRT")
	)
	(gr_poly
		(pts
			(xy 148.250656 -82.566256) (xy 148.273955 -82.564669) (xy 148.319432 -82.554072) (xy 148.362212 -82.535357)
			(xy 148.400859 -82.50915) (xy 148.434077 -82.476332) (xy 148.46075 -82.438005) (xy 148.479982 -82.395455)
			(xy 148.491128 -82.35011) (xy 148.493815 -82.303493) (xy 148.487951 -82.257167) (xy 148.481288 -82.234786)
			(xy 148.476361 -82.22066) (xy 148.468476 -82.191798) (xy 148.46554 -82.177128) (xy 148.463762 -82.16773)
			(xy 148.458723 -82.145621) (xy 148.441883 -82.103524) (xy 148.417839 -82.065085) (xy 148.387354 -82.031523)
			(xy 148.351396 -82.003904) (xy 148.311108 -81.983106) (xy 148.267767 -81.969789) (xy 148.245322 -81.966562)
			(xy 148.217108 -81.96427) (xy 148.161761 -81.952408) (xy 148.108774 -81.932501) (xy 148.059308 -81.904985)
			(xy 148.014449 -81.870464) (xy 147.975182 -81.829696) (xy 147.942367 -81.783574) (xy 147.916725 -81.733112)
			(xy 147.898818 -81.679415) (xy 147.889039 -81.623663) (xy 147.887603 -81.567077) (xy 147.894541 -81.5109)
			(xy 147.909701 -81.456364) (xy 147.93275 -81.404666) (xy 147.963183 -81.356939) (xy 148.000331 -81.314231)
			(xy 148.021548 -81.295494) (xy 148.043391 -81.277525) (xy 148.091362 -81.247561) (xy 148.143232 -81.225013)
			(xy 148.197865 -81.210375) (xy 148.25406 -81.203967) (xy 148.310586 -81.205931) (xy 148.366201 -81.216224)
			(xy 148.419685 -81.234619) (xy 148.469866 -81.260713) (xy 148.515641 -81.293934) (xy 148.556007 -81.333552)
			(xy 148.590077 -81.378698) (xy 148.617105 -81.428382) (xy 148.627338 -81.454752) (xy 148.633208 -81.471315)
			(xy 148.642236 -81.505279) (xy 148.645372 -81.52257) (xy 148.65041 -81.544681) (xy 148.667248 -81.586783)
			(xy 148.69129 -81.625229) (xy 148.721773 -81.658799) (xy 148.757729 -81.686426) (xy 148.798017 -81.707234)
			(xy 148.841358 -81.720562) (xy 148.863812 -81.723738) (xy 148.890815 -81.725908) (xy 148.943856 -81.736914)
			(xy 148.994808 -81.75531) (xy 149.042646 -81.780726) (xy 149.086409 -81.812653) (xy 149.125217 -81.850447)
			(xy 149.158291 -81.893349) (xy 149.184966 -81.940497) (xy 149.195282 -81.965546) (xy 149.204851 -81.991363)
			(xy 149.217313 -82.044993) (xy 149.221943 -82.099856) (xy 149.218647 -82.154816) (xy 149.207491 -82.208732)
			(xy 149.198584 -82.234786) (xy 149.19193 -82.257185) (xy 149.185985 -82.303527) (xy 149.188613 -82.350175)
			(xy 149.199724 -82.395556) (xy 149.218945 -82.43814) (xy 149.245628 -82.476493) (xy 149.278872 -82.509322)
			(xy 149.317558 -82.535519) (xy 149.360382 -82.554202) (xy 149.405899 -82.56474) (xy 149.429216 -82.566256)
			(xy 149.520656 -82.566256) (xy 149.543955 -82.564669) (xy 149.589432 -82.554072) (xy 149.632212 -82.535357)
			(xy 149.670859 -82.50915) (xy 149.704077 -82.476332) (xy 149.73075 -82.438005) (xy 149.749982 -82.395455)
			(xy 149.761128 -82.35011) (xy 149.763815 -82.303493) (xy 149.757951 -82.257167) (xy 149.751288 -82.234786)
			(xy 149.74247 -82.209118) (xy 149.731352 -82.155995) (xy 149.727873 -82.101834) (xy 149.732103 -82.047726)
			(xy 149.743957 -81.994763) (xy 149.763196 -81.944014) (xy 149.789431 -81.896503) (xy 149.822134 -81.853189)
			(xy 149.860643 -81.814946) (xy 149.904183 -81.782544) (xy 149.951875 -81.756639) (xy 150.002756 -81.737753)
			(xy 150.0558 -81.726266) (xy 150.109936 -81.722412) (xy 150.164072 -81.726266) (xy 150.217116 -81.737753)
			(xy 150.267997 -81.756639) (xy 150.315689 -81.782544) (xy 150.359229 -81.814946) (xy 150.397738 -81.853189)
			(xy 150.430441 -81.896503) (xy 150.456676 -81.944014) (xy 150.475915 -81.994763) (xy 150.487769 -82.047726)
			(xy 150.491999 -82.101834) (xy 150.48852 -82.155995) (xy 150.477402 -82.209118) (xy 150.468584 -82.234786)
			(xy 150.46193 -82.257185) (xy 150.455985 -82.303527) (xy 150.458613 -82.350175) (xy 150.469724 -82.395556)
			(xy 150.488945 -82.43814) (xy 150.515628 -82.476493) (xy 150.548872 -82.509322) (xy 150.587558 -82.535519)
			(xy 150.630382 -82.554202) (xy 150.675899 -82.56474) (xy 150.699216 -82.566256) (xy 152.663144 -82.566256)
			(xy 152.67813 -82.562446) (xy 152.70777 -82.555843) (xy 152.7683 -82.55102) (xy 152.82883 -82.555843)
			(xy 152.85847 -82.562446) (xy 152.873456 -82.566256) (xy 154.88539 -82.566256) (xy 154.902073 -82.565757)
			(xy 154.934297 -82.5571) (xy 154.963169 -82.540376) (xy 154.975306 -82.528918) (xy 157.513274 -79.990696)
			(xy 157.513274 -76.961238) (xy 158.23819 -76.236322) (xy 160.087056 -76.236322) (xy 160.174686 -76.2)
			(xy 160.190942 -76.185776) (xy 160.212016 -76.167682) (xy 160.258416 -76.137151) (xy 160.308752 -76.11367)
			(xy 160.36196 -76.097735) (xy 160.416916 -76.089682) (xy 160.47246 -76.089682) (xy 160.527416 -76.097735)
			(xy 160.580624 -76.11367) (xy 160.63096 -76.137151) (xy 160.67736 -76.167682) (xy 160.698434 -76.185776)
			(xy 160.71469 -76.2) (xy 160.80232 -76.236322) (xy 163.75253 -76.236322) (xy 164.96538 -77.449172)
			(xy 164.96538 -77.585062) (xy 164.990627 -77.610309) (xy 170.084906 -77.610309) (xy 170.089777 -77.555828)
			(xy 170.102377 -77.502601) (xy 170.12245 -77.451719) (xy 170.149582 -77.404225) (xy 170.16603 -77.38237)
			(xy 170.18016 -77.363458) (xy 170.201791 -77.321498) (xy 170.215297 -77.276264) (xy 170.220214 -77.229314)
			(xy 170.216374 -77.182263) (xy 170.203907 -77.136732) (xy 170.183243 -77.094288) (xy 170.169586 -77.07503)
			(xy 170.153617 -77.052825) (xy 170.127644 -77.004688) (xy 170.108811 -76.953336) (xy 170.097503 -76.899821)
			(xy 170.093954 -76.84524) (xy 170.098235 -76.790711) (xy 170.110258 -76.737352) (xy 170.129778 -76.686257)
			(xy 170.156394 -76.638473) (xy 170.18956 -76.59498) (xy 170.228597 -76.556668) (xy 170.272706 -76.524323)
			(xy 170.320981 -76.498608) (xy 170.372433 -76.48005) (xy 170.426008 -76.46903) (xy 170.480607 -76.465773)
			(xy 170.535112 -76.470346) (xy 170.588406 -76.482655) (xy 170.639395 -76.502448) (xy 170.687036 -76.52932)
			(xy 170.730351 -76.562719) (xy 170.768453 -76.601961) (xy 170.800562 -76.646242) (xy 170.826017 -76.694654)
			(xy 170.844299 -76.746205) (xy 170.855032 -76.799838) (xy 170.857997 -76.854454) (xy 170.853132 -76.908934)
			(xy 170.840538 -76.96216) (xy 170.820471 -77.013043) (xy 170.793345 -77.060539) (xy 170.7769 -77.082396)
			(xy 170.7628 -77.101331) (xy 170.741165 -77.143284) (xy 170.727653 -77.188513) (xy 170.722731 -77.235459)
			(xy 170.726567 -77.282507) (xy 170.739029 -77.328036) (xy 170.759689 -77.370478) (xy 170.773344 -77.389736)
			(xy 170.789276 -77.41197) (xy 170.815251 -77.460107) (xy 170.834085 -77.51146) (xy 170.845393 -77.564976)
			(xy 170.848944 -77.619559) (xy 170.844663 -77.674089) (xy 170.832639 -77.727449) (xy 170.813118 -77.778545)
			(xy 170.786501 -77.82633) (xy 170.753333 -77.869824) (xy 170.714294 -77.908136) (xy 170.670184 -77.94048)
			(xy 170.621907 -77.966194) (xy 170.570453 -77.984751) (xy 170.516876 -77.995769) (xy 170.462275 -77.999024)
			(xy 170.407769 -77.994448) (xy 170.354475 -77.982136) (xy 170.303485 -77.962339) (xy 170.255845 -77.935464)
			(xy 170.212531 -77.902061) (xy 170.17443 -77.862815) (xy 170.142325 -77.818531) (xy 170.116872 -77.770116)
			(xy 170.098594 -77.718562) (xy 170.087866 -77.664927) (xy 170.084906 -77.610309) (xy 164.990627 -77.610309)
			(xy 166.0652 -78.684882) (xy 170.909742 -78.684882) (xy 172.09262 -77.502004) (xy 172.09262 -73.916286)
			(xy 162.430968 -64.254634) (xy 161.014918 -64.254634) (xy 157.236414 -60.47613) (xy 155.429966 -60.47613)
			(xy 155.375102 -60.504578) (xy 155.357068 -60.529978) (xy 155.357068 -60.530232) (xy 155.339578 -60.554021)
			(xy 155.298484 -60.596417) (xy 155.251357 -60.631986) (xy 155.199318 -60.659881) (xy 155.171648 -60.670186)
			(xy 155.150264 -60.678886) (xy 155.110814 -60.702859) (xy 155.076338 -60.733556) (xy 155.047967 -60.769971)
			(xy 155.026633 -60.810907) (xy 155.013035 -60.855022) (xy 155.007622 -60.900865) (xy 155.00858 -60.923932)
			(xy 155.010104 -60.95111) (xy 155.010264 -60.967488) (xy 155.008104 -61.000174) (xy 155.005786 -61.016388)
			(xy 155.001183 -61.043467) (xy 154.985219 -61.096024) (xy 154.961883 -61.145748) (xy 154.931659 -61.191611)
			(xy 154.895169 -61.232666) (xy 154.853169 -61.268065) (xy 154.806528 -61.297074) (xy 154.756208 -61.319095)
			(xy 154.70325 -61.333673) (xy 154.64875 -61.340506) (xy 154.593832 -61.339452) (xy 154.539634 -61.330534)
			(xy 154.487274 -61.313936) (xy 154.437836 -61.290001) (xy 154.392341 -61.259224) (xy 154.35173 -61.222241)
			(xy 154.333956 -61.2013) (xy 154.315522 -61.17798) (xy 154.285349 -61.126766) (xy 154.263475 -61.071496)
			(xy 154.250429 -61.013504) (xy 154.246525 -60.954192) (xy 154.251857 -60.89499) (xy 154.258518 -60.86602)
			(xy 154.261921 -60.853011) (xy 154.270314 -60.827461) (xy 154.275282 -60.814966) (xy 154.282217 -60.793977)
			(xy 154.289555 -60.750392) (xy 154.28924 -60.706194) (xy 154.281282 -60.662717) (xy 154.26592 -60.621273)
			(xy 154.243619 -60.583113) (xy 154.215051 -60.549387) (xy 154.181079 -60.521113) (xy 154.142726 -60.499144)
			(xy 154.10115 -60.484143) (xy 154.057606 -60.476562) (xy 154.035506 -60.47613) (xy 154.034998 -60.47613)
			(xy 154.020086 -60.476539) (xy 153.991076 -60.483466) (xy 153.964469 -60.496941) (xy 153.941719 -60.516227)
			(xy 153.92407 -60.54027) (xy 153.917904 -60.553854) (xy 153.874978 -60.65647) (xy 153.901394 -60.74156)
			(xy 153.910284 -60.755784) (xy 153.924716 -60.779667) (xy 153.9472 -60.830738) (xy 153.962003 -60.88454)
			(xy 153.968809 -60.939925) (xy 153.967474 -60.99571) (xy 153.958025 -61.050705) (xy 153.940664 -61.103737)
			(xy 153.915762 -61.153673) (xy 153.88385 -61.199449) (xy 153.845609 -61.240087) (xy 153.801856 -61.274719)
			(xy 153.753523 -61.302607) (xy 153.701643 -61.323155) (xy 153.647323 -61.335926) (xy 153.591722 -61.340646)
			(xy 153.536026 -61.337214) (xy 153.481425 -61.325705) (xy 153.429083 -61.306363) (xy 153.404316 -61.293502)
			(xy 153.375363 -61.276923) (xy 153.323244 -61.235278) (xy 153.300684 -61.210698) (xy 153.284428 -61.190886)
			(xy 153.270953 -61.173994) (xy 153.239264 -61.14462) (xy 153.203061 -61.121034) (xy 153.163388 -61.103914)
			(xy 153.121391 -61.093756) (xy 153.07828 -61.090852) (xy 153.035299 -61.095286) (xy 152.993689 -61.10693)
			(xy 152.95465 -61.125448) (xy 152.919308 -61.150306) (xy 152.903682 -61.165232) (xy 152.883854 -61.186158)
			(xy 152.839015 -61.222386) (xy 152.789236 -61.251457) (xy 152.73565 -61.272708) (xy 152.679477 -61.285655)
			(xy 152.621996 -61.290003) (xy 152.564515 -61.285655) (xy 152.508342 -61.272708) (xy 152.454756 -61.251457)
			(xy 152.404977 -61.222386) (xy 152.360138 -61.186158) (xy 152.34031 -61.165232) (xy 152.324685 -61.15031)
			(xy 152.289336 -61.125471) (xy 152.250295 -61.106968) (xy 152.208687 -61.095335) (xy 152.165711 -61.090906)
			(xy 152.122606 -61.093809) (xy 152.080612 -61.10396) (xy 152.04094 -61.121068) (xy 152.004732 -61.144638)
			(xy 151.973033 -61.173992) (xy 151.959564 -61.190886) (xy 151.952301 -61.200186) (xy 151.936794 -61.217977)
			(xy 151.928576 -61.226446) (xy 151.908964 -61.245684) (xy 151.865204 -61.278896) (xy 151.81713 -61.305483)
			(xy 151.765738 -61.324894) (xy 151.712091 -61.336728) (xy 151.657302 -61.340738) (xy 151.629872 -61.339222)
			(xy 151.60324 -61.336911) (xy 151.550957 -61.325769) (xy 151.500746 -61.307428) (xy 151.453591 -61.282248)
			(xy 151.431752 -61.266832) (xy 151.412278 -61.254149) (xy 151.369786 -61.235342) (xy 151.324583 -61.224578)
			(xy 151.278175 -61.222215) (xy 151.232112 -61.228334) (xy 151.18793 -61.242729) (xy 151.147104 -61.264921)
			(xy 151.110995 -61.294168) (xy 151.080809 -61.329496) (xy 151.068786 -61.349382) (xy 151.054665 -61.372787)
			(xy 151.020769 -61.41567) (xy 150.981104 -61.45328) (xy 150.93648 -61.484848) (xy 150.887809 -61.509728)
			(xy 150.836087 -61.527412) (xy 150.782372 -61.537537) (xy 150.727761 -61.539898) (xy 150.673373 -61.534446)
			(xy 150.620318 -61.521291) (xy 150.594822 -61.511434) (xy 150.568805 -61.500284) (xy 150.520112 -61.471427)
			(xy 150.476217 -61.435692) (xy 150.438084 -61.393863) (xy 150.40655 -61.34686) (xy 150.382306 -61.295713)
			(xy 150.365885 -61.241546) (xy 150.357648 -61.185547) (xy 150.357774 -61.128946) (xy 150.366263 -61.072984)
			(xy 150.382926 -61.018891) (xy 150.407399 -60.967853) (xy 150.439144 -60.920992) (xy 150.477464 -60.879335)
			(xy 150.521518 -60.843797) (xy 150.57034 -60.815158) (xy 150.622857 -60.794047) (xy 150.677917 -60.780927)
			(xy 150.734312 -60.776086) (xy 150.790802 -60.77963) (xy 150.818596 -60.784994) (xy 150.844595 -60.79107)
			(xy 150.894716 -60.809467) (xy 150.94179 -60.834659) (xy 150.96363 -60.850018) (xy 150.983101 -60.862694)
			(xy 151.025586 -60.881489) (xy 151.070781 -60.892242) (xy 151.117178 -60.894594) (xy 151.163229 -60.888466)
			(xy 151.207397 -60.874064) (xy 151.248207 -60.851866) (xy 151.284298 -60.822615) (xy 151.314466 -60.787286)
			(xy 151.326596 -60.767468) (xy 151.34209 -60.74283) (xy 151.351996 -60.728352) (xy 151.363426 -60.694824)
			(xy 151.368236 -60.678868) (xy 151.370353 -60.645622) (xy 151.363796 -60.61296) (xy 151.349011 -60.583108)
			(xy 151.327005 -60.558098) (xy 151.299277 -60.539634) (xy 151.28367 -60.533788) (xy 151.259794 -60.52566)
			(xy 151.247063 -60.526785) (xy 151.221515 -60.527545) (xy 151.20874 -60.527184) (xy 151.182735 -60.52564)
			(xy 151.131479 -60.516328) (xy 151.081971 -60.500118) (xy 151.058372 -60.489084) (xy 151.031956 -60.47613)
			(xy 150.34006 -60.47613) (xy 149.687534 -59.823604) (xy 141.92631 -59.823604) (xy 140.659358 -61.090556)
			(xy 138.92276 -61.090556) (xy 138.920474 -61.092842) (xy 136.905238 -61.092842) (xy 136.881932 -61.093345)
			(xy 136.836093 -61.1018) (xy 136.792564 -61.11847) (xy 136.752803 -61.142796) (xy 136.718144 -61.173964)
			(xy 136.689747 -61.210928) (xy 136.668566 -61.252449) (xy 136.655309 -61.297136) (xy 136.650421 -61.343491)
			(xy 136.654066 -61.38996) (xy 136.666121 -61.434986) (xy 136.686183 -61.47706) (xy 136.699498 -61.496194)
			(xy 136.715528 -61.519112) (xy 136.74142 -61.568684) (xy 136.759794 -61.621507) (xy 136.770256 -61.676447)
			(xy 136.772582 -61.732325) (xy 136.766721 -61.787944) (xy 136.752799 -61.842111) (xy 136.731116 -61.893663)
			(xy 136.702135 -61.941496) (xy 136.674906 -61.974399) (xy 139.328549 -61.974399) (xy 139.330195 -61.918979)
			(xy 139.339846 -61.864382) (xy 139.357299 -61.811756) (xy 139.382185 -61.762211) (xy 139.413982 -61.716791)
			(xy 139.452019 -61.676452) (xy 139.495495 -61.642044) (xy 139.543493 -61.614291) (xy 139.595004 -61.59378)
			(xy 139.648941 -61.58094) (xy 139.704168 -61.576044) (xy 139.759523 -61.579194) (xy 139.813838 -61.590324)
			(xy 139.86597 -61.609199) (xy 139.914821 -61.635422) (xy 139.959362 -61.66844) (xy 139.998653 -61.707558)
			(xy 140.031869 -61.751951) (xy 140.058308 -61.800686) (xy 140.077413 -61.852734) (xy 140.088784 -61.907)
			(xy 140.092179 -61.96234) (xy 140.087527 -62.017588) (xy 140.074927 -62.071582) (xy 140.054644 -62.123182)
			(xy 140.027104 -62.171303) (xy 140.010388 -62.193424) (xy 139.997392 -62.210729) (xy 139.976835 -62.248809)
			(xy 139.963029 -62.289821) (xy 139.956372 -62.33258) (xy 139.957057 -62.375848) (xy 139.965064 -62.418375)
			(xy 139.980162 -62.458929) (xy 140.001914 -62.496339) (xy 140.015468 -62.51321) (xy 140.032937 -62.534752)
			(xy 140.062004 -62.581988) (xy 140.083927 -62.632934) (xy 140.091165 -62.660022) (xy 143.045686 -62.660022)
			(xy 143.049757 -62.6044) (xy 143.061883 -62.549963) (xy 143.081806 -62.497872) (xy 143.109102 -62.449237)
			(xy 143.143188 -62.405094) (xy 143.183337 -62.366385) (xy 143.228695 -62.333934) (xy 143.278295 -62.308433)
			(xy 143.331079 -62.290426) (xy 143.385922 -62.280296) (xy 143.441656 -62.278259) (xy 143.497093 -62.284359)
			(xy 143.55105 -62.298465) (xy 143.602379 -62.320277) (xy 143.649985 -62.349331) (xy 143.692853 -62.385006)
			(xy 143.73007 -62.426543) (xy 143.760843 -62.473056) (xy 143.784515 -62.523553) (xy 143.800583 -62.57696)
			(xy 143.808703 -62.632136) (xy 143.809212 -62.660022) (xy 144.798286 -62.660022) (xy 144.802357 -62.6044)
			(xy 144.814483 -62.549963) (xy 144.834406 -62.497872) (xy 144.861702 -62.449237) (xy 144.895788 -62.405094)
			(xy 144.935937 -62.366385) (xy 144.981295 -62.333934) (xy 145.030895 -62.308433) (xy 145.083679 -62.290426)
			(xy 145.138522 -62.280296) (xy 145.194256 -62.278259) (xy 145.249693 -62.284359) (xy 145.30365 -62.298465)
			(xy 145.354979 -62.320277) (xy 145.402585 -62.349331) (xy 145.445453 -62.385006) (xy 145.48267 -62.426543)
			(xy 145.513443 -62.473056) (xy 145.537115 -62.523553) (xy 145.553183 -62.57696) (xy 145.561303 -62.632136)
			(xy 145.561812 -62.660022) (xy 146.449286 -62.660022) (xy 146.453357 -62.6044) (xy 146.465483 -62.549963)
			(xy 146.485406 -62.497872) (xy 146.512702 -62.449237) (xy 146.546788 -62.405094) (xy 146.586937 -62.366385)
			(xy 146.632295 -62.333934) (xy 146.681895 -62.308433) (xy 146.734679 -62.290426) (xy 146.789522 -62.280296)
			(xy 146.845256 -62.278259) (xy 146.900693 -62.284359) (xy 146.95465 -62.298465) (xy 147.005979 -62.320277)
			(xy 147.053585 -62.349331) (xy 147.096453 -62.385006) (xy 147.13367 -62.426543) (xy 147.164443 -62.473056)
			(xy 147.188115 -62.523553) (xy 147.204183 -62.57696) (xy 147.212303 -62.632136) (xy 147.212812 -62.660022)
			(xy 147.212303 -62.687908) (xy 147.204319 -62.74216) (xy 150.204447 -62.74216) (xy 150.210774 -62.68708)
			(xy 150.225008 -62.633495) (xy 150.24685 -62.582536) (xy 150.275838 -62.535275) (xy 150.311362 -62.492709)
			(xy 150.352674 -62.455733) (xy 150.398904 -62.425127) (xy 150.449077 -62.401536) (xy 150.502136 -62.385456)
			(xy 150.556965 -62.377227) (xy 150.612407 -62.377021) (xy 150.667295 -62.384843) (xy 150.720473 -62.400529)
			(xy 150.77082 -62.423747) (xy 150.817275 -62.454009) (xy 150.85886 -62.490677) (xy 150.8947 -62.532978)
			(xy 150.924038 -62.580023) (xy 150.946257 -62.630818) (xy 150.960888 -62.684296) (xy 150.967625 -62.739327)
			(xy 150.966323 -62.794755) (xy 150.957012 -62.84941) (xy 150.939887 -62.902142) (xy 150.915309 -62.951839)
			(xy 150.883796 -62.997455) (xy 150.846011 -63.038028) (xy 150.824692 -63.055754) (xy 150.80717 -63.07042)
			(xy 150.777211 -63.104917) (xy 150.753902 -63.144213) (xy 150.737993 -63.187044) (xy 150.729998 -63.232029)
			(xy 150.730173 -63.277718) (xy 150.738514 -63.32264) (xy 150.754751 -63.365348) (xy 150.778361 -63.404464)
			(xy 150.808584 -63.43873) (xy 150.819745 -63.44793) (xy 151.198578 -63.44793) (xy 151.202649 -63.392308)
			(xy 151.214775 -63.337871) (xy 151.234698 -63.28578) (xy 151.261994 -63.237145) (xy 151.29608 -63.193002)
			(xy 151.336229 -63.154293) (xy 151.381587 -63.121842) (xy 151.431187 -63.096341) (xy 151.483971 -63.078334)
			(xy 151.538814 -63.068204) (xy 151.594548 -63.066167) (xy 151.649985 -63.072267) (xy 151.703942 -63.086373)
			(xy 151.755271 -63.108185) (xy 151.802877 -63.137239) (xy 151.845745 -63.172914) (xy 151.882962 -63.214451)
			(xy 151.913735 -63.260964) (xy 151.937407 -63.311461) (xy 151.953475 -63.364868) (xy 151.961595 -63.420044)
			(xy 151.962104 -63.44793) (xy 151.9616 -63.475548) (xy 152.240944 -63.475548) (xy 152.240948 -63.420206)
			(xy 152.248947 -63.365444) (xy 152.264773 -63.312413) (xy 152.288095 -63.262225) (xy 152.318423 -63.215933)
			(xy 152.355121 -63.174508) (xy 152.397418 -63.138819) (xy 152.444428 -63.109616) (xy 152.495164 -63.087511)
			(xy 152.548561 -63.072967) (xy 152.603499 -63.066291) (xy 152.658825 -63.067622) (xy 152.713379 -63.076931)
			(xy 152.766015 -63.094025) (xy 152.815629 -63.118544) (xy 152.861181 -63.149973) (xy 152.901714 -63.187654)
			(xy 152.91943 -63.208916) (xy 152.934053 -63.226285) (xy 152.96835 -63.256032) (xy 153.007386 -63.279211)
			(xy 153.049919 -63.295087) (xy 153.094596 -63.303153) (xy 153.139996 -63.303153) (xy 153.184673 -63.295087)
			(xy 153.227206 -63.279211) (xy 153.266242 -63.256032) (xy 153.300539 -63.226285) (xy 153.315162 -63.208916)
			(xy 153.332197 -63.188559) (xy 153.370863 -63.152198) (xy 153.414197 -63.121547) (xy 153.46136 -63.097198)
			(xy 153.511443 -63.079622) (xy 153.563479 -63.069156) (xy 153.616463 -63.066005) (xy 153.669372 -63.070227)
			(xy 153.721186 -63.081742) (xy 153.770903 -63.100328) (xy 153.817564 -63.125626) (xy 153.860269 -63.157147)
			(xy 153.87955 -63.175388) (xy 153.895499 -63.190343) (xy 153.93153 -63.215103) (xy 153.971268 -63.23333)
			(xy 154.013539 -63.244485) (xy 154.057096 -63.248241) (xy 154.100653 -63.244485) (xy 154.142924 -63.23333)
			(xy 154.182662 -63.215103) (xy 154.218693 -63.190343) (xy 154.234642 -63.175388) (xy 154.254945 -63.156126)
			(xy 154.300217 -63.123223) (xy 154.34981 -63.097286) (xy 154.40266 -63.078872) (xy 154.457633 -63.068377)
			(xy 154.513549 -63.066026) (xy 154.569209 -63.071869) (xy 154.623419 -63.08578) (xy 154.675014 -63.107462)
			(xy 154.722888 -63.136448) (xy 154.766014 -63.172118) (xy 154.803466 -63.213705) (xy 154.834441 -63.260318)
			(xy 154.858275 -63.310955) (xy 154.874454 -63.364531) (xy 154.882633 -63.419896) (xy 154.882636 -63.475862)
			(xy 154.874463 -63.531228) (xy 154.85829 -63.584806) (xy 154.834462 -63.635446) (xy 154.803492 -63.682062)
			(xy 154.766045 -63.723653) (xy 154.722922 -63.759327) (xy 154.675051 -63.788319) (xy 154.623458 -63.810007)
			(xy 154.569251 -63.823924) (xy 154.513591 -63.829773) (xy 154.457675 -63.827428) (xy 154.4027 -63.816939)
			(xy 154.349848 -63.798531) (xy 154.300253 -63.7726) (xy 154.254977 -63.739701) (xy 154.234642 -63.720472)
			(xy 154.218693 -63.705517) (xy 154.182662 -63.680757) (xy 154.142924 -63.66253) (xy 154.100653 -63.651375)
			(xy 154.057096 -63.647619) (xy 154.013539 -63.651375) (xy 153.971268 -63.66253) (xy 153.93153 -63.680757)
			(xy 153.895499 -63.705517) (xy 153.87955 -63.720472) (xy 153.860226 -63.738674) (xy 153.817531 -63.770214)
			(xy 153.770875 -63.79553) (xy 153.721159 -63.814132) (xy 153.669345 -63.825661) (xy 153.616432 -63.829895)
			(xy 153.563443 -63.826752) (xy 153.511402 -63.816292) (xy 153.461314 -63.798717) (xy 153.414147 -63.774367)
			(xy 153.370811 -63.743713) (xy 153.332144 -63.707346) (xy 153.315162 -63.686944) (xy 153.300539 -63.669575)
			(xy 153.266242 -63.639828) (xy 153.227206 -63.616649) (xy 153.184673 -63.600773) (xy 153.139996 -63.592707)
			(xy 153.094596 -63.592707) (xy 153.049919 -63.600773) (xy 153.007386 -63.616649) (xy 152.96835 -63.639828)
			(xy 152.934053 -63.669575) (xy 152.91943 -63.686944) (xy 152.901682 -63.70818) (xy 152.861144 -63.745856)
			(xy 152.815589 -63.77728) (xy 152.765971 -63.801793) (xy 152.713333 -63.81888) (xy 152.658779 -63.828183)
			(xy 152.603452 -63.829507) (xy 152.548515 -63.822824) (xy 152.49512 -63.808274) (xy 152.444387 -63.786162)
			(xy 152.39738 -63.756953) (xy 152.355087 -63.721259) (xy 152.318394 -63.67983) (xy 152.288072 -63.633534)
			(xy 152.264756 -63.583343) (xy 152.248936 -63.53031) (xy 152.240944 -63.475548) (xy 151.9616 -63.475548)
			(xy 151.961595 -63.475816) (xy 151.953475 -63.530992) (xy 151.937407 -63.584399) (xy 151.913735 -63.634896)
			(xy 151.882962 -63.681409) (xy 151.845745 -63.722946) (xy 151.802877 -63.758621) (xy 151.755271 -63.787675)
			(xy 151.703942 -63.809487) (xy 151.649985 -63.823593) (xy 151.594548 -63.829693) (xy 151.538814 -63.827656)
			(xy 151.483971 -63.817526) (xy 151.431187 -63.799519) (xy 151.381587 -63.774018) (xy 151.336229 -63.741567)
			(xy 151.29608 -63.702858) (xy 151.261994 -63.658715) (xy 151.234698 -63.61008) (xy 151.214775 -63.557989)
			(xy 151.202649 -63.503552) (xy 151.198578 -63.44793) (xy 150.819745 -63.44793) (xy 150.826216 -63.453264)
			(xy 150.847631 -63.470874) (xy 150.885712 -63.511167) (xy 150.91756 -63.556547) (xy 150.942503 -63.60606)
			(xy 150.960015 -63.658662) (xy 150.969729 -63.713246) (xy 150.971438 -63.76866) (xy 150.965108 -63.823738)
			(xy 150.950871 -63.87732) (xy 150.929028 -63.928276) (xy 150.900038 -63.975533) (xy 150.864513 -64.018096)
			(xy 150.8232 -64.055069) (xy 150.776971 -64.085671) (xy 150.726798 -64.109259) (xy 150.673739 -64.125335)
			(xy 150.618912 -64.133561) (xy 150.563472 -64.133763) (xy 150.508586 -64.125938) (xy 150.455411 -64.11025)
			(xy 150.405068 -64.08703) (xy 150.358616 -64.056766) (xy 150.317034 -64.020097) (xy 150.281199 -63.977795)
			(xy 150.251864 -63.93075) (xy 150.229649 -63.879955) (xy 150.215021 -63.826479) (xy 150.208289 -63.771448)
			(xy 150.209593 -63.716023) (xy 150.218907 -63.66137) (xy 150.236035 -63.608642) (xy 150.260615 -63.558948)
			(xy 150.29213 -63.513336) (xy 150.329916 -63.472766) (xy 150.351236 -63.455042) (xy 150.36876 -63.440379)
			(xy 150.398716 -63.405881) (xy 150.422022 -63.366583) (xy 150.437929 -63.323752) (xy 150.445923 -63.278768)
			(xy 150.445747 -63.23308) (xy 150.437407 -63.188158) (xy 150.421171 -63.145451) (xy 150.397563 -63.106334)
			(xy 150.367342 -63.072068) (xy 150.349712 -63.057532) (xy 150.328274 -63.039949) (xy 150.290189 -62.999658)
			(xy 150.258338 -62.954277) (xy 150.233392 -62.904764) (xy 150.215876 -62.852161) (xy 150.206159 -62.797576)
			(xy 150.204447 -62.74216) (xy 147.204319 -62.74216) (xy 147.204183 -62.743084) (xy 147.188115 -62.796491)
			(xy 147.164443 -62.846988) (xy 147.13367 -62.893501) (xy 147.096453 -62.935038) (xy 147.053585 -62.970713)
			(xy 147.005979 -62.999767) (xy 146.95465 -63.021579) (xy 146.900693 -63.035685) (xy 146.845256 -63.041785)
			(xy 146.789522 -63.039748) (xy 146.734679 -63.029618) (xy 146.681895 -63.011611) (xy 146.632295 -62.98611)
			(xy 146.586937 -62.953659) (xy 146.546788 -62.91495) (xy 146.512702 -62.870807) (xy 146.485406 -62.822172)
			(xy 146.465483 -62.770081) (xy 146.453357 -62.715644) (xy 146.449286 -62.660022) (xy 145.561812 -62.660022)
			(xy 145.561303 -62.687908) (xy 145.553183 -62.743084) (xy 145.537115 -62.796491) (xy 145.513443 -62.846988)
			(xy 145.48267 -62.893501) (xy 145.445453 -62.935038) (xy 145.402585 -62.970713) (xy 145.354979 -62.999767)
			(xy 145.30365 -63.021579) (xy 145.249693 -63.035685) (xy 145.194256 -63.041785) (xy 145.138522 -63.039748)
			(xy 145.083679 -63.029618) (xy 145.030895 -63.011611) (xy 144.981295 -62.98611) (xy 144.935937 -62.953659)
			(xy 144.895788 -62.91495) (xy 144.861702 -62.870807) (xy 144.834406 -62.822172) (xy 144.814483 -62.770081)
			(xy 144.802357 -62.715644) (xy 144.798286 -62.660022) (xy 143.809212 -62.660022) (xy 143.808703 -62.687908)
			(xy 143.800583 -62.743084) (xy 143.784515 -62.796491) (xy 143.760843 -62.846988) (xy 143.73007 -62.893501)
			(xy 143.692853 -62.935038) (xy 143.649985 -62.970713) (xy 143.602379 -62.999767) (xy 143.55105 -63.021579)
			(xy 143.497093 -63.035685) (xy 143.441656 -63.041785) (xy 143.385922 -63.039748) (xy 143.331079 -63.029618)
			(xy 143.278295 -63.011611) (xy 143.228695 -62.98611) (xy 143.183337 -62.953659) (xy 143.143188 -62.91495)
			(xy 143.109102 -62.870807) (xy 143.081806 -62.822172) (xy 143.061883 -62.770081) (xy 143.049757 -62.715644)
			(xy 143.045686 -62.660022) (xy 140.091165 -62.660022) (xy 140.098244 -62.686517) (xy 140.104653 -62.741608)
			(xy 140.103019 -62.797047) (xy 140.093376 -62.851665) (xy 140.075929 -62.904312) (xy 140.051043 -62.953879)
			(xy 140.019244 -62.999321) (xy 139.981202 -63.03968) (xy 139.937717 -63.074108) (xy 139.889707 -63.101877)
			(xy 139.838182 -63.122404) (xy 139.784229 -63.135255) (xy 139.728983 -63.14016) (xy 139.67361 -63.137016)
			(xy 139.619274 -63.125889) (xy 139.567122 -63.107013) (xy 139.518252 -63.080787) (xy 139.473694 -63.047761)
			(xy 139.434386 -63.008633) (xy 139.401156 -62.964227) (xy 139.374705 -62.915478) (xy 139.35559 -62.863413)
			(xy 139.344214 -62.809129) (xy 139.340816 -62.753771) (xy 139.345467 -62.698503) (xy 139.358071 -62.644491)
			(xy 139.378361 -62.592873) (xy 139.40591 -62.544736) (xy 139.422632 -62.522608) (xy 139.435596 -62.50528)
			(xy 139.456153 -62.467205) (xy 139.469962 -62.426198) (xy 139.476622 -62.383444) (xy 139.475941 -62.340179)
			(xy 139.467939 -62.297656) (xy 139.452847 -62.257103) (xy 139.431102 -62.219694) (xy 139.417552 -62.202822)
			(xy 139.400189 -62.181204) (xy 139.371144 -62.133976) (xy 139.349241 -62.083042) (xy 139.334942 -62.029473)
			(xy 139.328549 -61.974399) (xy 136.674906 -61.974399) (xy 136.666479 -61.984582) (xy 136.624912 -62.021999)
			(xy 136.578326 -62.052944) (xy 136.52772 -62.076752) (xy 136.474179 -62.092914) (xy 136.418851 -62.101082)
			(xy 136.362925 -62.101082) (xy 136.307597 -62.092914) (xy 136.254056 -62.076752) (xy 136.20345 -62.052944)
			(xy 136.156864 -62.021999) (xy 136.115297 -61.984582) (xy 136.079641 -61.941496) (xy 136.05066 -61.893663)
			(xy 136.028977 -61.842111) (xy 136.015055 -61.787944) (xy 136.009194 -61.732325) (xy 136.01152 -61.676447)
			(xy 136.021982 -61.621507) (xy 136.040356 -61.568684) (xy 136.066248 -61.519112) (xy 136.082278 -61.496194)
			(xy 136.095561 -61.477032) (xy 136.11564 -61.434958) (xy 136.127711 -61.389928) (xy 136.131369 -61.343451)
			(xy 136.12649 -61.297088) (xy 136.113239 -61.252391) (xy 136.09206 -61.210859) (xy 136.063662 -61.173887)
			(xy 136.028999 -61.142712) (xy 135.989232 -61.11838) (xy 135.945695 -61.101708) (xy 135.899848 -61.093255)
			(xy 135.876538 -61.092842) (xy 135.183372 -61.092842) (xy 134.586472 -61.689742) (xy 129.52349 -61.689742)
			(xy 129.19837 -62.014862) (xy 129.071624 -62.141862) (xy 129.071624 -62.871858) (xy 131.106162 -62.871858)
			(xy 131.110233 -62.816236) (xy 131.122359 -62.761799) (xy 131.142282 -62.709708) (xy 131.169578 -62.661073)
			(xy 131.203664 -62.61693) (xy 131.243813 -62.578221) (xy 131.289171 -62.54577) (xy 131.338771 -62.520269)
			(xy 131.391555 -62.502262) (xy 131.446398 -62.492132) (xy 131.502132 -62.490095) (xy 131.557569 -62.496195)
			(xy 131.611526 -62.510301) (xy 131.662855 -62.532113) (xy 131.710461 -62.561167) (xy 131.753329 -62.596842)
			(xy 131.790546 -62.638379) (xy 131.821319 -62.684892) (xy 131.844991 -62.735389) (xy 131.845242 -62.736222)
			(xy 135.908286 -62.736222) (xy 135.912357 -62.6806) (xy 135.924483 -62.626163) (xy 135.944406 -62.574072)
			(xy 135.971702 -62.525437) (xy 136.005788 -62.481294) (xy 136.045937 -62.442585) (xy 136.091295 -62.410134)
			(xy 136.140895 -62.384633) (xy 136.193679 -62.366626) (xy 136.248522 -62.356496) (xy 136.304256 -62.354459)
			(xy 136.359693 -62.360559) (xy 136.41365 -62.374665) (xy 136.464979 -62.396477) (xy 136.493937 -62.41415)
			(xy 138.226544 -62.41415) (xy 138.230615 -62.358528) (xy 138.242741 -62.304091) (xy 138.262664 -62.252)
			(xy 138.28996 -62.203365) (xy 138.324046 -62.159222) (xy 138.364195 -62.120513) (xy 138.409553 -62.088062)
			(xy 138.459153 -62.062561) (xy 138.511937 -62.044554) (xy 138.56678 -62.034424) (xy 138.622514 -62.032387)
			(xy 138.677951 -62.038487) (xy 138.731908 -62.052593) (xy 138.783237 -62.074405) (xy 138.830843 -62.103459)
			(xy 138.873711 -62.139134) (xy 138.910928 -62.180671) (xy 138.941701 -62.227184) (xy 138.965373 -62.277681)
			(xy 138.981441 -62.331088) (xy 138.989561 -62.386264) (xy 138.99007 -62.41415) (xy 138.989561 -62.442036)
			(xy 138.981441 -62.497212) (xy 138.965373 -62.550619) (xy 138.941701 -62.601116) (xy 138.910928 -62.647629)
			(xy 138.873711 -62.689166) (xy 138.830843 -62.724841) (xy 138.783237 -62.753895) (xy 138.731908 -62.775707)
			(xy 138.677951 -62.789813) (xy 138.622514 -62.795913) (xy 138.56678 -62.793876) (xy 138.511937 -62.783746)
			(xy 138.459153 -62.765739) (xy 138.409553 -62.740238) (xy 138.364195 -62.707787) (xy 138.324046 -62.669078)
			(xy 138.28996 -62.624935) (xy 138.262664 -62.5763) (xy 138.242741 -62.524209) (xy 138.230615 -62.469772)
			(xy 138.226544 -62.41415) (xy 136.493937 -62.41415) (xy 136.512585 -62.425531) (xy 136.555453 -62.461206)
			(xy 136.59267 -62.502743) (xy 136.623443 -62.549256) (xy 136.647115 -62.599753) (xy 136.663183 -62.65316)
			(xy 136.671303 -62.708336) (xy 136.671812 -62.736222) (xy 136.671303 -62.764108) (xy 136.663183 -62.819284)
			(xy 136.647115 -62.872691) (xy 136.623443 -62.923188) (xy 136.59267 -62.969701) (xy 136.555453 -63.011238)
			(xy 136.512585 -63.046913) (xy 136.464979 -63.075967) (xy 136.41365 -63.097779) (xy 136.359693 -63.111885)
			(xy 136.304256 -63.117985) (xy 136.248522 -63.115948) (xy 136.193679 -63.105818) (xy 136.140895 -63.087811)
			(xy 136.091295 -63.06231) (xy 136.045937 -63.029859) (xy 136.005788 -62.99115) (xy 135.971702 -62.947007)
			(xy 135.944406 -62.898372) (xy 135.924483 -62.846281) (xy 135.912357 -62.791844) (xy 135.908286 -62.736222)
			(xy 131.845242 -62.736222) (xy 131.861059 -62.788796) (xy 131.869179 -62.843972) (xy 131.869688 -62.871858)
			(xy 131.869179 -62.899744) (xy 131.861059 -62.95492) (xy 131.844991 -63.008327) (xy 131.821319 -63.058824)
			(xy 131.790546 -63.105337) (xy 131.753329 -63.146874) (xy 131.710461 -63.182549) (xy 131.662855 -63.211603)
			(xy 131.611526 -63.233415) (xy 131.557569 -63.247521) (xy 131.502132 -63.253621) (xy 131.446398 -63.251584)
			(xy 131.391555 -63.241454) (xy 131.338771 -63.223447) (xy 131.289171 -63.197946) (xy 131.243813 -63.165495)
			(xy 131.203664 -63.126786) (xy 131.169578 -63.082643) (xy 131.142282 -63.034008) (xy 131.122359 -62.981917)
			(xy 131.110233 -62.92748) (xy 131.106162 -62.871858) (xy 129.071624 -62.871858) (xy 129.071624 -63.582042)
			(xy 136.635234 -63.582042) (xy 136.639305 -63.52642) (xy 136.651431 -63.471983) (xy 136.671354 -63.419892)
			(xy 136.69865 -63.371257) (xy 136.732736 -63.327114) (xy 136.772885 -63.288405) (xy 136.818243 -63.255954)
			(xy 136.867843 -63.230453) (xy 136.920627 -63.212446) (xy 136.97547 -63.202316) (xy 137.031204 -63.200279)
			(xy 137.086641 -63.206379) (xy 137.140598 -63.220485) (xy 137.191927 -63.242297) (xy 137.239533 -63.271351)
			(xy 137.282401 -63.307026) (xy 137.319618 -63.348563) (xy 137.350391 -63.395076) (xy 137.374063 -63.445573)
			(xy 137.390131 -63.49898) (xy 137.398251 -63.554156) (xy 137.39876 -63.582042) (xy 137.398251 -63.609928)
			(xy 137.390131 -63.665104) (xy 137.374063 -63.718511) (xy 137.350391 -63.769008) (xy 137.319618 -63.815521)
			(xy 137.282401 -63.857058) (xy 137.239533 -63.892733) (xy 137.191927 -63.921787) (xy 137.140598 -63.943599)
			(xy 137.086641 -63.957705) (xy 137.031204 -63.963805) (xy 136.97547 -63.961768) (xy 136.920627 -63.951638)
			(xy 136.867843 -63.933631) (xy 136.818243 -63.90813) (xy 136.772885 -63.875679) (xy 136.732736 -63.83697)
			(xy 136.69865 -63.792827) (xy 136.671354 -63.744192) (xy 136.651431 -63.692101) (xy 136.639305 -63.637664)
			(xy 136.635234 -63.582042) (xy 129.071624 -63.582042) (xy 129.071624 -64.540892) (xy 130.599432 -64.540892)
			(xy 130.603503 -64.48527) (xy 130.615629 -64.430833) (xy 130.635552 -64.378742) (xy 130.662848 -64.330107)
			(xy 130.696934 -64.285964) (xy 130.737083 -64.247255) (xy 130.782441 -64.214804) (xy 130.832041 -64.189303)
			(xy 130.884825 -64.171296) (xy 130.939668 -64.161166) (xy 130.995402 -64.159129) (xy 131.050839 -64.165229)
			(xy 131.104796 -64.179335) (xy 131.156125 -64.201147) (xy 131.203731 -64.230201) (xy 131.246599 -64.265876)
			(xy 131.283816 -64.307413) (xy 131.314589 -64.353926) (xy 131.338261 -64.404423) (xy 131.34837 -64.438022)
			(xy 143.045686 -64.438022) (xy 143.049757 -64.3824) (xy 143.061883 -64.327963) (xy 143.081806 -64.275872)
			(xy 143.109102 -64.227237) (xy 143.143188 -64.183094) (xy 143.183337 -64.144385) (xy 143.228695 -64.111934)
			(xy 143.278295 -64.086433) (xy 143.331079 -64.068426) (xy 143.385922 -64.058296) (xy 143.441656 -64.056259)
			(xy 143.497093 -64.062359) (xy 143.55105 -64.076465) (xy 143.602379 -64.098277) (xy 143.649985 -64.127331)
			(xy 143.692853 -64.163006) (xy 143.73007 -64.204543) (xy 143.760843 -64.251056) (xy 143.784515 -64.301553)
			(xy 143.800583 -64.35496) (xy 143.801593 -64.361822) (xy 146.449286 -64.361822) (xy 146.453357 -64.3062)
			(xy 146.465483 -64.251763) (xy 146.485406 -64.199672) (xy 146.512702 -64.151037) (xy 146.546788 -64.106894)
			(xy 146.586937 -64.068185) (xy 146.632295 -64.035734) (xy 146.681895 -64.010233) (xy 146.734679 -63.992226)
			(xy 146.789522 -63.982096) (xy 146.845256 -63.980059) (xy 146.900693 -63.986159) (xy 146.95465 -64.000265)
			(xy 147.005979 -64.022077) (xy 147.053585 -64.051131) (xy 147.096453 -64.086806) (xy 147.13367 -64.128343)
			(xy 147.164443 -64.174856) (xy 147.188115 -64.225353) (xy 147.204183 -64.27876) (xy 147.212303 -64.333936)
			(xy 147.212812 -64.361822) (xy 147.212303 -64.389708) (xy 147.204183 -64.444884) (xy 147.188115 -64.498291)
			(xy 147.164443 -64.548788) (xy 147.13367 -64.595301) (xy 147.096453 -64.636838) (xy 147.053585 -64.672513)
			(xy 147.005979 -64.701567) (xy 146.95465 -64.723379) (xy 146.900693 -64.737485) (xy 146.845256 -64.743585)
			(xy 146.789522 -64.741548) (xy 146.734679 -64.731418) (xy 146.681895 -64.713411) (xy 146.632295 -64.68791)
			(xy 146.586937 -64.655459) (xy 146.546788 -64.61675) (xy 146.512702 -64.572607) (xy 146.485406 -64.523972)
			(xy 146.465483 -64.471881) (xy 146.453357 -64.417444) (xy 146.449286 -64.361822) (xy 143.801593 -64.361822)
			(xy 143.808703 -64.410136) (xy 143.809212 -64.438022) (xy 143.808703 -64.465908) (xy 143.800583 -64.521084)
			(xy 143.784515 -64.574491) (xy 143.760843 -64.624988) (xy 143.73007 -64.671501) (xy 143.692853 -64.713038)
			(xy 143.649985 -64.748713) (xy 143.602379 -64.777767) (xy 143.55105 -64.799579) (xy 143.497093 -64.813685)
			(xy 143.441656 -64.819785) (xy 143.385922 -64.817748) (xy 143.331079 -64.807618) (xy 143.278295 -64.789611)
			(xy 143.228695 -64.76411) (xy 143.183337 -64.731659) (xy 143.143188 -64.69295) (xy 143.109102 -64.648807)
			(xy 143.081806 -64.600172) (xy 143.061883 -64.548081) (xy 143.049757 -64.493644) (xy 143.045686 -64.438022)
			(xy 131.34837 -64.438022) (xy 131.354329 -64.45783) (xy 131.362449 -64.513006) (xy 131.362958 -64.540892)
			(xy 131.362449 -64.568778) (xy 131.354329 -64.623954) (xy 131.338261 -64.677361) (xy 131.314589 -64.727858)
			(xy 131.283816 -64.774371) (xy 131.246599 -64.815908) (xy 131.203731 -64.851583) (xy 131.156125 -64.880637)
			(xy 131.104796 -64.902449) (xy 131.050839 -64.916555) (xy 130.995402 -64.922655) (xy 130.939668 -64.920618)
			(xy 130.884825 -64.910488) (xy 130.832041 -64.892481) (xy 130.782441 -64.86698) (xy 130.737083 -64.834529)
			(xy 130.696934 -64.79582) (xy 130.662848 -64.751677) (xy 130.635552 -64.703042) (xy 130.615629 -64.650951)
			(xy 130.603503 -64.596514) (xy 130.599432 -64.540892) (xy 129.071624 -64.540892) (xy 129.071624 -65.557908)
			(xy 138.791948 -65.557908) (xy 138.796019 -65.502286) (xy 138.808145 -65.447849) (xy 138.828068 -65.395758)
			(xy 138.855364 -65.347123) (xy 138.88945 -65.30298) (xy 138.929599 -65.264271) (xy 138.974957 -65.23182)
			(xy 139.024557 -65.206319) (xy 139.077341 -65.188312) (xy 139.132184 -65.178182) (xy 139.187918 -65.176145)
			(xy 139.243355 -65.182245) (xy 139.297312 -65.196351) (xy 139.307146 -65.20053) (xy 150.538178 -65.20053)
			(xy 150.542249 -65.144908) (xy 150.554375 -65.090471) (xy 150.574298 -65.03838) (xy 150.601594 -64.989745)
			(xy 150.63568 -64.945602) (xy 150.675829 -64.906893) (xy 150.721187 -64.874442) (xy 150.770787 -64.848941)
			(xy 150.823571 -64.830934) (xy 150.878414 -64.820804) (xy 150.934148 -64.818767) (xy 150.989585 -64.824867)
			(xy 151.043542 -64.838973) (xy 151.094871 -64.860785) (xy 151.142477 -64.889839) (xy 151.185345 -64.925514)
			(xy 151.222562 -64.967051) (xy 151.253335 -65.013564) (xy 151.277007 -65.064061) (xy 151.293075 -65.117468)
			(xy 151.301195 -65.172644) (xy 151.301704 -65.20053) (xy 151.301195 -65.228416) (xy 151.293075 -65.283592)
			(xy 151.277007 -65.336999) (xy 151.253335 -65.387496) (xy 151.222562 -65.434009) (xy 151.185345 -65.475546)
			(xy 151.142477 -65.511221) (xy 151.094871 -65.540275) (xy 151.043542 -65.562087) (xy 150.989585 -65.576193)
			(xy 150.934148 -65.582293) (xy 150.878414 -65.580256) (xy 150.823571 -65.570126) (xy 150.770787 -65.552119)
			(xy 150.721187 -65.526618) (xy 150.675829 -65.494167) (xy 150.63568 -65.455458) (xy 150.601594 -65.411315)
			(xy 150.574298 -65.36268) (xy 150.554375 -65.310589) (xy 150.542249 -65.256152) (xy 150.538178 -65.20053)
			(xy 139.307146 -65.20053) (xy 139.348641 -65.218163) (xy 139.396247 -65.247217) (xy 139.439115 -65.282892)
			(xy 139.476332 -65.324429) (xy 139.507105 -65.370942) (xy 139.530777 -65.421439) (xy 139.546845 -65.474846)
			(xy 139.554965 -65.530022) (xy 139.555474 -65.557908) (xy 139.554965 -65.585794) (xy 139.546845 -65.64097)
			(xy 139.530777 -65.694377) (xy 139.507105 -65.744874) (xy 139.476332 -65.791387) (xy 139.439115 -65.832924)
			(xy 139.396247 -65.868599) (xy 139.348641 -65.897653) (xy 139.297312 -65.919465) (xy 139.243355 -65.933571)
			(xy 139.187918 -65.939671) (xy 139.132184 -65.937634) (xy 139.077341 -65.927504) (xy 139.024557 -65.909497)
			(xy 138.974957 -65.883996) (xy 138.929599 -65.851545) (xy 138.88945 -65.812836) (xy 138.855364 -65.768693)
			(xy 138.828068 -65.720058) (xy 138.808145 -65.667967) (xy 138.796019 -65.61353) (xy 138.791948 -65.557908)
			(xy 129.071624 -65.557908) (xy 129.071624 -66.063622) (xy 143.045686 -66.063622) (xy 143.049757 -66.008)
			(xy 143.061883 -65.953563) (xy 143.081806 -65.901472) (xy 143.109102 -65.852837) (xy 143.143188 -65.808694)
			(xy 143.183337 -65.769985) (xy 143.228695 -65.737534) (xy 143.278295 -65.712033) (xy 143.331079 -65.694026)
			(xy 143.385922 -65.683896) (xy 143.441656 -65.681859) (xy 143.497093 -65.687959) (xy 143.55105 -65.702065)
			(xy 143.602379 -65.723877) (xy 143.649985 -65.752931) (xy 143.692853 -65.788606) (xy 143.73007 -65.830143)
			(xy 143.760843 -65.876656) (xy 143.784515 -65.927153) (xy 143.800583 -65.98056) (xy 143.808703 -66.035736)
			(xy 143.809212 -66.063622) (xy 144.772886 -66.063622) (xy 144.776957 -66.008) (xy 144.789083 -65.953563)
			(xy 144.809006 -65.901472) (xy 144.836302 -65.852837) (xy 144.870388 -65.808694) (xy 144.910537 -65.769985)
			(xy 144.955895 -65.737534) (xy 145.005495 -65.712033) (xy 145.058279 -65.694026) (xy 145.113122 -65.683896)
			(xy 145.168856 -65.681859) (xy 145.224293 -65.687959) (xy 145.27825 -65.702065) (xy 145.329579 -65.723877)
			(xy 145.377185 -65.752931) (xy 145.420053 -65.788606) (xy 145.45727 -65.830143) (xy 145.488043 -65.876656)
			(xy 145.511715 -65.927153) (xy 145.527783 -65.98056) (xy 145.535903 -66.035736) (xy 145.536412 -66.063622)
			(xy 146.449286 -66.063622) (xy 146.453357 -66.008) (xy 146.465483 -65.953563) (xy 146.485406 -65.901472)
			(xy 146.512702 -65.852837) (xy 146.546788 -65.808694) (xy 146.586937 -65.769985) (xy 146.632295 -65.737534)
			(xy 146.681895 -65.712033) (xy 146.734679 -65.694026) (xy 146.789522 -65.683896) (xy 146.845256 -65.681859)
			(xy 146.900693 -65.687959) (xy 146.95465 -65.702065) (xy 147.005979 -65.723877) (xy 147.053585 -65.752931)
			(xy 147.096453 -65.788606) (xy 147.13367 -65.830143) (xy 147.164443 -65.876656) (xy 147.188115 -65.927153)
			(xy 147.204183 -65.98056) (xy 147.212303 -66.035736) (xy 147.212812 -66.063622) (xy 147.212303 -66.091508)
			(xy 147.204183 -66.146684) (xy 147.188115 -66.200091) (xy 147.164443 -66.250588) (xy 147.13367 -66.297101)
			(xy 147.096453 -66.338638) (xy 147.053585 -66.374313) (xy 147.005979 -66.403367) (xy 146.95465 -66.425179)
			(xy 146.900693 -66.439285) (xy 146.845256 -66.445385) (xy 146.789522 -66.443348) (xy 146.734679 -66.433218)
			(xy 146.681895 -66.415211) (xy 146.632295 -66.38971) (xy 146.586937 -66.357259) (xy 146.546788 -66.31855)
			(xy 146.512702 -66.274407) (xy 146.485406 -66.225772) (xy 146.465483 -66.173681) (xy 146.453357 -66.119244)
			(xy 146.449286 -66.063622) (xy 145.536412 -66.063622) (xy 145.535903 -66.091508) (xy 145.527783 -66.146684)
			(xy 145.511715 -66.200091) (xy 145.488043 -66.250588) (xy 145.45727 -66.297101) (xy 145.420053 -66.338638)
			(xy 145.377185 -66.374313) (xy 145.329579 -66.403367) (xy 145.27825 -66.425179) (xy 145.224293 -66.439285)
			(xy 145.168856 -66.445385) (xy 145.113122 -66.443348) (xy 145.058279 -66.433218) (xy 145.005495 -66.415211)
			(xy 144.955895 -66.38971) (xy 144.910537 -66.357259) (xy 144.870388 -66.31855) (xy 144.836302 -66.274407)
			(xy 144.809006 -66.225772) (xy 144.789083 -66.173681) (xy 144.776957 -66.119244) (xy 144.772886 -66.063622)
			(xy 143.809212 -66.063622) (xy 143.808703 -66.091508) (xy 143.800583 -66.146684) (xy 143.784515 -66.200091)
			(xy 143.760843 -66.250588) (xy 143.73007 -66.297101) (xy 143.692853 -66.338638) (xy 143.649985 -66.374313)
			(xy 143.602379 -66.403367) (xy 143.55105 -66.425179) (xy 143.497093 -66.439285) (xy 143.441656 -66.445385)
			(xy 143.385922 -66.443348) (xy 143.331079 -66.433218) (xy 143.278295 -66.415211) (xy 143.228695 -66.38971)
			(xy 143.183337 -66.357259) (xy 143.143188 -66.31855) (xy 143.109102 -66.274407) (xy 143.081806 -66.225772)
			(xy 143.061883 -66.173681) (xy 143.049757 -66.119244) (xy 143.045686 -66.063622) (xy 129.071624 -66.063622)
			(xy 129.071624 -66.660933) (xy 150.462148 -66.660933) (xy 150.464378 -66.605197) (xy 150.4747 -66.550379)
			(xy 150.492895 -66.497649) (xy 150.518573 -66.44813) (xy 150.551189 -66.402878) (xy 150.590046 -66.362857)
			(xy 150.634316 -66.328921) (xy 150.683056 -66.301792) (xy 150.735226 -66.28205) (xy 150.789716 -66.270115)
			(xy 150.845362 -66.266241) (xy 150.900979 -66.270512) (xy 150.955382 -66.282835) (xy 151.007411 -66.302949)
			(xy 151.055956 -66.330424) (xy 151.099983 -66.364675) (xy 151.138554 -66.404972) (xy 151.170846 -66.450455)
			(xy 151.19617 -66.500156) (xy 151.213988 -66.553015) (xy 151.22392 -66.607905) (xy 151.225752 -66.663656)
			(xy 151.219448 -66.719079) (xy 151.20514 -66.772994) (xy 151.183134 -66.824251) (xy 151.153899 -66.871757)
			(xy 151.13635 -66.89344) (xy 151.126263 -66.90622) (xy 151.112353 -66.935647) (xy 151.106329 -66.967634)
			(xy 151.108581 -67.000106) (xy 151.118963 -67.030955) (xy 151.136802 -67.05818) (xy 151.148542 -67.069462)
			(xy 151.168949 -67.088477) (xy 151.204482 -67.131474) (xy 151.233375 -67.179187) (xy 151.255012 -67.230599)
			(xy 151.268933 -67.284613) (xy 151.274841 -67.340078) (xy 151.272609 -67.395813) (xy 151.269636 -67.4116)
			(xy 160.907728 -67.4116) (xy 160.911801 -67.355941) (xy 160.923936 -67.301468) (xy 160.943872 -67.249342)
			(xy 160.971186 -67.200674) (xy 161.005294 -67.156502) (xy 161.045471 -67.117767) (xy 161.090859 -67.085295)
			(xy 161.140491 -67.059777) (xy 161.193311 -67.041758) (xy 161.24819 -67.031621) (xy 161.303961 -67.029583)
			(xy 161.359435 -67.035686) (xy 161.413428 -67.049802) (xy 161.464791 -67.071629) (xy 161.512429 -67.100702)
			(xy 161.555325 -67.136401) (xy 161.592567 -67.177965) (xy 161.623361 -67.224509) (xy 161.647049 -67.27504)
			(xy 161.663127 -67.328482) (xy 161.671253 -67.383696) (xy 161.671762 -67.4116) (xy 161.671253 -67.439504)
			(xy 161.663127 -67.494718) (xy 161.647049 -67.54816) (xy 161.623361 -67.598691) (xy 161.592567 -67.645235)
			(xy 161.555325 -67.686799) (xy 161.512429 -67.722498) (xy 161.464791 -67.751571) (xy 161.413428 -67.773398)
			(xy 161.359435 -67.787514) (xy 161.303961 -67.793617) (xy 161.24819 -67.791579) (xy 161.193311 -67.781442)
			(xy 161.140491 -67.763423) (xy 161.090859 -67.737905) (xy 161.045471 -67.705433) (xy 161.005294 -67.666698)
			(xy 160.971186 -67.622526) (xy 160.943872 -67.573858) (xy 160.923936 -67.521732) (xy 160.911801 -67.467259)
			(xy 160.907728 -67.4116) (xy 151.269636 -67.4116) (xy 151.262285 -67.450628) (xy 151.24409 -67.503356)
			(xy 151.218411 -67.552873) (xy 151.185795 -67.598123) (xy 151.146939 -67.638141) (xy 151.102669 -67.672075)
			(xy 151.05393 -67.699201) (xy 151.001761 -67.718941) (xy 150.947273 -67.730874) (xy 150.891628 -67.734747)
			(xy 150.836013 -67.730475) (xy 150.781612 -67.718151) (xy 150.729586 -67.698037) (xy 150.681043 -67.670561)
			(xy 150.637018 -67.63631) (xy 150.59845 -67.596014) (xy 150.56616 -67.550531) (xy 150.540837 -67.500831)
			(xy 150.523021 -67.447974) (xy 150.513092 -67.393086) (xy 150.51126 -67.337337) (xy 150.517566 -67.281915)
			(xy 150.531874 -67.228002) (xy 150.55388 -67.176748) (xy 150.583115 -67.129244) (xy 150.600664 -67.107562)
			(xy 150.610762 -67.094787) (xy 150.624682 -67.06536) (xy 150.630711 -67.033369) (xy 150.628458 -67.000894)
			(xy 150.618069 -66.970042) (xy 150.600218 -66.942819) (xy 150.588472 -66.93154) (xy 150.56805 -66.912539)
			(xy 150.532515 -66.869542) (xy 150.50362 -66.821828) (xy 150.48198 -66.770416) (xy 150.468057 -66.7164)
			(xy 150.462148 -66.660933) (xy 129.071624 -66.660933) (xy 129.071624 -67.458336) (xy 134.11784 -67.458336)
			(xy 134.121911 -67.402714) (xy 134.134037 -67.348277) (xy 134.15396 -67.296186) (xy 134.181256 -67.247551)
			(xy 134.215342 -67.203408) (xy 134.255491 -67.164699) (xy 134.300849 -67.132248) (xy 134.350449 -67.106747)
			(xy 134.403233 -67.08874) (xy 134.458076 -67.07861) (xy 134.51381 -67.076573) (xy 134.569247 -67.082673)
			(xy 134.623204 -67.096779) (xy 134.674533 -67.118591) (xy 134.722139 -67.147645) (xy 134.765007 -67.18332)
			(xy 134.802224 -67.224857) (xy 134.832997 -67.27137) (xy 134.856669 -67.321867) (xy 134.872737 -67.375274)
			(xy 134.880857 -67.43045) (xy 134.881366 -67.458336) (xy 134.880857 -67.486222) (xy 134.872737 -67.541398)
			(xy 134.856669 -67.594805) (xy 134.832997 -67.645302) (xy 134.802224 -67.691815) (xy 134.765007 -67.733352)
			(xy 134.722139 -67.769027) (xy 134.674533 -67.798081) (xy 134.623204 -67.819893) (xy 134.569247 -67.833999)
			(xy 134.51381 -67.840099) (xy 134.458076 -67.838062) (xy 134.403233 -67.827932) (xy 134.350449 -67.809925)
			(xy 134.300849 -67.784424) (xy 134.255491 -67.751973) (xy 134.215342 -67.713264) (xy 134.181256 -67.669121)
			(xy 134.15396 -67.620486) (xy 134.134037 -67.568395) (xy 134.121911 -67.513958) (xy 134.11784 -67.458336)
			(xy 129.071624 -67.458336) (xy 129.071624 -67.843908) (xy 136.5918 -67.843908) (xy 136.595871 -67.788286)
			(xy 136.607997 -67.733849) (xy 136.62792 -67.681758) (xy 136.655216 -67.633123) (xy 136.689302 -67.58898)
			(xy 136.729451 -67.550271) (xy 136.774809 -67.51782) (xy 136.824409 -67.492319) (xy 136.877193 -67.474312)
			(xy 136.932036 -67.464182) (xy 136.98777 -67.462145) (xy 137.043207 -67.468245) (xy 137.097164 -67.482351)
			(xy 137.148493 -67.504163) (xy 137.196099 -67.533217) (xy 137.238967 -67.568892) (xy 137.276184 -67.610429)
			(xy 137.306957 -67.656942) (xy 137.330629 -67.707439) (xy 137.346697 -67.760846) (xy 137.349389 -67.779138)
			(xy 138.077446 -67.779138) (xy 138.081517 -67.723516) (xy 138.093643 -67.669079) (xy 138.113566 -67.616988)
			(xy 138.140862 -67.568353) (xy 138.174948 -67.52421) (xy 138.215097 -67.485501) (xy 138.260455 -67.45305)
			(xy 138.310055 -67.427549) (xy 138.362839 -67.409542) (xy 138.417682 -67.399412) (xy 138.473416 -67.397375)
			(xy 138.528853 -67.403475) (xy 138.58281 -67.417581) (xy 138.634139 -67.439393) (xy 138.681745 -67.468447)
			(xy 138.724613 -67.504122) (xy 138.76183 -67.545659) (xy 138.792603 -67.592172) (xy 138.816275 -67.642669)
			(xy 138.832343 -67.696076) (xy 138.840463 -67.751252) (xy 138.840972 -67.779138) (xy 138.840463 -67.807024)
			(xy 138.832343 -67.8622) (xy 138.816275 -67.915607) (xy 138.792603 -67.966104) (xy 138.76183 -68.012617)
			(xy 138.724613 -68.054154) (xy 138.681745 -68.089829) (xy 138.634139 -68.118883) (xy 138.58281 -68.140695)
			(xy 138.528853 -68.154801) (xy 138.473416 -68.160901) (xy 138.417682 -68.158864) (xy 138.362839 -68.148734)
			(xy 138.310055 -68.130727) (xy 138.260455 -68.105226) (xy 138.215097 -68.072775) (xy 138.174948 -68.034066)
			(xy 138.140862 -67.989923) (xy 138.113566 -67.941288) (xy 138.093643 -67.889197) (xy 138.081517 -67.83476)
			(xy 138.077446 -67.779138) (xy 137.349389 -67.779138) (xy 137.354817 -67.816022) (xy 137.355326 -67.843908)
			(xy 137.354817 -67.871794) (xy 137.346697 -67.92697) (xy 137.330629 -67.980377) (xy 137.306957 -68.030874)
			(xy 137.276184 -68.077387) (xy 137.238967 -68.118924) (xy 137.196099 -68.154599) (xy 137.148493 -68.183653)
			(xy 137.097164 -68.205465) (xy 137.043207 -68.219571) (xy 136.98777 -68.225671) (xy 136.932036 -68.223634)
			(xy 136.877193 -68.213504) (xy 136.824409 -68.195497) (xy 136.774809 -68.169996) (xy 136.729451 -68.137545)
			(xy 136.689302 -68.098836) (xy 136.655216 -68.054693) (xy 136.62792 -68.006058) (xy 136.607997 -67.953967)
			(xy 136.595871 -67.89953) (xy 136.5918 -67.843908) (xy 129.071624 -67.843908) (xy 129.071624 -68.315586)
			(xy 133.089902 -68.315586) (xy 133.093973 -68.259964) (xy 133.106099 -68.205527) (xy 133.126022 -68.153436)
			(xy 133.153318 -68.104801) (xy 133.187404 -68.060658) (xy 133.227553 -68.021949) (xy 133.272911 -67.989498)
			(xy 133.322511 -67.963997) (xy 133.375295 -67.94599) (xy 133.430138 -67.93586) (xy 133.485872 -67.933823)
			(xy 133.541309 -67.939923) (xy 133.595266 -67.954029) (xy 133.646595 -67.975841) (xy 133.694201 -68.004895)
			(xy 133.737069 -68.04057) (xy 133.774286 -68.082107) (xy 133.805059 -68.12862) (xy 133.828731 -68.179117)
			(xy 133.844799 -68.232524) (xy 133.852919 -68.2877) (xy 133.853428 -68.315586) (xy 133.852919 -68.343472)
			(xy 133.844799 -68.398648) (xy 133.828731 -68.452055) (xy 133.805059 -68.502552) (xy 133.774286 -68.549065)
			(xy 133.737069 -68.590602) (xy 133.694201 -68.626277) (xy 133.646595 -68.655331) (xy 133.595266 -68.677143)
			(xy 133.541309 -68.691249) (xy 133.485872 -68.697349) (xy 133.430138 -68.695312) (xy 133.375295 -68.685182)
			(xy 133.322511 -68.667175) (xy 133.272911 -68.641674) (xy 133.227553 -68.609223) (xy 133.187404 -68.570514)
			(xy 133.153318 -68.526371) (xy 133.126022 -68.477736) (xy 133.106099 -68.425645) (xy 133.093973 -68.371208)
			(xy 133.089902 -68.315586) (xy 129.071624 -68.315586) (xy 129.071624 -68.909827) (xy 150.589507 -68.909827)
			(xy 150.597147 -68.854506) (xy 150.61277 -68.800891) (xy 150.636042 -68.750125) (xy 150.666465 -68.703294)
			(xy 150.70339 -68.661399) (xy 150.746027 -68.625333) (xy 150.793467 -68.595868) (xy 150.844695 -68.573633)
			(xy 150.898617 -68.559103) (xy 150.926292 -68.555362) (xy 150.947837 -68.552364) (xy 150.989545 -68.540029)
			(xy 151.028544 -68.520771) (xy 151.063692 -68.495152) (xy 151.093964 -68.463921) (xy 151.118474 -68.427991)
			(xy 151.136506 -68.388411) (xy 151.147534 -68.346338) (xy 151.151235 -68.303001) (xy 151.149812 -68.281296)
			(xy 151.147882 -68.25344) (xy 151.151256 -68.197705) (xy 151.162719 -68.143057) (xy 151.182024 -68.090664)
			(xy 151.208761 -68.041644) (xy 151.242357 -67.997045) (xy 151.282094 -67.957819) (xy 151.327126 -67.924804)
			(xy 151.376488 -67.898705) (xy 151.429128 -67.880081) (xy 151.48392 -67.869328) (xy 151.539694 -67.866677)
			(xy 151.595259 -67.872183) (xy 151.649428 -67.88573) (xy 151.701043 -67.907028) (xy 151.749003 -67.935622)
			(xy 151.792283 -67.970902) (xy 151.829958 -68.012113) (xy 151.861224 -68.058375) (xy 151.885413 -68.108701)
			(xy 151.902008 -68.162015) (xy 151.910655 -68.217179) (xy 151.911168 -68.273014) (xy 151.907232 -68.301548)
			(xy 152.190144 -68.301548) (xy 152.190148 -68.246206) (xy 152.198147 -68.191444) (xy 152.213973 -68.138413)
			(xy 152.237295 -68.088225) (xy 152.267623 -68.041933) (xy 152.304321 -68.000508) (xy 152.346618 -67.964819)
			(xy 152.393628 -67.935616) (xy 152.444364 -67.913511) (xy 152.497761 -67.898967) (xy 152.552699 -67.892291)
			(xy 152.608025 -67.893622) (xy 152.662579 -67.902931) (xy 152.715215 -67.920025) (xy 152.764829 -67.944544)
			(xy 152.810381 -67.975973) (xy 152.850914 -68.013654) (xy 152.86863 -68.034916) (xy 152.883253 -68.052285)
			(xy 152.91755 -68.082032) (xy 152.956586 -68.105211) (xy 152.999119 -68.121087) (xy 153.043796 -68.129153)
			(xy 153.089196 -68.129153) (xy 153.133873 -68.121087) (xy 153.176406 -68.105211) (xy 153.215442 -68.082032)
			(xy 153.249739 -68.052285) (xy 153.264362 -68.034916) (xy 153.281957 -68.013831) (xy 153.32214 -67.976404)
			(xy 153.367274 -67.945123) (xy 153.416426 -67.920635) (xy 153.46858 -67.903446) (xy 153.52266 -67.89391)
			(xy 153.577548 -67.892225) (xy 153.63211 -67.898425) (xy 153.685221 -67.912382) (xy 153.735782 -67.933808)
			(xy 153.78275 -67.962261) (xy 153.825155 -67.997153) (xy 153.84399 -68.017136) (xy 153.860185 -68.034162)
			(xy 153.897669 -68.062492) (xy 153.939722 -68.083447) (xy 153.984911 -68.096313) (xy 154.031696 -68.10065)
			(xy 154.078481 -68.096313) (xy 154.12367 -68.083447) (xy 154.165723 -68.062492) (xy 154.203207 -68.034162)
			(xy 154.219402 -68.017136) (xy 154.238134 -67.997247) (xy 154.280291 -67.962495) (xy 154.326974 -67.934111)
			(xy 154.377229 -67.912676) (xy 154.430027 -67.898629) (xy 154.484289 -67.892257) (xy 154.538905 -67.893691)
			(xy 154.592758 -67.9029) (xy 154.644746 -67.919697) (xy 154.693807 -67.943738) (xy 154.738937 -67.974531)
			(xy 154.779213 -68.011447) (xy 154.813812 -68.053731) (xy 154.842025 -68.100517) (xy 154.863276 -68.15085)
			(xy 154.87713 -68.203699) (xy 154.883303 -68.257983) (xy 154.88167 -68.312594) (xy 154.872264 -68.366413)
			(xy 154.855278 -68.41834) (xy 154.831058 -68.467312) (xy 154.8001 -68.51233) (xy 154.763037 -68.552471)
			(xy 154.720627 -68.586914) (xy 154.673738 -68.614956) (xy 154.623328 -68.636023) (xy 154.570429 -68.649684)
			(xy 154.516122 -68.655659) (xy 154.461518 -68.653827) (xy 154.407734 -68.644224) (xy 154.355869 -68.627048)
			(xy 154.306985 -68.602649) (xy 154.262081 -68.571527) (xy 154.222076 -68.534317) (xy 154.187788 -68.491782)
			(xy 154.159917 -68.444791) (xy 154.149044 -68.419726) (xy 154.14222 -68.404518) (xy 154.121948 -68.37807)
			(xy 154.095518 -68.357773) (xy 154.064734 -68.345014) (xy 154.031696 -68.340662) (xy 153.998658 -68.345014)
			(xy 153.967874 -68.357773) (xy 153.941444 -68.37807) (xy 153.921172 -68.404518) (xy 153.914348 -68.419726)
			(xy 153.906384 -68.438373) (xy 153.887038 -68.474009) (xy 153.87574 -68.490846) (xy 153.864029 -68.508598)
			(xy 153.845978 -68.547101) (xy 153.834603 -68.588075) (xy 153.830223 -68.630373) (xy 153.832959 -68.672808)
			(xy 153.842737 -68.714193) (xy 153.85928 -68.753367) (xy 153.882127 -68.789232) (xy 153.89606 -68.805298)
			(xy 153.914143 -68.826134) (xy 153.944793 -68.872004) (xy 153.968518 -68.921809) (xy 153.984824 -68.974512)
			(xy 153.99337 -69.029013) (xy 153.993979 -69.084177) (xy 153.986637 -69.138854) (xy 153.971498 -69.191904)
			(xy 153.948878 -69.24222) (xy 153.919248 -69.288755) (xy 153.883225 -69.330538) (xy 153.84156 -69.366698)
			(xy 153.795123 -69.396481) (xy 153.744881 -69.419266) (xy 153.691881 -69.434579) (xy 153.637229 -69.4421)
			(xy 153.582063 -69.441672) (xy 153.527534 -69.433305) (xy 153.474778 -69.417172) (xy 153.424895 -69.393611)
			(xy 153.378925 -69.363112) (xy 153.337827 -69.32631) (xy 153.302456 -69.283974) (xy 153.27355 -69.236986)
			(xy 153.251712 -69.186324) (xy 153.237398 -69.133047) (xy 153.230905 -69.078263) (xy 153.232368 -69.023115)
			(xy 153.241759 -68.968752) (xy 153.258879 -68.916308) (xy 153.283374 -68.866877) (xy 153.298652 -68.843906)
			(xy 153.310412 -68.826184) (xy 153.328459 -68.787674) (xy 153.339829 -68.746693) (xy 153.344204 -68.70439)
			(xy 153.341461 -68.66195) (xy 153.331676 -68.620562) (xy 153.315125 -68.581386) (xy 153.29227 -68.54552)
			(xy 153.278332 -68.529454) (xy 153.264362 -68.512944) (xy 153.249739 -68.495575) (xy 153.215442 -68.465828)
			(xy 153.176406 -68.442649) (xy 153.133873 -68.426773) (xy 153.089196 -68.418707) (xy 153.043796 -68.418707)
			(xy 152.999119 -68.426773) (xy 152.956586 -68.442649) (xy 152.91755 -68.465828) (xy 152.883253 -68.495575)
			(xy 152.86863 -68.512944) (xy 152.850882 -68.53418) (xy 152.810344 -68.571856) (xy 152.764789 -68.60328)
			(xy 152.715171 -68.627793) (xy 152.662533 -68.64488) (xy 152.607979 -68.654183) (xy 152.552652 -68.655507)
			(xy 152.497715 -68.648824) (xy 152.44432 -68.634274) (xy 152.393587 -68.612162) (xy 152.34658 -68.582953)
			(xy 152.304287 -68.547259) (xy 152.267594 -68.50583) (xy 152.237272 -68.459534) (xy 152.213956 -68.409343)
			(xy 152.198136 -68.35631) (xy 152.190144 -68.301548) (xy 151.907232 -68.301548) (xy 151.903538 -68.328327)
			(xy 151.887926 -68.381937) (xy 151.864667 -68.432699) (xy 151.834257 -68.479529) (xy 151.797346 -68.521426)
			(xy 151.754722 -68.557495) (xy 151.707296 -68.586967) (xy 151.656081 -68.60921) (xy 151.60217 -68.623751)
			(xy 151.5745 -68.627498) (xy 151.552944 -68.630427) (xy 151.511229 -68.642767) (xy 151.472226 -68.662032)
			(xy 151.437075 -68.687659) (xy 151.406802 -68.718899) (xy 151.382294 -68.754839) (xy 151.364266 -68.794429)
			(xy 151.353244 -68.836511) (xy 151.349552 -68.879856) (xy 151.35098 -68.901564) (xy 151.352847 -68.929429)
			(xy 151.349476 -68.985173) (xy 151.338015 -69.039829) (xy 151.31871 -69.092232) (xy 151.291971 -69.14126)
			(xy 151.258372 -69.185867) (xy 151.218629 -69.2251) (xy 151.173591 -69.25812) (xy 151.124222 -69.284222)
			(xy 151.071574 -69.302849) (xy 151.016774 -69.313602) (xy 150.960991 -69.316252) (xy 150.905419 -69.310742)
			(xy 150.851242 -69.29719) (xy 150.79962 -69.275886) (xy 150.751655 -69.247284) (xy 150.708372 -69.211996)
			(xy 150.670695 -69.170775) (xy 150.639429 -69.124503) (xy 150.615243 -69.074167) (xy 150.598652 -69.020843)
			(xy 150.590012 -68.96567) (xy 150.589507 -68.909827) (xy 129.071624 -68.909827) (xy 129.071624 -69.14515)
			(xy 129.077974 -69.164708) (xy 129.087208 -69.194032) (xy 129.099386 -69.254295) (xy 129.104217 -69.315586)
			(xy 129.103374 -69.346318) (xy 129.071624 -69.378068) (xy 129.071624 -69.662548) (xy 139.658596 -69.662548)
			(xy 139.662667 -69.606926) (xy 139.674793 -69.552489) (xy 139.694716 -69.500398) (xy 139.722012 -69.451763)
			(xy 139.756098 -69.40762) (xy 139.796247 -69.368911) (xy 139.841605 -69.33646) (xy 139.891205 -69.310959)
			(xy 139.943989 -69.292952) (xy 139.998832 -69.282822) (xy 140.054566 -69.280785) (xy 140.110003 -69.286885)
			(xy 140.16396 -69.300991) (xy 140.215289 -69.322803) (xy 140.262895 -69.351857) (xy 140.305763 -69.387532)
			(xy 140.34298 -69.429069) (xy 140.373753 -69.475582) (xy 140.397425 -69.526079) (xy 140.413493 -69.579486)
			(xy 140.421613 -69.634662) (xy 140.422122 -69.662548) (xy 140.421613 -69.690434) (xy 140.413493 -69.74561)
			(xy 140.397425 -69.799017) (xy 140.394005 -69.806312) (xy 141.14856 -69.806312) (xy 141.152631 -69.75069)
			(xy 141.164757 -69.696253) (xy 141.18468 -69.644162) (xy 141.211976 -69.595527) (xy 141.246062 -69.551384)
			(xy 141.286211 -69.512675) (xy 141.331569 -69.480224) (xy 141.381169 -69.454723) (xy 141.433953 -69.436716)
			(xy 141.488796 -69.426586) (xy 141.54453 -69.424549) (xy 141.599967 -69.430649) (xy 141.653924 -69.444755)
			(xy 141.705253 -69.466567) (xy 141.752859 -69.495621) (xy 141.795727 -69.531296) (xy 141.832944 -69.572833)
			(xy 141.863717 -69.619346) (xy 141.887389 -69.669843) (xy 141.903457 -69.72325) (xy 141.911577 -69.778426)
			(xy 141.912086 -69.806312) (xy 141.911577 -69.834198) (xy 141.903457 -69.889374) (xy 141.900401 -69.89953)
			(xy 143.578578 -69.89953) (xy 143.582649 -69.843908) (xy 143.594775 -69.789471) (xy 143.614698 -69.73738)
			(xy 143.641994 -69.688745) (xy 143.67608 -69.644602) (xy 143.716229 -69.605893) (xy 143.761587 -69.573442)
			(xy 143.811187 -69.547941) (xy 143.863971 -69.529934) (xy 143.918814 -69.519804) (xy 143.974548 -69.517767)
			(xy 144.029985 -69.523867) (xy 144.083942 -69.537973) (xy 144.135271 -69.559785) (xy 144.182877 -69.588839)
			(xy 144.225745 -69.624514) (xy 144.262962 -69.666051) (xy 144.293735 -69.712564) (xy 144.317407 -69.763061)
			(xy 144.327898 -69.79793) (xy 147.312378 -69.79793) (xy 147.316449 -69.742308) (xy 147.328575 -69.687871)
			(xy 147.348498 -69.63578) (xy 147.375794 -69.587145) (xy 147.40988 -69.543002) (xy 147.450029 -69.504293)
			(xy 147.495387 -69.471842) (xy 147.544987 -69.446341) (xy 147.597771 -69.428334) (xy 147.652614 -69.418204)
			(xy 147.708348 -69.416167) (xy 147.763785 -69.422267) (xy 147.817742 -69.436373) (xy 147.869071 -69.458185)
			(xy 147.916677 -69.487239) (xy 147.959545 -69.522914) (xy 147.996762 -69.564451) (xy 148.027535 -69.610964)
			(xy 148.051207 -69.661461) (xy 148.067275 -69.714868) (xy 148.075395 -69.770044) (xy 148.075904 -69.79793)
			(xy 148.075395 -69.825816) (xy 148.067275 -69.880992) (xy 148.061698 -69.89953) (xy 149.699978 -69.89953)
			(xy 149.704049 -69.843908) (xy 149.716175 -69.789471) (xy 149.736098 -69.73738) (xy 149.763394 -69.688745)
			(xy 149.79748 -69.644602) (xy 149.837629 -69.605893) (xy 149.882987 -69.573442) (xy 149.932587 -69.547941)
			(xy 149.985371 -69.529934) (xy 150.040214 -69.519804) (xy 150.095948 -69.517767) (xy 150.151385 -69.523867)
			(xy 150.205342 -69.537973) (xy 150.256671 -69.559785) (xy 150.304277 -69.588839) (xy 150.347145 -69.624514)
			(xy 150.384362 -69.666051) (xy 150.415135 -69.712564) (xy 150.438807 -69.763061) (xy 150.454875 -69.816468)
			(xy 150.462995 -69.871644) (xy 150.463504 -69.89953) (xy 150.462995 -69.927416) (xy 150.454875 -69.982592)
			(xy 150.438807 -70.035999) (xy 150.415135 -70.086496) (xy 150.384362 -70.133009) (xy 150.347145 -70.174546)
			(xy 150.311966 -70.203822) (xy 151.147778 -70.203822) (xy 151.151849 -70.1482) (xy 151.163975 -70.093763)
			(xy 151.183898 -70.041672) (xy 151.211194 -69.993037) (xy 151.24528 -69.948894) (xy 151.285429 -69.910185)
			(xy 151.330787 -69.877734) (xy 151.380387 -69.852233) (xy 151.433171 -69.834226) (xy 151.488014 -69.824096)
			(xy 151.543748 -69.822059) (xy 151.599185 -69.828159) (xy 151.653142 -69.842265) (xy 151.704471 -69.864077)
			(xy 151.752077 -69.893131) (xy 151.794945 -69.928806) (xy 151.832162 -69.970343) (xy 151.862935 -70.016856)
			(xy 151.886607 -70.067353) (xy 151.902675 -70.12076) (xy 151.910795 -70.175936) (xy 151.911304 -70.203822)
			(xy 151.910795 -70.231708) (xy 151.902675 -70.286884) (xy 151.886607 -70.340291) (xy 151.862935 -70.390788)
			(xy 151.832162 -70.437301) (xy 151.794945 -70.478838) (xy 151.752077 -70.514513) (xy 151.704471 -70.543567)
			(xy 151.653142 -70.565379) (xy 151.599185 -70.579485) (xy 151.543748 -70.585585) (xy 151.488014 -70.583548)
			(xy 151.433171 -70.573418) (xy 151.380387 -70.555411) (xy 151.330787 -70.52991) (xy 151.285429 -70.497459)
			(xy 151.24528 -70.45875) (xy 151.211194 -70.414607) (xy 151.183898 -70.365972) (xy 151.163975 -70.313881)
			(xy 151.151849 -70.259444) (xy 151.147778 -70.203822) (xy 150.311966 -70.203822) (xy 150.304277 -70.210221)
			(xy 150.256671 -70.239275) (xy 150.205342 -70.261087) (xy 150.151385 -70.275193) (xy 150.095948 -70.281293)
			(xy 150.040214 -70.279256) (xy 149.985371 -70.269126) (xy 149.932587 -70.251119) (xy 149.882987 -70.225618)
			(xy 149.837629 -70.193167) (xy 149.79748 -70.154458) (xy 149.763394 -70.110315) (xy 149.736098 -70.06168)
			(xy 149.716175 -70.009589) (xy 149.704049 -69.955152) (xy 149.699978 -69.89953) (xy 148.061698 -69.89953)
			(xy 148.051207 -69.934399) (xy 148.027535 -69.984896) (xy 147.996762 -70.031409) (xy 147.959545 -70.072946)
			(xy 147.916677 -70.108621) (xy 147.869071 -70.137675) (xy 147.817742 -70.159487) (xy 147.763785 -70.173593)
			(xy 147.708348 -70.179693) (xy 147.652614 -70.177656) (xy 147.597771 -70.167526) (xy 147.544987 -70.149519)
			(xy 147.495387 -70.124018) (xy 147.450029 -70.091567) (xy 147.40988 -70.052858) (xy 147.375794 -70.008715)
			(xy 147.348498 -69.96008) (xy 147.328575 -69.907989) (xy 147.316449 -69.853552) (xy 147.312378 -69.79793)
			(xy 144.327898 -69.79793) (xy 144.333475 -69.816468) (xy 144.341595 -69.871644) (xy 144.342104 -69.89953)
			(xy 144.341595 -69.927416) (xy 144.333475 -69.982592) (xy 144.317407 -70.035999) (xy 144.293735 -70.086496)
			(xy 144.262962 -70.133009) (xy 144.225745 -70.174546) (xy 144.182877 -70.210221) (xy 144.135271 -70.239275)
			(xy 144.083942 -70.261087) (xy 144.029985 -70.275193) (xy 143.974548 -70.281293) (xy 143.918814 -70.279256)
			(xy 143.863971 -70.269126) (xy 143.811187 -70.251119) (xy 143.761587 -70.225618) (xy 143.716229 -70.193167)
			(xy 143.67608 -70.154458) (xy 143.641994 -70.110315) (xy 143.614698 -70.06168) (xy 143.594775 -70.009589)
			(xy 143.582649 -69.955152) (xy 143.578578 -69.89953) (xy 141.900401 -69.89953) (xy 141.887389 -69.942781)
			(xy 141.863717 -69.993278) (xy 141.832944 -70.039791) (xy 141.795727 -70.081328) (xy 141.752859 -70.117003)
			(xy 141.705253 -70.146057) (xy 141.653924 -70.167869) (xy 141.599967 -70.181975) (xy 141.54453 -70.188075)
			(xy 141.488796 -70.186038) (xy 141.433953 -70.175908) (xy 141.381169 -70.157901) (xy 141.331569 -70.1324)
			(xy 141.286211 -70.099949) (xy 141.246062 -70.06124) (xy 141.211976 -70.017097) (xy 141.18468 -69.968462)
			(xy 141.164757 -69.916371) (xy 141.152631 -69.861934) (xy 141.14856 -69.806312) (xy 140.394005 -69.806312)
			(xy 140.373753 -69.849514) (xy 140.34298 -69.896027) (xy 140.305763 -69.937564) (xy 140.262895 -69.973239)
			(xy 140.215289 -70.002293) (xy 140.16396 -70.024105) (xy 140.110003 -70.038211) (xy 140.054566 -70.044311)
			(xy 139.998832 -70.042274) (xy 139.943989 -70.032144) (xy 139.891205 -70.014137) (xy 139.841605 -69.988636)
			(xy 139.796247 -69.956185) (xy 139.756098 -69.917476) (xy 139.722012 -69.873333) (xy 139.694716 -69.824698)
			(xy 139.674793 -69.772607) (xy 139.662667 -69.71817) (xy 139.658596 -69.662548) (xy 129.071624 -69.662548)
			(xy 129.071624 -70.301104) (xy 129.080006 -70.30974) (xy 129.076462 -70.323907) (xy 129.075382 -70.33133)
			(xy 138.104624 -70.33133) (xy 138.108695 -70.275708) (xy 138.120821 -70.221271) (xy 138.140744 -70.16918)
			(xy 138.16804 -70.120545) (xy 138.202126 -70.076402) (xy 138.242275 -70.037693) (xy 138.287633 -70.005242)
			(xy 138.337233 -69.979741) (xy 138.390017 -69.961734) (xy 138.44486 -69.951604) (xy 138.500594 -69.949567)
			(xy 138.556031 -69.955667) (xy 138.609988 -69.969773) (xy 138.661317 -69.991585) (xy 138.708923 -70.020639)
			(xy 138.751791 -70.056314) (xy 138.789008 -70.097851) (xy 138.819781 -70.144364) (xy 138.843453 -70.194861)
			(xy 138.859521 -70.248268) (xy 138.867641 -70.303444) (xy 138.86815 -70.33133) (xy 138.867641 -70.359216)
			(xy 138.859521 -70.414392) (xy 138.843453 -70.467799) (xy 138.819781 -70.518296) (xy 138.789008 -70.564809)
			(xy 138.751791 -70.606346) (xy 138.708923 -70.642021) (xy 138.661317 -70.671075) (xy 138.609988 -70.692887)
			(xy 138.556031 -70.706993) (xy 138.500594 -70.713093) (xy 138.44486 -70.711056) (xy 138.390017 -70.700926)
			(xy 138.337233 -70.682919) (xy 138.287633 -70.657418) (xy 138.242275 -70.624967) (xy 138.202126 -70.586258)
			(xy 138.16804 -70.542115) (xy 138.140744 -70.49348) (xy 138.120821 -70.441389) (xy 138.108695 -70.386952)
			(xy 138.104624 -70.33133) (xy 129.075382 -70.33133) (xy 129.072256 -70.352808) (xy 129.071624 -70.367398)
			(xy 129.071624 -70.527926) (xy 129.122424 -70.59549) (xy 129.163318 -70.607428) (xy 129.204783 -70.61993)
			(xy 129.285423 -70.651533) (xy 129.362814 -70.690419) (xy 129.436302 -70.736257) (xy 129.505262 -70.788659)
			(xy 129.569111 -70.847182) (xy 129.627307 -70.911328) (xy 129.679357 -70.980555) (xy 129.72482 -71.054275)
			(xy 129.76331 -71.131864) (xy 129.770335 -71.150062) (xy 134.268094 -71.150062) (xy 134.271384 -71.095364)
			(xy 134.282464 -71.041699) (xy 134.301106 -70.99017) (xy 134.326926 -70.941837) (xy 134.359394 -70.897695)
			(xy 134.397842 -70.85865) (xy 134.441478 -70.825505) (xy 134.489407 -70.798943) (xy 134.540643 -70.779509)
			(xy 134.594131 -70.767603) (xy 134.648772 -70.76347) (xy 134.703442 -70.767195) (xy 134.757018 -70.778701)
			(xy 134.808397 -70.797751) (xy 134.856523 -70.823954) (xy 134.900406 -70.856771) (xy 134.939145 -70.895528)
			(xy 134.971942 -70.939426) (xy 134.998123 -70.987565) (xy 135.017149 -71.038953) (xy 135.023352 -71.065644)
			(xy 135.028681 -71.088071) (xy 135.046338 -71.130649) (xy 135.07138 -71.169346) (xy 135.102986 -71.202896)
			(xy 135.103552 -71.203312) (xy 141.14856 -71.203312) (xy 141.152631 -71.14769) (xy 141.164757 -71.093253)
			(xy 141.18468 -71.041162) (xy 141.211976 -70.992527) (xy 141.246062 -70.948384) (xy 141.286211 -70.909675)
			(xy 141.331569 -70.877224) (xy 141.381169 -70.851723) (xy 141.433953 -70.833716) (xy 141.488796 -70.823586)
			(xy 141.54453 -70.821549) (xy 141.599967 -70.827649) (xy 141.653924 -70.841755) (xy 141.705253 -70.863567)
			(xy 141.752859 -70.892621) (xy 141.795727 -70.928296) (xy 141.829805 -70.96633) (xy 142.943578 -70.96633)
			(xy 142.947649 -70.910708) (xy 142.959775 -70.856271) (xy 142.979698 -70.80418) (xy 143.006994 -70.755545)
			(xy 143.04108 -70.711402) (xy 143.081229 -70.672693) (xy 143.126587 -70.640242) (xy 143.176187 -70.614741)
			(xy 143.228971 -70.596734) (xy 143.283814 -70.586604) (xy 143.339548 -70.584567) (xy 143.394985 -70.590667)
			(xy 143.448942 -70.604773) (xy 143.500271 -70.626585) (xy 143.547877 -70.655639) (xy 143.590745 -70.691314)
			(xy 143.627962 -70.732851) (xy 143.627997 -70.732904) (xy 153.269186 -70.732904) (xy 153.273257 -70.677282)
			(xy 153.285383 -70.622845) (xy 153.305306 -70.570754) (xy 153.332602 -70.522119) (xy 153.366688 -70.477976)
			(xy 153.406837 -70.439267) (xy 153.452195 -70.406816) (xy 153.501795 -70.381315) (xy 153.554579 -70.363308)
			(xy 153.609422 -70.353178) (xy 153.665156 -70.351141) (xy 153.720593 -70.357241) (xy 153.77455 -70.371347)
			(xy 153.825879 -70.393159) (xy 153.873485 -70.422213) (xy 153.916353 -70.457888) (xy 153.95357 -70.499425)
			(xy 153.984343 -70.545938) (xy 154.008015 -70.596435) (xy 154.024083 -70.649842) (xy 154.032203 -70.705018)
			(xy 154.032712 -70.732904) (xy 154.032203 -70.76079) (xy 154.024083 -70.815966) (xy 154.008015 -70.869373)
			(xy 153.984343 -70.91987) (xy 153.95357 -70.966383) (xy 153.916353 -71.00792) (xy 153.873485 -71.043595)
			(xy 153.825879 -71.072649) (xy 153.77455 -71.094461) (xy 153.720593 -71.108567) (xy 153.665156 -71.114667)
			(xy 153.609422 -71.11263) (xy 153.554579 -71.1025) (xy 153.501795 -71.084493) (xy 153.452195 -71.058992)
			(xy 153.406837 -71.026541) (xy 153.366688 -70.987832) (xy 153.332602 -70.943689) (xy 153.305306 -70.895054)
			(xy 153.285383 -70.842963) (xy 153.273257 -70.788526) (xy 153.269186 -70.732904) (xy 143.627997 -70.732904)
			(xy 143.658735 -70.779364) (xy 143.682407 -70.829861) (xy 143.698475 -70.883268) (xy 143.706595 -70.938444)
			(xy 143.707104 -70.96633) (xy 143.706595 -70.994216) (xy 143.698475 -71.049392) (xy 143.682407 -71.102799)
			(xy 143.658735 -71.153296) (xy 143.627962 -71.199809) (xy 143.590745 -71.241346) (xy 143.547877 -71.277021)
			(xy 143.500271 -71.306075) (xy 143.448942 -71.327887) (xy 143.394985 -71.341993) (xy 143.339548 -71.348093)
			(xy 143.283814 -71.346056) (xy 143.228971 -71.335926) (xy 143.176187 -71.317919) (xy 143.126587 -71.292418)
			(xy 143.081229 -71.259967) (xy 143.04108 -71.221258) (xy 143.006994 -71.177115) (xy 142.979698 -71.12848)
			(xy 142.959775 -71.076389) (xy 142.947649 -71.021952) (xy 142.943578 -70.96633) (xy 141.829805 -70.96633)
			(xy 141.832944 -70.969833) (xy 141.863717 -71.016346) (xy 141.887389 -71.066843) (xy 141.903457 -71.12025)
			(xy 141.911577 -71.175426) (xy 141.912086 -71.203312) (xy 141.911577 -71.231198) (xy 141.903457 -71.286374)
			(xy 141.887389 -71.339781) (xy 141.863717 -71.390278) (xy 141.832944 -71.436791) (xy 141.795727 -71.478328)
			(xy 141.752859 -71.514003) (xy 141.705253 -71.543057) (xy 141.653924 -71.564869) (xy 141.599967 -71.578975)
			(xy 141.54453 -71.585075) (xy 141.488796 -71.583038) (xy 141.433953 -71.572908) (xy 141.381169 -71.554901)
			(xy 141.331569 -71.5294) (xy 141.286211 -71.496949) (xy 141.246062 -71.45824) (xy 141.211976 -71.414097)
			(xy 141.18468 -71.365462) (xy 141.164757 -71.313371) (xy 141.152631 -71.258934) (xy 141.14856 -71.203312)
			(xy 135.103552 -71.203312) (xy 135.140122 -71.2302) (xy 135.181571 -71.250364) (xy 135.225976 -71.262726)
			(xy 135.271881 -71.266883) (xy 135.294878 -71.265288) (xy 135.322203 -71.263238) (xy 135.376926 -71.266093)
			(xy 135.430677 -71.276747) (xy 135.482352 -71.294978) (xy 135.530888 -71.320413) (xy 135.575287 -71.352529)
			(xy 135.614637 -71.390665) (xy 135.648127 -71.434036) (xy 135.675069 -71.481752) (xy 135.69491 -71.532831)
			(xy 135.707242 -71.586222) (xy 135.71181 -71.640828) (xy 135.708521 -71.695526) (xy 135.700808 -71.732886)
			(xy 145.88997 -71.732886) (xy 145.893265 -71.678061) (xy 145.904386 -71.624275) (xy 145.923105 -71.57264)
			(xy 145.949034 -71.524222) (xy 145.981638 -71.480022) (xy 146.020243 -71.440954) (xy 146.064051 -71.407825)
			(xy 146.112156 -71.381321) (xy 146.163565 -71.361987) (xy 146.217214 -71.350225) (xy 146.271996 -71.346277)
			(xy 146.326778 -71.350225) (xy 146.380427 -71.361987) (xy 146.431836 -71.381321) (xy 146.479941 -71.407825)
			(xy 146.523749 -71.440954) (xy 146.562354 -71.480022) (xy 146.594958 -71.524222) (xy 146.605646 -71.54418)
			(xy 160.70783 -71.54418) (xy 160.711901 -71.488558) (xy 160.724027 -71.434121) (xy 160.74395 -71.38203)
			(xy 160.771246 -71.333395) (xy 160.805332 -71.289252) (xy 160.845481 -71.250543) (xy 160.890839 -71.218092)
			(xy 160.940439 -71.192591) (xy 160.993223 -71.174584) (xy 161.048066 -71.164454) (xy 161.1038 -71.162417)
			(xy 161.159237 -71.168517) (xy 161.213194 -71.182623) (xy 161.264523 -71.204435) (xy 161.312129 -71.233489)
			(xy 161.354997 -71.269164) (xy 161.392214 -71.310701) (xy 161.422987 -71.357214) (xy 161.446659 -71.407711)
			(xy 161.462727 -71.461118) (xy 161.470847 -71.516294) (xy 161.471356 -71.54418) (xy 161.470847 -71.572066)
			(xy 161.462727 -71.627242) (xy 161.446659 -71.680649) (xy 161.422987 -71.731146) (xy 161.392214 -71.777659)
			(xy 161.354997 -71.819196) (xy 161.312129 -71.854871) (xy 161.264523 -71.883925) (xy 161.213194 -71.905737)
			(xy 161.159237 -71.919843) (xy 161.1038 -71.925943) (xy 161.048066 -71.923906) (xy 160.993223 -71.913776)
			(xy 160.940439 -71.895769) (xy 160.890839 -71.870268) (xy 160.845481 -71.837817) (xy 160.805332 -71.799108)
			(xy 160.771246 -71.754965) (xy 160.74395 -71.70633) (xy 160.724027 -71.654239) (xy 160.711901 -71.599802)
			(xy 160.70783 -71.54418) (xy 146.605646 -71.54418) (xy 146.620887 -71.57264) (xy 146.639606 -71.624275)
			(xy 146.650727 -71.678061) (xy 146.654022 -71.732886) (xy 146.649421 -71.787617) (xy 146.63702 -71.841122)
			(xy 146.617075 -71.892297) (xy 146.589998 -71.940083) (xy 146.556349 -71.983492) (xy 146.536918 -72.002904)
			(xy 146.520938 -72.018981) (xy 146.494452 -72.055763) (xy 146.47491 -72.09666) (xy 146.462933 -72.140375)
			(xy 146.4589 -72.185521) (xy 146.46294 -72.230667) (xy 146.474924 -72.274379) (xy 146.494473 -72.315273)
			(xy 146.520965 -72.352051) (xy 146.536918 -72.368156) (xy 146.551962 -72.383104) (xy 162.206955 -72.383104)
			(xy 162.213344 -72.328975) (xy 162.227373 -72.276307) (xy 162.248756 -72.226172) (xy 162.277057 -72.17959)
			(xy 162.3117 -72.137512) (xy 162.35198 -72.100792) (xy 162.397077 -72.07018) (xy 162.446071 -72.046299)
			(xy 162.497966 -72.029634) (xy 162.551704 -72.020526) (xy 162.606192 -72.019159) (xy 162.660319 -72.025562)
			(xy 162.712984 -72.039604) (xy 162.763114 -72.061) (xy 162.809688 -72.089313) (xy 162.831018 -72.106282)
			(xy 162.844198 -72.116539) (xy 162.874587 -72.130369) (xy 162.907524 -72.135844) (xy 162.940753 -72.132588)
			(xy 162.972 -72.120824) (xy 162.999127 -72.101358) (xy 163.010088 -72.088756) (xy 163.027703 -72.067953)
			(xy 163.067965 -72.031203) (xy 163.113049 -72.000559) (xy 163.162036 -71.976644) (xy 163.213928 -71.959945)
			(xy 163.267668 -71.950802) (xy 163.322163 -71.949403) (xy 163.376302 -71.955774) (xy 163.428983 -71.969786)
			(xy 163.479133 -71.991155) (xy 163.52573 -72.019444) (xy 163.567827 -72.054078) (xy 163.604565 -72.094351)
			(xy 163.635196 -72.139444) (xy 163.659097 -72.188437) (xy 163.675781 -72.240334) (xy 163.684908 -72.294077)
			(xy 163.686292 -72.348572) (xy 163.679906 -72.40271) (xy 163.665878 -72.455386) (xy 163.644495 -72.50553)
			(xy 163.616193 -72.55212) (xy 163.581547 -72.594206) (xy 163.541263 -72.630933) (xy 163.496161 -72.661551)
			(xy 163.447161 -72.685438) (xy 163.395259 -72.702107) (xy 163.341514 -72.711219) (xy 163.287018 -72.712587)
			(xy 163.232883 -72.706185) (xy 163.18021 -72.692142) (xy 163.130073 -72.670745) (xy 163.083491 -72.642429)
			(xy 163.062158 -72.625458) (xy 163.049001 -72.615168) (xy 163.018605 -72.601335) (xy 162.985661 -72.595862)
			(xy 162.952425 -72.599124) (xy 162.921174 -72.610898) (xy 162.894047 -72.630376) (xy 162.883088 -72.642984)
			(xy 162.865432 -72.663749) (xy 162.825171 -72.700488) (xy 162.78009 -72.731123) (xy 162.731108 -72.755029)
			(xy 162.679221 -72.77172) (xy 162.625488 -72.780855) (xy 162.571001 -72.78225) (xy 162.51687 -72.775874)
			(xy 162.464198 -72.761858) (xy 162.414057 -72.740488) (xy 162.367469 -72.712199) (xy 162.325381 -72.677566)
			(xy 162.288652 -72.637295) (xy 162.258029 -72.592207) (xy 162.234135 -72.543218) (xy 162.217457 -72.491328)
			(xy 162.208335 -72.437592) (xy 162.206955 -72.383104) (xy 146.551962 -72.383104) (xy 146.55607 -72.387186)
			(xy 146.589251 -72.42978) (xy 146.616096 -72.476626) (xy 146.63607 -72.526788) (xy 146.648774 -72.579264)
			(xy 146.653954 -72.633008) (xy 146.651507 -72.686944) (xy 146.641481 -72.739998) (xy 146.624077 -72.791108)
			(xy 146.599642 -72.839255) (xy 146.568664 -72.883477) (xy 146.531762 -72.92289) (xy 146.51101 -72.940164)
			(xy 146.493613 -72.954755) (xy 146.46387 -72.989058) (xy 146.440694 -73.028099) (xy 146.424822 -73.070637)
			(xy 146.416759 -73.115318) (xy 146.416763 -73.16072) (xy 146.424832 -73.205399) (xy 146.44071 -73.247935)
			(xy 146.463892 -73.286973) (xy 146.49364 -73.321272) (xy 146.51101 -73.335896) (xy 146.532272 -73.353614)
			(xy 146.569953 -73.394152) (xy 146.601382 -73.439708) (xy 146.625899 -73.489327) (xy 146.642991 -73.541967)
			(xy 146.652298 -73.596524) (xy 146.653626 -73.651854) (xy 146.646946 -73.706795) (xy 146.632398 -73.760194)
			(xy 146.610289 -73.810932) (xy 146.581081 -73.857943) (xy 146.545388 -73.900241) (xy 146.503958 -73.936938)
			(xy 146.457661 -73.967265) (xy 146.407469 -73.990586) (xy 146.354434 -74.00641) (xy 146.299669 -74.014406)
			(xy 146.244323 -74.014406) (xy 146.189558 -74.00641) (xy 146.136523 -73.990586) (xy 146.086331 -73.967265)
			(xy 146.040034 -73.936938) (xy 145.998604 -73.900241) (xy 145.962911 -73.857943) (xy 145.933703 -73.810932)
			(xy 145.911594 -73.760194) (xy 145.897046 -73.706795) (xy 145.890366 -73.651854) (xy 145.891694 -73.596524)
			(xy 145.901001 -73.541967) (xy 145.918093 -73.489327) (xy 145.94261 -73.439708) (xy 145.974039 -73.394152)
			(xy 146.01172 -73.353614) (xy 146.032982 -73.335896) (xy 146.05032 -73.321238) (xy 146.080064 -73.286946)
			(xy 146.103242 -73.247915) (xy 146.119118 -73.205388) (xy 146.127186 -73.160716) (xy 146.127189 -73.115322)
			(xy 146.119128 -73.070649) (xy 146.103258 -73.028119) (xy 146.080086 -72.989085) (xy 146.050347 -72.954788)
			(xy 146.032982 -72.940164) (xy 146.012279 -72.922838) (xy 145.975385 -72.883432) (xy 145.944413 -72.839218)
			(xy 145.919983 -72.79108) (xy 145.902583 -72.739979) (xy 145.892559 -72.686936) (xy 145.890112 -72.633009)
			(xy 145.895291 -72.579276) (xy 145.907992 -72.52681) (xy 145.927962 -72.476657) (xy 145.954802 -72.42982)
			(xy 145.987976 -72.387235) (xy 146.007074 -72.368156) (xy 146.022989 -72.35202) (xy 146.049468 -72.315246)
			(xy 146.069005 -72.274359) (xy 146.080983 -72.230656) (xy 146.085021 -72.185521) (xy 146.08099 -72.140385)
			(xy 146.06902 -72.09668) (xy 146.049489 -72.05579) (xy 146.023016 -72.019012) (xy 146.007074 -72.002904)
			(xy 145.987643 -71.983492) (xy 145.953994 -71.940083) (xy 145.926917 -71.892297) (xy 145.906972 -71.841122)
			(xy 145.894571 -71.787617) (xy 145.88997 -71.732886) (xy 135.700808 -71.732886) (xy 135.697442 -71.749192)
			(xy 135.678802 -71.800721) (xy 135.652984 -71.849054) (xy 135.620518 -71.893197) (xy 135.582072 -71.932243)
			(xy 135.538436 -71.965389) (xy 135.490509 -71.991953) (xy 135.439274 -72.011389) (xy 135.385787 -72.023298)
			(xy 135.331147 -72.027433) (xy 135.276476 -72.023711) (xy 135.2229 -72.012208) (xy 135.171521 -71.993161)
			(xy 135.123393 -71.96696) (xy 135.079508 -71.934146) (xy 135.040768 -71.895392) (xy 135.007968 -71.851496)
			(xy 134.981784 -71.803359) (xy 134.962755 -71.751973) (xy 134.95655 -71.725282) (xy 134.951201 -71.70286)
			(xy 134.933549 -71.660282) (xy 134.908511 -71.621584) (xy 134.876907 -71.588033) (xy 134.839774 -71.560728)
			(xy 134.798327 -71.540563) (xy 134.753924 -71.5282) (xy 134.70802 -71.524044) (xy 134.685024 -71.525638)
			(xy 134.657696 -71.527659) (xy 134.602973 -71.524803) (xy 134.549222 -71.514149) (xy 134.497546 -71.495917)
			(xy 134.44901 -71.470482) (xy 134.404611 -71.438365) (xy 134.365262 -71.400229) (xy 134.331773 -71.356856)
			(xy 134.304831 -71.30914) (xy 134.284991 -71.258061) (xy 134.27266 -71.204669) (xy 134.268094 -71.150062)
			(xy 129.770335 -71.150062) (xy 129.794501 -71.212664) (xy 129.81813 -71.29599) (xy 129.833994 -71.381137)
			(xy 129.841961 -71.467381) (xy 129.841962 -71.553992) (xy 129.833998 -71.640237) (xy 129.818136 -71.725384)
			(xy 129.79451 -71.80871) (xy 129.763321 -71.889511) (xy 129.724833 -71.967101) (xy 129.679372 -72.040823)
			(xy 129.627324 -72.110051) (xy 129.56913 -72.174199) (xy 129.505283 -72.232724) (xy 129.436324 -72.285128)
			(xy 129.362838 -72.330968) (xy 129.285447 -72.369856) (xy 129.204808 -72.401461) (xy 129.163318 -72.413876)
			(xy 129.122424 -72.425814) (xy 129.112586 -72.438899) (xy 141.152958 -72.438899) (xy 141.153894 -72.383609)
			(xy 141.162802 -72.329033) (xy 141.179496 -72.276314) (xy 141.203625 -72.226558) (xy 141.234686 -72.180807)
			(xy 141.272025 -72.140019) (xy 141.314863 -72.105049) (xy 141.3623 -72.07663) (xy 141.413343 -72.055357)
			(xy 141.466922 -72.041676) (xy 141.521915 -72.035874) (xy 141.57717 -72.038071) (xy 141.631528 -72.048223)
			(xy 141.683852 -72.066116) (xy 141.733044 -72.091376) (xy 141.778074 -72.123472) (xy 141.817999 -72.161734)
			(xy 141.835378 -72.183244) (xy 141.850051 -72.201159) (xy 141.884661 -72.231914) (xy 141.924274 -72.255885)
			(xy 141.967575 -72.272277) (xy 142.013131 -72.280548) (xy 142.059431 -72.280424) (xy 142.104942 -72.271908)
			(xy 142.148155 -72.255283) (xy 142.187637 -72.231099) (xy 142.205202 -72.21601) (xy 142.226097 -72.197895)
			(xy 142.272187 -72.167337) (xy 142.322207 -72.143753) (xy 142.375107 -72.127638) (xy 142.42978 -72.119328)
			(xy 142.48508 -72.118999) (xy 142.539848 -72.126656) (xy 142.592936 -72.14214) (xy 142.643233 -72.165126)
			(xy 142.689685 -72.195133) (xy 142.731318 -72.231532) (xy 142.76726 -72.27356) (xy 142.796757 -72.320336)
			(xy 142.819193 -72.370881) (xy 142.834097 -72.424136) (xy 142.841156 -72.478984) (xy 142.840223 -72.534276)
			(xy 142.831317 -72.588855) (xy 142.814624 -72.641576) (xy 142.790496 -72.691336) (xy 142.759436 -72.73709)
			(xy 142.722097 -72.777881) (xy 142.679259 -72.812854) (xy 142.631821 -72.841276) (xy 142.580777 -72.862552)
			(xy 142.527197 -72.876236) (xy 142.472202 -72.882041) (xy 142.416944 -72.879845) (xy 142.362583 -72.869696)
			(xy 142.310257 -72.851804) (xy 142.261062 -72.826546) (xy 142.216028 -72.79445) (xy 142.176101 -72.756188)
			(xy 142.15872 -72.734678) (xy 142.144054 -72.716759) (xy 142.109439 -72.686012) (xy 142.069824 -72.662048)
			(xy 142.026523 -72.64566) (xy 141.980968 -72.637392) (xy 141.93467 -72.637516) (xy 141.88916 -72.646029)
			(xy 141.845947 -72.66265) (xy 141.806462 -72.686826) (xy 141.788896 -72.701912) (xy 141.767981 -72.720003)
			(xy 141.721891 -72.750558) (xy 141.671872 -72.774139) (xy 141.618974 -72.790251) (xy 141.564303 -72.798558)
			(xy 141.509005 -72.798885) (xy 141.45424 -72.791226) (xy 141.401154 -72.77574) (xy 141.35086 -72.752753)
			(xy 141.304411 -72.722745) (xy 141.262782 -72.686346) (xy 141.226843 -72.644318) (xy 141.197348 -72.597543)
			(xy 141.174916 -72.546999) (xy 141.160015 -72.493746) (xy 141.152958 -72.438899) (xy 129.112586 -72.438899)
			(xy 129.071624 -72.493378) (xy 129.071624 -73.549002) (xy 140.60627 -73.549002) (xy 140.610341 -73.49338)
			(xy 140.622467 -73.438943) (xy 140.64239 -73.386852) (xy 140.669686 -73.338217) (xy 140.703772 -73.294074)
			(xy 140.743921 -73.255365) (xy 140.789279 -73.222914) (xy 140.838879 -73.197413) (xy 140.891663 -73.179406)
			(xy 140.946506 -73.169276) (xy 141.00224 -73.167239) (xy 141.057677 -73.173339) (xy 141.111634 -73.187445)
			(xy 141.162963 -73.209257) (xy 141.210569 -73.238311) (xy 141.253437 -73.273986) (xy 141.290654 -73.315523)
			(xy 141.321427 -73.362036) (xy 141.345099 -73.412533) (xy 141.361167 -73.46594) (xy 141.369287 -73.521116)
			(xy 141.369796 -73.549002) (xy 141.369287 -73.576888) (xy 141.361168 -73.63206) (xy 143.604486 -73.63206)
			(xy 143.608557 -73.576438) (xy 143.620683 -73.522001) (xy 143.640606 -73.46991) (xy 143.667902 -73.421275)
			(xy 143.701988 -73.377132) (xy 143.742137 -73.338423) (xy 143.787495 -73.305972) (xy 143.837095 -73.280471)
			(xy 143.889879 -73.262464) (xy 143.944722 -73.252334) (xy 144.000456 -73.250297) (xy 144.055893 -73.256397)
			(xy 144.10985 -73.270503) (xy 144.161179 -73.292315) (xy 144.208785 -73.321369) (xy 144.251653 -73.357044)
			(xy 144.28887 -73.398581) (xy 144.319643 -73.445094) (xy 144.343315 -73.495591) (xy 144.359383 -73.548998)
			(xy 144.367503 -73.604174) (xy 144.368012 -73.63206) (xy 144.367503 -73.659946) (xy 144.359383 -73.715122)
			(xy 144.343315 -73.768529) (xy 144.319643 -73.819026) (xy 144.28887 -73.865539) (xy 144.251653 -73.907076)
			(xy 144.208785 -73.942751) (xy 144.161179 -73.971805) (xy 144.10985 -73.993617) (xy 144.055893 -74.007723)
			(xy 144.000456 -74.013823) (xy 143.944722 -74.011786) (xy 143.889879 -74.001656) (xy 143.837095 -73.983649)
			(xy 143.787495 -73.958148) (xy 143.742137 -73.925697) (xy 143.701988 -73.886988) (xy 143.667902 -73.842845)
			(xy 143.640606 -73.79421) (xy 143.620683 -73.742119) (xy 143.608557 -73.687682) (xy 143.604486 -73.63206)
			(xy 141.361168 -73.63206) (xy 141.361167 -73.632064) (xy 141.345099 -73.685471) (xy 141.321427 -73.735968)
			(xy 141.290654 -73.782481) (xy 141.253437 -73.824018) (xy 141.210569 -73.859693) (xy 141.162963 -73.888747)
			(xy 141.111634 -73.910559) (xy 141.057677 -73.924665) (xy 141.00224 -73.930765) (xy 140.946506 -73.928728)
			(xy 140.891663 -73.918598) (xy 140.838879 -73.900591) (xy 140.789279 -73.87509) (xy 140.743921 -73.842639)
			(xy 140.703772 -73.80393) (xy 140.669686 -73.759787) (xy 140.64239 -73.711152) (xy 140.622467 -73.659061)
			(xy 140.610341 -73.604624) (xy 140.60627 -73.549002) (xy 129.071624 -73.549002) (xy 129.071624 -75.305251)
			(xy 158.139968 -75.305251) (xy 158.14577 -75.249904) (xy 158.159552 -75.195987) (xy 158.18102 -75.144644)
			(xy 158.209721 -75.096965) (xy 158.245044 -75.053962) (xy 158.28624 -75.016547) (xy 158.309056 -75.000612)
			(xy 158.327868 -74.987257) (xy 158.360863 -74.955021) (xy 158.387498 -74.917362) (xy 158.406901 -74.875513)
			(xy 158.418433 -74.830851) (xy 158.421717 -74.784841) (xy 158.416643 -74.738993) (xy 158.40338 -74.694814)
			(xy 158.382362 -74.653753) (xy 158.354279 -74.61716) (xy 158.337504 -74.601324) (xy 158.317214 -74.582271)
			(xy 158.281761 -74.539369) (xy 158.252917 -74.491771) (xy 158.231294 -74.440487) (xy 158.217352 -74.386606)
			(xy 158.211387 -74.331271) (xy 158.213525 -74.275656) (xy 158.223721 -74.220942) (xy 158.241758 -74.16829)
			(xy 158.267254 -74.118818) (xy 158.299667 -74.073575) (xy 158.338309 -74.033521) (xy 158.382362 -73.999507)
			(xy 158.430888 -73.972254) (xy 158.48286 -73.952341) (xy 158.537173 -73.940191) (xy 158.592675 -73.936061)
			(xy 158.648189 -73.940038) (xy 158.702535 -73.95204) (xy 158.754561 -73.97181) (xy 158.803162 -73.998929)
			(xy 158.820906 -74.012552) (xy 165.56939 -74.012552) (xy 165.573461 -73.95693) (xy 165.585587 -73.902493)
			(xy 165.60551 -73.850402) (xy 165.632806 -73.801767) (xy 165.666892 -73.757624) (xy 165.707041 -73.718915)
			(xy 165.752399 -73.686464) (xy 165.801999 -73.660963) (xy 165.854783 -73.642956) (xy 165.909626 -73.632826)
			(xy 165.96536 -73.630789) (xy 166.020797 -73.636889) (xy 166.074754 -73.650995) (xy 166.126083 -73.672807)
			(xy 166.173689 -73.701861) (xy 166.216557 -73.737536) (xy 166.253774 -73.779073) (xy 166.284547 -73.825586)
			(xy 166.308219 -73.876083) (xy 166.324287 -73.92949) (xy 166.332407 -73.984666) (xy 166.332916 -74.012552)
			(xy 166.332407 -74.040438) (xy 166.324287 -74.095614) (xy 166.308219 -74.149021) (xy 166.284547 -74.199518)
			(xy 166.253774 -74.246031) (xy 166.216557 -74.287568) (xy 166.173689 -74.323243) (xy 166.126083 -74.352297)
			(xy 166.074754 -74.374109) (xy 166.020797 -74.388215) (xy 165.96536 -74.394315) (xy 165.909626 -74.392278)
			(xy 165.854783 -74.382148) (xy 165.801999 -74.364141) (xy 165.752399 -74.33864) (xy 165.707041 -74.306189)
			(xy 165.666892 -74.26748) (xy 165.632806 -74.223337) (xy 165.60551 -74.174702) (xy 165.585587 -74.122611)
			(xy 165.573461 -74.068174) (xy 165.56939 -74.012552) (xy 158.820906 -74.012552) (xy 158.847308 -74.032822)
			(xy 158.88606 -74.072769) (xy 158.918598 -74.117923) (xy 158.944229 -74.167326) (xy 158.962411 -74.219928)
			(xy 158.972757 -74.274613) (xy 158.975047 -74.330222) (xy 158.969234 -74.385573) (xy 158.955441 -74.439492)
			(xy 158.933959 -74.490835) (xy 158.905246 -74.538513) (xy 158.86991 -74.581512) (xy 158.828702 -74.618921)
			(xy 158.80588 -74.634852) (xy 158.78701 -74.648131) (xy 158.75401 -74.680375) (xy 158.727371 -74.718046)
			(xy 158.707968 -74.759905) (xy 158.705365 -74.76999) (xy 162.292005 -74.76999) (xy 162.29786 -74.715292)
			(xy 162.311511 -74.662002) (xy 162.332674 -74.611225) (xy 162.36091 -74.564014) (xy 162.395635 -74.521348)
			(xy 162.436127 -74.484112) (xy 162.481547 -74.453077) (xy 162.530954 -74.428888) (xy 162.583322 -74.412045)
			(xy 162.637567 -74.402898) (xy 162.692563 -74.401637) (xy 162.74717 -74.408288) (xy 162.800256 -74.422713)
			(xy 162.850719 -74.444612) (xy 162.897515 -74.473532) (xy 162.918902 -74.490834) (xy 162.931367 -74.500619)
			(xy 162.959956 -74.514268) (xy 162.991025 -74.520466) (xy 163.022663 -74.518831) (xy 163.052927 -74.509464)
			(xy 163.079957 -74.492941) (xy 163.091368 -74.481944) (xy 163.111439 -74.461904) (xy 163.156524 -74.427489)
			(xy 163.206207 -74.400126) (xy 163.259393 -74.380419) (xy 163.314909 -74.368802) (xy 163.371534 -74.365531)
			(xy 163.428019 -74.370677) (xy 163.48312 -74.384128) (xy 163.535623 -74.405587) (xy 163.584372 -74.434581)
			(xy 163.628291 -74.470472) (xy 163.666414 -74.512469) (xy 163.697901 -74.559645) (xy 163.722058 -74.610963)
			(xy 163.738352 -74.665292) (xy 163.746425 -74.721433) (xy 163.746098 -74.778152) (xy 163.73738 -74.834197)
			(xy 163.729416 -74.86142) (xy 163.723076 -74.883371) (xy 163.717402 -74.928703) (xy 163.719929 -74.974318)
			(xy 163.730575 -75.018745) (xy 163.748996 -75.060551) (xy 163.7746 -75.098388) (xy 163.806558 -75.131034)
			(xy 163.82492 -75.14463) (xy 163.846868 -75.160791) (xy 163.886446 -75.198264) (xy 163.920287 -75.240987)
			(xy 163.947704 -75.288092) (xy 163.950086 -75.293982) (xy 164.716712 -75.293982) (xy 164.720783 -75.23836)
			(xy 164.732909 -75.183923) (xy 164.752832 -75.131832) (xy 164.780128 -75.083197) (xy 164.814214 -75.039054)
			(xy 164.854363 -75.000345) (xy 164.899721 -74.967894) (xy 164.949321 -74.942393) (xy 165.002105 -74.924386)
			(xy 165.056948 -74.914256) (xy 165.112682 -74.912219) (xy 165.168119 -74.918319) (xy 165.222076 -74.932425)
			(xy 165.273405 -74.954237) (xy 165.321011 -74.983291) (xy 165.363879 -75.018966) (xy 165.401096 -75.060503)
			(xy 165.431869 -75.107016) (xy 165.455541 -75.157513) (xy 165.471609 -75.21092) (xy 165.479729 -75.266096)
			(xy 165.480238 -75.293982) (xy 165.479729 -75.321868) (xy 165.471609 -75.377044) (xy 165.455541 -75.430451)
			(xy 165.431869 -75.480948) (xy 165.401096 -75.527461) (xy 165.363879 -75.568998) (xy 165.321011 -75.604673)
			(xy 165.273405 -75.633727) (xy 165.222076 -75.655539) (xy 165.168119 -75.669645) (xy 165.112682 -75.675745)
			(xy 165.056948 -75.673708) (xy 165.002105 -75.663578) (xy 164.949321 -75.645571) (xy 164.899721 -75.62007)
			(xy 164.854363 -75.587619) (xy 164.814214 -75.54891) (xy 164.780128 -75.504767) (xy 164.752832 -75.456132)
			(xy 164.732909 -75.404041) (xy 164.720783 -75.349604) (xy 164.716712 -75.293982) (xy 163.950086 -75.293982)
			(xy 163.968137 -75.33862) (xy 163.981172 -75.391541) (xy 163.986542 -75.445778) (xy 163.984138 -75.500228)
			(xy 163.97401 -75.553782) (xy 163.956362 -75.605348) (xy 163.931556 -75.653879) (xy 163.900095 -75.698384)
			(xy 163.862621 -75.73796) (xy 163.819895 -75.771799) (xy 163.772789 -75.799213) (xy 163.72226 -75.819644)
			(xy 163.669338 -75.832675) (xy 163.615101 -75.838042) (xy 163.560651 -75.835636) (xy 163.507098 -75.825504)
			(xy 163.455532 -75.807854) (xy 163.407004 -75.783045) (xy 163.384484 -75.767692) (xy 163.366012 -75.755165)
			(xy 163.325632 -75.736163) (xy 163.282552 -75.724508) (xy 163.238099 -75.720559) (xy 163.193639 -75.724439)
			(xy 163.150541 -75.736026) (xy 163.110131 -75.754966) (xy 163.091622 -75.767438) (xy 163.068339 -75.783355)
			(xy 163.017973 -75.808736) (xy 162.964418 -75.826425) (xy 162.908843 -75.836036) (xy 162.852458 -75.837361)
			(xy 162.796493 -75.830371) (xy 162.742167 -75.815217) (xy 162.690664 -75.79223) (xy 162.643106 -75.761911)
			(xy 162.60053 -75.724921) (xy 162.563864 -75.682066) (xy 162.533906 -75.634279) (xy 162.511311 -75.582603)
			(xy 162.49657 -75.528163) (xy 162.490004 -75.472146) (xy 162.491756 -75.415773) (xy 162.501789 -75.360273)
			(xy 162.519884 -75.306854) (xy 162.532314 -75.281536) (xy 162.539236 -75.266947) (xy 162.546291 -75.235448)
			(xy 162.545225 -75.203185) (xy 162.536107 -75.17222) (xy 162.519518 -75.144529) (xy 162.496518 -75.121879)
			(xy 162.482784 -75.113388) (xy 162.459189 -75.099245) (xy 162.416023 -75.065145) (xy 162.378201 -75.025199)
			(xy 162.346509 -74.980235) (xy 162.321603 -74.931186) (xy 162.304 -74.879068) (xy 162.294066 -74.824962)
			(xy 162.292005 -74.76999) (xy 158.705365 -74.76999) (xy 158.696438 -74.804579) (xy 158.693161 -74.850601)
			(xy 158.698243 -74.896458) (xy 158.711518 -74.940645) (xy 158.73255 -74.98171) (xy 158.760649 -75.018305)
			(xy 158.777432 -75.03414) (xy 158.797769 -75.053137) (xy 158.83322 -75.096035) (xy 158.862063 -75.143628)
			(xy 158.883685 -75.194906) (xy 158.897627 -75.248782) (xy 158.903594 -75.304112) (xy 158.901459 -75.359721)
			(xy 158.891268 -75.414431) (xy 158.873236 -75.467079) (xy 158.847746 -75.516549) (xy 158.815339 -75.56179)
			(xy 158.776703 -75.601844) (xy 158.732658 -75.635859) (xy 158.684138 -75.663113) (xy 158.632174 -75.68303)
			(xy 158.577867 -75.695185) (xy 158.52237 -75.699321) (xy 158.466861 -75.695351) (xy 158.412519 -75.683358)
			(xy 158.360495 -75.663597) (xy 158.311894 -75.636487) (xy 158.267747 -75.602603) (xy 158.228992 -75.562666)
			(xy 158.196451 -75.517521) (xy 158.170813 -75.468127) (xy 158.152624 -75.415533) (xy 158.142269 -75.360855)
			(xy 158.139968 -75.305251) (xy 129.071624 -75.305251) (xy 129.071624 -75.740768) (xy 142.245332 -75.740768)
			(xy 142.249403 -75.685146) (xy 142.261529 -75.630709) (xy 142.281452 -75.578618) (xy 142.308748 -75.529983)
			(xy 142.342834 -75.48584) (xy 142.382983 -75.447131) (xy 142.428341 -75.41468) (xy 142.477941 -75.389179)
			(xy 142.530725 -75.371172) (xy 142.585568 -75.361042) (xy 142.641302 -75.359005) (xy 142.696739 -75.365105)
			(xy 142.750696 -75.379211) (xy 142.802025 -75.401023) (xy 142.849631 -75.430077) (xy 142.892499 -75.465752)
			(xy 142.929716 -75.507289) (xy 142.960489 -75.553802) (xy 142.984161 -75.604299) (xy 143.000229 -75.657706)
			(xy 143.008349 -75.712882) (xy 143.008858 -75.740768) (xy 143.008349 -75.768654) (xy 143.000229 -75.82383)
			(xy 142.984161 -75.877237) (xy 142.960489 -75.927734) (xy 142.929716 -75.974247) (xy 142.892499 -76.015784)
			(xy 142.849631 -76.051459) (xy 142.802025 -76.080513) (xy 142.750696 -76.102325) (xy 142.696739 -76.116431)
			(xy 142.641302 -76.122531) (xy 142.585568 -76.120494) (xy 142.530725 -76.110364) (xy 142.477941 -76.092357)
			(xy 142.428341 -76.066856) (xy 142.382983 -76.034405) (xy 142.342834 -75.995696) (xy 142.308748 -75.951553)
			(xy 142.281452 -75.902918) (xy 142.261529 -75.850827) (xy 142.249403 -75.79639) (xy 142.245332 -75.740768)
			(xy 129.071624 -75.740768) (xy 129.071624 -76.61529) (xy 143.370044 -76.61529) (xy 143.374115 -76.559668)
			(xy 143.386241 -76.505231) (xy 143.406164 -76.45314) (xy 143.43346 -76.404505) (xy 143.467546 -76.360362)
			(xy 143.507695 -76.321653) (xy 143.553053 -76.289202) (xy 143.602653 -76.263701) (xy 143.655437 -76.245694)
			(xy 143.71028 -76.235564) (xy 143.766014 -76.233527) (xy 143.821451 -76.239627) (xy 143.875408 -76.253733)
			(xy 143.926737 -76.275545) (xy 143.974343 -76.304599) (xy 144.017211 -76.340274) (xy 144.054428 -76.381811)
			(xy 144.085201 -76.428324) (xy 144.108873 -76.478821) (xy 144.124941 -76.532228) (xy 144.133061 -76.587404)
			(xy 144.13357 -76.61529) (xy 144.133061 -76.643176) (xy 144.124941 -76.698352) (xy 144.108873 -76.751759)
			(xy 144.085201 -76.802256) (xy 144.054428 -76.848769) (xy 144.017211 -76.890306) (xy 143.974343 -76.925981)
			(xy 143.926737 -76.955035) (xy 143.875408 -76.976847) (xy 143.821451 -76.990953) (xy 143.766014 -76.997053)
			(xy 143.71028 -76.995016) (xy 143.655437 -76.984886) (xy 143.602653 -76.966879) (xy 143.553053 -76.941378)
			(xy 143.507695 -76.908927) (xy 143.467546 -76.870218) (xy 143.43346 -76.826075) (xy 143.406164 -76.77744)
			(xy 143.386241 -76.725349) (xy 143.374115 -76.670912) (xy 143.370044 -76.61529) (xy 129.071624 -76.61529)
			(xy 129.071624 -77.478636) (xy 149.12416 -77.478636) (xy 149.128231 -77.423014) (xy 149.140357 -77.368577)
			(xy 149.16028 -77.316486) (xy 149.187576 -77.267851) (xy 149.221662 -77.223708) (xy 149.261811 -77.184999)
			(xy 149.307169 -77.152548) (xy 149.356769 -77.127047) (xy 149.409553 -77.10904) (xy 149.464396 -77.09891)
			(xy 149.52013 -77.096873) (xy 149.575567 -77.102973) (xy 149.629524 -77.117079) (xy 149.680853 -77.138891)
			(xy 149.728459 -77.167945) (xy 149.771327 -77.20362) (xy 149.808544 -77.245157) (xy 149.839317 -77.29167)
			(xy 149.862989 -77.342167) (xy 149.879057 -77.395574) (xy 149.887177 -77.45075) (xy 149.887686 -77.478636)
			(xy 150.39416 -77.478636) (xy 150.398231 -77.423014) (xy 150.410357 -77.368577) (xy 150.43028 -77.316486)
			(xy 150.457576 -77.267851) (xy 150.491662 -77.223708) (xy 150.531811 -77.184999) (xy 150.577169 -77.152548)
			(xy 150.626769 -77.127047) (xy 150.679553 -77.10904) (xy 150.734396 -77.09891) (xy 150.79013 -77.096873)
			(xy 150.845567 -77.102973) (xy 150.899524 -77.117079) (xy 150.950853 -77.138891) (xy 150.998459 -77.167945)
			(xy 151.041327 -77.20362) (xy 151.078544 -77.245157) (xy 151.109317 -77.29167) (xy 151.132989 -77.342167)
			(xy 151.149057 -77.395574) (xy 151.157177 -77.45075) (xy 151.157686 -77.478636) (xy 151.157177 -77.506522)
			(xy 151.149057 -77.561698) (xy 151.132989 -77.615105) (xy 151.109317 -77.665602) (xy 151.078544 -77.712115)
			(xy 151.041327 -77.753652) (xy 150.998459 -77.789327) (xy 150.950853 -77.818381) (xy 150.899524 -77.840193)
			(xy 150.845567 -77.854299) (xy 150.79013 -77.860399) (xy 150.734396 -77.858362) (xy 150.679553 -77.848232)
			(xy 150.626769 -77.830225) (xy 150.577169 -77.804724) (xy 150.531811 -77.772273) (xy 150.491662 -77.733564)
			(xy 150.457576 -77.689421) (xy 150.43028 -77.640786) (xy 150.410357 -77.588695) (xy 150.398231 -77.534258)
			(xy 150.39416 -77.478636) (xy 149.887686 -77.478636) (xy 149.887177 -77.506522) (xy 149.879057 -77.561698)
			(xy 149.862989 -77.615105) (xy 149.839317 -77.665602) (xy 149.808544 -77.712115) (xy 149.771327 -77.753652)
			(xy 149.728459 -77.789327) (xy 149.680853 -77.818381) (xy 149.629524 -77.840193) (xy 149.575567 -77.854299)
			(xy 149.52013 -77.860399) (xy 149.464396 -77.858362) (xy 149.409553 -77.848232) (xy 149.356769 -77.830225)
			(xy 149.307169 -77.804724) (xy 149.261811 -77.772273) (xy 149.221662 -77.733564) (xy 149.187576 -77.689421)
			(xy 149.16028 -77.640786) (xy 149.140357 -77.588695) (xy 149.128231 -77.534258) (xy 149.12416 -77.478636)
			(xy 129.071624 -77.478636) (xy 129.071624 -78.455774) (xy 148.356318 -78.455774) (xy 148.360389 -78.400152)
			(xy 148.372515 -78.345715) (xy 148.392438 -78.293624) (xy 148.419734 -78.244989) (xy 148.45382 -78.200846)
			(xy 148.493969 -78.162137) (xy 148.539327 -78.129686) (xy 148.588927 -78.104185) (xy 148.641711 -78.086178)
			(xy 148.696554 -78.076048) (xy 148.752288 -78.074011) (xy 148.807725 -78.080111) (xy 148.861682 -78.094217)
			(xy 148.913011 -78.116029) (xy 148.960617 -78.145083) (xy 149.003485 -78.180758) (xy 149.040702 -78.222295)
			(xy 149.071475 -78.268808) (xy 149.095147 -78.319305) (xy 149.111215 -78.372712) (xy 149.119335 -78.427888)
			(xy 149.119844 -78.455774) (xy 149.119348 -78.482952) (xy 150.037036 -78.482952) (xy 150.041107 -78.42733)
			(xy 150.053233 -78.372893) (xy 150.073156 -78.320802) (xy 150.100452 -78.272167) (xy 150.134538 -78.228024)
			(xy 150.174687 -78.189315) (xy 150.220045 -78.156864) (xy 150.269645 -78.131363) (xy 150.322429 -78.113356)
			(xy 150.377272 -78.103226) (xy 150.433006 -78.101189) (xy 150.488443 -78.107289) (xy 150.5424 -78.121395)
			(xy 150.593729 -78.143207) (xy 150.641335 -78.172261) (xy 150.684203 -78.207936) (xy 150.72142 -78.249473)
			(xy 150.752193 -78.295986) (xy 150.775865 -78.346483) (xy 150.791933 -78.39989) (xy 150.800053 -78.455066)
			(xy 150.800562 -78.482952) (xy 150.800053 -78.510838) (xy 150.791933 -78.566014) (xy 150.775865 -78.619421)
			(xy 150.752193 -78.669918) (xy 150.72142 -78.716431) (xy 150.684203 -78.757968) (xy 150.641335 -78.793643)
			(xy 150.593729 -78.822697) (xy 150.5424 -78.844509) (xy 150.488443 -78.858615) (xy 150.433006 -78.864715)
			(xy 150.377272 -78.862678) (xy 150.322429 -78.852548) (xy 150.269645 -78.834541) (xy 150.220045 -78.80904)
			(xy 150.174687 -78.776589) (xy 150.134538 -78.73788) (xy 150.100452 -78.693737) (xy 150.073156 -78.645102)
			(xy 150.053233 -78.593011) (xy 150.041107 -78.538574) (xy 150.037036 -78.482952) (xy 149.119348 -78.482952)
			(xy 149.119335 -78.48366) (xy 149.111215 -78.538836) (xy 149.095147 -78.592243) (xy 149.071475 -78.64274)
			(xy 149.040702 -78.689253) (xy 149.003485 -78.73079) (xy 148.960617 -78.766465) (xy 148.913011 -78.795519)
			(xy 148.861682 -78.817331) (xy 148.807725 -78.831437) (xy 148.752288 -78.837537) (xy 148.696554 -78.8355)
			(xy 148.641711 -78.82537) (xy 148.588927 -78.807363) (xy 148.539327 -78.781862) (xy 148.493969 -78.749411)
			(xy 148.45382 -78.710702) (xy 148.419734 -78.666559) (xy 148.392438 -78.617924) (xy 148.372515 -78.565833)
			(xy 148.360389 -78.511396) (xy 148.356318 -78.455774) (xy 129.071624 -78.455774) (xy 129.071624 -79.08072)
			(xy 146.087926 -79.08072) (xy 146.095675 -79.026347) (xy 146.111138 -78.973647) (xy 146.133997 -78.923709)
			(xy 146.163779 -78.877563) (xy 146.199869 -78.836164) (xy 146.241522 -78.800367) (xy 146.287876 -78.770911)
			(xy 146.337975 -78.748404) (xy 146.390782 -78.733313) (xy 146.445208 -78.725948) (xy 146.500127 -78.726462)
			(xy 146.554406 -78.734845) (xy 146.606921 -78.750922) (xy 146.65659 -78.774362) (xy 146.702385 -78.804681)
			(xy 146.74336 -78.841252) (xy 146.778669 -78.88332) (xy 146.807582 -78.930015) (xy 146.829502 -78.980372)
			(xy 146.843976 -79.033353) (xy 146.847814 -79.060548) (xy 146.851208 -79.083522) (xy 146.865156 -79.127809)
			(xy 146.886925 -79.168822) (xy 146.915789 -79.205193) (xy 146.950785 -79.235708) (xy 146.990747 -79.259351)
			(xy 147.034342 -79.275333) (xy 147.080117 -79.28312) (xy 147.103338 -79.283306) (xy 147.108418 -79.283306)
			(xy 147.131406 -79.282812) (xy 147.176628 -79.274506) (xy 147.219619 -79.258205) (xy 147.258978 -79.23444)
			(xy 147.293423 -79.203985) (xy 147.321831 -79.167834) (xy 147.343276 -79.127163) (xy 147.357059 -79.0833)
			(xy 147.360386 -79.060548) (xy 147.364338 -79.032586) (xy 147.379459 -78.978176) (xy 147.402435 -78.92659)
			(xy 147.432764 -78.878953) (xy 147.469783 -78.836308) (xy 147.512684 -78.799586) (xy 147.56053 -78.769588)
			(xy 147.612275 -78.746971) (xy 147.666788 -78.732228) (xy 147.722879 -78.725682) (xy 147.779322 -78.727476)
			(xy 147.834885 -78.737569) (xy 147.888352 -78.755743) (xy 147.938556 -78.7816) (xy 147.984401 -78.814574)
			(xy 148.024884 -78.853947) (xy 148.059122 -78.898856) (xy 148.086365 -78.948322) (xy 148.10602 -79.001263)
			(xy 148.117655 -79.056523) (xy 148.119846 -79.084678) (xy 148.121659 -79.106757) (xy 148.131887 -79.149853)
			(xy 148.149436 -79.190522) (xy 148.173775 -79.227529) (xy 148.204165 -79.259753) (xy 148.239685 -79.286216)
			(xy 148.279257 -79.306115) (xy 148.321681 -79.318847) (xy 148.34362 -79.321914) (xy 148.370943 -79.32569)
			(xy 148.424209 -79.340003) (xy 148.474858 -79.361838) (xy 148.521835 -79.390739) (xy 148.56416 -79.426104)
			(xy 148.600951 -79.467196) (xy 148.631442 -79.513157) (xy 148.654995 -79.56303) (xy 148.671121 -79.615775)
			(xy 148.679484 -79.670293) (xy 148.679908 -79.725447) (xy 148.672385 -79.780087) (xy 148.657072 -79.833074)
			(xy 148.634288 -79.883303) (xy 148.604509 -79.929728) (xy 148.568354 -79.97138) (xy 148.526577 -80.007392)
			(xy 148.480051 -80.037013) (xy 148.429743 -80.059624) (xy 148.376704 -80.074755) (xy 148.322039 -80.08209)
			(xy 148.266887 -80.081477) (xy 148.212398 -80.072928) (xy 148.159709 -80.056621) (xy 148.109917 -80.032896)
			(xy 148.06406 -80.002248) (xy 148.023095 -79.965316) (xy 147.987875 -79.92287) (xy 147.959136 -79.875794)
			(xy 147.937475 -79.82507) (xy 147.923344 -79.771756) (xy 147.917038 -79.716962) (xy 147.918689 -79.661832)
			(xy 147.922996 -79.634588) (xy 147.925387 -79.617822) (xy 147.922376 -79.584108) (xy 147.910593 -79.552376)
			(xy 147.890871 -79.524867) (xy 147.864601 -79.503521) (xy 147.833638 -79.489846) (xy 147.800167 -79.484806)
			(xy 147.783296 -79.486252) (xy 147.77235 -79.487445) (xy 147.750365 -79.488715) (xy 147.739354 -79.488792)
			(xy 147.716368 -79.489353) (xy 147.67115 -79.497647) (xy 147.62816 -79.513936) (xy 147.588801 -79.537691)
			(xy 147.554355 -79.568137) (xy 147.525945 -79.60428) (xy 147.504499 -79.644944) (xy 147.490714 -79.688801)
			(xy 147.487386 -79.71155) (xy 147.483514 -79.738922) (xy 147.468898 -79.792234) (xy 147.446742 -79.84288)
			(xy 147.41751 -79.889798) (xy 147.381813 -79.932007) (xy 147.3404 -79.968624) (xy 147.294136 -79.998882)
			(xy 147.243991 -80.022147) (xy 147.191013 -80.037934) (xy 147.136312 -80.04591) (xy 147.081032 -80.04591)
			(xy 147.026331 -80.037934) (xy 146.973353 -80.022147) (xy 146.923208 -79.998882) (xy 146.876944 -79.968624)
			(xy 146.835531 -79.932007) (xy 146.799834 -79.889798) (xy 146.770602 -79.84288) (xy 146.748446 -79.792234)
			(xy 146.73383 -79.738922) (xy 146.729958 -79.71155) (xy 146.726593 -79.688571) (xy 146.712643 -79.644281)
			(xy 146.69087 -79.603266) (xy 146.662002 -79.566895) (xy 146.627001 -79.536379) (xy 146.587035 -79.512738)
			(xy 146.543435 -79.496759) (xy 146.497657 -79.488975) (xy 146.474434 -79.488792) (xy 146.44697 -79.488758)
			(xy 146.392511 -79.481645) (xy 146.339634 -79.466798) (xy 146.289432 -79.444523) (xy 146.242942 -79.415281)
			(xy 146.201125 -79.379677) (xy 146.164844 -79.338445) (xy 146.134849 -79.292437) (xy 146.111759 -79.242605)
			(xy 146.096053 -79.189977) (xy 146.088053 -79.135641) (xy 146.087926 -79.08072) (xy 129.071624 -79.08072)
			(xy 129.071624 -79.707994) (xy 130.480943 -81.11744) (xy 149.98014 -81.11744) (xy 149.984211 -81.061818)
			(xy 149.996337 -81.007381) (xy 150.01626 -80.95529) (xy 150.043556 -80.906655) (xy 150.077642 -80.862512)
			(xy 150.117791 -80.823803) (xy 150.163149 -80.791352) (xy 150.212749 -80.765851) (xy 150.265533 -80.747844)
			(xy 150.320376 -80.737714) (xy 150.37611 -80.735677) (xy 150.431547 -80.741777) (xy 150.485504 -80.755883)
			(xy 150.536833 -80.777695) (xy 150.584439 -80.806749) (xy 150.627307 -80.842424) (xy 150.664524 -80.883961)
			(xy 150.695297 -80.930474) (xy 150.718969 -80.980971) (xy 150.735037 -81.034378) (xy 150.743157 -81.089554)
			(xy 150.743666 -81.11744) (xy 150.743157 -81.145326) (xy 150.735037 -81.200502) (xy 150.718969 -81.253909)
			(xy 150.695297 -81.304406) (xy 150.664524 -81.350919) (xy 150.627307 -81.392456) (xy 150.584439 -81.428131)
			(xy 150.536833 -81.457185) (xy 150.485504 -81.478997) (xy 150.431547 -81.493103) (xy 150.37611 -81.499203)
			(xy 150.320376 -81.497166) (xy 150.265533 -81.487036) (xy 150.212749 -81.469029) (xy 150.163149 -81.443528)
			(xy 150.117791 -81.411077) (xy 150.077642 -81.372368) (xy 150.043556 -81.328225) (xy 150.01626 -81.27959)
			(xy 149.996337 -81.227499) (xy 149.984211 -81.173062) (xy 149.98014 -81.11744) (xy 130.480943 -81.11744)
			(xy 131.892294 -82.528918) (xy 131.904425 -82.540384) (xy 131.933302 -82.557106) (xy 131.965526 -82.565775)
			(xy 131.98221 -82.566256)
		)
		(stroke
			(width 0)
			(type solid)
		)
		(fill yes)
		(layer "In7.Cu")
		(net "P1V8_NODE1")
	)
	(gr_poly
		(pts
			(xy 15.030196 -127.916178) (xy 15.052097 -127.91572) (xy 15.09525 -127.908212) (xy 15.136478 -127.893417)
			(xy 15.174559 -127.871774) (xy 15.208365 -127.843923) (xy 15.236898 -127.810689) (xy 15.25931 -127.773056)
			(xy 15.274939 -127.732137) (xy 15.283323 -127.689146) (xy 15.284196 -127.667258) (xy 15.285111 -127.642265)
			(xy 15.292637 -127.592822) (xy 15.306549 -127.544783) (xy 15.326609 -127.49897) (xy 15.352472 -127.456164)
			(xy 15.367762 -127.436372) (xy 15.378017 -127.422622) (xy 15.391499 -127.391096) (xy 15.396107 -127.357119)
			(xy 15.391509 -127.323141) (xy 15.378037 -127.29161) (xy 15.367762 -127.277876) (xy 15.350534 -127.255513)
			(xy 15.322164 -127.206709) (xy 15.301295 -127.154257) (xy 15.288383 -127.099303) (xy 15.28371 -127.043046)
			(xy 15.287377 -126.986714) (xy 15.299304 -126.931538) (xy 15.319232 -126.878722) (xy 15.346724 -126.829418)
			(xy 15.381182 -126.784704) (xy 15.421852 -126.745555) (xy 15.467846 -126.712826) (xy 15.518162 -126.687232)
			(xy 15.571699 -126.669332) (xy 15.62729 -126.659515) (xy 15.68372 -126.657997) (xy 15.739758 -126.664811)
			(xy 15.79418 -126.679808) (xy 15.845799 -126.70266) (xy 15.893486 -126.732868) (xy 15.936202 -126.769774)
			(xy 15.973014 -126.812571) (xy 16.003117 -126.860326) (xy 16.014954 -126.885954) (xy 16.024091 -126.905567)
			(xy 16.048019 -126.941614) (xy 16.077705 -126.973088) (xy 16.112292 -126.999082) (xy 16.15078 -127.018843)
			(xy 16.192059 -127.031802) (xy 16.234937 -127.037585) (xy 16.278174 -127.036023) (xy 16.299434 -127.032004)
			(xy 16.327003 -127.02671) (xy 16.383038 -127.023324) (xy 16.438964 -127.028187) (xy 16.493573 -127.041193)
			(xy 16.545687 -127.062062) (xy 16.59418 -127.090344) (xy 16.638004 -127.125427) (xy 16.676213 -127.166553)
			(xy 16.707983 -127.212836) (xy 16.732626 -127.263274) (xy 16.749612 -127.31678) (xy 16.758572 -127.372197)
			(xy 16.759314 -127.428329) (xy 16.751822 -127.483964) (xy 16.744442 -127.511048) (xy 16.738416 -127.533804)
			(xy 16.733928 -127.580659) (xy 16.738143 -127.627539) (xy 16.750917 -127.672841) (xy 16.771812 -127.715018)
			(xy 16.800115 -127.752627) (xy 16.834859 -127.784382) (xy 16.874855 -127.809198) (xy 16.918736 -127.826227)
			(xy 16.965001 -127.834886) (xy 16.988536 -127.835406) (xy 20.151852 -127.835406) (xy 20.266152 -127.760222)
			(xy 20.281392 -127.731774) (xy 20.295275 -127.706843) (xy 20.329304 -127.661038) (xy 20.369773 -127.620811)
			(xy 20.41578 -127.587058) (xy 20.466301 -127.560531) (xy 20.520209 -127.541823) (xy 20.576301 -127.53135)
			(xy 20.633327 -127.529345) (xy 20.690016 -127.535854) (xy 20.745104 -127.550732) (xy 20.797362 -127.573646)
			(xy 20.845626 -127.604086) (xy 20.88882 -127.641372) (xy 20.92598 -127.684675) (xy 20.956278 -127.733028)
			(xy 20.968208 -127.758952) (xy 20.968208 -127.759206) (xy 20.974506 -127.77256) (xy 20.992226 -127.796166)
			(xy 21.014896 -127.815068) (xy 21.041304 -127.828253) (xy 21.070035 -127.835016) (xy 21.084794 -127.835406)
			(xy 21.397214 -127.835406) (xy 21.418662 -127.834958) (xy 21.460947 -127.827748) (xy 21.50142 -127.813534)
			(xy 21.538928 -127.792722) (xy 21.572406 -127.765903) (xy 21.600901 -127.73384) (xy 21.623604 -127.697444)
			(xy 21.639867 -127.657751) (xy 21.64923 -127.61589) (xy 21.651425 -127.57305) (xy 21.649436 -127.551688)
			(xy 21.646882 -127.526183) (xy 21.647815 -127.474933) (xy 21.655594 -127.424268) (xy 21.670079 -127.375099)
			(xy 21.68017 -127.351536) (xy 21.692325 -127.3257) (xy 21.723161 -127.277647) (xy 21.760805 -127.234719)
			(xy 21.782278 -127.2159) (xy 21.798335 -127.201043) (xy 21.825599 -127.166835) (xy 21.846598 -127.128462)
			(xy 21.860711 -127.087059) (xy 21.867522 -127.043849) (xy 21.866828 -127.000112) (xy 21.85865 -126.95714)
			(xy 21.84323 -126.916205) (xy 21.821025 -126.878517) (xy 21.79269 -126.845191) (xy 21.776182 -126.830836)
			(xy 21.767739 -126.823693) (xy 21.751601 -126.80857) (xy 21.743924 -126.80061) (xy 21.727414 -126.783084)
			(xy 21.688044 -126.764796) (xy 21.674798 -126.759096) (xy 21.646579 -126.753193) (xy 21.617754 -126.753793)
			(xy 21.589805 -126.760867) (xy 21.576792 -126.767082) (xy 21.53031 -126.790958) (xy 21.513546 -126.811532)
			(xy 21.495829 -126.83247) (xy 21.455406 -126.86954) (xy 21.410091 -126.90044) (xy 21.360818 -126.924531)
			(xy 21.308603 -126.941317) (xy 21.254522 -126.950453) (xy 21.19969 -126.951749) (xy 21.145238 -126.94518)
			(xy 21.092288 -126.93088) (xy 21.041931 -126.909144) (xy 20.995206 -126.880421) (xy 20.953077 -126.845303)
			(xy 20.916411 -126.804513) (xy 20.885964 -126.758892) (xy 20.862365 -126.709382) (xy 20.8461 -126.657002)
			(xy 20.837503 -126.602833) (xy 20.836753 -126.54799) (xy 20.843864 -126.493606) (xy 20.858691 -126.440801)
			(xy 20.880927 -126.390664) (xy 20.910114 -126.344227) (xy 20.945651 -126.30245) (xy 20.965922 -126.283974)
			(xy 20.982179 -126.268999) (xy 21.009766 -126.234471) (xy 21.030967 -126.195693) (xy 21.045143 -126.153833)
			(xy 21.051867 -126.110152) (xy 21.050936 -126.065966) (xy 21.042379 -126.022607) (xy 21.026453 -125.981381)
			(xy 21.003638 -125.94353) (xy 20.974622 -125.910194) (xy 20.957794 -125.895862) (xy 20.936976 -125.878417)
			(xy 20.900008 -125.838628) (xy 20.869057 -125.793998) (xy 20.844749 -125.745429) (xy 20.827575 -125.693903)
			(xy 20.817884 -125.640462) (xy 20.81587 -125.586187) (xy 20.821575 -125.532175) (xy 20.834883 -125.479518)
			(xy 20.855526 -125.429281) (xy 20.883085 -125.38248) (xy 20.899628 -125.360938) (xy 20.909881 -125.347189)
			(xy 20.923358 -125.315666) (xy 20.927959 -125.281692) (xy 20.923354 -125.247719) (xy 20.909873 -125.216197)
			(xy 20.899628 -125.202442) (xy 20.882163 -125.17978) (xy 20.853508 -125.130261) (xy 20.832569 -125.077017)
			(xy 20.819815 -125.021244) (xy 20.815533 -124.964192) (xy 20.819818 -124.90714) (xy 20.832574 -124.851368)
			(xy 20.853515 -124.798125) (xy 20.882172 -124.748607) (xy 20.899628 -124.725938) (xy 20.909881 -124.712189)
			(xy 20.923358 -124.680666) (xy 20.927959 -124.646692) (xy 20.923354 -124.612719) (xy 20.909873 -124.581197)
			(xy 20.899628 -124.567442) (xy 20.882626 -124.545366) (xy 20.854532 -124.497248) (xy 20.833735 -124.445555)
			(xy 20.82068 -124.391387) (xy 20.815643 -124.335895) (xy 20.818732 -124.280262) (xy 20.829881 -124.225669)
			(xy 20.848853 -124.173279) (xy 20.875244 -124.124206) (xy 20.908493 -124.079494) (xy 20.947892 -124.040095)
			(xy 20.992604 -124.006845) (xy 21.041676 -123.980454) (xy 21.094066 -123.961482) (xy 21.148659 -123.950332)
			(xy 21.204292 -123.947243) (xy 21.259784 -123.952279) (xy 21.313952 -123.965334) (xy 21.365645 -123.98613)
			(xy 21.413763 -124.014225) (xy 21.435822 -124.031248) (xy 21.47062 -124.058934) (xy 21.55952 -124.058934)
			(xy 21.594318 -124.031248) (xy 21.615218 -124.015107) (xy 21.660614 -123.988128) (xy 21.709296 -123.967668)
			(xy 21.760335 -123.954117) (xy 21.812755 -123.947735) (xy 21.865555 -123.948643) (xy 21.917724 -123.956825)
			(xy 21.968267 -123.972123) (xy 22.016217 -123.994246) (xy 22.060657 -124.02277) (xy 22.080982 -124.03963)
			(xy 22.092656 -124.049106) (xy 22.119409 -124.062809) (xy 22.14863 -124.069858) (xy 22.178688 -124.069858)
			(xy 22.207909 -124.062809) (xy 22.234662 -124.049106) (xy 22.246336 -124.03963) (xy 22.26805 -124.021633)
			(xy 22.315764 -123.991566) (xy 22.367385 -123.968853) (xy 22.421788 -123.953988) (xy 22.477786 -123.947294)
			(xy 22.53416 -123.948919) (xy 22.58968 -123.958826) (xy 22.643136 -123.976799) (xy 22.693363 -124.002447)
			(xy 22.739267 -124.035211) (xy 22.779846 -124.074377) (xy 22.814217 -124.11909) (xy 22.841629 -124.168377)
			(xy 22.861486 -124.221162) (xy 22.873355 -124.276296) (xy 22.876976 -124.332577) (xy 22.872272 -124.388777)
			(xy 22.859344 -124.443673) (xy 22.838475 -124.496066) (xy 22.810118 -124.544816) (xy 22.792944 -124.567188)
			(xy 22.765258 -124.601986) (xy 22.765258 -124.690886) (xy 22.792944 -124.725684) (xy 22.810408 -124.748345)
			(xy 22.839061 -124.797864) (xy 22.859998 -124.851106) (xy 22.872749 -124.906878) (xy 22.877029 -124.963928)
			(xy 22.872741 -125.020978) (xy 22.859982 -125.076748) (xy 22.852801 -125.095) (xy 27.056586 -125.095)
			(xy 27.060657 -125.039378) (xy 27.072783 -124.984941) (xy 27.092706 -124.93285) (xy 27.120002 -124.884215)
			(xy 27.154088 -124.840072) (xy 27.194237 -124.801363) (xy 27.239595 -124.768912) (xy 27.289195 -124.743411)
			(xy 27.341979 -124.725404) (xy 27.396822 -124.715274) (xy 27.452556 -124.713237) (xy 27.507993 -124.719337)
			(xy 27.56195 -124.733443) (xy 27.613279 -124.755255) (xy 27.660885 -124.784309) (xy 27.703753 -124.819984)
			(xy 27.74097 -124.861521) (xy 27.771743 -124.908034) (xy 27.795415 -124.958531) (xy 27.811483 -125.011938)
			(xy 27.819603 -125.067114) (xy 27.820112 -125.095) (xy 27.819603 -125.122886) (xy 27.811483 -125.178062)
			(xy 27.795415 -125.231469) (xy 27.771743 -125.281966) (xy 27.74097 -125.328479) (xy 27.703753 -125.370016)
			(xy 27.660885 -125.405691) (xy 27.613279 -125.434745) (xy 27.56195 -125.456557) (xy 27.507993 -125.470663)
			(xy 27.452556 -125.476763) (xy 27.396822 -125.474726) (xy 27.341979 -125.464596) (xy 27.289195 -125.446589)
			(xy 27.239595 -125.421088) (xy 27.194237 -125.388637) (xy 27.154088 -125.349928) (xy 27.120002 -125.305785)
			(xy 27.092706 -125.25715) (xy 27.072783 -125.205059) (xy 27.060657 -125.150622) (xy 27.056586 -125.095)
			(xy 22.852801 -125.095) (xy 22.839037 -125.129987) (xy 22.810376 -125.179501) (xy 22.792944 -125.202188)
			(xy 22.765258 -125.236986) (xy 22.765258 -125.325886) (xy 22.792944 -125.360684) (xy 22.810153 -125.383018)
			(xy 22.838498 -125.431756) (xy 22.859362 -125.484134) (xy 22.872289 -125.539013) (xy 22.876999 -125.595197)
			(xy 22.873388 -125.651463) (xy 22.861535 -125.706584) (xy 22.841699 -125.75936) (xy 22.814312 -125.808643)
			(xy 22.779969 -125.853357) (xy 22.73942 -125.892531) (xy 22.693546 -125.92531) (xy 22.643348 -125.95098)
			(xy 22.589918 -125.968983) (xy 22.534421 -125.978926) (xy 22.478065 -125.980592) (xy 22.422077 -125.973946)
			(xy 22.367677 -125.959133) (xy 22.316049 -125.936474) (xy 22.268319 -125.906463) (xy 22.24659 -125.888496)
			(xy 22.234897 -125.879065) (xy 22.208134 -125.865436) (xy 22.17893 -125.858428) (xy 22.148896 -125.858428)
			(xy 22.119692 -125.865436) (xy 22.092929 -125.879065) (xy 22.081236 -125.888496) (xy 22.068983 -125.898768)
			(xy 22.043042 -125.917462) (xy 22.02942 -125.925834) (xy 22.016306 -125.93428) (xy 21.994321 -125.956395)
			(xy 21.978357 -125.983183) (xy 21.969371 -126.013044) (xy 21.967898 -126.044193) (xy 21.974026 -126.074769)
			(xy 21.98739 -126.102945) (xy 22.00719 -126.127036) (xy 22.032244 -126.145603) (xy 22.061054 -126.157536)
			(xy 22.07641 -126.160276) (xy 22.103284 -126.164742) (xy 22.155491 -126.180299) (xy 22.204954 -126.203125)
			(xy 22.250666 -126.232757) (xy 22.291697 -126.26859) (xy 22.327213 -126.309897) (xy 22.35649 -126.355837)
			(xy 22.378934 -126.405475) (xy 22.394086 -126.457801) (xy 22.40164 -126.511751) (xy 22.401442 -126.566226)
			(xy 22.393495 -126.62012) (xy 22.377961 -126.672334) (xy 22.355156 -126.721807) (xy 22.325545 -126.767532)
			(xy 22.289729 -126.808579) (xy 22.26945 -126.826772) (xy 22.25307 -126.841527) (xy 22.225166 -126.875653)
			(xy 22.203574 -126.914085) (xy 22.18894 -126.955667) (xy 22.181705 -126.999151) (xy 22.182086 -127.043231)
			(xy 22.190072 -127.086583) (xy 22.205422 -127.127906) (xy 22.227676 -127.165958) (xy 22.256166 -127.199597)
			(xy 22.272752 -127.214122) (xy 22.293238 -127.231817) (xy 22.329499 -127.272012) (xy 22.359713 -127.316929)
			(xy 22.383272 -127.365666) (xy 22.399705 -127.417245) (xy 22.40868 -127.470629) (xy 22.410017 -127.524746)
			(xy 22.407372 -127.551688) (xy 22.405306 -127.573042) (xy 22.407517 -127.615883) (xy 22.416893 -127.657743)
			(xy 22.433168 -127.697434) (xy 22.455881 -127.733825) (xy 22.484384 -127.765884) (xy 22.517868 -127.792699)
			(xy 22.555381 -127.813507) (xy 22.595857 -127.827717) (xy 22.638145 -127.834925) (xy 22.659594 -127.835406)
			(xy 27.406346 -127.835406) (xy 27.428895 -127.834915) (xy 27.473285 -127.82695) (xy 27.515573 -127.811279)
			(xy 27.554434 -127.788393) (xy 27.588647 -127.75901) (xy 27.617139 -127.724052) (xy 27.639017 -127.684615)
			(xy 27.653594 -127.641937) (xy 27.660413 -127.597357) (xy 27.660346 -127.574802) (xy 27.660051 -127.548792)
			(xy 27.665664 -127.49708) (xy 27.678259 -127.446613) (xy 27.697604 -127.398328) (xy 27.723337 -127.353124)
			(xy 27.738832 -127.332232) (xy 27.75077 -127.316992) (xy 27.780234 -127.23622) (xy 27.753056 -127.158242)
			(xy 27.742134 -127.143256) (xy 27.725579 -127.119617) (xy 27.699027 -127.068379) (xy 27.6805 -127.013725)
			(xy 27.67042 -126.956903) (xy 27.669017 -126.899211) (xy 27.676324 -126.841966) (xy 27.692173 -126.786476)
			(xy 27.716202 -126.734008) (xy 27.747863 -126.685759) (xy 27.766772 -126.663958) (xy 27.78125 -126.647702)
			(xy 27.817826 -126.559564) (xy 27.783536 -126.473712) (xy 27.76982 -126.45771) (xy 27.75221 -126.436387)
			(xy 27.722685 -126.389628) (xy 27.700219 -126.339096) (xy 27.685282 -126.285851) (xy 27.678189 -126.231007)
			(xy 27.679087 -126.175714) (xy 27.687958 -126.121129) (xy 27.704616 -126.068397) (xy 27.728711 -126.018622)
			(xy 27.75974 -125.972847) (xy 27.797052 -125.93203) (xy 27.839865 -125.897027) (xy 27.887282 -125.868571)
			(xy 27.938311 -125.847259) (xy 27.991882 -125.833536) (xy 28.046873 -125.82769) (xy 28.102132 -125.829844)
			(xy 28.1565 -125.839952) (xy 28.208841 -125.857804) (xy 28.258056 -125.883023) (xy 28.280868 -125.898656)
			(xy 28.29945 -125.911291) (xy 28.340068 -125.930502) (xy 28.383431 -125.942274) (xy 28.428188 -125.946238)
			(xy 28.472945 -125.942274) (xy 28.516308 -125.930502) (xy 28.556926 -125.911291) (xy 28.575508 -125.898656)
			(xy 28.598346 -125.883004) (xy 28.647615 -125.85775) (xy 28.700017 -125.839883) (xy 28.754451 -125.829776)
			(xy 28.809775 -125.827642) (xy 28.864825 -125.833526) (xy 28.918448 -125.847304) (xy 28.969516 -125.868688)
			(xy 29.016958 -125.897227) (xy 29.059777 -125.932323) (xy 29.097075 -125.973239) (xy 29.128067 -126.019116)
			(xy 29.152104 -126.068991) (xy 29.168681 -126.121815) (xy 29.177449 -126.176481) (xy 29.178225 -126.23184)
			(xy 29.170992 -126.28673) (xy 29.155902 -126.339998) (xy 29.133272 -126.390527) (xy 29.103577 -126.437254)
			(xy 29.085794 -126.458472) (xy 29.072078 -126.474474) (xy 29.03728 -126.56058) (xy 29.067506 -126.642114)
			(xy 29.079444 -126.657608) (xy 29.0957 -126.679289) (xy 29.122576 -126.726342) (xy 29.142528 -126.776724)
			(xy 29.155154 -126.82942) (xy 29.1602 -126.883373) (xy 29.157566 -126.937497) (xy 29.147303 -126.990705)
			(xy 29.129619 -127.041926) (xy 29.104868 -127.090132) (xy 29.089604 -127.112522) (xy 29.078936 -127.127508)
			(xy 29.05252 -127.204216) (xy 29.081222 -127.283972) (xy 29.092652 -127.299212) (xy 29.11173 -127.325775)
			(xy 29.141476 -127.384014) (xy 29.151834 -127.415036) (xy 29.158709 -127.43569) (xy 29.178501 -127.474458)
			(xy 29.204611 -127.509286) (xy 29.236275 -127.539153) (xy 29.272566 -127.563187) (xy 29.312423 -127.580684)
			(xy 29.354678 -127.591131) (xy 29.398096 -127.594224) (xy 29.441406 -127.589872) (xy 29.48334 -127.578201)
			(xy 29.522671 -127.559554) (xy 29.558249 -127.534476) (xy 29.573982 -127.51943) (xy 31.37408 -125.719332)
			(xy 32.586168 -125.719332) (xy 32.608615 -125.718848) (xy 32.652809 -125.710949) (xy 32.694928 -125.695409)
			(xy 32.733661 -125.672711) (xy 32.767805 -125.643561) (xy 32.796296 -125.608866) (xy 32.818249 -125.569705)
			(xy 32.83298 -125.527297) (xy 32.840032 -125.48296) (xy 32.840168 -125.460506) (xy 32.840105 -125.433198)
			(xy 32.84684 -125.379008) (xy 32.861233 -125.326331) (xy 32.88299 -125.276245) (xy 32.911665 -125.229773)
			(xy 32.946674 -125.187864) (xy 32.9873 -125.151375) (xy 33.032714 -125.121051) (xy 33.081988 -125.097512)
			(xy 33.134114 -125.081239) (xy 33.188028 -125.072564) (xy 33.242628 -125.071665) (xy 33.296798 -125.078561)
			(xy 33.349432 -125.093109) (xy 33.399454 -125.115013) (xy 33.445841 -125.143826) (xy 33.46704 -125.16104)
			(xy 33.479394 -125.17078) (xy 33.50771 -125.184462) (xy 33.538515 -125.190798) (xy 33.569933 -125.1894)
			(xy 33.600053 -125.180354) (xy 33.627042 -125.16421) (xy 33.63849 -125.15342) (xy 39.497 -119.29491)
			(xy 39.497 -117.487954) (xy 38.91026 -116.901214) (xy 38.893211 -116.884915) (xy 38.854271 -116.858308)
			(xy 38.811095 -116.839333) (xy 38.765161 -116.828639) (xy 38.718044 -116.826594) (xy 38.671356 -116.833267)
			(xy 38.626698 -116.84843) (xy 38.585599 -116.871563) (xy 38.549468 -116.901874) (xy 38.534086 -116.919756)
			(xy 38.51615 -116.940889) (xy 38.475209 -116.978253) (xy 38.42929 -117.009296) (xy 38.379362 -117.033367)
			(xy 38.326476 -117.049958) (xy 38.271745 -117.058719) (xy 38.216322 -117.059466) (xy 38.161375 -117.052183)
			(xy 38.108061 -117.037024) (xy 38.057502 -117.014307) (xy 38.010764 -116.984512) (xy 37.96883 -116.948266)
			(xy 37.932584 -116.906332) (xy 37.90279 -116.859593) (xy 37.880074 -116.809034) (xy 37.864916 -116.755719)
			(xy 37.857634 -116.700772) (xy 37.858382 -116.645349) (xy 37.867143 -116.590619) (xy 37.883735 -116.537733)
			(xy 37.907806 -116.487805) (xy 37.938851 -116.441887) (xy 37.976215 -116.400946) (xy 37.997384 -116.383054)
			(xy 38.015313 -116.36771) (xy 38.045681 -116.331597) (xy 38.068859 -116.290498) (xy 38.08405 -116.245825)
			(xy 38.090731 -116.199116) (xy 38.088672 -116.151976) (xy 38.077945 -116.106027) (xy 38.058917 -116.062849)
			(xy 38.032244 -116.023927) (xy 38.015926 -116.00688) (xy 36.564316 -114.555016) (xy 36.564316 -113.165128)
			(xy 35.724084 -112.324896) (xy 35.707681 -112.309202) (xy 35.670391 -112.28332) (xy 35.629097 -112.264474)
			(xy 35.585111 -112.253263) (xy 35.539834 -112.250045) (xy 35.494705 -112.254921) (xy 35.45116 -112.267737)
			(xy 35.410584 -112.288085) (xy 35.392106 -112.301274) (xy 35.369767 -112.317443) (xy 35.321364 -112.343864)
			(xy 35.269661 -112.363042) (xy 35.215736 -112.374576) (xy 35.160713 -112.378227) (xy 35.105737 -112.373917)
			(xy 35.051954 -112.361738) (xy 35.000484 -112.341943) (xy 34.952401 -112.314944) (xy 34.908706 -112.281304)
			(xy 34.870309 -112.241723) (xy 34.838011 -112.197027) (xy 34.812484 -112.148146) (xy 34.79426 -112.0961)
			(xy 34.783719 -112.041972) (xy 34.78108 -111.986891) (xy 34.786399 -111.932003) (xy 34.799565 -111.878453)
			(xy 34.820303 -111.827357) (xy 34.848181 -111.779778) (xy 34.865056 -111.757968) (xy 34.875311 -111.744218)
			(xy 34.888793 -111.712692) (xy 34.8934 -111.678716) (xy 34.888801 -111.644738) (xy 34.875327 -111.613209)
			(xy 34.865056 -111.599472) (xy 34.849977 -111.580008) (xy 34.824424 -111.53792) (xy 34.804504 -111.492892)
			(xy 34.790551 -111.445673) (xy 34.786316 -111.421418) (xy 34.779966 -111.380778) (xy 34.40684 -111.007652)
			(xy 34.40684 -107.47375) (xy 34.355532 -107.405932) (xy 34.314638 -107.394248) (xy 34.288363 -107.386296)
			(xy 34.238247 -107.363896) (xy 34.191858 -107.334545) (xy 34.150154 -107.298849) (xy 34.113996 -107.257544)
			(xy 34.084131 -107.211484) (xy 34.061176 -107.16162) (xy 34.045603 -107.10898) (xy 34.037736 -107.054652)
			(xy 34.037735 -106.999758) (xy 34.045601 -106.945429) (xy 34.061172 -106.892789) (xy 34.084127 -106.842924)
			(xy 34.11399 -106.796864) (xy 34.150147 -106.755558) (xy 34.19185 -106.719861) (xy 34.238238 -106.690508)
			(xy 34.288354 -106.668107) (xy 34.314638 -106.660188) (xy 34.355532 -106.648504) (xy 34.40684 -106.580686)
			(xy 34.40684 -103.392732) (xy 34.290254 -103.268526) (xy 34.248344 -103.261414) (xy 34.220711 -103.256201)
			(xy 34.167261 -103.23873) (xy 34.116954 -103.213604) (xy 34.070878 -103.181369) (xy 34.030032 -103.142721)
			(xy 33.995299 -103.098497) (xy 33.967431 -103.049655) (xy 33.947033 -102.997253) (xy 33.934545 -102.942424)
			(xy 33.930238 -102.886357) (xy 33.934206 -102.830264) (xy 33.946362 -102.775361) (xy 33.966442 -102.722836)
			(xy 33.994013 -102.673826) (xy 34.010854 -102.651306) (xy 34.024402 -102.632972) (xy 34.045429 -102.592531)
			(xy 34.058914 -102.548991) (xy 34.064423 -102.503744) (xy 34.061781 -102.458239) (xy 34.051071 -102.413934)
			(xy 34.032638 -102.372247) (xy 34.020252 -102.35311) (xy 34.004407 -102.328825) (xy 33.979459 -102.276482)
			(xy 33.962721 -102.220966) (xy 33.954581 -102.163557) (xy 33.955226 -102.105576) (xy 33.96464 -102.048361)
			(xy 33.982608 -101.993231) (xy 34.008714 -101.941456) (xy 34.042357 -101.89423) (xy 34.062162 -101.87305)
			(xy 34.077098 -101.856959) (xy 34.101765 -101.820646) (xy 34.119831 -101.780636) (xy 34.130759 -101.738119)
			(xy 34.134225 -101.694357) (xy 34.130126 -101.65065) (xy 34.118584 -101.608295) (xy 34.099941 -101.568552)
			(xy 34.074751 -101.532599) (xy 34.059622 -101.516688) (xy 32.24022 -99.697286) (xy 30.329886 -99.697286)
			(xy 30.307296 -99.697778) (xy 30.262827 -99.705765) (xy 30.22047 -99.721486) (xy 30.181559 -99.744446)
			(xy 30.147317 -99.773921) (xy 30.118824 -99.808984) (xy 30.096977 -99.848531) (xy 30.082463 -99.891317)
			(xy 30.075739 -99.935994) (xy 30.077017 -99.981156) (xy 30.08122 -100.003356) (xy 30.086336 -100.03002)
			(xy 30.08986 -100.084199) (xy 30.085668 -100.13833) (xy 30.073845 -100.191321) (xy 30.054629 -100.2421)
			(xy 30.028408 -100.289642) (xy 29.995713 -100.332987) (xy 29.957204 -100.37126) (xy 29.913658 -100.403687)
			(xy 29.865955 -100.429613) (xy 29.815058 -100.448515) (xy 29.761996 -100.460011) (xy 29.70784 -100.463869)
			(xy 29.653684 -100.460011) (xy 29.600622 -100.448515) (xy 29.549725 -100.429613) (xy 29.502022 -100.403687)
			(xy 29.458476 -100.37126) (xy 29.419967 -100.332987) (xy 29.387272 -100.289642) (xy 29.361051 -100.2421)
			(xy 29.341835 -100.191321) (xy 29.330012 -100.13833) (xy 29.32582 -100.084199) (xy 29.329344 -100.03002)
			(xy 29.33446 -100.003356) (xy 29.338609 -99.981147) (xy 29.339905 -99.93599) (xy 29.333194 -99.891315)
			(xy 29.31869 -99.848531) (xy 29.296849 -99.808986) (xy 29.268359 -99.773926) (xy 29.234118 -99.744457)
			(xy 29.195206 -99.721507) (xy 29.152849 -99.705799) (xy 29.108382 -99.69783) (xy 29.085794 -99.697286)
			(xy 27.93492 -99.697286) (xy 27.912334 -99.697783) (xy 27.867875 -99.70578) (xy 27.825529 -99.721506)
			(xy 27.786627 -99.744468) (xy 27.752396 -99.773943) (xy 27.723912 -99.809003) (xy 27.702071 -99.848544)
			(xy 27.687561 -99.891323) (xy 27.680839 -99.935992) (xy 27.682116 -99.981147) (xy 27.686254 -100.003356)
			(xy 27.691545 -100.030951) (xy 27.694916 -100.087036) (xy 27.690024 -100.143009) (xy 27.676976 -100.197659)
			(xy 27.656054 -100.249804) (xy 27.627711 -100.298318) (xy 27.592559 -100.342149) (xy 27.551358 -100.380352)
			(xy 27.505001 -100.412098) (xy 27.454488 -100.436703) (xy 27.400913 -100.453633) (xy 27.345435 -100.462522)
			(xy 27.289253 -100.463179) (xy 27.233581 -100.455589) (xy 27.179625 -100.439916) (xy 27.128552 -100.416499)
			(xy 27.081464 -100.385845) (xy 27.039382 -100.348616) (xy 27.003215 -100.305618) (xy 26.973745 -100.25778)
			(xy 26.95161 -100.206138) (xy 26.937289 -100.151808) (xy 26.93109 -100.095965) (xy 26.93162 -100.067872)
			(xy 26.931931 -100.045186) (xy 26.925479 -100.000281) (xy 26.911159 -99.957234) (xy 26.889427 -99.917412)
			(xy 26.860972 -99.88208) (xy 26.826699 -99.852358) (xy 26.787694 -99.829191) (xy 26.745197 -99.813315)
			(xy 26.700557 -99.805233) (xy 26.677874 -99.804728) (xy 19.811746 -99.804728) (xy 19.09826 -100.518214)
			(xy 19.08272 -100.53439) (xy 19.057024 -100.571153) (xy 19.038186 -100.611858) (xy 19.026792 -100.655239)
			(xy 19.023196 -100.699948) (xy 19.027511 -100.744592) (xy 19.039602 -100.787785) (xy 19.059093 -100.828181)
			(xy 19.071844 -100.846636) (xy 19.088008 -100.869916) (xy 19.114011 -100.920271) (xy 19.132279 -100.973918)
			(xy 19.142409 -101.029678) (xy 19.143667 -101.069902) (xy 20.762212 -101.069902) (xy 20.766283 -101.01428)
			(xy 20.778409 -100.959843) (xy 20.798332 -100.907752) (xy 20.825628 -100.859117) (xy 20.859714 -100.814974)
			(xy 20.899863 -100.776265) (xy 20.945221 -100.743814) (xy 20.994821 -100.718313) (xy 21.047605 -100.700306)
			(xy 21.102448 -100.690176) (xy 21.158182 -100.688139) (xy 21.213619 -100.694239) (xy 21.267576 -100.708345)
			(xy 21.318905 -100.730157) (xy 21.366511 -100.759211) (xy 21.409379 -100.794886) (xy 21.446596 -100.836423)
			(xy 21.477369 -100.882936) (xy 21.499407 -100.929948) (xy 27.682442 -100.929948) (xy 27.686513 -100.874326)
			(xy 27.698639 -100.819889) (xy 27.718562 -100.767798) (xy 27.745858 -100.719163) (xy 27.779944 -100.67502)
			(xy 27.820093 -100.636311) (xy 27.865451 -100.60386) (xy 27.915051 -100.578359) (xy 27.967835 -100.560352)
			(xy 28.022678 -100.550222) (xy 28.078412 -100.548185) (xy 28.133849 -100.554285) (xy 28.187806 -100.568391)
			(xy 28.239135 -100.590203) (xy 28.286741 -100.619257) (xy 28.329609 -100.654932) (xy 28.366826 -100.696469)
			(xy 28.397599 -100.742982) (xy 28.421271 -100.793479) (xy 28.437339 -100.846886) (xy 28.445459 -100.902062)
			(xy 28.445968 -100.929948) (xy 28.445459 -100.957834) (xy 28.437339 -101.01301) (xy 28.421271 -101.066417)
			(xy 28.409124 -101.092329) (xy 30.791187 -101.092329) (xy 30.795184 -101.037185) (xy 30.807098 -100.983196)
			(xy 30.826682 -100.931492) (xy 30.853524 -100.883156) (xy 30.887061 -100.839202) (xy 30.926593 -100.800549)
			(xy 30.97129 -100.768007) (xy 31.020216 -100.742257) (xy 31.072347 -100.72384) (xy 31.12659 -100.713141)
			(xy 31.181809 -100.710384) (xy 31.236848 -100.715626) (xy 31.290554 -100.728759) (xy 31.341802 -100.749507)
			(xy 31.389519 -100.777434) (xy 31.411418 -100.794312) (xy 31.425166 -100.804568) (xy 31.456691 -100.818048)
			(xy 31.490666 -100.822652) (xy 31.524641 -100.818048) (xy 31.556166 -100.804568) (xy 31.569914 -100.794312)
			(xy 31.592575 -100.776845) (xy 31.642095 -100.748187) (xy 31.695338 -100.727245) (xy 31.751112 -100.714489)
			(xy 31.808166 -100.710204) (xy 31.86522 -100.714489) (xy 31.920994 -100.727245) (xy 31.974237 -100.748187)
			(xy 32.023757 -100.776845) (xy 32.046418 -100.794312) (xy 32.060166 -100.804568) (xy 32.091691 -100.818048)
			(xy 32.125666 -100.822652) (xy 32.159641 -100.818048) (xy 32.191166 -100.804568) (xy 32.204914 -100.794312)
			(xy 32.226856 -100.777488) (xy 32.274568 -100.749554) (xy 32.325812 -100.728801) (xy 32.379516 -100.715662)
			(xy 32.434554 -100.710414) (xy 32.489773 -100.713166) (xy 32.544016 -100.72386) (xy 32.596147 -100.742273)
			(xy 32.645074 -100.768019) (xy 32.689773 -100.800558) (xy 32.729305 -100.839208) (xy 32.762844 -100.883161)
			(xy 32.789687 -100.931495) (xy 32.809271 -100.983198) (xy 32.821187 -101.037186) (xy 32.825184 -101.092329)
			(xy 32.821179 -101.147471) (xy 32.809255 -101.201457) (xy 32.789663 -101.253157) (xy 32.762813 -101.301487)
			(xy 32.729267 -101.345435) (xy 32.689729 -101.384079) (xy 32.645026 -101.416612) (xy 32.596095 -101.44235)
			(xy 32.54396 -101.460755) (xy 32.489716 -101.471441) (xy 32.434496 -101.474185) (xy 32.379459 -101.468928)
			(xy 32.325757 -101.455782) (xy 32.274516 -101.43502) (xy 32.226808 -101.40708) (xy 32.204914 -101.390196)
			(xy 32.191166 -101.37994) (xy 32.159641 -101.36646) (xy 32.125666 -101.361856) (xy 32.091691 -101.36646)
			(xy 32.060166 -101.37994) (xy 32.046418 -101.390196) (xy 32.023757 -101.407663) (xy 31.974237 -101.436321)
			(xy 31.920994 -101.457263) (xy 31.86522 -101.470019) (xy 31.808166 -101.474304) (xy 31.751112 -101.470019)
			(xy 31.695338 -101.457263) (xy 31.642095 -101.436321) (xy 31.592575 -101.407663) (xy 31.569914 -101.390196)
			(xy 31.556166 -101.37994) (xy 31.524641 -101.36646) (xy 31.490666 -101.361856) (xy 31.456691 -101.36646)
			(xy 31.425166 -101.37994) (xy 31.411418 -101.390196) (xy 31.389566 -101.407133) (xy 31.341854 -101.435068)
			(xy 31.290609 -101.455823) (xy 31.236905 -101.468964) (xy 31.181867 -101.474215) (xy 31.126647 -101.471466)
			(xy 31.072402 -101.460775) (xy 31.020269 -101.442366) (xy 30.971338 -101.416624) (xy 30.926637 -101.384089)
			(xy 30.887099 -101.345441) (xy 30.853555 -101.301492) (xy 30.826706 -101.25316) (xy 30.807115 -101.201459)
			(xy 30.795192 -101.147472) (xy 30.791187 -101.092329) (xy 28.409124 -101.092329) (xy 28.397599 -101.116914)
			(xy 28.366826 -101.163427) (xy 28.329609 -101.204964) (xy 28.286741 -101.240639) (xy 28.239135 -101.269693)
			(xy 28.187806 -101.291505) (xy 28.133849 -101.305611) (xy 28.078412 -101.311711) (xy 28.022678 -101.309674)
			(xy 27.967835 -101.299544) (xy 27.915051 -101.281537) (xy 27.865451 -101.256036) (xy 27.820093 -101.223585)
			(xy 27.779944 -101.184876) (xy 27.745858 -101.140733) (xy 27.718562 -101.092098) (xy 27.698639 -101.040007)
			(xy 27.686513 -100.98557) (xy 27.682442 -100.929948) (xy 21.499407 -100.929948) (xy 21.501041 -100.933433)
			(xy 21.517109 -100.98684) (xy 21.525229 -101.042016) (xy 21.525738 -101.069902) (xy 21.525229 -101.097788)
			(xy 21.517109 -101.152964) (xy 21.501041 -101.206371) (xy 21.477369 -101.256868) (xy 21.446596 -101.303381)
			(xy 21.409379 -101.344918) (xy 21.366511 -101.380593) (xy 21.318905 -101.409647) (xy 21.267576 -101.431459)
			(xy 21.213619 -101.445565) (xy 21.158182 -101.451665) (xy 21.102448 -101.449628) (xy 21.047605 -101.439498)
			(xy 20.994821 -101.421491) (xy 20.945221 -101.39599) (xy 20.899863 -101.363539) (xy 20.859714 -101.32483)
			(xy 20.825628 -101.280687) (xy 20.798332 -101.232052) (xy 20.778409 -101.179961) (xy 20.766283 -101.125524)
			(xy 20.762212 -101.069902) (xy 19.143667 -101.069902) (xy 19.14418 -101.086323) (xy 19.13755 -101.142606)
			(xy 19.122668 -101.19729) (xy 19.099859 -101.24917) (xy 19.069627 -101.297105) (xy 19.032636 -101.34004)
			(xy 18.9897 -101.377031) (xy 18.941764 -101.407262) (xy 18.889883 -101.43007) (xy 18.8352 -101.444952)
			(xy 18.778916 -101.45158) (xy 18.722271 -101.449809) (xy 18.666512 -101.439677) (xy 18.612864 -101.421408)
			(xy 18.56251 -101.395404) (xy 18.539206 -101.379274) (xy 18.520741 -101.36655) (xy 18.480335 -101.347114)
			(xy 18.437147 -101.335061) (xy 18.392515 -101.330764) (xy 18.347822 -101.334355) (xy 18.304449 -101.345723)
			(xy 18.26374 -101.364518) (xy 18.226955 -101.390156) (xy 18.210784 -101.40569) (xy 16.78171 -102.834764)
			(xy 28.424647 -102.834764) (xy 28.427398 -102.779293) (xy 28.438162 -102.724805) (xy 28.456712 -102.672455)
			(xy 28.482657 -102.623347) (xy 28.515448 -102.57852) (xy 28.554391 -102.53892) (xy 28.598664 -102.505385)
			(xy 28.647332 -102.478624) (xy 28.699365 -102.459202) (xy 28.753665 -102.447529) (xy 28.809083 -102.443852)
			(xy 28.864449 -102.448249) (xy 28.918593 -102.460627) (xy 28.970369 -102.480724) (xy 29.018685 -102.508116)
			(xy 29.062518 -102.542223) (xy 29.100944 -102.582326) (xy 29.133149 -102.627575) (xy 29.146246 -102.652068)
			(xy 29.154691 -102.667279) (xy 29.178305 -102.692807) (xy 29.207934 -102.711012) (xy 29.241378 -102.720542)
			(xy 29.276153 -102.720689) (xy 29.293058 -102.716584) (xy 29.319865 -102.709689) (xy 29.374791 -102.702837)
			(xy 29.430131 -102.703994) (xy 29.484723 -102.713134) (xy 29.537421 -102.730066) (xy 29.587119 -102.754436)
			(xy 29.632775 -102.78573) (xy 29.67343 -102.823294) (xy 29.708231 -102.866337) (xy 29.736447 -102.913957)
			(xy 29.757486 -102.965154) (xy 29.770907 -103.018854) (xy 29.776428 -103.07393) (xy 29.773933 -103.129225)
			(xy 29.763474 -103.18358) (xy 29.745272 -103.235853) (xy 29.719707 -103.284947) (xy 29.687317 -103.329832)
			(xy 29.648781 -103.369566) (xy 29.604908 -103.403315) (xy 29.55662 -103.430371) (xy 29.504928 -103.450165)
			(xy 29.450919 -103.462283) (xy 29.42336 -103.464868) (xy 29.401211 -103.467032) (xy 29.358107 -103.478081)
			(xy 29.317587 -103.49647) (xy 29.280889 -103.521637) (xy 29.249137 -103.552812) (xy 29.223301 -103.589041)
			(xy 29.204172 -103.629218) (xy 29.197808 -103.650542) (xy 29.189958 -103.677138) (xy 29.167613 -103.727889)
			(xy 29.138159 -103.774872) (xy 29.102214 -103.817097) (xy 29.060537 -103.853675) (xy 29.014004 -103.883835)
			(xy 28.963595 -103.906942) (xy 28.910373 -103.92251) (xy 28.855459 -103.930211) (xy 28.800007 -103.929883)
			(xy 28.745187 -103.921532) (xy 28.692154 -103.905335) (xy 28.642022 -103.881632) (xy 28.59585 -103.850922)
			(xy 28.554609 -103.813854) (xy 28.519167 -103.771206) (xy 28.490271 -103.723878) (xy 28.468529 -103.672865)
			(xy 28.4544 -103.619243) (xy 28.448181 -103.564141) (xy 28.450003 -103.508718) (xy 28.459827 -103.454143)
			(xy 28.477447 -103.401565) (xy 28.502492 -103.352091) (xy 28.534433 -103.306762) (xy 28.553156 -103.286306)
			(xy 28.564372 -103.273801) (xy 28.580361 -103.244271) (xy 28.588079 -103.211588) (xy 28.586991 -103.178025)
			(xy 28.577171 -103.145911) (xy 28.559303 -103.117479) (xy 28.547314 -103.105712) (xy 28.527237 -103.086521)
			(xy 28.492403 -103.043263) (xy 28.464208 -102.995412) (xy 28.443248 -102.943978) (xy 28.429968 -102.890049)
			(xy 28.424647 -102.834764) (xy 16.78171 -102.834764) (xy 15.409672 -104.206802) (xy 21.449536 -104.206802)
			(xy 21.453607 -104.15118) (xy 21.465733 -104.096743) (xy 21.485656 -104.044652) (xy 21.512952 -103.996017)
			(xy 21.547038 -103.951874) (xy 21.587187 -103.913165) (xy 21.632545 -103.880714) (xy 21.682145 -103.855213)
			(xy 21.734929 -103.837206) (xy 21.789772 -103.827076) (xy 21.845506 -103.825039) (xy 21.900943 -103.831139)
			(xy 21.9549 -103.845245) (xy 22.006229 -103.867057) (xy 22.053835 -103.896111) (xy 22.096703 -103.931786)
			(xy 22.13392 -103.973323) (xy 22.164693 -104.019836) (xy 22.188365 -104.070333) (xy 22.204433 -104.12374)
			(xy 22.212553 -104.178916) (xy 22.213062 -104.206802) (xy 22.212553 -104.234688) (xy 22.204433 -104.289864)
			(xy 22.188365 -104.343271) (xy 22.164693 -104.393768) (xy 22.13392 -104.440281) (xy 22.115761 -104.460548)
			(xy 26.458162 -104.460548) (xy 26.462233 -104.404926) (xy 26.474359 -104.350489) (xy 26.494282 -104.298398)
			(xy 26.521578 -104.249763) (xy 26.555664 -104.20562) (xy 26.595813 -104.166911) (xy 26.641171 -104.13446)
			(xy 26.690771 -104.108959) (xy 26.743555 -104.090952) (xy 26.798398 -104.080822) (xy 26.854132 -104.078785)
			(xy 26.909569 -104.084885) (xy 26.963526 -104.098991) (xy 27.014855 -104.120803) (xy 27.062461 -104.149857)
			(xy 27.105329 -104.185532) (xy 27.142546 -104.227069) (xy 27.173319 -104.273582) (xy 27.196991 -104.324079)
			(xy 27.213059 -104.377486) (xy 27.221179 -104.432662) (xy 27.221688 -104.460548) (xy 27.221179 -104.488434)
			(xy 27.213059 -104.54361) (xy 27.196991 -104.597017) (xy 27.173319 -104.647514) (xy 27.142546 -104.694027)
			(xy 27.105329 -104.735564) (xy 27.062461 -104.771239) (xy 27.014855 -104.800293) (xy 26.963526 -104.822105)
			(xy 26.909569 -104.836211) (xy 26.854132 -104.842311) (xy 26.798398 -104.840274) (xy 26.743555 -104.830144)
			(xy 26.690771 -104.812137) (xy 26.641171 -104.786636) (xy 26.595813 -104.754185) (xy 26.555664 -104.715476)
			(xy 26.521578 -104.671333) (xy 26.494282 -104.622698) (xy 26.474359 -104.570607) (xy 26.462233 -104.51617)
			(xy 26.458162 -104.460548) (xy 22.115761 -104.460548) (xy 22.096703 -104.481818) (xy 22.053835 -104.517493)
			(xy 22.006229 -104.546547) (xy 21.9549 -104.568359) (xy 21.900943 -104.582465) (xy 21.845506 -104.588565)
			(xy 21.789772 -104.586528) (xy 21.734929 -104.576398) (xy 21.682145 -104.558391) (xy 21.632545 -104.53289)
			(xy 21.587187 -104.500439) (xy 21.547038 -104.46173) (xy 21.512952 -104.417587) (xy 21.485656 -104.368952)
			(xy 21.465733 -104.316861) (xy 21.453607 -104.262424) (xy 21.449536 -104.206802) (xy 15.409672 -104.206802)
			(xy 15.077186 -104.539288) (xy 15.063216 -104.617266) (xy 15.079472 -104.653334) (xy 15.090254 -104.678294)
			(xy 15.105438 -104.7305) (xy 15.113056 -104.784333) (xy 15.112954 -104.838703) (xy 15.105133 -104.892507)
			(xy 15.089752 -104.944655) (xy 15.067124 -104.994092) (xy 15.037706 -105.039816) (xy 15.002094 -105.080899)
			(xy 14.96101 -105.11651) (xy 14.915286 -105.145927) (xy 14.865849 -105.168555) (xy 14.8137 -105.183934)
			(xy 14.759896 -105.191754) (xy 14.705526 -105.191855) (xy 14.651693 -105.184237) (xy 14.599487 -105.169052)
			(xy 14.57452 -105.158286) (xy 14.538452 -105.14203) (xy 14.460474 -105.156) (xy 12.16152 -107.454954)
			(xy 12.16152 -107.617268) (xy 20.062527 -107.617268) (xy 20.06642 -107.562904) (xy 20.078011 -107.509649)
			(xy 20.097063 -107.458584) (xy 20.123189 -107.410751) (xy 20.139152 -107.38866) (xy 20.152787 -107.369674)
			(xy 20.17352 -107.327785) (xy 20.186244 -107.282811) (xy 20.19053 -107.236268) (xy 20.186232 -107.189726)
			(xy 20.173497 -107.144755) (xy 20.152754 -107.102871) (xy 20.139152 -107.08386) (xy 20.123192 -107.061772)
			(xy 20.097071 -107.013946) (xy 20.078023 -106.96289) (xy 20.066435 -106.909643) (xy 20.062543 -106.855288)
			(xy 20.066427 -106.800933) (xy 20.078007 -106.747684) (xy 20.097048 -106.696625) (xy 20.123162 -106.648795)
			(xy 20.155817 -106.605169) (xy 20.194348 -106.566635) (xy 20.237972 -106.533977) (xy 20.285799 -106.50786)
			(xy 20.336857 -106.488815) (xy 20.390105 -106.477231) (xy 20.44446 -106.473343) (xy 20.498815 -106.477231)
			(xy 20.552063 -106.488815) (xy 20.603121 -106.50786) (xy 20.650948 -106.533977) (xy 20.694572 -106.566635)
			(xy 20.733103 -106.605169) (xy 20.765758 -106.648795) (xy 20.791872 -106.696625) (xy 20.810913 -106.747684)
			(xy 20.822493 -106.800933) (xy 20.826377 -106.855288) (xy 20.822485 -106.909643) (xy 20.810897 -106.96289)
			(xy 20.791849 -107.013946) (xy 20.765728 -107.061772) (xy 20.749768 -107.08386) (xy 20.736211 -107.102898)
			(xy 20.720775 -107.134077) (xy 22.486583 -107.134077) (xy 22.487079 -107.079087) (xy 22.495465 -107.024738)
			(xy 22.511566 -106.972155) (xy 22.53505 -106.922429) (xy 22.565429 -106.87659) (xy 22.583394 -106.855768)
			(xy 22.598994 -106.83746) (xy 22.623733 -106.796217) (xy 22.640278 -106.75106) (xy 22.64804 -106.703597)
			(xy 22.646743 -106.655522) (xy 22.636432 -106.608547) (xy 22.617476 -106.564348) (xy 22.604476 -106.54411)
			(xy 22.589465 -106.521067) (xy 22.565498 -106.471573) (xy 22.548884 -106.419149) (xy 22.539969 -106.364884)
			(xy 22.538937 -106.309901) (xy 22.545809 -106.25534) (xy 22.560443 -106.20233) (xy 22.582536 -106.151971)
			(xy 22.61163 -106.105304) (xy 22.647122 -106.063299) (xy 22.688277 -106.026823) (xy 22.734243 -105.996634)
			(xy 22.784066 -105.973357) (xy 22.836715 -105.957474) (xy 22.891099 -105.949314) (xy 22.946091 -105.949046)
			(xy 23.000551 -105.956676) (xy 23.053352 -105.972046) (xy 23.1034 -105.994837) (xy 23.149657 -106.024577)
			(xy 23.191166 -106.06065) (xy 23.227065 -106.102308) (xy 23.256612 -106.148688) (xy 23.279194 -106.198831)
			(xy 23.294344 -106.251695) (xy 23.301747 -106.306187) (xy 23.30125 -106.361178) (xy 23.292864 -106.415527)
			(xy 23.276762 -106.468109) (xy 23.253277 -106.517835) (xy 23.222897 -106.563675) (xy 23.204932 -106.584496)
			(xy 23.189364 -106.602831) (xy 23.164621 -106.644066) (xy 23.148071 -106.689218) (xy 23.140304 -106.736676)
			(xy 23.141596 -106.784748) (xy 23.151901 -106.83172) (xy 23.170853 -106.875917) (xy 23.18385 -106.896154)
			(xy 23.198865 -106.919193) (xy 23.222833 -106.968688) (xy 23.239446 -107.021111) (xy 23.248361 -107.075376)
			(xy 23.249393 -107.130359) (xy 23.246665 -107.152021) (xy 24.614274 -107.152021) (xy 24.620036 -107.097337)
			(xy 24.633589 -107.044047) (xy 24.65465 -106.993253) (xy 24.682783 -106.946009) (xy 24.699722 -106.924348)
			(xy 24.714438 -106.905357) (xy 24.737148 -106.863027) (xy 24.751494 -106.817181) (xy 24.756962 -106.769455)
			(xy 24.753357 -106.721552) (xy 24.740809 -106.675182) (xy 24.719765 -106.631999) (xy 24.705818 -106.612436)
			(xy 24.689735 -106.590132) (xy 24.663457 -106.541832) (xy 24.644383 -106.490259) (xy 24.63291 -106.436483)
			(xy 24.629274 -106.381617) (xy 24.63355 -106.326797) (xy 24.645652 -106.273159) (xy 24.665327 -106.221813)
			(xy 24.692168 -106.173823) (xy 24.725619 -106.130182) (xy 24.764988 -106.091795) (xy 24.80946 -106.059456)
			(xy 24.858112 -106.033835) (xy 24.909939 -106.015463) (xy 24.963866 -106.00472) (xy 25.018776 -106.001829)
			(xy 25.073533 -106.006849) (xy 25.127002 -106.019677) (xy 25.178076 -106.040047) (xy 25.225698 -106.067536)
			(xy 25.268881 -106.101577) (xy 25.30673 -106.141463) (xy 25.312135 -106.149112) (xy 28.626661 -106.149112)
			(xy 28.630553 -106.094757) (xy 28.642141 -106.04151) (xy 28.661189 -105.990454) (xy 28.68731 -105.942628)
			(xy 28.70327 -105.92054) (xy 28.71683 -105.901503) (xy 28.737568 -105.859627) (xy 28.7503 -105.814664)
			(xy 28.754596 -105.768132) (xy 28.750312 -105.721599) (xy 28.737591 -105.676633) (xy 28.716863 -105.634751)
			(xy 28.70327 -105.61574) (xy 28.68731 -105.593652) (xy 28.661189 -105.545826) (xy 28.642141 -105.49477)
			(xy 28.630553 -105.441523) (xy 28.626661 -105.387168) (xy 28.630545 -105.332813) (xy 28.642125 -105.279564)
			(xy 28.661166 -105.228505) (xy 28.68728 -105.180675) (xy 28.719935 -105.137049) (xy 28.758466 -105.098515)
			(xy 28.80209 -105.065857) (xy 28.849917 -105.03974) (xy 28.900975 -105.020695) (xy 28.954223 -105.009111)
			(xy 29.008578 -105.005223) (xy 29.062933 -105.009111) (xy 29.116181 -105.020695) (xy 29.167239 -105.03974)
			(xy 29.215066 -105.065857) (xy 29.25869 -105.098515) (xy 29.297041 -105.136869) (xy 30.917438 -105.136869)
			(xy 30.921443 -105.081731) (xy 30.933366 -105.027749) (xy 30.952956 -104.976054) (xy 30.979803 -104.927728)
			(xy 31.013346 -104.883784) (xy 31.05288 -104.845142) (xy 31.097579 -104.812611) (xy 31.146505 -104.786874)
			(xy 31.198635 -104.768469) (xy 31.252875 -104.757782) (xy 31.308089 -104.755037) (xy 31.363122 -104.760291)
			(xy 31.41682 -104.773434) (xy 31.468058 -104.794191) (xy 31.515763 -104.822127) (xy 31.537656 -104.839008)
			(xy 31.551404 -104.849264) (xy 31.582929 -104.862744) (xy 31.616904 -104.867348) (xy 31.650879 -104.862744)
			(xy 31.682404 -104.849264) (xy 31.696152 -104.839008) (xy 31.718813 -104.821541) (xy 31.768333 -104.792883)
			(xy 31.821576 -104.771941) (xy 31.87735 -104.759185) (xy 31.934404 -104.7549) (xy 31.991458 -104.759185)
			(xy 32.047232 -104.771941) (xy 32.100475 -104.792883) (xy 32.149995 -104.821541) (xy 32.172656 -104.839008)
			(xy 32.186404 -104.849264) (xy 32.217929 -104.862744) (xy 32.251904 -104.867348) (xy 32.285879 -104.862744)
			(xy 32.317404 -104.849264) (xy 32.331152 -104.839008) (xy 32.353001 -104.822063) (xy 32.400715 -104.794122)
			(xy 32.451963 -104.773362) (xy 32.505671 -104.760217) (xy 32.560714 -104.754963) (xy 32.615938 -104.75771)
			(xy 32.670188 -104.768399) (xy 32.722327 -104.786808) (xy 32.771262 -104.81255) (xy 32.815969 -104.845087)
			(xy 32.855511 -104.883736) (xy 32.889059 -104.927689) (xy 32.915911 -104.976024) (xy 32.935505 -105.027729)
			(xy 32.94743 -105.081721) (xy 32.951436 -105.136869) (xy 32.947439 -105.192017) (xy 32.935523 -105.246011)
			(xy 32.915938 -105.297719) (xy 32.889093 -105.346059) (xy 32.855552 -105.390017) (xy 32.816017 -105.428673)
			(xy 32.771315 -105.461217) (xy 32.722384 -105.486967) (xy 32.670249 -105.505384) (xy 32.616 -105.516083)
			(xy 32.560776 -105.518838) (xy 32.505732 -105.513593) (xy 32.452022 -105.500457) (xy 32.400771 -105.479705)
			(xy 32.353052 -105.451773) (xy 32.331152 -105.434892) (xy 32.317404 -105.424636) (xy 32.285879 -105.411156)
			(xy 32.251904 -105.406552) (xy 32.217929 -105.411156) (xy 32.186404 -105.424636) (xy 32.172656 -105.434892)
			(xy 32.149995 -105.452359) (xy 32.100475 -105.481017) (xy 32.047232 -105.501959) (xy 31.991458 -105.514715)
			(xy 31.934404 -105.519) (xy 31.87735 -105.514715) (xy 31.821576 -105.501959) (xy 31.768333 -105.481017)
			(xy 31.718813 -105.452359) (xy 31.696152 -105.434892) (xy 31.682404 -105.424636) (xy 31.650879 -105.411156)
			(xy 31.616904 -105.406552) (xy 31.582929 -105.411156) (xy 31.551404 -105.424636) (xy 31.537656 -105.434892)
			(xy 31.515711 -105.451709) (xy 31.468002 -105.479637) (xy 31.41676 -105.500385) (xy 31.36306 -105.51352)
			(xy 31.308027 -105.518764) (xy 31.252813 -105.51601) (xy 31.198574 -105.505314) (xy 31.146448 -105.486901)
			(xy 31.097526 -105.461156) (xy 31.052833 -105.428618) (xy 31.013304 -105.38997) (xy 30.979769 -105.34602)
			(xy 30.95293 -105.297689) (xy 30.933348 -105.245991) (xy 30.921434 -105.192007) (xy 30.917438 -105.136869)
			(xy 29.297041 -105.136869) (xy 29.297221 -105.137049) (xy 29.329876 -105.180675) (xy 29.35599 -105.228505)
			(xy 29.375031 -105.279564) (xy 29.386611 -105.332813) (xy 29.390495 -105.387168) (xy 29.386603 -105.441523)
			(xy 29.375015 -105.49477) (xy 29.355967 -105.545826) (xy 29.329846 -105.593652) (xy 29.313886 -105.61574)
			(xy 29.300254 -105.634727) (xy 29.279526 -105.676617) (xy 29.266805 -105.721591) (xy 29.262521 -105.768132)
			(xy 29.266817 -105.814672) (xy 29.279549 -105.859643) (xy 29.300288 -105.901528) (xy 29.313886 -105.92054)
			(xy 29.329846 -105.942628) (xy 29.355967 -105.990454) (xy 29.375015 -106.04151) (xy 29.386603 -106.094757)
			(xy 29.390495 -106.149112) (xy 29.386611 -106.203467) (xy 29.375031 -106.256716) (xy 29.35599 -106.307775)
			(xy 29.329876 -106.355605) (xy 29.297221 -106.399231) (xy 29.25869 -106.437765) (xy 29.215066 -106.470423)
			(xy 29.167239 -106.49654) (xy 29.116181 -106.515585) (xy 29.062933 -106.527169) (xy 29.008578 -106.531057)
			(xy 28.954223 -106.527169) (xy 28.900975 -106.515585) (xy 28.849917 -106.49654) (xy 28.80209 -106.470423)
			(xy 28.758466 -106.437765) (xy 28.719935 -106.399231) (xy 28.68728 -106.355605) (xy 28.661166 -106.307775)
			(xy 28.642125 -106.256716) (xy 28.630545 -106.203467) (xy 28.626661 -106.149112) (xy 25.312135 -106.149112)
			(xy 25.338463 -106.186369) (xy 25.363421 -106.235365) (xy 25.381089 -106.287436) (xy 25.391099 -106.341503)
			(xy 25.393245 -106.396448) (xy 25.387483 -106.451131) (xy 25.373931 -106.504422) (xy 25.35287 -106.555215)
			(xy 25.324737 -106.602459) (xy 25.307798 -106.62412) (xy 25.293112 -106.643133) (xy 25.270397 -106.685457)
			(xy 25.256047 -106.731298) (xy 25.250574 -106.77902) (xy 25.254174 -106.82692) (xy 25.266717 -106.873288)
			(xy 25.287757 -106.916469) (xy 25.301702 -106.936032) (xy 25.317785 -106.958336) (xy 25.344064 -107.006636)
			(xy 25.363138 -107.058209) (xy 25.374612 -107.111985) (xy 25.378248 -107.166852) (xy 25.373971 -107.221672)
			(xy 25.36187 -107.27531) (xy 25.342195 -107.326657) (xy 25.315354 -107.374647) (xy 25.281902 -107.418288)
			(xy 25.242533 -107.456675) (xy 25.198061 -107.489015) (xy 25.149408 -107.514636) (xy 25.097582 -107.533008)
			(xy 25.043655 -107.543751) (xy 24.988744 -107.546642) (xy 24.933987 -107.541622) (xy 24.880518 -107.528794)
			(xy 24.829443 -107.508424) (xy 24.781821 -107.480934) (xy 24.738638 -107.446894) (xy 24.700788 -107.407007)
			(xy 24.669056 -107.362101) (xy 24.644097 -107.313105) (xy 24.62643 -107.261034) (xy 24.61642 -107.206966)
			(xy 24.614274 -107.152021) (xy 23.246665 -107.152021) (xy 23.242521 -107.18492) (xy 23.227887 -107.23793)
			(xy 23.205795 -107.288289) (xy 23.176701 -107.334955) (xy 23.141209 -107.376961) (xy 23.100054 -107.413436)
			(xy 23.054089 -107.443625) (xy 23.004266 -107.466902) (xy 22.951617 -107.482786) (xy 22.897233 -107.490946)
			(xy 22.842242 -107.491214) (xy 22.787781 -107.483584) (xy 22.73498 -107.468215) (xy 22.684932 -107.445425)
			(xy 22.638675 -107.415685) (xy 22.597167 -107.379613) (xy 22.561267 -107.337955) (xy 22.531719 -107.291575)
			(xy 22.509137 -107.241433) (xy 22.493987 -107.188569) (xy 22.486583 -107.134077) (xy 20.720775 -107.134077)
			(xy 20.715478 -107.144775) (xy 20.702749 -107.189737) (xy 20.698454 -107.236268) (xy 20.702738 -107.2828)
			(xy 20.715455 -107.327765) (xy 20.736178 -107.369647) (xy 20.749768 -107.38866) (xy 20.765694 -107.410776)
			(xy 20.791822 -107.458602) (xy 20.810876 -107.50966) (xy 20.822467 -107.56291) (xy 20.826361 -107.617268)
			(xy 20.822476 -107.671627) (xy 20.810894 -107.724879) (xy 20.791848 -107.77594) (xy 20.765728 -107.82377)
			(xy 20.749768 -107.84586) (xy 20.736211 -107.864898) (xy 20.715478 -107.906775) (xy 20.702749 -107.951737)
			(xy 20.698454 -107.998268) (xy 20.702738 -108.0448) (xy 20.715455 -108.089765) (xy 20.736178 -108.131647)
			(xy 20.749768 -108.15066) (xy 20.765728 -108.172748) (xy 20.791849 -108.220574) (xy 20.810897 -108.27163)
			(xy 20.822485 -108.324877) (xy 20.826377 -108.379232) (xy 20.822493 -108.433587) (xy 20.810913 -108.486836)
			(xy 20.791872 -108.537895) (xy 20.765758 -108.585725) (xy 20.733103 -108.629351) (xy 20.694572 -108.667885)
			(xy 20.650948 -108.700543) (xy 20.603121 -108.72666) (xy 20.552063 -108.745705) (xy 20.498815 -108.757289)
			(xy 20.44446 -108.761177) (xy 20.390105 -108.757289) (xy 20.336857 -108.745705) (xy 20.285799 -108.72666)
			(xy 20.237972 -108.700543) (xy 20.194348 -108.667885) (xy 20.155817 -108.629351) (xy 20.123162 -108.585725)
			(xy 20.097048 -108.537895) (xy 20.078007 -108.486836) (xy 20.066427 -108.433587) (xy 20.062543 -108.379232)
			(xy 20.066435 -108.324877) (xy 20.078023 -108.27163) (xy 20.097071 -108.220574) (xy 20.123192 -108.172748)
			(xy 20.139152 -108.15066) (xy 20.152787 -108.131674) (xy 20.17352 -108.089785) (xy 20.186244 -108.044811)
			(xy 20.19053 -107.998268) (xy 20.186232 -107.951726) (xy 20.173497 -107.906755) (xy 20.152754 -107.864871)
			(xy 20.139152 -107.84586) (xy 20.123154 -107.823795) (xy 20.097037 -107.775957) (xy 20.077993 -107.72489)
			(xy 20.066411 -107.671632) (xy 20.062527 -107.617268) (xy 12.16152 -107.617268) (xy 12.16152 -108.674662)
			(xy 12.161968 -108.696377) (xy 12.169361 -108.739174) (xy 12.183921 -108.780092) (xy 12.205225 -108.817938)
			(xy 12.232652 -108.851613) (xy 12.265404 -108.880136) (xy 12.280755 -108.889456) (xy 21.474849 -108.889456)
			(xy 21.479505 -108.834722) (xy 21.491965 -108.781221) (xy 21.511973 -108.730062) (xy 21.539113 -108.682303)
			(xy 21.572825 -108.638932) (xy 21.592286 -108.619544) (xy 21.608307 -108.603404) (xy 21.634939 -108.566547)
			(xy 21.654592 -108.525543) (xy 21.666641 -108.481697) (xy 21.670701 -108.436407) (xy 21.666643 -108.391117)
			(xy 21.654597 -108.34727) (xy 21.634946 -108.306265) (xy 21.608316 -108.269406) (xy 21.592286 -108.253276)
			(xy 21.572825 -108.233888) (xy 21.539113 -108.190517) (xy 21.511973 -108.142758) (xy 21.491965 -108.091599)
			(xy 21.479505 -108.038098) (xy 21.474849 -107.983364) (xy 21.478094 -107.928528) (xy 21.489173 -107.874724)
			(xy 21.507857 -107.823067) (xy 21.533759 -107.774625) (xy 21.566343 -107.730401) (xy 21.604935 -107.691309)
			(xy 21.648737 -107.658158) (xy 21.696842 -107.631634) (xy 21.748254 -107.612287) (xy 21.80191 -107.600516)
			(xy 21.8567 -107.596565) (xy 21.91149 -107.600516) (xy 21.965146 -107.612287) (xy 22.016558 -107.631634)
			(xy 22.064663 -107.658158) (xy 22.108465 -107.691309) (xy 22.147057 -107.730401) (xy 22.179641 -107.774625)
			(xy 22.205543 -107.823067) (xy 22.224227 -107.874724) (xy 22.235306 -107.928528) (xy 22.238551 -107.983364)
			(xy 22.233895 -108.038098) (xy 22.221435 -108.091599) (xy 22.201427 -108.142758) (xy 22.174287 -108.190517)
			(xy 22.140575 -108.233888) (xy 22.121114 -108.253276) (xy 22.105073 -108.269397) (xy 22.078442 -108.306257)
			(xy 22.05879 -108.347265) (xy 22.046743 -108.391114) (xy 22.042685 -108.436407) (xy 22.046745 -108.481699)
			(xy 22.058795 -108.525548) (xy 22.078449 -108.566555) (xy 22.105082 -108.603414) (xy 22.121114 -108.619544)
			(xy 22.140575 -108.638932) (xy 22.174287 -108.682303) (xy 22.201427 -108.730062) (xy 22.221435 -108.781221)
			(xy 22.233895 -108.834722) (xy 22.238414 -108.887843) (xy 25.437478 -108.887843) (xy 25.443485 -108.832471)
			(xy 25.457483 -108.778562) (xy 25.479174 -108.727262) (xy 25.508097 -108.679664) (xy 25.525476 -108.657898)
			(xy 25.539156 -108.640656) (xy 25.561018 -108.602461) (xy 25.575968 -108.561069) (xy 25.583558 -108.517719)
			(xy 25.58356 -108.47371) (xy 25.575976 -108.430359) (xy 25.561031 -108.388966) (xy 25.539173 -108.350768)
			(xy 25.525476 -108.33354) (xy 25.508097 -108.311774) (xy 25.479174 -108.264176) (xy 25.457483 -108.212876)
			(xy 25.443485 -108.158967) (xy 25.437478 -108.103595) (xy 25.43959 -108.047939) (xy 25.449776 -107.993181)
			(xy 25.467819 -107.940488) (xy 25.493335 -107.89098) (xy 25.525782 -107.84571) (xy 25.564469 -107.805642)
			(xy 25.608573 -107.771628) (xy 25.657156 -107.744392) (xy 25.709185 -107.724512) (xy 25.763551 -107.712413)
			(xy 25.8191 -107.708351) (xy 25.874649 -107.712413) (xy 25.929015 -107.724512) (xy 25.981044 -107.744392)
			(xy 26.029627 -107.771628) (xy 26.073731 -107.805642) (xy 26.112418 -107.84571) (xy 26.144865 -107.89098)
			(xy 26.170381 -107.940488) (xy 26.188424 -107.993181) (xy 26.19861 -108.047939) (xy 26.200609 -108.100622)
			(xy 32.391094 -108.100622) (xy 32.395165 -108.045) (xy 32.407291 -107.990563) (xy 32.427214 -107.938472)
			(xy 32.45451 -107.889837) (xy 32.488596 -107.845694) (xy 32.528745 -107.806985) (xy 32.574103 -107.774534)
			(xy 32.623703 -107.749033) (xy 32.676487 -107.731026) (xy 32.73133 -107.720896) (xy 32.787064 -107.718859)
			(xy 32.842501 -107.724959) (xy 32.896458 -107.739065) (xy 32.947787 -107.760877) (xy 32.995393 -107.789931)
			(xy 33.038261 -107.825606) (xy 33.075478 -107.867143) (xy 33.106251 -107.913656) (xy 33.129923 -107.964153)
			(xy 33.145991 -108.01756) (xy 33.154111 -108.072736) (xy 33.15462 -108.100622) (xy 33.154111 -108.128508)
			(xy 33.145991 -108.183684) (xy 33.129923 -108.237091) (xy 33.106251 -108.287588) (xy 33.075478 -108.334101)
			(xy 33.038261 -108.375638) (xy 32.995393 -108.411313) (xy 32.947787 -108.440367) (xy 32.896458 -108.462179)
			(xy 32.842501 -108.476285) (xy 32.787064 -108.482385) (xy 32.73133 -108.480348) (xy 32.676487 -108.470218)
			(xy 32.623703 -108.452211) (xy 32.574103 -108.42671) (xy 32.528745 -108.394259) (xy 32.488596 -108.35555)
			(xy 32.45451 -108.311407) (xy 32.427214 -108.262772) (xy 32.407291 -108.210681) (xy 32.395165 -108.156244)
			(xy 32.391094 -108.100622) (xy 26.200609 -108.100622) (xy 26.200722 -108.103595) (xy 26.194715 -108.158967)
			(xy 26.180717 -108.212876) (xy 26.159026 -108.264176) (xy 26.130103 -108.311774) (xy 26.112724 -108.33354)
			(xy 26.09904 -108.350769) (xy 26.07724 -108.388983) (xy 26.062336 -108.430377) (xy 26.054773 -108.473717)
			(xy 26.054775 -108.517712) (xy 26.062344 -108.561051) (xy 26.077252 -108.602444) (xy 26.099057 -108.640655)
			(xy 26.112724 -108.657898) (xy 26.130103 -108.679664) (xy 26.159026 -108.727262) (xy 26.180717 -108.778562)
			(xy 26.194715 -108.832471) (xy 26.200722 -108.887843) (xy 26.19861 -108.943499) (xy 26.188424 -108.998257)
			(xy 26.170381 -109.05095) (xy 26.144865 -109.100458) (xy 26.112418 -109.145728) (xy 26.073731 -109.185796)
			(xy 26.029627 -109.21981) (xy 25.981044 -109.247046) (xy 25.929015 -109.266926) (xy 25.874649 -109.279025)
			(xy 25.8191 -109.283087) (xy 25.763551 -109.279025) (xy 25.709185 -109.266926) (xy 25.657156 -109.247046)
			(xy 25.608573 -109.21981) (xy 25.564469 -109.185796) (xy 25.525782 -109.145728) (xy 25.493335 -109.100458)
			(xy 25.467819 -109.05095) (xy 25.449776 -108.998257) (xy 25.43959 -108.943499) (xy 25.437478 -108.887843)
			(xy 22.238414 -108.887843) (xy 22.238551 -108.889456) (xy 22.235306 -108.944292) (xy 22.224227 -108.998096)
			(xy 22.205543 -109.049753) (xy 22.179641 -109.098195) (xy 22.147057 -109.142419) (xy 22.108465 -109.181511)
			(xy 22.064663 -109.214662) (xy 22.016558 -109.241186) (xy 21.965146 -109.260533) (xy 21.91149 -109.272304)
			(xy 21.8567 -109.276255) (xy 21.80191 -109.272304) (xy 21.748254 -109.260533) (xy 21.696842 -109.241186)
			(xy 21.648737 -109.214662) (xy 21.604935 -109.181511) (xy 21.566343 -109.142419) (xy 21.533759 -109.098195)
			(xy 21.507857 -109.049753) (xy 21.489173 -108.998096) (xy 21.478094 -108.944292) (xy 21.474849 -108.889456)
			(xy 12.280755 -108.889456) (xy 12.302528 -108.902675) (xy 12.342943 -108.918577) (xy 12.385473 -108.927377)
			(xy 12.42888 -108.928819) (xy 12.471901 -108.922862) (xy 12.492736 -108.916724) (xy 12.519023 -108.908854)
			(xy 12.573153 -108.899867) (xy 12.628012 -108.898727) (xy 12.682468 -108.905457) (xy 12.735399 -108.919918)
			(xy 12.785713 -108.941812) (xy 12.832372 -108.970687) (xy 12.874413 -109.005948) (xy 12.91097 -109.046868)
			(xy 12.941288 -109.092602) (xy 12.964743 -109.142207) (xy 12.98085 -109.194661) (xy 12.989277 -109.24888)
			(xy 12.989851 -109.303748) (xy 12.98256 -109.358133) (xy 12.967553 -109.410912) (xy 12.956794 -109.436154)
			(xy 12.948071 -109.456762) (xy 12.937198 -109.500167) (xy 12.934099 -109.544806) (xy 12.938868 -109.589297)
			(xy 12.951359 -109.632265) (xy 12.971185 -109.672379) (xy 12.997732 -109.708399) (xy 13.030179 -109.739212)
			(xy 13.067523 -109.763862) (xy 13.108608 -109.781589) (xy 13.130276 -109.787182) (xy 13.15736 -109.794063)
			(xy 13.209302 -109.814671) (xy 13.257682 -109.842635) (xy 13.301467 -109.877356) (xy 13.339718 -109.918093)
			(xy 13.371619 -109.963973) (xy 13.396486 -110.014015) (xy 13.413788 -110.06715) (xy 13.423155 -110.12224)
			(xy 13.424386 -110.178107) (xy 13.417455 -110.233556) (xy 13.402511 -110.287401) (xy 13.379873 -110.338491)
			(xy 13.350025 -110.385732) (xy 13.313605 -110.428114) (xy 13.271393 -110.464731) (xy 13.224292 -110.4948)
			(xy 13.173309 -110.517676) (xy 13.119534 -110.532871) (xy 13.064118 -110.540061) (xy 13.008245 -110.53909)
			(xy 12.953112 -110.529981) (xy 12.899898 -110.512927) (xy 12.84974 -110.488293) (xy 12.803711 -110.456607)
			(xy 12.762796 -110.418546) (xy 12.744958 -110.397036) (xy 12.730221 -110.379442) (xy 12.695554 -110.349373)
			(xy 12.656051 -110.326019) (xy 12.612996 -110.310138) (xy 12.567789 -110.302246) (xy 12.5219 -110.3026)
			(xy 12.47682 -110.311188) (xy 12.434015 -110.327732) (xy 12.394877 -110.351693) (xy 12.360678 -110.382293)
			(xy 12.346178 -110.400084) (xy 12.329795 -110.420461) (xy 12.292371 -110.456975) (xy 12.250311 -110.488038)
			(xy 12.22756 -110.500922) (xy 12.227306 -110.501176) (xy 12.212692 -110.509834) (xy 12.188316 -110.533473)
			(xy 12.171032 -110.562701) (xy 12.162063 -110.59545) (xy 12.16152 -110.612428) (xy 12.16152 -111.117352)
			(xy 21.474783 -111.117352) (xy 21.478675 -111.062997) (xy 21.490263 -111.00975) (xy 21.509311 -110.958694)
			(xy 21.535432 -110.910868) (xy 21.551392 -110.88878) (xy 21.565007 -110.869781) (xy 21.585738 -110.827894)
			(xy 21.598462 -110.782923) (xy 21.60275 -110.736384) (xy 21.598456 -110.689845) (xy 21.585727 -110.644876)
			(xy 21.56499 -110.602992) (xy 21.551392 -110.58398) (xy 21.535432 -110.561892) (xy 21.509311 -110.514066)
			(xy 21.490263 -110.46301) (xy 21.478675 -110.409763) (xy 21.474783 -110.355408) (xy 21.478667 -110.301053)
			(xy 21.490247 -110.247804) (xy 21.509288 -110.196745) (xy 21.535402 -110.148915) (xy 21.568057 -110.105289)
			(xy 21.606588 -110.066755) (xy 21.650212 -110.034097) (xy 21.698039 -110.00798) (xy 21.749097 -109.988935)
			(xy 21.802345 -109.977351) (xy 21.8567 -109.973463) (xy 21.911055 -109.977351) (xy 21.964303 -109.988935)
			(xy 22.015361 -110.00798) (xy 22.063188 -110.034097) (xy 22.106812 -110.066755) (xy 22.145343 -110.105289)
			(xy 22.177998 -110.148915) (xy 22.204112 -110.196745) (xy 22.223153 -110.247804) (xy 22.234733 -110.301053)
			(xy 22.238617 -110.355408) (xy 22.234725 -110.409763) (xy 22.223137 -110.46301) (xy 22.204089 -110.514066)
			(xy 22.177968 -110.561892) (xy 22.162008 -110.58398) (xy 22.148431 -110.603005) (xy 22.127696 -110.644885)
			(xy 22.114967 -110.68985) (xy 22.110674 -110.736384) (xy 22.114419 -110.777023) (xy 25.43748 -110.777023)
			(xy 25.439512 -110.721312) (xy 25.449633 -110.666491) (xy 25.467629 -110.613727) (xy 25.493115 -110.564146)
			(xy 25.525548 -110.518804) (xy 25.544526 -110.498382) (xy 25.555488 -110.486316) (xy 25.571483 -110.457925)
			(xy 25.579753 -110.426405) (xy 25.579756 -110.393819) (xy 25.571492 -110.362297) (xy 25.555503 -110.333903)
			(xy 25.544526 -110.321852) (xy 25.525548 -110.30143) (xy 25.493115 -110.256088) (xy 25.467629 -110.206507)
			(xy 25.449633 -110.153743) (xy 25.439512 -110.098922) (xy 25.43748 -110.043211) (xy 25.44358 -109.987798)
			(xy 25.457684 -109.933864) (xy 25.47949 -109.882558) (xy 25.508533 -109.834973) (xy 25.544196 -109.792124)
			(xy 25.585716 -109.754924) (xy 25.632211 -109.724165) (xy 25.682688 -109.700503) (xy 25.736072 -109.684443)
			(xy 25.791226 -109.676327) (xy 25.846974 -109.676327) (xy 25.902128 -109.684443) (xy 25.955512 -109.700503)
			(xy 26.005989 -109.724165) (xy 26.052484 -109.754924) (xy 26.094004 -109.792124) (xy 26.129667 -109.834973)
			(xy 26.15871 -109.882558) (xy 26.180516 -109.933864) (xy 26.19462 -109.987798) (xy 26.20072 -110.043211)
			(xy 26.198688 -110.098922) (xy 26.188567 -110.153743) (xy 26.170571 -110.206507) (xy 26.145085 -110.256088)
			(xy 26.112652 -110.30143) (xy 26.093674 -110.321852) (xy 26.082722 -110.33391) (xy 26.066805 -110.36232)
			(xy 26.058582 -110.39383) (xy 26.058585 -110.426395) (xy 26.066815 -110.457903) (xy 26.082737 -110.48631)
			(xy 26.093674 -110.498382) (xy 26.112652 -110.518804) (xy 26.145085 -110.564146) (xy 26.170571 -110.613727)
			(xy 26.188567 -110.666491) (xy 26.198688 -110.721312) (xy 26.20072 -110.777023) (xy 26.19462 -110.832436)
			(xy 26.180516 -110.88637) (xy 26.15871 -110.937676) (xy 26.129667 -110.985261) (xy 26.094004 -111.02811)
			(xy 26.052484 -111.06531) (xy 26.005989 -111.096069) (xy 25.955512 -111.119731) (xy 25.902128 -111.135791)
			(xy 25.846974 -111.143907) (xy 25.791226 -111.143907) (xy 25.736072 -111.135791) (xy 25.682688 -111.119731)
			(xy 25.632211 -111.096069) (xy 25.585716 -111.06531) (xy 25.544196 -111.02811) (xy 25.508533 -110.985261)
			(xy 25.47949 -110.937676) (xy 25.457684 -110.88637) (xy 25.44358 -110.832436) (xy 25.43748 -110.777023)
			(xy 22.114419 -110.777023) (xy 22.114962 -110.782919) (xy 22.127684 -110.827885) (xy 22.148414 -110.869768)
			(xy 22.162008 -110.88878) (xy 22.177968 -110.910868) (xy 22.204089 -110.958694) (xy 22.223137 -111.00975)
			(xy 22.234725 -111.062997) (xy 22.238617 -111.117352) (xy 22.234733 -111.171707) (xy 22.223153 -111.224956)
			(xy 22.204112 -111.276015) (xy 22.177998 -111.323845) (xy 22.145343 -111.367471) (xy 22.106812 -111.406005)
			(xy 22.063188 -111.438663) (xy 22.015361 -111.46478) (xy 21.964303 -111.483825) (xy 21.911055 -111.495409)
			(xy 21.8567 -111.499297) (xy 21.802345 -111.495409) (xy 21.749097 -111.483825) (xy 21.698039 -111.46478)
			(xy 21.650212 -111.438663) (xy 21.606588 -111.406005) (xy 21.568057 -111.367471) (xy 21.535402 -111.323845)
			(xy 21.509288 -111.276015) (xy 21.490247 -111.224956) (xy 21.478667 -111.171707) (xy 21.474783 -111.117352)
			(xy 12.16152 -111.117352) (xy 12.16152 -113.078994) (xy 19.912683 -113.078994) (xy 19.916575 -113.024639)
			(xy 19.928163 -112.971392) (xy 19.947211 -112.920336) (xy 19.973332 -112.87251) (xy 19.989292 -112.850422)
			(xy 20.002867 -112.831396) (xy 20.023602 -112.789516) (xy 20.036331 -112.744552) (xy 20.040624 -112.698018)
			(xy 20.036338 -112.651483) (xy 20.023615 -112.606516) (xy 20.002886 -112.564634) (xy 19.989292 -112.545622)
			(xy 19.973351 -112.523517) (xy 19.947227 -112.475688) (xy 19.928176 -112.424628) (xy 19.916588 -112.371377)
			(xy 19.912697 -112.317018) (xy 19.916583 -112.262658) (xy 19.928166 -112.209405) (xy 19.947212 -112.158344)
			(xy 19.973332 -112.110513) (xy 19.989292 -112.088422) (xy 20.002867 -112.069396) (xy 20.023602 -112.027516)
			(xy 20.036331 -111.982552) (xy 20.040624 -111.936018) (xy 20.036338 -111.889483) (xy 20.023615 -111.844516)
			(xy 20.002886 -111.802634) (xy 19.989292 -111.783622) (xy 19.973332 -111.761534) (xy 19.947211 -111.713708)
			(xy 19.928163 -111.662652) (xy 19.916575 -111.609405) (xy 19.912683 -111.55505) (xy 19.916567 -111.500695)
			(xy 19.928147 -111.447446) (xy 19.947188 -111.396387) (xy 19.973302 -111.348557) (xy 20.005957 -111.304931)
			(xy 20.044488 -111.266397) (xy 20.088112 -111.233739) (xy 20.135939 -111.207622) (xy 20.186997 -111.188577)
			(xy 20.240245 -111.176993) (xy 20.2946 -111.173105) (xy 20.348955 -111.176993) (xy 20.402203 -111.188577)
			(xy 20.453261 -111.207622) (xy 20.501088 -111.233739) (xy 20.544712 -111.266397) (xy 20.583243 -111.304931)
			(xy 20.615898 -111.348557) (xy 20.642012 -111.396387) (xy 20.661053 -111.447446) (xy 20.672633 -111.500695)
			(xy 20.676517 -111.55505) (xy 20.672625 -111.609405) (xy 20.661037 -111.662652) (xy 20.641989 -111.713708)
			(xy 20.615868 -111.761534) (xy 20.599908 -111.783622) (xy 20.586292 -111.80262) (xy 20.56556 -111.844507)
			(xy 20.552836 -111.889478) (xy 20.548549 -111.936018) (xy 20.552843 -111.982557) (xy 20.565573 -112.027526)
			(xy 20.58631 -112.06941) (xy 20.599908 -112.088422) (xy 20.61589 -112.110498) (xy 20.642012 -112.158333)
			(xy 20.661059 -112.209398) (xy 20.672643 -112.262654) (xy 20.67653 -112.317018) (xy 20.672638 -112.37138)
			(xy 20.661049 -112.424636) (xy 20.641997 -112.475699) (xy 20.615871 -112.523531) (xy 20.599908 -112.545622)
			(xy 20.586292 -112.56462) (xy 20.56556 -112.606507) (xy 20.552836 -112.651478) (xy 20.548549 -112.698018)
			(xy 20.552843 -112.744557) (xy 20.565573 -112.789526) (xy 20.58631 -112.83141) (xy 20.599908 -112.850422)
			(xy 20.615868 -112.87251) (xy 20.641989 -112.920336) (xy 20.661037 -112.971392) (xy 20.672625 -113.024639)
			(xy 20.676517 -113.078994) (xy 20.672633 -113.133349) (xy 20.661053 -113.186598) (xy 20.642012 -113.237657)
			(xy 20.615898 -113.285487) (xy 20.583243 -113.329113) (xy 20.544712 -113.367647) (xy 20.509911 -113.3937)
			(xy 21.474783 -113.3937) (xy 21.478675 -113.339345) (xy 21.490263 -113.286098) (xy 21.509311 -113.235042)
			(xy 21.535432 -113.187216) (xy 21.551392 -113.165128) (xy 21.564962 -113.146098) (xy 21.585697 -113.10422)
			(xy 21.598427 -113.059256) (xy 21.602721 -113.012722) (xy 21.598435 -112.966188) (xy 21.585713 -112.921222)
			(xy 21.564985 -112.87934) (xy 21.551392 -112.860328) (xy 21.535432 -112.83824) (xy 21.509311 -112.790414)
			(xy 21.490263 -112.739358) (xy 21.478675 -112.686111) (xy 21.474783 -112.631756) (xy 21.478667 -112.577401)
			(xy 21.490247 -112.524152) (xy 21.509288 -112.473093) (xy 21.535402 -112.425263) (xy 21.568057 -112.381637)
			(xy 21.606588 -112.343103) (xy 21.650212 -112.310445) (xy 21.698039 -112.284328) (xy 21.749097 -112.265283)
			(xy 21.802345 -112.253699) (xy 21.8567 -112.249811) (xy 21.911055 -112.253699) (xy 21.964303 -112.265283)
			(xy 22.015361 -112.284328) (xy 22.063188 -112.310445) (xy 22.106812 -112.343103) (xy 22.145343 -112.381637)
			(xy 22.177998 -112.425263) (xy 22.204112 -112.473093) (xy 22.223153 -112.524152) (xy 22.234733 -112.577401)
			(xy 22.238617 -112.631756) (xy 22.234725 -112.686111) (xy 22.223137 -112.739358) (xy 22.204089 -112.790414)
			(xy 22.177968 -112.83824) (xy 22.162008 -112.860328) (xy 22.148386 -112.879322) (xy 22.127655 -112.92121)
			(xy 22.114932 -112.966182) (xy 22.110646 -113.012722) (xy 22.11494 -113.059262) (xy 22.127671 -113.104232)
			(xy 22.14841 -113.146116) (xy 22.162008 -113.165128) (xy 22.177968 -113.187216) (xy 22.204089 -113.235042)
			(xy 22.223137 -113.286098) (xy 22.229833 -113.316868) (xy 25.42232 -113.316868) (xy 25.429064 -113.261734)
			(xy 25.443732 -113.208161) (xy 25.466014 -113.157281) (xy 25.495439 -113.110171) (xy 25.51303 -113.088674)
			(xy 25.526791 -113.071806) (xy 25.548909 -113.034316) (xy 25.56431 -112.993603) (xy 25.572544 -112.95086)
			(xy 25.573368 -112.90734) (xy 25.56676 -112.864316) (xy 25.552911 -112.823049) (xy 25.532229 -112.784748)
			(xy 25.519126 -112.767364) (xy 25.502358 -112.74522) (xy 25.474736 -112.697031) (xy 25.454395 -112.645346)
			(xy 25.441764 -112.591257) (xy 25.43711 -112.535909) (xy 25.440531 -112.48047) (xy 25.451956 -112.426114)
			(xy 25.471143 -112.373989) (xy 25.497686 -112.325198) (xy 25.531024 -112.280771) (xy 25.570452 -112.241649)
			(xy 25.615137 -112.208658) (xy 25.664134 -112.182496) (xy 25.716406 -112.163716) (xy 25.77085 -112.152714)
			(xy 25.826313 -112.149724) (xy 25.881624 -112.154809) (xy 25.935613 -112.167861) (xy 25.987138 -112.188605)
			(xy 26.03511 -112.216601) (xy 26.078516 -112.251258) (xy 26.116436 -112.291843) (xy 26.148071 -112.337498)
			(xy 26.17275 -112.387258) (xy 26.189952 -112.440071) (xy 26.199313 -112.494821) (xy 26.200637 -112.550349)
			(xy 26.193893 -112.605482) (xy 26.179226 -112.659054) (xy 26.156945 -112.709933) (xy 26.127521 -112.757043)
			(xy 26.10993 -112.77854) (xy 26.096154 -112.795397) (xy 26.074032 -112.832888) (xy 26.058628 -112.873603)
			(xy 26.050394 -112.916349) (xy 26.049571 -112.959872) (xy 26.056183 -113.002899) (xy 26.070037 -113.044167)
			(xy 26.090727 -113.082467) (xy 26.103834 -113.09985) (xy 26.120603 -113.121994) (xy 26.148225 -113.170184)
			(xy 26.168568 -113.221869) (xy 26.1812 -113.275959) (xy 26.185854 -113.331308) (xy 26.182433 -113.386747)
			(xy 26.171008 -113.441105) (xy 26.151821 -113.49323) (xy 26.125278 -113.542023) (xy 26.09194 -113.58645)
			(xy 26.052511 -113.625573) (xy 26.007826 -113.658565) (xy 25.958829 -113.684727) (xy 25.906555 -113.703508)
			(xy 25.852111 -113.71451) (xy 25.796647 -113.7175) (xy 25.741335 -113.712415) (xy 25.687346 -113.699362)
			(xy 25.63582 -113.678618) (xy 25.587847 -113.650622) (xy 25.544441 -113.615964) (xy 25.50652 -113.575378)
			(xy 25.474885 -113.529722) (xy 25.450206 -113.479961) (xy 25.433004 -113.427147) (xy 25.423642 -113.372397)
			(xy 25.42232 -113.316868) (xy 22.229833 -113.316868) (xy 22.234725 -113.339345) (xy 22.238617 -113.3937)
			(xy 22.234733 -113.448055) (xy 22.223153 -113.501304) (xy 22.204112 -113.552363) (xy 22.177998 -113.600193)
			(xy 22.145343 -113.643819) (xy 22.106812 -113.682353) (xy 22.063188 -113.715011) (xy 22.015361 -113.741128)
			(xy 21.964303 -113.760173) (xy 21.911055 -113.771757) (xy 21.8567 -113.775645) (xy 21.802345 -113.771757)
			(xy 21.749097 -113.760173) (xy 21.698039 -113.741128) (xy 21.650212 -113.715011) (xy 21.606588 -113.682353)
			(xy 21.568057 -113.643819) (xy 21.535402 -113.600193) (xy 21.509288 -113.552363) (xy 21.490247 -113.501304)
			(xy 21.478667 -113.448055) (xy 21.474783 -113.3937) (xy 20.509911 -113.3937) (xy 20.501088 -113.400305)
			(xy 20.453261 -113.426422) (xy 20.402203 -113.445467) (xy 20.348955 -113.457051) (xy 20.2946 -113.460939)
			(xy 20.240245 -113.457051) (xy 20.186997 -113.445467) (xy 20.135939 -113.426422) (xy 20.088112 -113.400305)
			(xy 20.044488 -113.367647) (xy 20.005957 -113.329113) (xy 19.973302 -113.285487) (xy 19.947188 -113.237657)
			(xy 19.928147 -113.186598) (xy 19.916567 -113.133349) (xy 19.912683 -113.078994) (xy 12.16152 -113.078994)
			(xy 12.16152 -114.56142) (xy 16.018373 -114.56142) (xy 16.022258 -114.507065) (xy 16.033839 -114.453816)
			(xy 16.05288 -114.402757) (xy 16.078994 -114.354928) (xy 16.111649 -114.311302) (xy 16.150181 -114.272768)
			(xy 16.193804 -114.240109) (xy 16.241631 -114.213992) (xy 16.292689 -114.194947) (xy 16.345937 -114.183362)
			(xy 16.400292 -114.179473) (xy 16.454647 -114.183359) (xy 16.507895 -114.194942) (xy 16.558954 -114.213985)
			(xy 16.606782 -114.2401) (xy 16.628872 -114.256058) (xy 16.647884 -114.269654) (xy 16.689767 -114.290386)
			(xy 16.734735 -114.303112) (xy 16.781272 -114.307402) (xy 16.827809 -114.303112) (xy 16.872777 -114.290386)
			(xy 16.91466 -114.269654) (xy 16.933672 -114.256058) (xy 16.955763 -114.240096) (xy 17.003594 -114.213973)
			(xy 17.054657 -114.194924) (xy 17.107911 -114.183338) (xy 17.162272 -114.179449) (xy 17.216633 -114.183338)
			(xy 17.269887 -114.194924) (xy 17.32095 -114.213973) (xy 17.368781 -114.240096) (xy 17.390872 -114.256058)
			(xy 17.409884 -114.269654) (xy 17.451767 -114.290386) (xy 17.496735 -114.303112) (xy 17.543272 -114.307402)
			(xy 17.589809 -114.303112) (xy 17.634777 -114.290386) (xy 17.67666 -114.269654) (xy 17.695672 -114.256058)
			(xy 17.717793 -114.240142) (xy 17.765618 -114.214021) (xy 17.816674 -114.194973) (xy 17.869922 -114.183385)
			(xy 17.924276 -114.179494) (xy 17.978632 -114.183378) (xy 18.03188 -114.194959) (xy 18.082939 -114.214001)
			(xy 18.130768 -114.240116) (xy 18.174393 -114.272772) (xy 18.212926 -114.311305) (xy 18.245582 -114.35493)
			(xy 18.271697 -114.402758) (xy 18.29074 -114.453817) (xy 18.302321 -114.507065) (xy 18.306206 -114.56142)
			(xy 18.302315 -114.615775) (xy 18.300575 -114.62377) (xy 20.602813 -114.62377) (xy 20.606705 -114.569419)
			(xy 20.618292 -114.516174) (xy 20.63734 -114.465121) (xy 20.66346 -114.417299) (xy 20.69612 -114.373681)
			(xy 20.734655 -114.335156) (xy 20.778282 -114.302507) (xy 20.826111 -114.276399) (xy 20.877169 -114.257365)
			(xy 20.930416 -114.245791) (xy 20.984768 -114.241913) (xy 21.039119 -114.24581) (xy 21.092362 -114.257403)
			(xy 21.143413 -114.276456) (xy 21.191233 -114.30258) (xy 21.213318 -114.318542) (xy 21.23233 -114.332138)
			(xy 21.274213 -114.35287) (xy 21.319181 -114.365596) (xy 21.365718 -114.369886) (xy 21.412255 -114.365596)
			(xy 21.457223 -114.35287) (xy 21.499106 -114.332138) (xy 21.518118 -114.318542) (xy 21.540209 -114.30258)
			(xy 21.58804 -114.276457) (xy 21.639103 -114.257408) (xy 21.692357 -114.245822) (xy 21.746718 -114.241933)
			(xy 21.801079 -114.245822) (xy 21.854333 -114.257408) (xy 21.905396 -114.276457) (xy 21.953227 -114.30258)
			(xy 21.975318 -114.318542) (xy 21.99433 -114.332138) (xy 22.036213 -114.35287) (xy 22.081181 -114.365596)
			(xy 22.127718 -114.369886) (xy 22.174255 -114.365596) (xy 22.219223 -114.35287) (xy 22.261106 -114.332138)
			(xy 22.280118 -114.318542) (xy 22.302159 -114.302516) (xy 22.349986 -114.276392) (xy 22.401044 -114.25734)
			(xy 22.454295 -114.245749) (xy 22.508652 -114.241854) (xy 22.563011 -114.245735) (xy 22.616264 -114.257313)
			(xy 22.667327 -114.276352) (xy 22.715161 -114.302464) (xy 22.758791 -114.335119) (xy 22.79733 -114.37365)
			(xy 22.829993 -114.417274) (xy 22.856116 -114.465102) (xy 22.875165 -114.516162) (xy 22.886754 -114.569412)
			(xy 22.890646 -114.62377) (xy 22.886762 -114.678128) (xy 22.875182 -114.731381) (xy 22.856141 -114.782443)
			(xy 22.838434 -114.814875) (xy 29.585164 -114.814875) (xy 29.587452 -114.7598) (xy 29.597643 -114.705628)
			(xy 29.615525 -114.653487) (xy 29.640726 -114.604463) (xy 29.67272 -114.559576) (xy 29.710842 -114.519762)
			(xy 29.754297 -114.485849) (xy 29.802182 -114.458544) (xy 29.853497 -114.438415) (xy 29.907176 -114.425882)
			(xy 29.962099 -114.421205) (xy 30.017124 -114.424483) (xy 30.071104 -114.435646) (xy 30.122915 -114.454462)
			(xy 30.171479 -114.48054) (xy 30.215783 -114.513335) (xy 30.254906 -114.552167) (xy 30.288032 -114.596225)
			(xy 30.314472 -114.644592) (xy 30.333675 -114.696261) (xy 30.345242 -114.750156) (xy 30.34893 -114.805155)
			(xy 30.344665 -114.860112) (xy 30.332533 -114.913883) (xy 30.312789 -114.965347) (xy 30.285842 -115.013434)
			(xy 30.269434 -115.035584) (xy 30.256833 -115.052648) (xy 30.236964 -115.090124) (xy 30.223594 -115.130379)
			(xy 30.217095 -115.172295) (xy 30.217647 -115.214709) (xy 30.225235 -115.256442) (xy 30.239649 -115.296336)
			(xy 30.260487 -115.333282) (xy 30.273498 -115.350036) (xy 30.290417 -115.371798) (xy 30.318574 -115.419182)
			(xy 30.339618 -115.470126) (xy 30.353111 -115.523568) (xy 30.358771 -115.578395) (xy 30.35648 -115.633467)
			(xy 30.346287 -115.687635) (xy 30.328403 -115.739772) (xy 30.303201 -115.788792) (xy 30.271206 -115.833675)
			(xy 30.233084 -115.873484) (xy 30.189629 -115.907393) (xy 30.141746 -115.934693) (xy 30.090432 -115.954818)
			(xy 30.036756 -115.967347) (xy 29.981836 -115.972019) (xy 29.926814 -115.968739) (xy 29.872838 -115.957573)
			(xy 29.821031 -115.938754) (xy 29.772472 -115.912674) (xy 29.728173 -115.879877) (xy 29.689055 -115.841045)
			(xy 29.655934 -115.796988) (xy 29.629499 -115.748621) (xy 29.610301 -115.696954) (xy 29.598739 -115.643061)
			(xy 29.595055 -115.588065) (xy 29.599325 -115.533112) (xy 29.61146 -115.479345) (xy 29.631208 -115.427885)
			(xy 29.658157 -115.379803) (xy 29.674566 -115.357656) (xy 29.687129 -115.340566) (xy 29.707001 -115.303096)
			(xy 29.720374 -115.262846) (xy 29.726878 -115.220934) (xy 29.726331 -115.178524) (xy 29.718748 -115.136794)
			(xy 29.704342 -115.096903) (xy 29.68351 -115.059958) (xy 29.670502 -115.043204) (xy 29.653532 -115.021481)
			(xy 29.625371 -114.974096) (xy 29.604323 -114.92315) (xy 29.590827 -114.869705) (xy 29.585164 -114.814875)
			(xy 22.838434 -114.814875) (xy 22.830026 -114.830276) (xy 22.79737 -114.873905) (xy 22.758837 -114.912442)
			(xy 22.715211 -114.945103) (xy 22.667382 -114.971223) (xy 22.616321 -114.99027) (xy 22.56307 -115.001856)
			(xy 22.508712 -115.005746) (xy 22.454354 -115.00186) (xy 22.401102 -114.990277) (xy 22.350041 -114.971233)
			(xy 22.302209 -114.945116) (xy 22.280118 -114.929158) (xy 22.261106 -114.915562) (xy 22.219223 -114.89483)
			(xy 22.174255 -114.882104) (xy 22.127718 -114.877814) (xy 22.081181 -114.882104) (xy 22.036213 -114.89483)
			(xy 21.99433 -114.915562) (xy 21.975318 -114.929158) (xy 21.953227 -114.94512) (xy 21.905396 -114.971243)
			(xy 21.854333 -114.990292) (xy 21.801079 -115.001878) (xy 21.746718 -115.005767) (xy 21.692357 -115.001878)
			(xy 21.639103 -114.990292) (xy 21.58804 -114.971243) (xy 21.540209 -114.94512) (xy 21.518118 -114.929158)
			(xy 21.499106 -114.915562) (xy 21.457223 -114.89483) (xy 21.412255 -114.882104) (xy 21.365718 -114.877814)
			(xy 21.319181 -114.882104) (xy 21.274213 -114.89483) (xy 21.23233 -114.915562) (xy 21.213318 -114.929158)
			(xy 21.191183 -114.945052) (xy 21.143359 -114.971169) (xy 21.092305 -114.990214) (xy 21.03906 -115.001799)
			(xy 20.984708 -115.005687) (xy 20.930357 -115.001801) (xy 20.877111 -114.990219) (xy 20.826056 -114.971176)
			(xy 20.778231 -114.945061) (xy 20.73461 -114.912405) (xy 20.696081 -114.873873) (xy 20.663427 -114.83025)
			(xy 20.637315 -114.782424) (xy 20.618275 -114.731368) (xy 20.606696 -114.678122) (xy 20.602813 -114.62377)
			(xy 18.300575 -114.62377) (xy 18.290728 -114.669023) (xy 18.271681 -114.720079) (xy 18.24556 -114.767905)
			(xy 18.212899 -114.811526) (xy 18.174362 -114.850054) (xy 18.130733 -114.882706) (xy 18.082902 -114.908816)
			(xy 18.031841 -114.927852) (xy 17.978591 -114.939427) (xy 17.924236 -114.943306) (xy 17.869881 -114.939409)
			(xy 17.816635 -114.927816) (xy 17.765581 -114.908762) (xy 17.717758 -114.882636) (xy 17.695672 -114.866674)
			(xy 17.67666 -114.853078) (xy 17.634777 -114.832346) (xy 17.589809 -114.81962) (xy 17.543272 -114.81533)
			(xy 17.496735 -114.81962) (xy 17.451767 -114.832346) (xy 17.409884 -114.853078) (xy 17.390872 -114.866674)
			(xy 17.368781 -114.882636) (xy 17.32095 -114.908759) (xy 17.269887 -114.927808) (xy 17.216633 -114.939394)
			(xy 17.162272 -114.943283) (xy 17.107911 -114.939394) (xy 17.054657 -114.927808) (xy 17.003594 -114.908759)
			(xy 16.955763 -114.882636) (xy 16.933672 -114.866674) (xy 16.91466 -114.853078) (xy 16.872777 -114.832346)
			(xy 16.827809 -114.81962) (xy 16.781272 -114.81533) (xy 16.734735 -114.81962) (xy 16.689767 -114.832346)
			(xy 16.647884 -114.853078) (xy 16.628872 -114.866674) (xy 16.606816 -114.882677) (xy 16.558991 -114.908798)
			(xy 16.507935 -114.927846) (xy 16.454687 -114.939435) (xy 16.400333 -114.943327) (xy 16.345977 -114.939444)
			(xy 16.292728 -114.927865) (xy 16.241668 -114.908825) (xy 16.193838 -114.882713) (xy 16.150211 -114.850059)
			(xy 16.111676 -114.811529) (xy 16.079016 -114.767906) (xy 16.052897 -114.72008) (xy 16.03385 -114.669023)
			(xy 16.022264 -114.615775) (xy 16.018373 -114.56142) (xy 12.16152 -114.56142) (xy 12.16152 -116.867499)
			(xy 30.372467 -116.867499) (xy 30.374793 -116.811363) (xy 30.385326 -116.756176) (xy 30.40384 -116.70313)
			(xy 30.429934 -116.653374) (xy 30.463043 -116.607982) (xy 30.502451 -116.567938) (xy 30.547307 -116.534106)
			(xy 30.596639 -116.507219) (xy 30.649382 -116.487859) (xy 30.704393 -116.476443) (xy 30.760484 -116.473219)
			(xy 30.816442 -116.478257) (xy 30.871055 -116.491448) (xy 30.923143 -116.512506) (xy 30.947614 -116.52631)
			(xy 30.967809 -116.537602) (xy 31.011272 -116.553456) (xy 31.056887 -116.56118) (xy 31.103147 -116.56052)
			(xy 31.148523 -116.551497) (xy 31.191516 -116.53441) (xy 31.230706 -116.509822) (xy 31.248096 -116.49456)
			(xy 31.26942 -116.475705) (xy 31.316603 -116.443869) (xy 31.367993 -116.419396) (xy 31.422448 -116.402831)
			(xy 31.47876 -116.394539) (xy 31.535679 -116.394706) (xy 31.591941 -116.403328) (xy 31.646298 -116.420214)
			(xy 31.697543 -116.444988) (xy 31.744538 -116.4771) (xy 31.765748 -116.496084) (xy 31.783436 -116.511807)
			(xy 31.823472 -116.537033) (xy 31.867486 -116.55441) (xy 31.913957 -116.563335) (xy 31.961277 -116.5635)
			(xy 32.00781 -116.554899) (xy 32.051944 -116.537829) (xy 32.072326 -116.525802) (xy 32.095868 -116.511861)
			(xy 32.146016 -116.489993) (xy 32.198775 -116.475516) (xy 32.253061 -116.468725) (xy 32.30776 -116.469761)
			(xy 32.36175 -116.478601) (xy 32.413923 -116.495066) (xy 32.463208 -116.518816) (xy 32.508594 -116.549364)
			(xy 32.549149 -116.586084) (xy 32.584042 -116.628222) (xy 32.612555 -116.674913) (xy 32.634105 -116.725199)
			(xy 32.648248 -116.778049) (xy 32.654695 -116.832377) (xy 32.653313 -116.887068) (xy 32.64413 -116.941001)
			(xy 32.627336 -116.993069) (xy 32.603274 -117.042202) (xy 32.572439 -117.087394) (xy 32.535463 -117.127716)
			(xy 32.493105 -117.162341) (xy 32.446234 -117.190558) (xy 32.395813 -117.211788) (xy 32.342875 -117.225597)
			(xy 32.288507 -117.231699) (xy 32.233825 -117.229971) (xy 32.179952 -117.220447) (xy 32.127991 -117.203323)
			(xy 32.079011 -117.178951) (xy 32.034016 -117.14783) (xy 32.013652 -117.12956) (xy 31.995966 -117.113835)
			(xy 31.955929 -117.088613) (xy 31.911914 -117.071241) (xy 31.865443 -117.062317) (xy 31.818124 -117.062152)
			(xy 31.771592 -117.070751) (xy 31.727457 -117.087817) (xy 31.707074 -117.099842) (xy 31.681617 -117.11497)
			(xy 31.627058 -117.137991) (xy 31.569598 -117.152308) (xy 31.510616 -117.157577) (xy 31.451528 -117.153672)
			(xy 31.393753 -117.140687) (xy 31.338676 -117.118933) (xy 31.312866 -117.104414) (xy 31.292683 -117.093099)
			(xy 31.249216 -117.077246) (xy 31.203598 -117.069523) (xy 31.157336 -117.070186) (xy 31.111958 -117.079213)
			(xy 31.068963 -117.096306) (xy 31.029774 -117.120899) (xy 31.012384 -117.136164) (xy 30.99135 -117.154791)
			(xy 30.944846 -117.186319) (xy 30.894221 -117.210685) (xy 30.84057 -117.227363) (xy 30.785053 -117.235991)
			(xy 30.728871 -117.236383) (xy 30.673238 -117.228532) (xy 30.619359 -117.212605) (xy 30.568399 -117.188949)
			(xy 30.521459 -117.158074) (xy 30.479555 -117.120648) (xy 30.443594 -117.077482) (xy 30.414352 -117.029507)
			(xy 30.392463 -116.977763) (xy 30.3784 -116.923368) (xy 30.372467 -116.867499) (xy 12.16152 -116.867499)
			(xy 12.16152 -117.357144) (xy 12.161922 -117.371979) (xy 12.168777 -117.400847) (xy 12.182106 -117.427356)
			(xy 12.201191 -117.450074) (xy 12.225003 -117.467777) (xy 12.238482 -117.473984) (xy 12.262822 -117.484929)
			(xy 12.308437 -117.512629) (xy 12.349746 -117.546416) (xy 12.385941 -117.585633) (xy 12.416316 -117.629512)
			(xy 12.440277 -117.677198) (xy 12.457357 -117.727758) (xy 12.462764 -117.753892) (xy 12.470384 -117.79377)
			(xy 12.5095 -117.831616) (xy 12.541536 -117.820636) (xy 12.608016 -117.807746) (xy 12.641834 -117.805962)
			(xy 12.658093 -117.80489) (xy 12.689286 -117.795511) (xy 12.717071 -117.778511) (xy 12.728702 -117.7671)
			(xy 12.743688 -117.751606) (xy 12.761722 -117.694964) (xy 12.760706 -117.689122) (xy 12.752776 -117.662761)
			(xy 12.743705 -117.608467) (xy 12.742528 -117.553432) (xy 12.74927 -117.498799) (xy 12.763791 -117.445702)
			(xy 12.78579 -117.395242) (xy 12.814809 -117.348465) (xy 12.850249 -117.306343) (xy 12.891371 -117.26975)
			(xy 12.937325 -117.239444) (xy 12.987156 -117.216054) (xy 13.03983 -117.200066) (xy 13.094255 -117.191812)
			(xy 13.149301 -117.191462) (xy 13.203826 -117.199024) (xy 13.256699 -117.214341) (xy 13.306823 -117.237096)
			(xy 13.353158 -117.266815) (xy 13.394743 -117.302883) (xy 13.430715 -117.344551) (xy 13.460327 -117.390955)
			(xy 13.482965 -117.441132) (xy 13.498159 -117.494041) (xy 13.505595 -117.548583) (xy 13.505118 -117.603628)
			(xy 13.496737 -117.658034) (xy 13.480627 -117.710671) (xy 13.457122 -117.760447) (xy 13.42671 -117.80633)
			(xy 13.390021 -117.847368) (xy 13.347817 -117.88271) (xy 13.300973 -117.911621) (xy 13.250462 -117.933503)
			(xy 13.224002 -117.94109) (xy 13.201295 -117.947779) (xy 13.15868 -117.968378) (xy 13.120605 -117.996498)
			(xy 13.104114 -118.01348) (xy 13.093729 -118.025398) (xy 13.078622 -118.053156) (xy 13.070814 -118.083777)
			(xy 13.070783 -118.115379) (xy 13.074142 -118.130828) (xy 13.080935 -118.159836) (xy 13.081813 -118.167888)
			(xy 15.159009 -118.167888) (xy 15.166229 -118.112696) (xy 15.181391 -118.059139) (xy 15.204174 -118.008353)
			(xy 15.234094 -117.961416) (xy 15.270516 -117.919325) (xy 15.312667 -117.882971) (xy 15.359652 -117.853128)
			(xy 15.410475 -117.830428) (xy 15.464057 -117.815354) (xy 15.51926 -117.808224) (xy 15.574914 -117.809191)
			(xy 15.629837 -117.818233) (xy 15.682863 -117.835159) (xy 15.732867 -117.85961) (xy 15.778788 -117.891067)
			(xy 15.799562 -117.909594) (xy 15.816336 -117.924366) (xy 15.853973 -117.948466) (xy 15.895242 -117.965617)
			(xy 15.938874 -117.975293) (xy 15.983525 -117.977195) (xy 16.027821 -117.971265) (xy 16.070399 -117.957686)
			(xy 16.090392 -117.947694) (xy 16.115908 -117.934752) (xy 16.169914 -117.915865) (xy 16.226134 -117.905254)
			(xy 16.283308 -117.903155) (xy 16.340155 -117.909616) (xy 16.3954 -117.924492) (xy 16.447805 -117.947449)
			(xy 16.496195 -117.977974) (xy 16.539485 -118.015381) (xy 16.576705 -118.058832) (xy 16.592296 -118.082822)
			(xy 16.601398 -118.096288) (xy 16.625047 -118.118563) (xy 16.653554 -118.134145) (xy 16.685072 -118.142022)
			(xy 16.717558 -118.141684) (xy 16.748905 -118.133154) (xy 16.763238 -118.125494) (xy 16.78763 -118.111951)
			(xy 16.839513 -118.091437) (xy 16.893831 -118.078696) (xy 16.949425 -118.074001) (xy 17.00511 -118.077451)
			(xy 17.059699 -118.088973) (xy 17.112028 -118.108321) (xy 17.160982 -118.135083) (xy 17.205518 -118.168688)
			(xy 17.244686 -118.20842) (xy 17.27765 -118.253432) (xy 17.303709 -118.302764) (xy 17.322306 -118.355365)
			(xy 17.333046 -118.410113) (xy 17.335699 -118.465842) (xy 17.330209 -118.521363) (xy 17.316692 -118.575493)
			(xy 17.295438 -118.627077) (xy 17.266898 -118.675017) (xy 17.231683 -118.71829) (xy 17.190541 -118.755974)
			(xy 17.14435 -118.787265) (xy 17.094095 -118.811497) (xy 17.040848 -118.828153) (xy 16.985742 -118.836877)
			(xy 16.929954 -118.837484) (xy 16.874672 -118.829962) (xy 16.821074 -118.814469) (xy 16.770304 -118.791337)
			(xy 16.723443 -118.761058) (xy 16.68149 -118.724279) (xy 16.645341 -118.681783) (xy 16.630142 -118.658386)
			(xy 16.621102 -118.644875) (xy 16.59744 -118.622597) (xy 16.568918 -118.607018) (xy 16.537387 -118.599149)
			(xy 16.504889 -118.599498) (xy 16.473534 -118.608045) (xy 16.4592 -118.615714) (xy 16.435665 -118.628779)
			(xy 16.385699 -118.648811) (xy 16.333415 -118.661625) (xy 16.27985 -118.666966) (xy 16.226065 -118.66473)
			(xy 16.173128 -118.654959) (xy 16.122089 -118.637848) (xy 16.073959 -118.613737) (xy 16.029694 -118.583104)
			(xy 16.00962 -118.565168) (xy 15.992854 -118.550385) (xy 15.955217 -118.526282) (xy 15.913946 -118.509128)
			(xy 15.870312 -118.499453) (xy 15.825659 -118.497553) (xy 15.781361 -118.503487) (xy 15.738783 -118.517073)
			(xy 15.71879 -118.527068) (xy 15.693948 -118.539625) (xy 15.64148 -118.558211) (xy 15.58687 -118.568977)
			(xy 15.531274 -118.571695) (xy 15.475873 -118.566305) (xy 15.421844 -118.552924) (xy 15.370332 -118.531834)
			(xy 15.32243 -118.503484) (xy 15.279157 -118.468475) (xy 15.241428 -118.42755) (xy 15.210047 -118.381578)
			(xy 15.185677 -118.331534) (xy 15.168838 -118.27848) (xy 15.159885 -118.223543) (xy 15.159009 -118.167888)
			(xy 13.081813 -118.167888) (xy 13.087391 -118.219061) (xy 13.085611 -118.278611) (xy 13.075629 -118.337345)
			(xy 13.057636 -118.39414) (xy 13.031976 -118.447907) (xy 12.999142 -118.497619) (xy 12.95976 -118.542323)
			(xy 12.914586 -118.581164) (xy 12.864483 -118.613398) (xy 12.837668 -118.626382) (xy 12.82355 -118.633492)
			(xy 12.799069 -118.653475) (xy 12.780249 -118.67886) (xy 12.768241 -118.70809) (xy 12.765532 -118.723664)
			(xy 12.762986 -118.744456) (xy 12.763926 -118.78633) (xy 12.771716 -118.827484) (xy 12.786147 -118.866805)
			(xy 12.806828 -118.903229) (xy 12.833199 -118.93577) (xy 12.84859 -118.949978) (xy 12.868432 -118.968142)
			(xy 12.90332 -119.009085) (xy 12.932109 -119.054525) (xy 12.954229 -119.103558) (xy 12.96924 -119.155213)
			(xy 12.976845 -119.208465) (xy 12.976893 -119.262256) (xy 12.969383 -119.315521) (xy 12.954464 -119.367203)
			(xy 12.932432 -119.416276) (xy 12.920216 -119.435632) (xy 31.688031 -119.435632) (xy 31.693649 -119.381451)
			(xy 31.706914 -119.328619) (xy 31.727556 -119.27821) (xy 31.755156 -119.231248) (xy 31.789154 -119.188688)
			(xy 31.808674 -119.169688) (xy 31.824433 -119.154178) (xy 31.850895 -119.11876) (xy 31.870834 -119.079299)
			(xy 31.883648 -119.036985) (xy 31.888952 -118.993092) (xy 31.886586 -118.948944) (xy 31.87662 -118.905869)
			(xy 31.859355 -118.865168) (xy 31.835312 -118.828065) (xy 31.820612 -118.811548) (xy 31.802346 -118.791336)
			(xy 31.771251 -118.746602) (xy 31.746834 -118.697901) (xy 31.729589 -118.646223) (xy 31.719867 -118.592618)
			(xy 31.717867 -118.538175) (xy 31.723628 -118.484001) (xy 31.737034 -118.431197) (xy 31.757812 -118.380835)
			(xy 31.785541 -118.33394) (xy 31.819655 -118.291464) (xy 31.859463 -118.254271) (xy 31.904155 -118.223115)
			(xy 31.952823 -118.198632) (xy 32.004477 -118.181317) (xy 32.058069 -118.171523) (xy 32.112509 -118.169449)
			(xy 32.166691 -118.175138) (xy 32.219513 -118.188472) (xy 32.269903 -118.209182) (xy 32.316835 -118.236847)
			(xy 32.359357 -118.270904) (xy 32.396605 -118.310662) (xy 32.42782 -118.355312) (xy 32.45237 -118.403946)
			(xy 32.469754 -118.455578) (xy 32.47962 -118.509156) (xy 32.481767 -118.563594) (xy 32.476152 -118.617783)
			(xy 32.462889 -118.670623) (xy 32.442247 -118.721041) (xy 32.414646 -118.76801) (xy 32.380646 -118.810578)
			(xy 32.361124 -118.829582) (xy 32.345394 -118.845121) (xy 32.318931 -118.880534) (xy 32.298991 -118.919989)
			(xy 32.286174 -118.962299) (xy 32.283456 -118.984776) (xy 33.984182 -118.984776) (xy 33.988253 -118.929154)
			(xy 34.000379 -118.874717) (xy 34.020302 -118.822626) (xy 34.047598 -118.773991) (xy 34.081684 -118.729848)
			(xy 34.121833 -118.691139) (xy 34.167191 -118.658688) (xy 34.216791 -118.633187) (xy 34.269575 -118.61518)
			(xy 34.324418 -118.60505) (xy 34.380152 -118.603013) (xy 34.435589 -118.609113) (xy 34.489546 -118.623219)
			(xy 34.540875 -118.645031) (xy 34.588481 -118.674085) (xy 34.631349 -118.70976) (xy 34.668566 -118.751297)
			(xy 34.699339 -118.79781) (xy 34.723011 -118.848307) (xy 34.739079 -118.901714) (xy 34.747199 -118.95689)
			(xy 34.747708 -118.984776) (xy 34.747199 -119.012662) (xy 34.739079 -119.067838) (xy 34.723011 -119.121245)
			(xy 34.699339 -119.171742) (xy 34.668566 -119.218255) (xy 34.631349 -119.259792) (xy 34.588481 -119.295467)
			(xy 34.540875 -119.324521) (xy 34.489546 -119.346333) (xy 34.435589 -119.360439) (xy 34.380152 -119.366539)
			(xy 34.324418 -119.364502) (xy 34.269575 -119.354372) (xy 34.216791 -119.336365) (xy 34.167191 -119.310864)
			(xy 34.121833 -119.278413) (xy 34.081684 -119.239704) (xy 34.047598 -119.195561) (xy 34.020302 -119.146926)
			(xy 34.000379 -119.094835) (xy 33.988253 -119.040398) (xy 33.984182 -118.984776) (xy 32.283456 -118.984776)
			(xy 32.280867 -119.006187) (xy 32.28323 -119.050332) (xy 32.293191 -119.093404) (xy 32.310451 -119.134103)
			(xy 32.334489 -119.171205) (xy 32.349186 -119.187722) (xy 32.367396 -119.207981) (xy 32.398481 -119.252712)
			(xy 32.42289 -119.301409) (xy 32.440127 -119.353082) (xy 32.44984 -119.406681) (xy 32.451834 -119.461116)
			(xy 32.446068 -119.515282) (xy 32.432658 -119.568078) (xy 32.411877 -119.61843) (xy 32.384148 -119.665316)
			(xy 32.350033 -119.707782) (xy 32.310227 -119.744967) (xy 32.265539 -119.776113) (xy 32.216875 -119.800589)
			(xy 32.165226 -119.817896) (xy 32.111641 -119.827683) (xy 32.057208 -119.829752) (xy 32.003034 -119.82406)
			(xy 31.95022 -119.810722) (xy 31.89984 -119.790011) (xy 31.852916 -119.762346) (xy 31.810402 -119.72829)
			(xy 31.773164 -119.688535) (xy 31.741956 -119.643889) (xy 31.717413 -119.595259) (xy 31.700035 -119.543634)
			(xy 31.690174 -119.490062) (xy 31.688031 -119.435632) (xy 12.920216 -119.435632) (xy 12.903723 -119.461766)
			(xy 12.868908 -119.502772) (xy 12.849098 -119.52097) (xy 12.832304 -119.536576) (xy 12.804087 -119.572702)
			(xy 12.782807 -119.613303) (xy 12.769153 -119.657063) (xy 12.763568 -119.702561) (xy 12.766233 -119.748324)
			(xy 12.777063 -119.792867) (xy 12.795705 -119.834745) (xy 12.808204 -119.853964) (xy 12.823235 -119.876811)
			(xy 12.83805 -119.907034) (xy 29.773358 -119.907034) (xy 29.77416 -119.852378) (xy 29.782754 -119.798396)
			(xy 29.798964 -119.746193) (xy 29.822457 -119.696837) (xy 29.852753 -119.651339) (xy 29.889232 -119.610629)
			(xy 29.931147 -119.575543) (xy 29.977639 -119.546797) (xy 30.027759 -119.524979) (xy 30.080478 -119.510538)
			(xy 30.13472 -119.503767) (xy 30.189372 -119.504807) (xy 30.243316 -119.513634) (xy 30.295449 -119.53007)
			(xy 30.344702 -119.553777) (xy 30.390069 -119.58427) (xy 30.410658 -119.60225) (xy 30.422326 -119.612075)
			(xy 30.44918 -119.626514) (xy 30.478695 -119.634164) (xy 30.509182 -119.634589) (xy 30.538899 -119.627763)
			(xy 30.566145 -119.614076) (xy 30.578044 -119.604536) (xy 30.599172 -119.587192) (xy 30.645413 -119.558044)
			(xy 30.695341 -119.535794) (xy 30.747932 -119.520896) (xy 30.802112 -119.513656) (xy 30.85677 -119.514221)
			(xy 30.910788 -119.52258) (xy 30.96306 -119.538563) (xy 31.012517 -119.561841) (xy 31.058145 -119.591938)
			(xy 31.099012 -119.628239) (xy 31.13428 -119.67) (xy 31.163228 -119.716366) (xy 31.185263 -119.766389)
			(xy 31.199934 -119.819044) (xy 31.206941 -119.873255) (xy 31.206312 -119.916194) (xy 36.762942 -119.916194)
			(xy 36.767013 -119.860572) (xy 36.779139 -119.806135) (xy 36.799062 -119.754044) (xy 36.826358 -119.705409)
			(xy 36.860444 -119.661266) (xy 36.900593 -119.622557) (xy 36.945951 -119.590106) (xy 36.995551 -119.564605)
			(xy 37.048335 -119.546598) (xy 37.103178 -119.536468) (xy 37.158912 -119.534431) (xy 37.214349 -119.540531)
			(xy 37.268306 -119.554637) (xy 37.319635 -119.576449) (xy 37.367241 -119.605503) (xy 37.410109 -119.641178)
			(xy 37.447326 -119.682715) (xy 37.478099 -119.729228) (xy 37.501771 -119.779725) (xy 37.517839 -119.833132)
			(xy 37.525959 -119.888308) (xy 37.526468 -119.916194) (xy 37.525959 -119.94408) (xy 37.517839 -119.999256)
			(xy 37.501771 -120.052663) (xy 37.478099 -120.10316) (xy 37.447326 -120.149673) (xy 37.410109 -120.19121)
			(xy 37.367241 -120.226885) (xy 37.319635 -120.255939) (xy 37.268306 -120.277751) (xy 37.214349 -120.291857)
			(xy 37.158912 -120.297957) (xy 37.103178 -120.29592) (xy 37.048335 -120.28579) (xy 36.995551 -120.267783)
			(xy 36.945951 -120.242282) (xy 36.900593 -120.209831) (xy 36.860444 -120.171122) (xy 36.826358 -120.126979)
			(xy 36.799062 -120.078344) (xy 36.779139 -120.026253) (xy 36.767013 -119.971816) (xy 36.762942 -119.916194)
			(xy 31.206312 -119.916194) (xy 31.206141 -119.92791) (xy 31.197549 -119.981891) (xy 31.181342 -120.034094)
			(xy 31.157851 -120.08345) (xy 31.127557 -120.128949) (xy 31.09108 -120.169659) (xy 31.049168 -120.204747)
			(xy 31.002677 -120.233495) (xy 30.95256 -120.255314) (xy 30.899842 -120.269758) (xy 30.845602 -120.276532)
			(xy 30.790951 -120.275495) (xy 30.737007 -120.266671) (xy 30.684874 -120.250239) (xy 30.63562 -120.226536)
			(xy 30.590252 -120.196046) (xy 30.569662 -120.178068) (xy 30.558054 -120.16817) (xy 30.53118 -120.153747)
			(xy 30.501651 -120.146112) (xy 30.471153 -120.145703) (xy 30.44143 -120.152541) (xy 30.414178 -120.166237)
			(xy 30.402276 -120.175782) (xy 30.381131 -120.193106) (xy 30.334889 -120.222255) (xy 30.284961 -120.244506)
			(xy 30.232368 -120.259404) (xy 30.178188 -120.266644) (xy 30.123529 -120.266079) (xy 30.06951 -120.257719)
			(xy 30.017237 -120.241736) (xy 29.967779 -120.218457) (xy 29.92215 -120.188359) (xy 29.881283 -120.152057)
			(xy 29.846015 -120.110294) (xy 29.817068 -120.063926) (xy 29.795033 -120.013902) (xy 29.780363 -119.961245)
			(xy 29.773358 -119.907034) (xy 12.83805 -119.907034) (xy 12.847307 -119.925917) (xy 12.864121 -119.977956)
			(xy 12.873333 -120.031863) (xy 12.874754 -120.086533) (xy 12.868355 -120.140846) (xy 12.854267 -120.193688)
			(xy 12.832778 -120.243978) (xy 12.80433 -120.290685) (xy 12.769504 -120.332851) (xy 12.729015 -120.369613)
			(xy 12.683692 -120.400217) (xy 12.634463 -120.424037) (xy 12.582338 -120.440584) (xy 12.528385 -120.449519)
			(xy 12.473708 -120.45066) (xy 12.446508 -120.447816) (xy 12.425107 -120.445647) (xy 12.382142 -120.447678)
			(xy 12.340133 -120.456915) (xy 12.300279 -120.473093) (xy 12.263718 -120.495751) (xy 12.231494 -120.524242)
			(xy 12.204528 -120.557752) (xy 12.18359 -120.595324) (xy 12.169277 -120.635886) (xy 12.161998 -120.678278)
			(xy 12.16152 -120.699784) (xy 12.16152 -120.925082) (xy 12.161963 -120.946723) (xy 12.169309 -120.989378)
			(xy 12.183776 -121.030172) (xy 12.204944 -121.067925) (xy 12.232202 -121.101546) (xy 12.264761 -121.130064)
			(xy 12.301681 -121.152654) (xy 12.341895 -121.168662) (xy 12.384239 -121.177626) (xy 12.42749 -121.179288)
			(xy 12.470397 -121.173598) (xy 12.491212 -121.167652) (xy 12.51714 -121.160057) (xy 12.570471 -121.15141)
			(xy 12.624488 -121.150372) (xy 12.678112 -121.156965) (xy 12.730269 -121.171056) (xy 12.779917 -121.192363)
			(xy 12.826062 -121.220461) (xy 12.867783 -121.254788) (xy 12.904244 -121.294657) (xy 12.934717 -121.339271)
			(xy 12.958591 -121.387737) (xy 12.97539 -121.439086) (xy 12.984777 -121.492291) (xy 12.986564 -121.546289)
			(xy 12.980717 -121.599999) (xy 12.967352 -121.652346) (xy 12.946736 -121.702285) (xy 12.919281 -121.748817)
			(xy 12.902692 -121.77014) (xy 12.875006 -121.804938) (xy 12.875006 -121.893838) (xy 12.902692 -121.928636)
			(xy 12.919193 -121.950024) (xy 12.946639 -121.99655) (xy 12.967247 -122.046482) (xy 12.980608 -122.098822)
			(xy 12.986452 -122.152522) (xy 12.984663 -122.206511) (xy 12.975278 -122.259707) (xy 12.958483 -122.311048)
			(xy 12.934615 -122.359507) (xy 12.90415 -122.404115) (xy 12.867698 -122.443979) (xy 12.825988 -122.478304)
			(xy 12.779854 -122.506403) (xy 12.730217 -122.527714) (xy 12.678071 -122.541811) (xy 12.624457 -122.548411)
			(xy 12.570449 -122.547384) (xy 12.517126 -122.538749) (xy 12.491212 -122.531124) (xy 12.470415 -122.525089)
			(xy 12.427491 -122.519376) (xy 12.38422 -122.521023) (xy 12.341855 -122.529982) (xy 12.301622 -122.545992)
			(xy 12.264685 -122.568592) (xy 12.232114 -122.597126) (xy 12.204851 -122.630769) (xy 12.183687 -122.668546)
			(xy 12.169233 -122.709365) (xy 12.161908 -122.752043) (xy 12.16152 -122.773694) (xy 12.16152 -123.678188)
			(xy 12.161964 -123.699929) (xy 12.169365 -123.742777) (xy 12.183953 -123.783739) (xy 12.205301 -123.821619)
			(xy 12.232787 -123.855312) (xy 12.265608 -123.883833) (xy 12.302806 -123.90635) (xy 12.343294 -123.922206)
			(xy 12.385891 -123.930936) (xy 12.429351 -123.932288) (xy 12.472408 -123.92622) (xy 12.493244 -123.919996)
			(xy 12.519186 -123.91217) (xy 12.572604 -123.903081) (xy 12.626771 -123.901642) (xy 12.680596 -123.907884)
			(xy 12.732997 -123.92168) (xy 12.782917 -123.942752) (xy 12.829353 -123.970677) (xy 12.87137 -124.004892)
			(xy 12.908122 -124.044709) (xy 12.93887 -124.089326) (xy 12.962994 -124.137845) (xy 12.98001 -124.18929)
			(xy 12.989574 -124.242625) (xy 12.991493 -124.296777) (xy 12.985731 -124.350656) (xy 12.982671 -124.362714)
			(xy 15.159724 -124.362714) (xy 15.164005 -124.305663) (xy 15.176757 -124.249891) (xy 15.197694 -124.196648)
			(xy 15.226346 -124.147128) (xy 15.24381 -124.124466) (xy 15.254049 -124.110706) (xy 15.267532 -124.079186)
			(xy 15.27214 -124.045214) (xy 15.26754 -124.011241) (xy 15.254063 -123.979718) (xy 15.24381 -123.96597)
			(xy 15.227242 -123.94456) (xy 15.199759 -123.897917) (xy 15.179146 -123.847858) (xy 15.165816 -123.795388)
			(xy 15.160038 -123.74156) (xy 15.161926 -123.687456) (xy 15.171444 -123.634162) (xy 15.188399 -123.582748)
			(xy 15.212453 -123.534248) (xy 15.243121 -123.489635) (xy 15.279787 -123.449805) (xy 15.300452 -123.432316)
			(xy 15.318534 -123.416904) (xy 15.349126 -123.380558) (xy 15.372434 -123.339161) (xy 15.387644 -123.294154)
			(xy 15.394228 -123.247106) (xy 15.391956 -123.199653) (xy 15.380908 -123.153448) (xy 15.361468 -123.110101)
			(xy 15.334313 -123.071119) (xy 15.317724 -123.05411) (xy 15.298006 -123.03414) (xy 15.264103 -122.989417)
			(xy 15.237118 -122.94021) (xy 15.217633 -122.887581) (xy 15.206067 -122.832665) (xy 15.202671 -122.776647)
			(xy 15.207518 -122.720736) (xy 15.220504 -122.666138) (xy 15.241347 -122.614032) (xy 15.269599 -122.565541)
			(xy 15.286736 -122.543316) (xy 15.29702 -122.529588) (xy 15.310494 -122.498056) (xy 15.315092 -122.464075)
			(xy 15.310481 -122.430096) (xy 15.296994 -122.398569) (xy 15.286736 -122.38482) (xy 15.269716 -122.362676)
			(xy 15.241587 -122.314427) (xy 15.220791 -122.262593) (xy 15.207773 -122.208282) (xy 15.20281 -122.152654)
			(xy 15.206008 -122.096896) (xy 15.217299 -122.042199) (xy 15.236443 -121.989733) (xy 15.263029 -121.940618)
			(xy 15.27937 -121.917968) (xy 15.292997 -121.898977) (xy 15.313729 -121.857088) (xy 15.326453 -121.812116)
			(xy 15.330739 -121.765574) (xy 15.326444 -121.719034) (xy 15.313711 -121.674064) (xy 15.29297 -121.63218)
			(xy 15.27937 -121.613168) (xy 15.26341 -121.59108) (xy 15.237289 -121.543254) (xy 15.218241 -121.492198)
			(xy 15.206653 -121.438951) (xy 15.202761 -121.384596) (xy 15.206645 -121.330241) (xy 15.218225 -121.276992)
			(xy 15.237266 -121.225933) (xy 15.26338 -121.178103) (xy 15.296035 -121.134477) (xy 15.334566 -121.095943)
			(xy 15.37819 -121.063285) (xy 15.426017 -121.037168) (xy 15.477075 -121.018123) (xy 15.530323 -121.006539)
			(xy 15.584678 -121.002651) (xy 15.639033 -121.006539) (xy 15.692281 -121.018123) (xy 15.743339 -121.037168)
			(xy 15.791166 -121.063285) (xy 15.83479 -121.095943) (xy 15.873321 -121.134477) (xy 15.905976 -121.178103)
			(xy 15.93209 -121.225933) (xy 15.951131 -121.276992) (xy 15.962711 -121.330241) (xy 15.966595 -121.384596)
			(xy 15.962778 -121.437908) (xy 35.002722 -121.437908) (xy 35.006793 -121.382286) (xy 35.018919 -121.327849)
			(xy 35.038842 -121.275758) (xy 35.066138 -121.227123) (xy 35.100224 -121.18298) (xy 35.140373 -121.144271)
			(xy 35.185731 -121.11182) (xy 35.235331 -121.086319) (xy 35.288115 -121.068312) (xy 35.342958 -121.058182)
			(xy 35.398692 -121.056145) (xy 35.454129 -121.062245) (xy 35.508086 -121.076351) (xy 35.559415 -121.098163)
			(xy 35.607021 -121.127217) (xy 35.649889 -121.162892) (xy 35.687106 -121.204429) (xy 35.717879 -121.250942)
			(xy 35.741551 -121.301439) (xy 35.757619 -121.354846) (xy 35.765739 -121.410022) (xy 35.766248 -121.437908)
			(xy 35.765739 -121.465794) (xy 35.757619 -121.52097) (xy 35.741551 -121.574377) (xy 35.717879 -121.624874)
			(xy 35.687106 -121.671387) (xy 35.649889 -121.712924) (xy 35.607021 -121.748599) (xy 35.559415 -121.777653)
			(xy 35.508086 -121.799465) (xy 35.454129 -121.813571) (xy 35.398692 -121.819671) (xy 35.342958 -121.817634)
			(xy 35.288115 -121.807504) (xy 35.235331 -121.789497) (xy 35.185731 -121.763996) (xy 35.140373 -121.731545)
			(xy 35.100224 -121.692836) (xy 35.066138 -121.648693) (xy 35.038842 -121.600058) (xy 35.018919 -121.547967)
			(xy 35.006793 -121.49353) (xy 35.002722 -121.437908) (xy 15.962778 -121.437908) (xy 15.962703 -121.438951)
			(xy 15.951115 -121.492198) (xy 15.932067 -121.543254) (xy 15.905946 -121.59108) (xy 15.889986 -121.613168)
			(xy 15.876421 -121.632201) (xy 15.855687 -121.674079) (xy 15.842958 -121.719042) (xy 15.838664 -121.765574)
			(xy 15.842949 -121.812108) (xy 15.855668 -121.857073) (xy 15.876394 -121.898956) (xy 15.889986 -121.917968)
			(xy 15.906344 -121.940612) (xy 15.932964 -121.989722) (xy 15.952134 -122.04219) (xy 15.963444 -122.096894)
			(xy 15.966651 -122.152662) (xy 15.965563 -122.164856) (xy 28.59227 -122.164856) (xy 28.596341 -122.109234)
			(xy 28.608467 -122.054797) (xy 28.62839 -122.002706) (xy 28.655686 -121.954071) (xy 28.689772 -121.909928)
			(xy 28.729921 -121.871219) (xy 28.775279 -121.838768) (xy 28.824879 -121.813267) (xy 28.877663 -121.79526)
			(xy 28.932506 -121.78513) (xy 28.98824 -121.783093) (xy 29.043677 -121.789193) (xy 29.097634 -121.803299)
			(xy 29.148963 -121.825111) (xy 29.196569 -121.854165) (xy 29.239437 -121.88984) (xy 29.276654 -121.931377)
			(xy 29.307427 -121.97789) (xy 29.331099 -122.028387) (xy 29.347167 -122.081794) (xy 29.355287 -122.13697)
			(xy 29.355332 -122.139456) (xy 31.64027 -122.139456) (xy 31.644341 -122.083834) (xy 31.656467 -122.029397)
			(xy 31.67639 -121.977306) (xy 31.703686 -121.928671) (xy 31.737772 -121.884528) (xy 31.777921 -121.845819)
			(xy 31.823279 -121.813368) (xy 31.872879 -121.787867) (xy 31.925663 -121.76986) (xy 31.980506 -121.75973)
			(xy 32.03624 -121.757693) (xy 32.091677 -121.763793) (xy 32.145634 -121.777899) (xy 32.196963 -121.799711)
			(xy 32.244569 -121.828765) (xy 32.287437 -121.86444) (xy 32.324654 -121.905977) (xy 32.355427 -121.95249)
			(xy 32.379099 -122.002987) (xy 32.395167 -122.056394) (xy 32.403287 -122.11157) (xy 32.403796 -122.139456)
			(xy 32.403287 -122.167342) (xy 32.395167 -122.222518) (xy 32.379099 -122.275925) (xy 32.355427 -122.326422)
			(xy 32.324654 -122.372935) (xy 32.287437 -122.414472) (xy 32.273013 -122.426476) (xy 34.281362 -122.426476)
			(xy 34.285433 -122.370854) (xy 34.297559 -122.316417) (xy 34.317482 -122.264326) (xy 34.344778 -122.215691)
			(xy 34.378864 -122.171548) (xy 34.419013 -122.132839) (xy 34.464371 -122.100388) (xy 34.513971 -122.074887)
			(xy 34.566755 -122.05688) (xy 34.621598 -122.04675) (xy 34.677332 -122.044713) (xy 34.732769 -122.050813)
			(xy 34.786726 -122.064919) (xy 34.838055 -122.086731) (xy 34.885661 -122.115785) (xy 34.928529 -122.15146)
			(xy 34.965746 -122.192997) (xy 34.996519 -122.23951) (xy 35.020191 -122.290007) (xy 35.036259 -122.343414)
			(xy 35.044379 -122.39859) (xy 35.044888 -122.426476) (xy 35.044379 -122.454362) (xy 35.036259 -122.509538)
			(xy 35.020191 -122.562945) (xy 34.996519 -122.613442) (xy 34.965746 -122.659955) (xy 34.928529 -122.701492)
			(xy 34.885661 -122.737167) (xy 34.838055 -122.766221) (xy 34.786726 -122.788033) (xy 34.732769 -122.802139)
			(xy 34.677332 -122.808239) (xy 34.621598 -122.806202) (xy 34.566755 -122.796072) (xy 34.513971 -122.778065)
			(xy 34.464371 -122.752564) (xy 34.419013 -122.720113) (xy 34.378864 -122.681404) (xy 34.344778 -122.637261)
			(xy 34.317482 -122.588626) (xy 34.297559 -122.536535) (xy 34.285433 -122.482098) (xy 34.281362 -122.426476)
			(xy 32.273013 -122.426476) (xy 32.244569 -122.450147) (xy 32.196963 -122.479201) (xy 32.145634 -122.501013)
			(xy 32.091677 -122.515119) (xy 32.03624 -122.521219) (xy 31.980506 -122.519182) (xy 31.925663 -122.509052)
			(xy 31.872879 -122.491045) (xy 31.823279 -122.465544) (xy 31.777921 -122.433093) (xy 31.737772 -122.394384)
			(xy 31.703686 -122.350241) (xy 31.67639 -122.301606) (xy 31.656467 -122.249515) (xy 31.644341 -122.195078)
			(xy 31.64027 -122.139456) (xy 29.355332 -122.139456) (xy 29.355796 -122.164856) (xy 29.355287 -122.192742)
			(xy 29.347167 -122.247918) (xy 29.331099 -122.301325) (xy 29.307427 -122.351822) (xy 29.276654 -122.398335)
			(xy 29.239437 -122.439872) (xy 29.196569 -122.475547) (xy 29.148963 -122.504601) (xy 29.097634 -122.526413)
			(xy 29.043677 -122.540519) (xy 28.98824 -122.546619) (xy 28.932506 -122.544582) (xy 28.877663 -122.534452)
			(xy 28.824879 -122.516445) (xy 28.775279 -122.490944) (xy 28.729921 -122.458493) (xy 28.689772 -122.419784)
			(xy 28.655686 -122.375641) (xy 28.62839 -122.327006) (xy 28.608467 -122.274915) (xy 28.596341 -122.220478)
			(xy 28.59227 -122.164856) (xy 15.965563 -122.164856) (xy 15.961686 -122.208302) (xy 15.948657 -122.262621)
			(xy 15.927842 -122.314459) (xy 15.899686 -122.362704) (xy 15.88262 -122.38482) (xy 15.872392 -122.398588)
			(xy 15.858904 -122.430105) (xy 15.854292 -122.464075) (xy 15.858891 -122.498047) (xy 15.872367 -122.529569)
			(xy 15.88262 -122.543316) (xy 15.899168 -122.56474) (xy 15.926649 -122.611381) (xy 15.947261 -122.661438)
			(xy 15.960591 -122.713906) (xy 15.96637 -122.767731) (xy 15.964483 -122.821833) (xy 15.954968 -122.875125)
			(xy 15.938015 -122.926537) (xy 15.913966 -122.975036) (xy 15.883302 -123.019649) (xy 15.846641 -123.05948)
			(xy 15.825978 -123.07697) (xy 15.80791 -123.092396) (xy 15.777325 -123.128743) (xy 15.754024 -123.170138)
			(xy 15.738817 -123.215141) (xy 15.732233 -123.262185) (xy 15.734502 -123.309634) (xy 15.745545 -123.355836)
			(xy 15.764977 -123.399182) (xy 15.792122 -123.438165) (xy 15.808706 -123.455176) (xy 15.828412 -123.475157)
			(xy 15.862312 -123.519879) (xy 15.889296 -123.569085) (xy 15.905522 -123.61291) (xy 18.487896 -123.61291)
			(xy 18.491967 -123.557288) (xy 18.504093 -123.502851) (xy 18.524016 -123.45076) (xy 18.551312 -123.402125)
			(xy 18.585398 -123.357982) (xy 18.625547 -123.319273) (xy 18.670905 -123.286822) (xy 18.720505 -123.261321)
			(xy 18.773289 -123.243314) (xy 18.828132 -123.233184) (xy 18.883866 -123.231147) (xy 18.939303 -123.237247)
			(xy 18.99326 -123.251353) (xy 19.044589 -123.273165) (xy 19.092195 -123.302219) (xy 19.135063 -123.337894)
			(xy 19.145358 -123.349384) (xy 28.959333 -123.349384) (xy 28.965725 -123.295092) (xy 28.9798 -123.242268)
			(xy 29.00127 -123.191994) (xy 29.029695 -123.145299) (xy 29.064494 -123.103138) (xy 29.104953 -123.066375)
			(xy 29.150244 -123.035763) (xy 29.199441 -123.011928) (xy 29.251536 -122.995358) (xy 29.305462 -122.986392)
			(xy 29.360116 -122.985214) (xy 29.414378 -122.991848) (xy 29.467139 -123.006158) (xy 29.517317 -123.027852)
			(xy 29.563885 -123.056485) (xy 29.60589 -123.09147) (xy 29.642473 -123.132093) (xy 29.672883 -123.17752)
			(xy 29.696499 -123.226822) (xy 29.712837 -123.27899) (xy 29.721563 -123.332956) (xy 29.722497 -123.387615)
			(xy 29.719524 -123.41479) (xy 29.717101 -123.438241) (xy 29.719888 -123.485298) (xy 29.73131 -123.531032)
			(xy 29.750976 -123.573873) (xy 29.778211 -123.61235) (xy 29.812077 -123.645139) (xy 29.851413 -123.671115)
			(xy 29.87294 -123.680728) (xy 29.898545 -123.692092) (xy 29.946418 -123.721181) (xy 29.989524 -123.756957)
			(xy 30.026935 -123.798651) (xy 30.057849 -123.845367) (xy 30.081599 -123.896101) (xy 30.09011 -123.92279)
			(xy 30.095062 -123.937571) (xy 30.111004 -123.964346) (xy 30.132962 -123.986456) (xy 30.159627 -124.002582)
			(xy 30.189407 -124.01176) (xy 30.220523 -124.013442) (xy 30.235906 -124.010928) (xy 30.259641 -124.006655)
			(xy 30.307762 -124.003436) (xy 30.355905 -124.006317) (xy 30.37967 -124.01042) (xy 30.401921 -124.014145)
			(xy 30.447027 -124.014631) (xy 30.491508 -124.007133) (xy 30.533962 -123.991889) (xy 30.573053 -123.969378)
			(xy 30.607547 -123.94031) (xy 30.636357 -123.905601) (xy 30.647894 -123.886214) (xy 30.662066 -123.862187)
			(xy 30.696327 -123.818164) (xy 30.736632 -123.779601) (xy 30.782124 -123.747317) (xy 30.831832 -123.722002)
			(xy 30.884696 -123.704194) (xy 30.93959 -123.694275) (xy 30.995343 -123.692455) (xy 31.050767 -123.698772)
			(xy 31.10468 -123.713093) (xy 31.155933 -123.735112) (xy 31.203433 -123.76436) (xy 31.246169 -123.800213)
			(xy 31.283228 -123.841906) (xy 31.31382 -123.888552) (xy 31.337295 -123.939155) (xy 31.35315 -123.992637)
			(xy 31.361048 -124.047858) (xy 31.360822 -124.10364) (xy 31.352474 -124.158795) (xy 31.336185 -124.212146)
			(xy 31.3123 -124.262557) (xy 31.281329 -124.308952) (xy 31.243932 -124.350343) (xy 31.200907 -124.385847)
			(xy 31.15317 -124.414708) (xy 31.101739 -124.436309) (xy 31.047712 -124.450191) (xy 30.992238 -124.456058)
			(xy 30.936502 -124.453785) (xy 30.909006 -124.449078) (xy 30.886759 -124.445331) (xy 30.841651 -124.444849)
			(xy 30.797168 -124.45235) (xy 30.754713 -124.467598) (xy 30.715622 -124.490113) (xy 30.681129 -124.519184)
			(xy 30.652318 -124.553896) (xy 30.640782 -124.573284) (xy 30.626672 -124.597312) (xy 30.592465 -124.641298)
			(xy 30.552223 -124.67984) (xy 30.506802 -124.712118) (xy 30.457169 -124.737446) (xy 30.40438 -124.755284)
			(xy 30.349557 -124.765253) (xy 30.293867 -124.767141) (xy 30.238495 -124.760909) (xy 30.184619 -124.746687)
			(xy 30.133384 -124.72478) (xy 30.085881 -124.695653) (xy 30.043121 -124.659925) (xy 30.006012 -124.618357)
			(xy 29.975345 -124.571834) (xy 29.951772 -124.521344) (xy 29.943298 -124.494798) (xy 29.938344 -124.480018)
			(xy 29.922402 -124.453244) (xy 29.900443 -124.431135) (xy 29.873779 -124.41501) (xy 29.844 -124.405831)
			(xy 29.812885 -124.404147) (xy 29.797502 -124.40666) (xy 29.770184 -124.411462) (xy 29.714781 -124.41408)
			(xy 29.659583 -124.408646) (xy 29.605754 -124.395274) (xy 29.55443 -124.374246) (xy 29.506693 -124.346005)
			(xy 29.46355 -124.311147) (xy 29.425912 -124.270408) (xy 29.394571 -124.224647) (xy 29.370189 -124.174828)
			(xy 29.353281 -124.122004) (xy 29.344202 -124.067287) (xy 29.343145 -124.011832) (xy 29.346144 -123.984258)
			(xy 29.348636 -123.960812) (xy 29.34584 -123.913749) (xy 29.334407 -123.86801) (xy 29.31473 -123.825167)
			(xy 29.287485 -123.78669) (xy 29.253606 -123.753902) (xy 29.21426 -123.72793) (xy 29.192728 -123.71832)
			(xy 29.167709 -123.707305) (xy 29.120887 -123.679088) (xy 29.078572 -123.644478) (xy 29.04163 -123.604183)
			(xy 29.010816 -123.559028) (xy 28.986762 -123.509938) (xy 28.96996 -123.457918) (xy 28.960754 -123.404032)
			(xy 28.959333 -123.349384) (xy 19.145358 -123.349384) (xy 19.17228 -123.379431) (xy 19.203053 -123.425944)
			(xy 19.226725 -123.476441) (xy 19.242793 -123.529848) (xy 19.250913 -123.585024) (xy 19.251422 -123.61291)
			(xy 19.250913 -123.640796) (xy 19.242793 -123.695972) (xy 19.226725 -123.749379) (xy 19.203053 -123.799876)
			(xy 19.17228 -123.846389) (xy 19.135063 -123.887926) (xy 19.092195 -123.923601) (xy 19.044589 -123.952655)
			(xy 18.99326 -123.974467) (xy 18.939303 -123.988573) (xy 18.883866 -123.994673) (xy 18.828132 -123.992636)
			(xy 18.773289 -123.982506) (xy 18.720505 -123.964499) (xy 18.670905 -123.938998) (xy 18.625547 -123.906547)
			(xy 18.585398 -123.867838) (xy 18.551312 -123.823695) (xy 18.524016 -123.77506) (xy 18.504093 -123.722969)
			(xy 18.491967 -123.668532) (xy 18.487896 -123.61291) (xy 15.905522 -123.61291) (xy 15.908781 -123.621712)
			(xy 15.920346 -123.676626) (xy 15.923743 -123.732642) (xy 15.918898 -123.788551) (xy 15.905916 -123.843148)
			(xy 15.885076 -123.895254) (xy 15.856829 -123.943745) (xy 15.839694 -123.96597) (xy 15.829421 -123.979706)
			(xy 15.815942 -124.011235) (xy 15.81134 -124.045214) (xy 15.815949 -124.079192) (xy 15.829435 -124.110718)
			(xy 15.839694 -124.124466) (xy 15.857176 -124.147116) (xy 15.88583 -124.196638) (xy 15.906768 -124.249884)
			(xy 15.91952 -124.30566) (xy 15.923802 -124.362714) (xy 15.919516 -124.419768) (xy 15.906759 -124.475543)
			(xy 15.885818 -124.528787) (xy 15.85716 -124.578308) (xy 15.839694 -124.60097) (xy 15.829421 -124.614706)
			(xy 15.815942 -124.646235) (xy 15.81134 -124.680214) (xy 15.815949 -124.714192) (xy 15.829435 -124.745718)
			(xy 15.839694 -124.759466) (xy 15.856575 -124.781363) (xy 15.884509 -124.829075) (xy 15.905263 -124.880319)
			(xy 15.918403 -124.934023) (xy 15.923652 -124.989061) (xy 15.920902 -125.044281) (xy 15.910209 -125.098525)
			(xy 15.891798 -125.150657) (xy 15.866055 -125.199586) (xy 15.833517 -125.244286) (xy 15.794868 -125.283821)
			(xy 15.750917 -125.317363) (xy 15.702585 -125.344209) (xy 15.650883 -125.363796) (xy 15.596895 -125.375715)
			(xy 15.541752 -125.379716) (xy 15.486609 -125.375715) (xy 15.432621 -125.363796) (xy 15.380919 -125.344209)
			(xy 15.332587 -125.317363) (xy 15.288636 -125.283821) (xy 15.249987 -125.244286) (xy 15.217449 -125.199586)
			(xy 15.191706 -125.150657) (xy 15.173295 -125.098525) (xy 15.162602 -125.044281) (xy 15.159852 -124.989061)
			(xy 15.165101 -124.934023) (xy 15.178241 -124.880319) (xy 15.198995 -124.829075) (xy 15.226929 -124.781363)
			(xy 15.24381 -124.759466) (xy 15.254049 -124.745706) (xy 15.267532 -124.714186) (xy 15.27214 -124.680214)
			(xy 15.26754 -124.646241) (xy 15.254063 -124.614718) (xy 15.24381 -124.60097) (xy 15.226362 -124.578295)
			(xy 15.197706 -124.528778) (xy 15.176765 -124.475536) (xy 15.164009 -124.419765) (xy 15.159724 -124.362714)
			(xy 12.982671 -124.362714) (xy 12.972401 -124.403177) (xy 12.951774 -124.453283) (xy 12.924263 -124.499965)
			(xy 12.907772 -124.521468) (xy 12.880086 -124.556266) (xy 12.880086 -124.645166) (xy 12.907772 -124.679964)
			(xy 12.924557 -124.70173) (xy 12.952362 -124.749144) (xy 12.973076 -124.800057) (xy 12.986272 -124.853414)
			(xy 12.991677 -124.908113) (xy 12.989178 -124.963021) (xy 12.978828 -125.017003) (xy 12.96084 -125.068941)
			(xy 12.935587 -125.117762) (xy 12.903591 -125.162454) (xy 12.865514 -125.202094) (xy 12.822144 -125.235861)
			(xy 12.774378 -125.263057) (xy 12.723205 -125.283118) (xy 12.669683 -125.295631) (xy 12.642342 -125.298454)
			(xy 12.619579 -125.300915) (xy 12.575414 -125.31297) (xy 12.53412 -125.332734) (xy 12.497031 -125.359571)
			(xy 12.465343 -125.392612) (xy 12.440081 -125.430792) (xy 12.422061 -125.472876) (xy 12.411865 -125.517507)
			(xy 12.409821 -125.563242) (xy 12.412472 -125.585982) (xy 12.415792 -125.613922) (xy 13.83741 -125.613922)
			(xy 13.841481 -125.5583) (xy 13.853607 -125.503863) (xy 13.87353 -125.451772) (xy 13.900826 -125.403137)
			(xy 13.934912 -125.358994) (xy 13.975061 -125.320285) (xy 14.020419 -125.287834) (xy 14.070019 -125.262333)
			(xy 14.122803 -125.244326) (xy 14.177646 -125.234196) (xy 14.23338 -125.232159) (xy 14.288817 -125.238259)
			(xy 14.342774 -125.252365) (xy 14.394103 -125.274177) (xy 14.441709 -125.303231) (xy 14.484577 -125.338906)
			(xy 14.521794 -125.380443) (xy 14.552567 -125.426956) (xy 14.576239 -125.477453) (xy 14.592307 -125.53086)
			(xy 14.600427 -125.586036) (xy 14.600936 -125.613922) (xy 14.600427 -125.641808) (xy 14.592307 -125.696984)
			(xy 14.576239 -125.750391) (xy 14.552567 -125.800888) (xy 14.521794 -125.847401) (xy 14.484577 -125.888938)
			(xy 14.441709 -125.924613) (xy 14.394103 -125.953667) (xy 14.342774 -125.975479) (xy 14.288817 -125.989585)
			(xy 14.23338 -125.995685) (xy 14.177646 -125.993648) (xy 14.122803 -125.983518) (xy 14.070019 -125.965511)
			(xy 14.020419 -125.94001) (xy 13.975061 -125.907559) (xy 13.934912 -125.86885) (xy 13.900826 -125.824707)
			(xy 13.87353 -125.776072) (xy 13.853607 -125.723981) (xy 13.841481 -125.669544) (xy 13.83741 -125.613922)
			(xy 12.415792 -125.613922) (xy 12.415827 -125.614219) (xy 12.415134 -125.671076) (xy 12.406015 -125.727201)
			(xy 12.388671 -125.781352) (xy 12.363487 -125.832332) (xy 12.347702 -125.855984) (xy 12.347448 -125.856238)
			(xy 12.33938 -125.86861) (xy 12.328582 -125.896095) (xy 12.324406 -125.925327) (xy 12.327074 -125.954735)
			(xy 12.336445 -125.982737) (xy 12.352014 -126.007829) (xy 12.36218 -126.018544) (xy 12.488672 -126.145036)
			(xy 12.57046 -126.157736) (xy 12.607544 -126.138432) (xy 12.631509 -126.12645) (xy 12.682018 -126.108576)
			(xy 12.734532 -126.09795) (xy 12.788017 -126.09478) (xy 12.841419 -126.09913) (xy 12.893685 -126.110914)
			(xy 12.943787 -126.1299) (xy 12.990738 -126.155713) (xy 13.01242 -126.171452) (xy 13.031432 -126.185048)
			(xy 13.073315 -126.20578) (xy 13.118283 -126.218506) (xy 13.16482 -126.222796) (xy 13.211357 -126.218506)
			(xy 13.256325 -126.20578) (xy 13.298208 -126.185048) (xy 13.31722 -126.171452) (xy 13.33927 -126.155552)
			(xy 13.386976 -126.129489) (xy 13.437899 -126.110462) (xy 13.491006 -126.098856) (xy 13.545224 -126.094906)
			(xy 13.599453 -126.098693) (xy 13.652596 -126.110138) (xy 13.703575 -126.129011) (xy 13.75136 -126.15493)
			(xy 13.794982 -126.187369) (xy 13.833557 -126.225672) (xy 13.866304 -126.269062) (xy 13.892561 -126.316662)
			(xy 13.911795 -126.367507) (xy 13.923618 -126.420567) (xy 13.927788 -126.474768) (xy 13.924223 -126.529012)
			(xy 13.912994 -126.582201) (xy 13.894328 -126.633257) (xy 13.868605 -126.681147) (xy 13.836343 -126.7249)
			(xy 13.798198 -126.763631) (xy 13.754942 -126.796555) (xy 13.707449 -126.823005) (xy 13.682218 -126.833122)
			(xy 13.660919 -126.841816) (xy 13.62163 -126.865736) (xy 13.587287 -126.896337) (xy 13.559012 -126.93262)
			(xy 13.537729 -126.973399) (xy 13.524132 -127.017342) (xy 13.518666 -127.063015) (xy 13.52151 -127.108925)
			(xy 13.532569 -127.153575) (xy 13.551484 -127.195504) (xy 13.577637 -127.233345) (xy 13.593572 -127.249936)
			(xy 14.259814 -127.916178)
		)
		(stroke
			(width 0)
			(type solid)
		)
		(fill yes)
		(layer "In7.Cu")
		(net "P5V_STB_NODE1")
	)
	(gr_poly
		(pts
			(xy 65.853818 -144.512538) (xy 65.869891 -144.512103) (xy 65.90103 -144.504125) (xy 65.929181 -144.488607)
			(xy 65.952551 -144.466536) (xy 65.969651 -144.439318) (xy 65.974976 -144.424146) (xy 65.984061 -144.397287)
			(xy 66.00905 -144.346394) (xy 66.041298 -144.299761) (xy 66.080093 -144.258416) (xy 66.124582 -144.223269)
			(xy 66.173784 -144.195096) (xy 66.226615 -144.174517) (xy 66.281909 -144.161985) (xy 66.33845 -144.157777)
			(xy 66.394991 -144.161985) (xy 66.450285 -144.174517) (xy 66.503116 -144.195096) (xy 66.552318 -144.223269)
			(xy 66.596807 -144.258416) (xy 66.635602 -144.299761) (xy 66.66785 -144.346394) (xy 66.692839 -144.397287)
			(xy 66.701924 -144.424146) (xy 66.707265 -144.439306) (xy 66.724389 -144.466495) (xy 66.74776 -144.488547)
			(xy 66.775896 -144.504066) (xy 66.807016 -144.512068) (xy 66.823082 -144.512538) (xy 80.023462 -144.512538)
			(xy 80.038665 -144.512122) (xy 80.068216 -144.504974) (xy 80.095233 -144.491027) (xy 80.118176 -144.471076)
			(xy 80.127348 -144.458944) (xy 80.143943 -144.436336) (xy 80.18268 -144.395784) (xy 80.226937 -144.36134)
			(xy 80.275761 -144.333749) (xy 80.328099 -144.313605) (xy 80.382823 -144.301342) (xy 80.438752 -144.297225)
			(xy 80.494681 -144.301342) (xy 80.549405 -144.313605) (xy 80.601743 -144.333749) (xy 80.650567 -144.36134)
			(xy 80.694824 -144.395784) (xy 80.733561 -144.436336) (xy 80.750156 -144.458944) (xy 80.76819 -144.48409)
			(xy 80.823054 -144.512538) (xy 82.709004 -144.512538) (xy 82.731227 -144.512078) (xy 82.774996 -144.504344)
			(xy 82.81675 -144.489111) (xy 82.855218 -144.466844) (xy 82.889223 -144.438224) (xy 82.91773 -144.404124)
			(xy 82.939868 -144.365583) (xy 82.954962 -144.323777) (xy 82.962551 -144.279983) (xy 82.962404 -144.235537)
			(xy 82.95894 -144.21358) (xy 82.954532 -144.186555) (xy 82.952592 -144.131835) (xy 82.958498 -144.077399)
			(xy 82.972129 -144.024367) (xy 82.993205 -143.973831) (xy 83.021291 -143.926828) (xy 83.055812 -143.884325)
			(xy 83.096056 -143.847196) (xy 83.141197 -143.816205) (xy 83.190306 -143.791989) (xy 83.242374 -143.775045)
			(xy 83.296329 -143.765723) (xy 83.323684 -143.764508) (xy 83.345752 -143.763392) (xy 83.389031 -143.754496)
			(xy 83.43012 -143.738254) (xy 83.467785 -143.715156) (xy 83.500891 -143.685896) (xy 83.528442 -143.651355)
			(xy 83.549609 -143.612572) (xy 83.55711 -143.591788) (xy 83.566472 -143.565644) (xy 83.591688 -143.516169)
			(xy 83.623812 -143.470873) (xy 83.662163 -143.430713) (xy 83.705932 -143.396538) (xy 83.754194 -143.369071)
			(xy 83.805928 -143.348892) (xy 83.860042 -143.336427) (xy 83.915391 -143.33194) (xy 83.970805 -143.335525)
			(xy 84.025114 -143.347107) (xy 84.07717 -143.366442) (xy 84.125873 -143.39312) (xy 84.170192 -143.426577)
			(xy 84.209193 -143.466107) (xy 84.242049 -143.510874) (xy 84.268067 -143.559932) (xy 84.286698 -143.612244)
			(xy 84.297546 -143.666705) (xy 84.299552 -143.694404) (xy 84.302092 -143.745204) (xy 84.375498 -143.815054)
			(xy 84.426552 -143.815054) (xy 84.452969 -143.815506) (xy 84.505297 -143.822803) (xy 84.556117 -143.83725)
			(xy 84.604458 -143.85857) (xy 84.649395 -143.886357) (xy 84.690069 -143.920078) (xy 84.708238 -143.93926)
			(xy 84.723988 -143.955769) (xy 84.760296 -143.983395) (xy 84.800954 -144.004094) (xy 84.844654 -144.017199)
			(xy 84.889993 -144.022289) (xy 84.935511 -144.019201) (xy 84.979747 -144.008035) (xy 85.021277 -143.989148)
			(xy 85.058767 -143.963148) (xy 85.075268 -143.947388) (xy 85.835998 -143.186658) (xy 85.84565 -143.160496)
			(xy 85.858012 -143.129139) (xy 85.892127 -143.071015) (xy 85.913468 -143.044926) (xy 85.922891 -143.033255)
			(xy 85.93651 -143.006537) (xy 85.943511 -142.977376) (xy 85.943507 -142.947387) (xy 85.936498 -142.918229)
			(xy 85.922871 -142.891514) (xy 85.913468 -142.879826) (xy 85.894839 -142.857173) (xy 85.864037 -142.807264)
			(xy 85.841235 -142.75323) (xy 85.826969 -142.696342) (xy 85.821575 -142.637942) (xy 85.825181 -142.579405)
			(xy 85.830918 -142.550642) (xy 85.831172 -142.549118) (xy 85.836986 -142.524914) (xy 85.854065 -142.478159)
			(xy 85.865208 -142.4559) (xy 85.87238 -142.440986) (xy 85.879607 -142.408703) (xy 85.878293 -142.375648)
			(xy 85.868528 -142.344041) (xy 85.850968 -142.316005) (xy 85.826791 -142.293425) (xy 85.797623 -142.277817)
			(xy 85.765424 -142.27023) (xy 85.748876 -142.270226) (xy 85.721747 -142.270543) (xy 85.667837 -142.264434)
			(xy 85.615338 -142.250748) (xy 85.565307 -142.229762) (xy 85.518753 -142.201899) (xy 85.476617 -142.167722)
			(xy 85.439748 -142.127921) (xy 85.40889 -142.083297) (xy 85.384665 -142.034751) (xy 85.367562 -141.983263)
			(xy 85.357927 -141.929871) (xy 85.355953 -141.875653) (xy 85.361681 -141.821702) (xy 85.374994 -141.769106)
			(xy 85.395625 -141.718928) (xy 85.423156 -141.672178) (xy 85.439758 -141.65072) (xy 85.450007 -141.636971)
			(xy 85.463475 -141.605448) (xy 85.468072 -141.571478) (xy 85.463464 -141.53751) (xy 85.449984 -141.505992)
			(xy 85.439758 -141.492224) (xy 85.422293 -141.469563) (xy 85.393639 -141.420044) (xy 85.372701 -141.366802)
			(xy 85.359948 -141.311029) (xy 85.355668 -141.253978) (xy 85.359955 -141.196927) (xy 85.372713 -141.141157)
			(xy 85.393658 -141.087916) (xy 85.422318 -141.038401) (xy 85.439758 -141.01572) (xy 85.450007 -141.001971)
			(xy 85.463475 -140.970448) (xy 85.468072 -140.936478) (xy 85.463464 -140.90251) (xy 85.449984 -140.870992)
			(xy 85.439758 -140.857224) (xy 85.423185 -140.835725) (xy 85.395645 -140.788947) (xy 85.375013 -140.738738)
			(xy 85.361704 -140.686112) (xy 85.355989 -140.632131) (xy 85.357982 -140.577885) (xy 85.367643 -140.524469)
			(xy 85.384778 -140.472962) (xy 85.409039 -140.424403) (xy 85.439937 -140.379772) (xy 85.47685 -140.339972)
			(xy 85.51903 -140.305804) (xy 85.565627 -140.27796) (xy 85.6157 -140.257001) (xy 85.668238 -140.24335)
			(xy 85.722181 -140.237283) (xy 85.776439 -140.238922) (xy 85.829917 -140.248235) (xy 85.881535 -140.265033)
			(xy 85.906102 -140.27658) (xy 85.921893 -140.283708) (xy 85.95593 -140.29009) (xy 85.990429 -140.287081)
			(xy 86.022847 -140.274903) (xy 86.037166 -140.26515) (xy 86.063328 -140.247624) (xy 86.076902 -140.238722)
			(xy 86.099394 -140.21533) (xy 86.115274 -140.18703) (xy 86.12352 -140.155644) (xy 86.124034 -140.13942)
			(xy 86.124034 -137.86104) (xy 86.10854 -137.832592) (xy 86.096009 -137.808521) (xy 86.077127 -137.757645)
			(xy 86.065645 -137.704607) (xy 86.061793 -137.650477) (xy 86.065651 -137.596348) (xy 86.07714 -137.543311)
			(xy 86.096028 -137.492438) (xy 86.10854 -137.468356) (xy 86.124034 -137.439908) (xy 86.124034 -137.225024)
			(xy 84.428584 -135.529574) (xy 84.411941 -135.513601) (xy 84.374008 -135.487361) (xy 84.331962 -135.468399)
			(xy 84.287183 -135.457338) (xy 84.241144 -135.454542) (xy 84.195356 -135.460102) (xy 84.151324 -135.473836)
			(xy 84.110494 -135.495293) (xy 84.074208 -135.523767) (xy 84.043658 -135.558323) (xy 84.019847 -135.597826)
			(xy 84.011262 -135.619236) (xy 84.0012 -135.644502) (xy 83.974949 -135.692129) (xy 83.942201 -135.735545)
			(xy 83.903618 -135.773871) (xy 83.859984 -135.806329) (xy 83.812183 -135.832261) (xy 83.761184 -135.851143)
			(xy 83.70802 -135.86259) (xy 83.653769 -135.866372) (xy 83.599531 -135.862411) (xy 83.546406 -135.850788)
			(xy 83.495469 -135.831738) (xy 83.447754 -135.805648) (xy 83.404227 -135.773046) (xy 83.365772 -135.734593)
			(xy 83.333166 -135.691069) (xy 83.307073 -135.643356) (xy 83.288019 -135.59242) (xy 83.276393 -135.539295)
			(xy 83.272428 -135.485058) (xy 83.276206 -135.430806) (xy 83.28765 -135.377642) (xy 83.306528 -135.326641)
			(xy 83.332457 -135.278838) (xy 83.364912 -135.235202) (xy 83.403235 -135.196617) (xy 83.446649 -135.163865)
			(xy 83.494274 -135.137611) (xy 83.519518 -135.127492) (xy 83.540894 -135.118852) (xy 83.58035 -135.095007)
			(xy 83.614862 -135.064442) (xy 83.6433 -135.028157) (xy 83.664733 -134.987341) (xy 83.678459 -134.943331)
			(xy 83.684028 -134.897567) (xy 83.681259 -134.851549) (xy 83.670241 -134.806784) (xy 83.651335 -134.764737)
			(xy 83.625161 -134.726787) (xy 83.60918 -134.71017) (xy 76.693776 -127.794766) (xy 74.119232 -127.794766)
			(xy 74.113644 -127.800354) (xy 74.101452 -127.800354) (xy 74.046334 -127.829564) (xy 74.0283 -127.855472)
			(xy 74.013253 -127.876561) (xy 73.977927 -127.914453) (xy 73.937363 -127.946674) (xy 73.89246 -127.972509)
			(xy 73.844216 -127.991383) (xy 73.793703 -128.002878) (xy 73.742042 -128.006739) (xy 73.690381 -128.002878)
			(xy 73.639868 -127.991383) (xy 73.591624 -127.972509) (xy 73.546721 -127.946674) (xy 73.506157 -127.914453)
			(xy 73.470831 -127.876561) (xy 73.455784 -127.855472) (xy 73.43775 -127.829564) (xy 73.382632 -127.800354)
			(xy 72.501506 -127.800354) (xy 72.446388 -127.829564) (xy 72.428354 -127.855472) (xy 72.413063 -127.876899)
			(xy 72.377073 -127.915312) (xy 72.335698 -127.947853) (xy 72.289886 -127.973777) (xy 72.240686 -127.992491)
			(xy 72.189226 -128.003565) (xy 72.136683 -128.006745) (xy 72.084263 -128.00196) (xy 72.033165 -127.989318)
			(xy 71.98456 -127.969109) (xy 71.939562 -127.941797) (xy 71.899201 -127.908006) (xy 71.864403 -127.868511)
			(xy 71.835963 -127.824216) (xy 71.82485 -127.800354) (xy 71.808594 -127.800354) (xy 71.721472 -127.887476)
			(xy 71.539354 -127.887476) (xy 71.375016 -128.051814) (xy 71.158862 -128.051814) (xy 71.077074 -128.082294)
			(xy 71.060818 -128.095248) (xy 71.033621 -128.116445) (xy 70.974586 -128.152076) (xy 70.911272 -128.179391)
			(xy 70.844845 -128.197888) (xy 70.776525 -128.207225) (xy 70.742048 -128.20777) (xy 70.292214 -128.20777)
			(xy 70.084696 -128.000252) (xy 70.072539 -127.988794) (xy 70.043613 -127.972102) (xy 70.011349 -127.963481)
			(xy 69.977952 -127.963521) (xy 69.945708 -127.972218) (xy 69.931026 -127.980186) (xy 69.907136 -127.993542)
			(xy 69.856321 -128.013871) (xy 69.803078 -128.026549) (xy 69.748554 -128.031302) (xy 69.69392 -128.028028)
			(xy 69.640354 -128.016797) (xy 69.589007 -127.997851) (xy 69.540983 -127.971597) (xy 69.497317 -127.938601)
			(xy 69.458947 -127.899572) (xy 69.426699 -127.85535) (xy 69.401268 -127.806886) (xy 69.383199 -127.755224)
			(xy 69.372882 -127.701474) (xy 69.370538 -127.646793) (xy 69.376219 -127.592357) (xy 69.389802 -127.539338)
			(xy 69.410994 -127.488877) (xy 69.43934 -127.442058) (xy 69.47423 -127.399889) (xy 69.514913 -127.363278)
			(xy 69.560515 -127.333012) (xy 69.610053 -127.309743) (xy 69.662462 -127.29397) (xy 69.716615 -127.286034)
			(xy 69.771346 -127.286104) (xy 69.825478 -127.29418) (xy 69.851778 -127.301752) (xy 69.869812 -127.307086)
			(xy 69.889116 -127.307086) (xy 69.905762 -127.306541) (xy 69.93792 -127.29792) (xy 69.96675 -127.28127)
			(xy 69.990289 -127.257726) (xy 70.006932 -127.228892) (xy 70.015545 -127.196732) (xy 70.016116 -127.180086)
			(xy 70.016116 -125.442726) (xy 68.452492 -123.879102) (xy 68.452492 -120.640602) (xy 68.955412 -120.137682)
			(xy 69.534532 -120.137682) (xy 69.758052 -119.914162) (xy 69.758052 -117.463062) (xy 69.265292 -116.970302)
			(xy 67.638422 -116.970302) (xy 67.615264 -116.970838) (xy 67.569723 -116.979278) (xy 67.526463 -116.995827)
			(xy 67.486917 -117.019938) (xy 67.452393 -117.050813) (xy 67.424032 -117.087431) (xy 67.402773 -117.128581)
			(xy 67.389319 -117.172901) (xy 67.3862 -117.195854) (xy 67.3826 -117.223482) (xy 67.368421 -117.277362)
			(xy 67.346557 -117.328606) (xy 67.317473 -117.376127) (xy 67.281788 -117.418912) (xy 67.240261 -117.456054)
			(xy 67.193773 -117.486762) (xy 67.143314 -117.510383) (xy 67.089957 -117.526415) (xy 67.034835 -117.534517)
			(xy 66.979121 -117.534517) (xy 66.923999 -117.526415) (xy 66.870642 -117.510383) (xy 66.820183 -117.486762)
			(xy 66.773695 -117.456054) (xy 66.732168 -117.418912) (xy 66.696483 -117.376127) (xy 66.667399 -117.328606)
			(xy 66.645535 -117.277362) (xy 66.631356 -117.223482) (xy 66.627756 -117.195854) (xy 66.624661 -117.172891)
			(xy 66.611229 -117.128552) (xy 66.58998 -117.087383) (xy 66.561621 -117.050748) (xy 66.527089 -117.019862)
			(xy 66.48753 -116.995748) (xy 66.444255 -116.979205) (xy 66.398698 -116.970782) (xy 66.375534 -116.970302)
			(xy 66.05778 -116.970302) (xy 66.035601 -116.970787) (xy 65.991919 -116.978493) (xy 65.950237 -116.993666)
			(xy 65.911824 -117.015847) (xy 65.877846 -117.044361) (xy 65.849335 -117.078342) (xy 65.827157 -117.116757)
			(xy 65.811987 -117.15844) (xy 65.804285 -117.202123) (xy 65.80378 -117.224302) (xy 65.80329 -117.25227)
			(xy 65.795121 -117.307606) (xy 65.778959 -117.361156) (xy 65.755151 -117.411772) (xy 65.724206 -117.458368)
			(xy 65.686789 -117.499946) (xy 65.643701 -117.535615) (xy 65.595867 -117.564609) (xy 65.544311 -117.586307)
			(xy 65.490139 -117.600243) (xy 65.434513 -117.60612) (xy 65.378625 -117.60381) (xy 65.323673 -117.593364)
			(xy 65.270836 -117.575005) (xy 65.221247 -117.549128) (xy 65.175967 -117.516286) (xy 65.135969 -117.477184)
			(xy 65.10211 -117.43266) (xy 65.075116 -117.383669) (xy 65.055565 -117.331261) (xy 65.043877 -117.276561)
			(xy 65.041526 -117.248686) (xy 65.038478 -117.200934) (xy 65.004696 -117.166898) (xy 64.992525 -117.155545)
			(xy 64.963686 -117.138956) (xy 64.931542 -117.130371) (xy 64.898272 -117.130371) (xy 64.866128 -117.138956)
			(xy 64.837289 -117.155545) (xy 64.825118 -117.166898) (xy 64.704722 -117.287294) (xy 64.699642 -117.293644)
			(xy 64.699134 -117.294152) (xy 64.684408 -117.312477) (xy 64.651164 -117.345719) (xy 64.63284 -117.360446)
			(xy 64.632332 -117.360954) (xy 64.625982 -117.366034) (xy 64.620394 -117.371622) (xy 64.605662 -117.380258)
			(xy 64.60363 -117.381528) (xy 64.600836 -117.383052) (xy 64.575854 -117.39805) (xy 64.522339 -117.421097)
			(xy 64.465937 -117.435717) (xy 64.437006 -117.439186) (xy 64.411082 -117.441381) (xy 64.359088 -117.439561)
			(xy 64.307825 -117.430683) (xy 64.258246 -117.414914) (xy 64.234568 -117.404134) (xy 64.221343 -117.398309)
			(xy 64.193116 -117.392143) (xy 64.164226 -117.392467) (xy 64.136145 -117.399267) (xy 64.123062 -117.405404)
			(xy 64.098192 -117.417324) (xy 64.045844 -117.434675) (xy 63.991542 -117.444304) (xy 63.936419 -117.44601)
			(xy 63.881626 -117.439757) (xy 63.828305 -117.425677) (xy 63.777568 -117.404062) (xy 63.753746 -117.390164)
			(xy 63.723266 -117.371622) (xy 59.24677 -117.371622) (xy 59.172602 -117.44579) (xy 59.172602 -117.498622)
			(xy 59.172082 -117.52585) (xy 59.164266 -117.579742) (xy 59.148867 -117.631976) (xy 59.126197 -117.681489)
			(xy 59.096717 -117.727276) (xy 59.061026 -117.768406) (xy 59.019849 -117.804042) (xy 58.974023 -117.833461)
			(xy 58.92448 -117.856065) (xy 58.872225 -117.871395) (xy 58.818322 -117.879138) (xy 58.763866 -117.879138)
			(xy 58.709963 -117.871395) (xy 58.657708 -117.856065) (xy 58.608165 -117.833461) (xy 58.562339 -117.804042)
			(xy 58.521162 -117.768406) (xy 58.485471 -117.727276) (xy 58.455991 -117.681489) (xy 58.433321 -117.631976)
			(xy 58.417922 -117.579742) (xy 58.410106 -117.52585) (xy 58.409586 -117.498622) (xy 58.409586 -117.44579)
			(xy 58.335418 -117.371622) (xy 57.620916 -117.371622) (xy 57.600342 -117.378734) (xy 57.575909 -117.386855)
			(xy 57.525474 -117.397205) (xy 57.474104 -117.400676) (xy 57.422734 -117.397205) (xy 57.372299 -117.386855)
			(xy 57.347866 -117.378734) (xy 57.327292 -117.371622) (xy 56.726328 -117.371622) (xy 56.467248 -117.630702)
			(xy 56.467248 -118.082822) (xy 62.220092 -118.082822) (xy 62.224163 -118.0272) (xy 62.236289 -117.972763)
			(xy 62.256212 -117.920672) (xy 62.283508 -117.872037) (xy 62.317594 -117.827894) (xy 62.357743 -117.789185)
			(xy 62.403101 -117.756734) (xy 62.452701 -117.731233) (xy 62.505485 -117.713226) (xy 62.560328 -117.703096)
			(xy 62.616062 -117.701059) (xy 62.671499 -117.707159) (xy 62.725456 -117.721265) (xy 62.776785 -117.743077)
			(xy 62.824391 -117.772131) (xy 62.867259 -117.807806) (xy 62.904476 -117.849343) (xy 62.935249 -117.895856)
			(xy 62.958921 -117.946353) (xy 62.974989 -117.99976) (xy 62.983109 -118.054936) (xy 62.983618 -118.082822)
			(xy 62.983109 -118.110708) (xy 62.974989 -118.165884) (xy 62.958921 -118.219291) (xy 62.935249 -118.269788)
			(xy 62.904476 -118.316301) (xy 62.867259 -118.357838) (xy 62.824391 -118.393513) (xy 62.776785 -118.422567)
			(xy 62.725456 -118.444379) (xy 62.671499 -118.458485) (xy 62.616062 -118.464585) (xy 62.560328 -118.462548)
			(xy 62.505485 -118.452418) (xy 62.452701 -118.434411) (xy 62.403101 -118.40891) (xy 62.357743 -118.376459)
			(xy 62.317594 -118.33775) (xy 62.283508 -118.293607) (xy 62.256212 -118.244972) (xy 62.236289 -118.192881)
			(xy 62.224163 -118.138444) (xy 62.220092 -118.082822) (xy 56.467248 -118.082822) (xy 56.467248 -120.035066)
			(xy 57.086752 -120.035066) (xy 57.090823 -119.979444) (xy 57.102949 -119.925007) (xy 57.122872 -119.872916)
			(xy 57.150168 -119.824281) (xy 57.184254 -119.780138) (xy 57.224403 -119.741429) (xy 57.269761 -119.708978)
			(xy 57.319361 -119.683477) (xy 57.372145 -119.66547) (xy 57.426988 -119.65534) (xy 57.482722 -119.653303)
			(xy 57.538159 -119.659403) (xy 57.592116 -119.673509) (xy 57.643445 -119.695321) (xy 57.691051 -119.724375)
			(xy 57.733919 -119.76005) (xy 57.771136 -119.801587) (xy 57.801909 -119.8481) (xy 57.825581 -119.898597)
			(xy 57.841649 -119.952004) (xy 57.849769 -120.00718) (xy 57.850278 -120.035066) (xy 57.849769 -120.062952)
			(xy 57.841649 -120.118128) (xy 57.825581 -120.171535) (xy 57.801909 -120.222032) (xy 57.771136 -120.268545)
			(xy 57.733919 -120.310082) (xy 57.691051 -120.345757) (xy 57.643445 -120.374811) (xy 57.592116 -120.396623)
			(xy 57.538159 -120.410729) (xy 57.482722 -120.416829) (xy 57.426988 -120.414792) (xy 57.372145 -120.404662)
			(xy 57.319361 -120.386655) (xy 57.269761 -120.361154) (xy 57.224403 -120.328703) (xy 57.184254 -120.289994)
			(xy 57.150168 -120.245851) (xy 57.122872 -120.197216) (xy 57.102949 -120.145125) (xy 57.090823 -120.090688)
			(xy 57.086752 -120.035066) (xy 56.467248 -120.035066) (xy 56.467248 -120.167654) (xy 56.407812 -120.22709)
			(xy 56.407812 -120.362726) (xy 55.873396 -120.362726) (xy 55.856732 -120.363223) (xy 55.824542 -120.371856)
			(xy 55.795687 -120.388532) (xy 55.772135 -120.412113) (xy 55.755495 -120.440989) (xy 55.750714 -120.45696)
			(xy 55.743072 -120.483669) (xy 55.721121 -120.5347) (xy 55.692 -120.582007) (xy 55.656324 -120.624589)
			(xy 55.614849 -120.661547) (xy 55.568452 -120.692097) (xy 55.518114 -120.715593) (xy 55.4649 -120.731539)
			(xy 55.409936 -120.739597) (xy 55.354384 -120.739597) (xy 55.29942 -120.731539) (xy 55.246206 -120.715593)
			(xy 55.195868 -120.692097) (xy 55.149471 -120.661547) (xy 55.107996 -120.624589) (xy 55.07232 -120.582007)
			(xy 55.043199 -120.5347) (xy 55.021248 -120.483669) (xy 55.013606 -120.45696) (xy 55.008821 -120.440995)
			(xy 54.992169 -120.412136) (xy 54.968616 -120.38857) (xy 54.939765 -120.371904) (xy 54.907583 -120.363274)
			(xy 54.890924 -120.362726) (xy 54.152292 -120.362726) (xy 53.504592 -121.010426) (xy 53.504592 -121.914832)
			(xy 56.112376 -121.914832) (xy 56.1146 -121.860171) (xy 56.124608 -121.806387) (xy 56.142194 -121.754583)
			(xy 56.166997 -121.705822) (xy 56.19851 -121.661103) (xy 56.236085 -121.621342) (xy 56.278953 -121.587355)
			(xy 56.326236 -121.559837) (xy 56.351424 -121.54916) (xy 56.372047 -121.540341) (xy 56.410068 -121.516553)
			(xy 56.443318 -121.486457) (xy 56.470764 -121.450987) (xy 56.491552 -121.411247) (xy 56.505036 -121.368473)
			(xy 56.510797 -121.323996) (xy 56.508654 -121.279199) (xy 56.498675 -121.235474) (xy 56.490362 -121.214642)
			(xy 56.480163 -121.189263) (xy 56.466281 -121.13636) (xy 56.460097 -121.082016) (xy 56.461736 -121.027346)
			(xy 56.471165 -120.97347) (xy 56.48819 -120.921493) (xy 56.512464 -120.87248) (xy 56.543488 -120.827436)
			(xy 56.580626 -120.787283) (xy 56.623117 -120.752845) (xy 56.670091 -120.724828) (xy 56.720584 -120.703805)
			(xy 56.773561 -120.690209) (xy 56.827937 -120.684316) (xy 56.882598 -120.68625) (xy 56.936422 -120.695968)
			(xy 56.988306 -120.713273) (xy 57.037188 -120.73781) (xy 57.082065 -120.769076) (xy 57.122018 -120.806429)
			(xy 57.156227 -120.849105) (xy 57.183991 -120.896229) (xy 57.204741 -120.946834) (xy 57.218053 -120.999884)
			(xy 57.223653 -121.054291) (xy 57.221426 -121.10894) (xy 57.211418 -121.162711) (xy 57.193834 -121.214502)
			(xy 57.169034 -121.263251) (xy 57.137528 -121.307959) (xy 57.09996 -121.34771) (xy 57.057101 -121.381689)
			(xy 57.009828 -121.4092) (xy 56.984646 -121.419874) (xy 56.963999 -121.42864) (xy 56.925978 -121.452436)
			(xy 56.892728 -121.482541) (xy 56.865284 -121.518019) (xy 56.844498 -121.557765) (xy 56.831018 -121.600545)
			(xy 56.825262 -121.645028) (xy 56.827409 -121.68983) (xy 56.837393 -121.733558) (xy 56.845708 -121.754392)
			(xy 56.855983 -121.779746) (xy 56.869877 -121.832659) (xy 56.870626 -121.839228) (xy 57.683398 -121.839228)
			(xy 57.687469 -121.783606) (xy 57.699595 -121.729169) (xy 57.719518 -121.677078) (xy 57.746814 -121.628443)
			(xy 57.7809 -121.5843) (xy 57.821049 -121.545591) (xy 57.866407 -121.51314) (xy 57.916007 -121.487639)
			(xy 57.968791 -121.469632) (xy 58.023634 -121.459502) (xy 58.079368 -121.457465) (xy 58.134805 -121.463565)
			(xy 58.188762 -121.477671) (xy 58.240091 -121.499483) (xy 58.287697 -121.528537) (xy 58.330565 -121.564212)
			(xy 58.367782 -121.605749) (xy 58.398555 -121.652262) (xy 58.422227 -121.702759) (xy 58.438295 -121.756166)
			(xy 58.446415 -121.811342) (xy 58.446924 -121.839228) (xy 58.446415 -121.867114) (xy 58.438295 -121.92229)
			(xy 58.422227 -121.975697) (xy 58.398555 -122.026194) (xy 58.367782 -122.072707) (xy 58.330565 -122.114244)
			(xy 58.287697 -122.149919) (xy 58.2678 -122.162062) (xy 59.107068 -122.162062) (xy 59.111139 -122.10644)
			(xy 59.123265 -122.052003) (xy 59.143188 -121.999912) (xy 59.170484 -121.951277) (xy 59.20457 -121.907134)
			(xy 59.244719 -121.868425) (xy 59.290077 -121.835974) (xy 59.339677 -121.810473) (xy 59.392461 -121.792466)
			(xy 59.447304 -121.782336) (xy 59.503038 -121.780299) (xy 59.558475 -121.786399) (xy 59.612432 -121.800505)
			(xy 59.663761 -121.822317) (xy 59.711367 -121.851371) (xy 59.754235 -121.887046) (xy 59.791452 -121.928583)
			(xy 59.822225 -121.975096) (xy 59.845897 -122.025593) (xy 59.861965 -122.079) (xy 59.870085 -122.134176)
			(xy 59.870594 -122.162062) (xy 59.870085 -122.189948) (xy 59.861965 -122.245124) (xy 59.845897 -122.298531)
			(xy 59.822225 -122.349028) (xy 59.791452 -122.395541) (xy 59.754235 -122.437078) (xy 59.711367 -122.472753)
			(xy 59.663761 -122.501807) (xy 59.612432 -122.523619) (xy 59.558475 -122.537725) (xy 59.503038 -122.543825)
			(xy 59.447304 -122.541788) (xy 59.392461 -122.531658) (xy 59.339677 -122.513651) (xy 59.290077 -122.48815)
			(xy 59.244719 -122.455699) (xy 59.20457 -122.41699) (xy 59.170484 -122.372847) (xy 59.143188 -122.324212)
			(xy 59.123265 -122.272121) (xy 59.111139 -122.217684) (xy 59.107068 -122.162062) (xy 58.2678 -122.162062)
			(xy 58.240091 -122.178973) (xy 58.188762 -122.200785) (xy 58.134805 -122.214891) (xy 58.079368 -122.220991)
			(xy 58.023634 -122.218954) (xy 57.968791 -122.208824) (xy 57.916007 -122.190817) (xy 57.866407 -122.165316)
			(xy 57.821049 -122.132865) (xy 57.7809 -122.094156) (xy 57.746814 -122.050013) (xy 57.719518 -122.001378)
			(xy 57.699595 -121.949287) (xy 57.687469 -121.89485) (xy 57.683398 -121.839228) (xy 56.870626 -121.839228)
			(xy 56.876073 -121.887014) (xy 56.874443 -121.941696) (xy 56.865021 -121.995586) (xy 56.848 -122.047577)
			(xy 56.823728 -122.096606) (xy 56.792704 -122.141665) (xy 56.755564 -122.181832) (xy 56.713067 -122.216284)
			(xy 56.666087 -122.244314) (xy 56.615585 -122.265348) (xy 56.562597 -122.278954) (xy 56.508209 -122.284854)
			(xy 56.453536 -122.282927) (xy 56.399699 -122.273212) (xy 56.347801 -122.255908) (xy 56.298906 -122.23137)
			(xy 56.254015 -122.200102) (xy 56.214051 -122.162743) (xy 56.179831 -122.12006) (xy 56.152056 -122.072928)
			(xy 56.131298 -122.022313) (xy 56.11798 -121.969251) (xy 56.112376 -121.914832) (xy 53.504592 -121.914832)
			(xy 53.504592 -123.404884) (xy 53.909976 -123.810268) (xy 53.983636 -123.825762) (xy 54.018688 -123.8123)
			(xy 54.033706 -123.806726) (xy 54.064481 -123.797821) (xy 54.080156 -123.79452) (xy 54.098068 -123.791163)
			(xy 54.134325 -123.787476) (xy 54.152546 -123.787154) (xy 54.16169 -123.787154) (xy 54.181231 -123.787743)
			(xy 54.220045 -123.792451) (xy 54.23916 -123.796552) (xy 54.263664 -123.802485) (xy 54.310961 -123.819943)
			(xy 54.355546 -123.84348) (xy 54.37632 -123.857766) (xy 54.381146 -123.861322) (xy 54.388258 -123.866656)
			(xy 54.406884 -123.879389) (xy 54.447627 -123.898759) (xy 54.49115 -123.91063) (xy 54.536086 -123.914629)
			(xy 54.581022 -123.91063) (xy 54.624545 -123.898759) (xy 54.665288 -123.879389) (xy 54.683914 -123.866656)
			(xy 54.707677 -123.84902) (xy 54.759542 -123.820529) (xy 54.815182 -123.800384) (xy 54.873265 -123.789069)
			(xy 54.932399 -123.786853) (xy 54.991166 -123.793791) (xy 55.048158 -123.809716) (xy 55.075328 -123.821444)
			(xy 55.099382 -123.832917) (xy 55.14433 -123.861548) (xy 55.184861 -123.896148) (xy 55.220189 -123.936047)
			(xy 55.249628 -123.98047) (xy 55.26151 -124.004324) (xy 55.272231 -124.027783) (xy 55.287966 -124.076903)
			(xy 55.29694 -124.127694) (xy 55.298989 -124.179232) (xy 55.294075 -124.230576) (xy 55.282289 -124.280789)
			(xy 55.263844 -124.328957) (xy 55.251858 -124.351796) (xy 55.241737 -124.37126) (xy 55.227606 -124.412789)
			(xy 55.220816 -124.456128) (xy 55.22157 -124.499988) (xy 55.229845 -124.543068) (xy 55.245395 -124.584087)
			(xy 55.267759 -124.621825) (xy 55.296271 -124.655163) (xy 55.330084 -124.683109) (xy 55.368195 -124.704833)
			(xy 55.40947 -124.719689) (xy 55.452683 -124.727237) (xy 55.474616 -124.727716) (xy 56.364632 -124.727716)
			(xy 56.766206 -124.326142) (xy 61.176916 -124.326142) (xy 61.743556 -124.892782) (xy 66.654839 -124.892782)
			(xy 66.660597 -124.838306) (xy 66.674085 -124.785214) (xy 66.695028 -124.734596) (xy 66.722994 -124.687493)
			(xy 66.757408 -124.644874) (xy 66.797564 -124.607613) (xy 66.842635 -124.576479) (xy 66.891695 -124.552109)
			(xy 66.943736 -124.535006) (xy 66.997688 -124.525521) (xy 67.052441 -124.523848) (xy 67.106872 -124.530023)
			(xy 67.159859 -124.543918) (xy 67.210315 -124.565247) (xy 67.257203 -124.593573) (xy 67.299557 -124.628313)
			(xy 67.318382 -124.648214) (xy 67.333632 -124.66416) (xy 67.368612 -124.691047) (xy 67.407708 -124.711492)
			(xy 67.449747 -124.72488) (xy 67.493465 -124.73081) (xy 67.537551 -124.729104) (xy 67.580681 -124.719813)
			(xy 67.621559 -124.703216) (xy 67.658958 -124.679811) (xy 67.691755 -124.650301) (xy 67.705732 -124.633228)
			(xy 67.723011 -124.611975) (xy 67.762591 -124.574114) (xy 67.807179 -124.542301) (xy 67.855857 -124.517192)
			(xy 67.907626 -124.499303) (xy 67.961421 -124.489) (xy 68.016136 -124.486496) (xy 68.070648 -124.491842)
			(xy 68.123834 -124.504928) (xy 68.174603 -124.525486) (xy 68.22191 -124.553092) (xy 68.264782 -124.58718)
			(xy 68.30234 -124.627048) (xy 68.33381 -124.671877) (xy 68.358547 -124.720746) (xy 68.37604 -124.77265)
			(xy 68.385931 -124.826523) (xy 68.388017 -124.881256) (xy 68.382255 -124.935724) (xy 68.368762 -124.988809)
			(xy 68.347817 -125.039419) (xy 68.31985 -125.086513) (xy 68.285435 -125.129125) (xy 68.245281 -125.166376)
			(xy 68.200213 -125.197503) (xy 68.151156 -125.221865) (xy 68.09912 -125.238961) (xy 68.045174 -125.24844)
			(xy 67.990426 -125.250108) (xy 67.936003 -125.243929) (xy 67.883023 -125.230031) (xy 67.832575 -125.2087)
			(xy 67.785695 -125.180373) (xy 67.743349 -125.145634) (xy 67.724528 -125.125734) (xy 67.709271 -125.109794)
			(xy 67.674294 -125.082902) (xy 67.635199 -125.062452) (xy 67.593161 -125.04906) (xy 67.549442 -125.043127)
			(xy 67.505355 -125.044833) (xy 67.462225 -125.054124) (xy 67.421346 -125.070723) (xy 67.383948 -125.094131)
			(xy 67.351153 -125.123645) (xy 67.337178 -125.14072) (xy 67.319952 -125.162019) (xy 67.280372 -125.199889)
			(xy 67.235783 -125.231711) (xy 67.187101 -125.256829) (xy 67.135329 -125.274727) (xy 67.081528 -125.285037)
			(xy 67.026807 -125.287548) (xy 66.972288 -125.282208) (xy 66.919094 -125.269126) (xy 66.868317 -125.248571)
			(xy 66.821002 -125.220967) (xy 66.77812 -125.18688) (xy 66.740553 -125.147011) (xy 66.709074 -125.10218)
			(xy 66.68433 -125.053308) (xy 66.666829 -125.001399) (xy 66.656931 -124.947522) (xy 66.654839 -124.892782)
			(xy 61.743556 -124.892782) (xy 63.084456 -126.233682) (xy 63.084456 -126.842048) (xy 68.588716 -126.842048)
			(xy 68.595217 -126.789231) (xy 68.609701 -126.738024) (xy 68.631829 -126.689627) (xy 68.661082 -126.645172)
			(xy 68.678552 -126.625096) (xy 68.69369 -126.607642) (xy 68.718018 -126.568369) (xy 68.734842 -126.525344)
			(xy 68.743607 -126.479986) (xy 68.744025 -126.43379) (xy 68.73608 -126.388281) (xy 68.720036 -126.34496)
			(xy 68.696421 -126.305254) (xy 68.6816 -126.28753) (xy 68.664485 -126.267147) (xy 68.635971 -126.222211)
			(xy 68.614647 -126.17345) (xy 68.601013 -126.122006) (xy 68.595388 -126.069085) (xy 68.597905 -126.015925)
			(xy 68.608503 -125.963771) (xy 68.626936 -125.913845) (xy 68.65277 -125.867317) (xy 68.685402 -125.825275)
			(xy 68.724067 -125.788704) (xy 68.767858 -125.758462) (xy 68.815752 -125.735256) (xy 68.866626 -125.719629)
			(xy 68.919289 -125.711949) (xy 68.972506 -125.712393) (xy 69.025033 -125.720953) (xy 69.075639 -125.737428)
			(xy 69.123138 -125.761431) (xy 69.166418 -125.792401) (xy 69.204466 -125.829612) (xy 69.236391 -125.872194)
			(xy 69.261444 -125.919148) (xy 69.27904 -125.969374) (xy 69.288765 -126.021698) (xy 69.290393 -126.074893)
			(xy 69.283885 -126.127713) (xy 69.269393 -126.178922) (xy 69.247257 -126.227319) (xy 69.217996 -126.271773)
			(xy 69.200522 -126.291848) (xy 69.185342 -126.309267) (xy 69.161019 -126.348548) (xy 69.1442 -126.39158)
			(xy 69.13544 -126.436944) (xy 69.135029 -126.483144) (xy 69.142979 -126.528657) (xy 69.159029 -126.571982)
			(xy 69.18265 -126.61169) (xy 69.197474 -126.629414) (xy 69.214616 -126.649771) (xy 69.243126 -126.694705)
			(xy 69.264447 -126.743463) (xy 69.278078 -126.794904) (xy 69.283701 -126.847822) (xy 69.281184 -126.900978)
			(xy 69.270586 -126.953128) (xy 69.252155 -127.00305) (xy 69.226323 -127.049576) (xy 69.193694 -127.091615)
			(xy 69.155033 -127.128183) (xy 69.111244 -127.158424) (xy 69.063355 -127.18163) (xy 69.012485 -127.197258)
			(xy 68.959827 -127.20494) (xy 68.906613 -127.204498) (xy 68.854089 -127.195942) (xy 68.803486 -127.179471)
			(xy 68.755988 -127.155473) (xy 68.712709 -127.124508) (xy 68.67466 -127.087303) (xy 68.642735 -127.044727)
			(xy 68.617679 -126.997779) (xy 68.600079 -126.947558) (xy 68.590349 -126.895239) (xy 68.588716 -126.842048)
			(xy 63.084456 -126.842048) (xy 63.084456 -127.031496) (xy 63.084916 -127.053736) (xy 63.092658 -127.097538)
			(xy 63.107906 -127.139323) (xy 63.130195 -127.177816) (xy 63.158844 -127.211842) (xy 63.192979 -127.240361)
			(xy 63.231556 -127.262503) (xy 63.273399 -127.277592) (xy 63.31723 -127.285167) (xy 63.339472 -127.285496)
			(xy 63.365449 -127.285845) (xy 63.416925 -127.292858) (xy 63.46693 -127.306945) (xy 63.514495 -127.327836)
			(xy 63.558702 -127.355125) (xy 63.578994 -127.371348) (xy 63.596218 -127.385014) (xy 63.634395 -127.406819)
			(xy 63.675755 -127.421727) (xy 63.719064 -127.429295) (xy 63.763028 -127.429295) (xy 63.806337 -127.421727)
			(xy 63.847697 -127.406819) (xy 63.885874 -127.385014) (xy 63.903098 -127.371348) (xy 63.921591 -127.356489)
			(xy 63.961643 -127.331065) (xy 64.004588 -127.310909) (xy 64.02705 -127.303276) (xy 64.055565 -127.29477)
			(xy 64.114398 -127.285876) (xy 64.173897 -127.286426) (xy 64.203326 -127.29083) (xy 64.228439 -127.295491)
			(xy 64.277173 -127.310787) (xy 64.32336 -127.332598) (xy 64.366132 -127.360516) (xy 64.385698 -127.376936)
			(xy 64.404934 -127.391124) (xy 64.447537 -127.412779) (xy 64.493439 -127.426086) (xy 64.541019 -127.430574)
			(xy 64.588599 -127.426086) (xy 64.634501 -127.412779) (xy 64.677104 -127.391124) (xy 64.69634 -127.376936)
			(xy 64.717915 -127.358846) (xy 64.765465 -127.328701) (xy 64.81701 -127.306053) (xy 64.871375 -127.291419)
			(xy 64.927324 -127.285132) (xy 64.983582 -127.287334) (xy 65.038867 -127.297976) (xy 65.091923 -127.316815)
			(xy 65.141539 -127.343422) (xy 65.186588 -127.377193) (xy 65.226042 -127.417356) (xy 65.259004 -127.463)
			(xy 65.284723 -127.513083) (xy 65.302613 -127.566465) (xy 65.307972 -127.594106) (xy 65.312035 -127.620086)
			(xy 65.313689 -127.672644) (xy 65.307955 -127.724915) (xy 65.294946 -127.775865) (xy 65.285366 -127.800354)
			(xy 65.27418 -127.826097) (xy 65.245223 -127.874179) (xy 65.227708 -127.896112) (xy 65.214039 -127.913337)
			(xy 65.192229 -127.951515) (xy 65.177316 -127.992877) (xy 65.169744 -128.036188) (xy 65.169739 -128.080157)
			(xy 65.177302 -128.12347) (xy 65.192206 -128.164835) (xy 65.214008 -128.203018) (xy 65.227708 -128.220216)
			(xy 65.245627 -128.242639) (xy 65.275073 -128.291908) (xy 65.296618 -128.345108) (xy 65.309751 -128.400983)
			(xy 65.314162 -128.458211) (xy 65.309748 -128.515438) (xy 65.296611 -128.571312) (xy 65.275064 -128.624511)
			(xy 65.245614 -128.673778) (xy 65.227708 -128.696212) (xy 65.214039 -128.713437) (xy 65.192229 -128.751615)
			(xy 65.177316 -128.792977) (xy 65.169744 -128.836288) (xy 65.169739 -128.880257) (xy 65.177302 -128.92357)
			(xy 65.192206 -128.964935) (xy 65.214008 -129.003118) (xy 65.227708 -129.020316) (xy 65.245241 -129.042236)
			(xy 65.274195 -129.090323) (xy 65.285366 -129.116074) (xy 65.294992 -129.140549) (xy 65.308033 -129.191499)
			(xy 65.313764 -129.243778) (xy 65.31207 -129.296343) (xy 65.307972 -129.322322) (xy 65.302623 -129.349961)
			(xy 65.284709 -129.403329) (xy 65.258974 -129.453396) (xy 65.226002 -129.499024) (xy 65.186543 -129.539174)
			(xy 65.141495 -129.572934) (xy 65.091882 -129.599536) (xy 65.038833 -129.618374) (xy 64.983555 -129.629021)
			(xy 64.927304 -129.631233) (xy 64.87136 -129.624962) (xy 64.816996 -129.610349) (xy 64.765447 -129.587726)
			(xy 64.717887 -129.557609) (xy 64.69634 -129.539492) (xy 64.677089 -129.525341) (xy 64.634475 -129.503748)
			(xy 64.588581 -129.490482) (xy 64.541019 -129.486007) (xy 64.493457 -129.490482) (xy 64.447563 -129.503748)
			(xy 64.404949 -129.525341) (xy 64.385698 -129.539492) (xy 64.366137 -129.555916) (xy 64.323356 -129.58382)
			(xy 64.277168 -129.605625) (xy 64.228437 -129.620925) (xy 64.203326 -129.625598) (xy 64.1739 -129.63004)
			(xy 64.114394 -129.630609) (xy 64.055558 -129.621693) (xy 64.02705 -129.613152) (xy 64.004578 -129.605544)
			(xy 63.96162 -129.585407) (xy 63.921577 -129.559959) (xy 63.903098 -129.54508) (xy 63.884777 -129.530588)
			(xy 63.843969 -129.507864) (xy 63.799695 -129.492982) (xy 63.753447 -129.486443) (xy 63.706783 -129.488468)
			(xy 63.661275 -129.498989) (xy 63.618457 -129.51765) (xy 63.579771 -129.543824) (xy 63.562738 -129.559812)
			(xy 63.54191 -129.601214) (xy 63.535675 -129.614605) (xy 63.528877 -129.643343) (xy 63.528879 -129.672874)
			(xy 63.535681 -129.701612) (xy 63.54191 -129.715006) (xy 63.5635 -129.757932) (xy 63.583058 -129.774696)
			(xy 63.604198 -129.793454) (xy 63.641122 -129.836238) (xy 63.671166 -129.884104) (xy 63.68288 -129.909824)
			(xy 63.695834 -129.944368) (xy 63.705176 -129.975759) (xy 63.713375 -130.036168) (xy 66.16832 -130.036168)
			(xy 66.175784 -129.980793) (xy 66.191431 -129.927153) (xy 66.214911 -129.87645) (xy 66.245697 -129.829821)
			(xy 66.264028 -129.808732) (xy 66.278753 -129.79167) (xy 66.302527 -129.753386) (xy 66.319176 -129.71151)
			(xy 66.328178 -129.667353) (xy 66.329249 -129.622301) (xy 66.322357 -129.577766) (xy 66.307718 -129.535145)
			(xy 66.28579 -129.495774) (xy 66.271902 -129.478024) (xy 66.255077 -129.456546) (xy 66.227621 -129.409403)
			(xy 66.207871 -129.358547) (xy 66.196313 -129.305229) (xy 66.193231 -129.25076) (xy 66.198701 -129.196479)
			(xy 66.212588 -129.14372) (xy 66.234552 -129.093781) (xy 66.264051 -129.047888) (xy 66.281808 -129.027174)
			(xy 66.296835 -129.009601) (xy 66.320824 -128.970076) (xy 66.337268 -128.926864) (xy 66.345626 -128.881391)
			(xy 66.345621 -128.835156) (xy 66.337254 -128.789684) (xy 66.3208 -128.746476) (xy 66.296803 -128.706956)
			(xy 66.281808 -128.689354) (xy 66.265318 -128.670156) (xy 66.237467 -128.627904) (xy 66.216045 -128.582055)
			(xy 66.201506 -128.533583) (xy 66.194158 -128.483513) (xy 66.194157 -128.432907) (xy 66.201502 -128.382837)
			(xy 66.216038 -128.334364) (xy 66.237457 -128.288515) (xy 66.265306 -128.24626) (xy 66.281808 -128.227074)
			(xy 66.296835 -128.209501) (xy 66.320824 -128.169976) (xy 66.337268 -128.126764) (xy 66.345626 -128.081291)
			(xy 66.345621 -128.035056) (xy 66.337254 -127.989584) (xy 66.3208 -127.946376) (xy 66.296803 -127.906856)
			(xy 66.281808 -127.889254) (xy 66.264916 -127.869613) (xy 66.2366 -127.826234) (xy 66.215043 -127.779129)
			(xy 66.200725 -127.729344) (xy 66.193962 -127.677984) (xy 66.194905 -127.626189) (xy 66.203533 -127.57511)
			(xy 66.219655 -127.525879) (xy 66.242913 -127.47959) (xy 66.27279 -127.43727) (xy 66.308623 -127.39986)
			(xy 66.349617 -127.368188) (xy 66.394862 -127.342959) (xy 66.443353 -127.324733) (xy 66.494013 -127.313913)
			(xy 66.545719 -127.31074) (xy 66.597323 -127.315286) (xy 66.647678 -127.327448) (xy 66.695668 -127.346956)
			(xy 66.740226 -127.373379) (xy 66.760598 -127.389382) (xy 66.778333 -127.403324) (xy 66.817755 -127.425253)
			(xy 66.860429 -127.439878) (xy 66.905014 -127.446741) (xy 66.95011 -127.445627) (xy 66.994302 -127.436571)
			(xy 67.036202 -127.419856) (xy 67.074493 -127.396008) (xy 67.09156 -127.381254) (xy 67.112577 -127.362981)
			(xy 67.159037 -127.332275) (xy 67.20955 -127.308825) (xy 67.26299 -127.293153) (xy 67.318167 -127.285607)
			(xy 67.373852 -127.286357) (xy 67.428806 -127.295385) (xy 67.481805 -127.31249) (xy 67.531668 -127.337292)
			(xy 67.577285 -127.369237) (xy 67.61764 -127.407616) (xy 67.651835 -127.451572) (xy 67.679108 -127.500128)
			(xy 67.698851 -127.552201) (xy 67.710626 -127.606632) (xy 67.714169 -127.66221) (xy 67.709403 -127.717696)
			(xy 67.696432 -127.771855) (xy 67.675546 -127.823481) (xy 67.647211 -127.871424) (xy 67.612056 -127.914617)
			(xy 67.570865 -127.952097) (xy 67.547998 -127.967994) (xy 67.535531 -127.976899) (xy 67.514852 -127.999492)
			(xy 67.500162 -128.026366) (xy 67.492309 -128.055969) (xy 67.491747 -128.086591) (xy 67.498509 -128.116463)
			(xy 67.512204 -128.143857) (xy 67.53204 -128.167193) (xy 67.544188 -128.176528) (xy 67.560698 -128.189482)
			(xy 67.578433 -128.203424) (xy 67.617855 -128.225353) (xy 67.660529 -128.239978) (xy 67.705114 -128.246841)
			(xy 67.75021 -128.245727) (xy 67.794402 -128.236671) (xy 67.836302 -128.219956) (xy 67.874593 -128.196108)
			(xy 67.89166 -128.181354) (xy 67.912736 -128.163011) (xy 67.959363 -128.132227) (xy 68.010063 -128.108749)
			(xy 68.0637 -128.093103) (xy 68.119072 -128.085639) (xy 68.174937 -128.086526) (xy 68.230044 -128.095742)
			(xy 68.283158 -128.113082) (xy 68.333088 -128.138157) (xy 68.378714 -128.170405) (xy 68.419016 -128.209103)
			(xy 68.453089 -128.253383) (xy 68.480169 -128.302255) (xy 68.49965 -128.354621) (xy 68.511095 -128.409308)
			(xy 68.514248 -128.465092) (xy 68.509037 -128.520721) (xy 68.495581 -128.574949) (xy 68.474179 -128.62656)
			(xy 68.445313 -128.674397) (xy 68.427854 -128.696212) (xy 68.414221 -128.713462) (xy 68.392411 -128.751632)
			(xy 68.377497 -128.792987) (xy 68.369925 -128.836291) (xy 68.36992 -128.880253) (xy 68.377483 -128.92356)
			(xy 68.392388 -128.964918) (xy 68.414189 -129.003092) (xy 68.427854 -129.020316) (xy 68.445044 -129.041804)
			(xy 68.473612 -129.088833) (xy 68.494952 -129.139553) (xy 68.5086 -129.19286) (xy 68.51426 -129.247594)
			(xy 68.511808 -129.302566) (xy 68.501298 -129.356579) (xy 68.482958 -129.408459) (xy 68.457188 -129.457077)
			(xy 68.424547 -129.501377) (xy 68.385746 -129.540394) (xy 68.341628 -129.57328) (xy 68.293153 -129.59932)
			(xy 68.241376 -129.617948) (xy 68.187422 -129.628757) (xy 68.132465 -129.631514) (xy 68.0777 -129.626159)
			(xy 68.024318 -129.612807) (xy 67.973481 -129.591749) (xy 67.926294 -129.563443) (xy 67.883782 -129.528505)
			(xy 67.846872 -129.487694) (xy 67.831208 -129.46507) (xy 67.822334 -129.452541) (xy 67.799728 -129.431781)
			(xy 67.772812 -129.417031) (xy 67.743149 -129.409148) (xy 67.712462 -129.408588) (xy 67.682532 -129.415385)
			(xy 67.655096 -129.429144) (xy 67.631748 -129.449065) (xy 67.62242 -129.46126) (xy 67.60972 -129.478024)
			(xy 67.595877 -129.495814) (xy 67.573947 -129.535187) (xy 67.559315 -129.577815) (xy 67.552441 -129.622356)
			(xy 67.553542 -129.667412) (xy 67.562583 -129.711564) (xy 67.579279 -129.753426) (xy 67.603106 -129.791682)
			(xy 67.617848 -129.808732) (xy 67.63616 -129.829835) (xy 67.666945 -129.876459) (xy 67.690424 -129.927157)
			(xy 67.706072 -129.980792) (xy 67.713537 -130.036162) (xy 67.712652 -130.092026) (xy 67.703437 -130.147131)
			(xy 67.686099 -130.200244) (xy 67.661025 -130.250172) (xy 67.628779 -130.295798) (xy 67.590083 -130.336098)
			(xy 67.545803 -130.37017) (xy 67.496933 -130.397249) (xy 67.444568 -130.416729) (xy 67.389882 -130.428173)
			(xy 67.3341 -130.431325) (xy 67.278473 -130.426113) (xy 67.224247 -130.412655) (xy 67.172638 -130.391253)
			(xy 67.124803 -130.362385) (xy 67.10299 -130.344926) (xy 67.085766 -130.33126) (xy 67.047589 -130.309455)
			(xy 67.006229 -130.294547) (xy 66.96292 -130.286979) (xy 66.918956 -130.286979) (xy 66.875647 -130.294547)
			(xy 66.834287 -130.309455) (xy 66.79611 -130.33126) (xy 66.778886 -130.344926) (xy 66.757107 -130.36243)
			(xy 66.709267 -130.391298) (xy 66.657653 -130.4127) (xy 66.603422 -130.426157) (xy 66.54779 -130.431368)
			(xy 66.492003 -130.428214) (xy 66.437313 -130.416768) (xy 66.384944 -130.397286) (xy 66.33607 -130.370204)
			(xy 66.291787 -130.336129) (xy 66.253088 -130.295825) (xy 66.220839 -130.250195) (xy 66.195763 -130.200263)
			(xy 66.178422 -130.147146) (xy 66.169206 -130.092036) (xy 66.16832 -130.036168) (xy 63.713375 -130.036168)
			(xy 63.713984 -130.040654) (xy 63.71336 -130.0734) (xy 63.711749 -130.100568) (xy 63.701635 -130.154042)
			(xy 63.683855 -130.205478) (xy 63.658787 -130.253782) (xy 63.626962 -130.29793) (xy 63.589058 -130.336982)
			(xy 63.54588 -130.370109) (xy 63.522352 -130.383788) (xy 63.497656 -130.396972) (xy 63.445228 -130.416596)
			(xy 63.390454 -130.428157) (xy 63.334566 -130.431393) (xy 63.278824 -130.426232) (xy 63.224481 -130.41279)
			(xy 63.172761 -130.391369) (xy 63.124827 -130.362453) (xy 63.102998 -130.344926) (xy 63.085774 -130.33126)
			(xy 63.047597 -130.309455) (xy 63.006237 -130.294547) (xy 62.962928 -130.286979) (xy 62.918964 -130.286979)
			(xy 62.875655 -130.294547) (xy 62.834295 -130.309455) (xy 62.796118 -130.33126) (xy 62.778894 -130.344926)
			(xy 62.77483 -130.348228) (xy 62.75832 -130.360928) (xy 62.733097 -130.378262) (xy 62.67821 -130.405328)
			(xy 62.6491 -130.414776) (xy 62.642242 -130.416808) (xy 62.62013 -130.422692) (xy 62.574904 -130.429647)
			(xy 62.529166 -130.431015) (xy 62.506352 -130.429254) (xy 62.483335 -130.42837) (xy 62.437615 -130.433934)
			(xy 62.393646 -130.447646) (xy 62.352867 -130.469056) (xy 62.316614 -130.497463) (xy 62.286074 -130.531939)
			(xy 62.262245 -130.571353) (xy 62.245909 -130.614416) (xy 62.2376 -130.659717) (xy 62.237322 -130.67284)
			(xy 75.033884 -130.67284) (xy 75.037955 -130.617218) (xy 75.050081 -130.562781) (xy 75.070004 -130.51069)
			(xy 75.0973 -130.462055) (xy 75.131386 -130.417912) (xy 75.171535 -130.379203) (xy 75.216893 -130.346752)
			(xy 75.266493 -130.321251) (xy 75.319277 -130.303244) (xy 75.37412 -130.293114) (xy 75.429854 -130.291077)
			(xy 75.485291 -130.297177) (xy 75.539248 -130.311283) (xy 75.590577 -130.333095) (xy 75.638183 -130.362149)
			(xy 75.681051 -130.397824) (xy 75.718268 -130.439361) (xy 75.749041 -130.485874) (xy 75.762506 -130.514598)
			(xy 76.18806 -130.514598) (xy 76.192131 -130.458976) (xy 76.204257 -130.404539) (xy 76.22418 -130.352448)
			(xy 76.251476 -130.303813) (xy 76.285562 -130.25967) (xy 76.325711 -130.220961) (xy 76.371069 -130.18851)
			(xy 76.420669 -130.163009) (xy 76.473453 -130.145002) (xy 76.528296 -130.134872) (xy 76.58403 -130.132835)
			(xy 76.639467 -130.138935) (xy 76.693424 -130.153041) (xy 76.744753 -130.174853) (xy 76.792359 -130.203907)
			(xy 76.835227 -130.239582) (xy 76.872444 -130.281119) (xy 76.903217 -130.327632) (xy 76.926889 -130.378129)
			(xy 76.942957 -130.431536) (xy 76.951077 -130.486712) (xy 76.951586 -130.514598) (xy 76.951077 -130.542484)
			(xy 76.942957 -130.59766) (xy 76.926889 -130.651067) (xy 76.903217 -130.701564) (xy 76.872444 -130.748077)
			(xy 76.835227 -130.789614) (xy 76.792359 -130.825289) (xy 76.744753 -130.854343) (xy 76.693424 -130.876155)
			(xy 76.639467 -130.890261) (xy 76.58403 -130.896361) (xy 76.528296 -130.894324) (xy 76.473453 -130.884194)
			(xy 76.420669 -130.866187) (xy 76.371069 -130.840686) (xy 76.325711 -130.808235) (xy 76.285562 -130.769526)
			(xy 76.251476 -130.725383) (xy 76.22418 -130.676748) (xy 76.204257 -130.624657) (xy 76.192131 -130.57022)
			(xy 76.18806 -130.514598) (xy 75.762506 -130.514598) (xy 75.772713 -130.536371) (xy 75.788781 -130.589778)
			(xy 75.796901 -130.644954) (xy 75.79741 -130.67284) (xy 75.796901 -130.700726) (xy 75.788781 -130.755902)
			(xy 75.772713 -130.809309) (xy 75.749041 -130.859806) (xy 75.718268 -130.906319) (xy 75.681051 -130.947856)
			(xy 75.638183 -130.983531) (xy 75.590577 -131.012585) (xy 75.539248 -131.034397) (xy 75.485291 -131.048503)
			(xy 75.429854 -131.054603) (xy 75.37412 -131.052566) (xy 75.319277 -131.042436) (xy 75.266493 -131.024429)
			(xy 75.216893 -130.998928) (xy 75.171535 -130.966477) (xy 75.131386 -130.927768) (xy 75.0973 -130.883625)
			(xy 75.070004 -130.83499) (xy 75.050081 -130.782899) (xy 75.037955 -130.728462) (xy 75.033884 -130.67284)
			(xy 62.237322 -130.67284) (xy 62.237112 -130.682746) (xy 62.237112 -130.73761) (xy 62.237577 -130.759898)
			(xy 62.245357 -130.803791) (xy 62.260676 -130.845654) (xy 62.283063 -130.884201) (xy 62.311834 -130.918251)
			(xy 62.346104 -130.946758) (xy 62.384822 -130.968849) (xy 62.426801 -130.983845) (xy 62.448694 -130.988054)
			(xy 62.475214 -130.993038) (xy 62.526606 -131.009488) (xy 62.575169 -131.033014) (xy 62.619933 -131.063145)
			(xy 62.660007 -131.099282) (xy 62.694592 -131.140702) (xy 62.722997 -131.186582) (xy 62.744657 -131.236004)
			(xy 62.759139 -131.287985) (xy 62.766155 -131.341488) (xy 62.765566 -131.395445) (xy 62.757381 -131.448782)
			(xy 62.749938 -131.474718) (xy 62.741668 -131.500432) (xy 62.718891 -131.549407) (xy 62.689435 -131.594682)
			(xy 62.653889 -131.63535) (xy 62.612964 -131.6706) (xy 62.567477 -131.699726) (xy 62.518337 -131.722148)
			(xy 62.466526 -131.737415) (xy 62.413081 -131.745225) (xy 62.359068 -131.74542) (xy 62.305567 -131.737996)
			(xy 62.253648 -131.723102) (xy 62.204348 -131.701036) (xy 62.181232 -131.687062) (xy 62.163778 -131.675757)
			(xy 62.131196 -131.649916) (xy 62.116208 -131.6355) (xy 62.11189 -131.630928) (xy 62.095783 -131.615977)
			(xy 62.059431 -131.591287) (xy 62.019378 -131.573211) (xy 61.976814 -131.562288) (xy 61.933006 -131.558841)
			(xy 61.889257 -131.562973) (xy 61.846869 -131.574562) (xy 61.807103 -131.593262) (xy 61.771142 -131.618518)
			(xy 61.755274 -131.633722) (xy 61.247782 -132.141214) (xy 61.237368 -132.228082) (xy 61.259974 -132.265674)
			(xy 61.274387 -132.290606) (xy 61.296194 -132.343903) (xy 61.309544 -132.399921) (xy 61.31412 -132.457325)
			(xy 61.309813 -132.514749) (xy 61.296726 -132.570829) (xy 61.27517 -132.624228) (xy 61.245658 -132.673677)
			(xy 61.227716 -132.696204) (xy 61.214046 -132.713429) (xy 61.192234 -132.751607) (xy 61.177319 -132.792969)
			(xy 61.169745 -132.836281) (xy 61.169739 -132.880251) (xy 61.177301 -132.923565) (xy 61.192206 -132.964932)
			(xy 61.214008 -133.003116) (xy 61.227716 -133.020308) (xy 61.242576 -133.0388) (xy 61.268001 -133.078852)
			(xy 61.288158 -133.121797) (xy 61.295788 -133.14426) (xy 61.300385 -133.159161) (xy 61.307381 -133.189554)
			(xy 61.309758 -133.204966) (xy 61.311841 -133.220306) (xy 61.313752 -133.251208) (xy 61.313568 -133.266688)
			(xy 61.312252 -133.29737) (xy 61.30083 -133.357706) (xy 61.279676 -133.415355) (xy 61.249362 -133.468759)
			(xy 61.23051 -133.493002) (xy 61.222128 -133.502908) (xy 61.207942 -133.522143) (xy 61.186289 -133.564745)
			(xy 61.172986 -133.610645) (xy 61.168502 -133.658223) (xy 61.172995 -133.7058) (xy 61.186306 -133.751698)
			(xy 61.207966 -133.794296) (xy 61.222128 -133.81355) (xy 61.239584 -133.834392) (xy 61.268909 -133.880167)
			(xy 61.280548 -133.904736) (xy 61.290843 -133.928627) (xy 61.305458 -133.978554) (xy 61.31299 -134.030027)
			(xy 61.313095 -134.048116) (xy 62.967957 -134.048116) (xy 62.973539 -133.993288) (xy 62.987135 -133.939881)
			(xy 63.008449 -133.889059) (xy 63.037014 -133.841929) (xy 63.05423 -133.820408) (xy 63.067941 -133.803217)
			(xy 63.089747 -133.765034) (xy 63.104655 -133.723667) (xy 63.112219 -133.680352) (xy 63.112213 -133.636381)
			(xy 63.104638 -133.593067) (xy 63.089719 -133.551704) (xy 63.067902 -133.513527) (xy 63.05423 -133.496304)
			(xy 63.037025 -133.474774) (xy 63.008458 -133.427646) (xy 62.987144 -133.376824) (xy 62.973547 -133.323417)
			(xy 62.967963 -133.26859) (xy 62.970516 -133.213538) (xy 62.981148 -133.159463) (xy 62.999628 -133.107544)
			(xy 63.025554 -133.058912) (xy 63.058358 -133.014628) (xy 63.097327 -132.975659) (xy 63.141611 -132.942854)
			(xy 63.190242 -132.916929) (xy 63.242162 -132.898448) (xy 63.296237 -132.887816) (xy 63.351288 -132.885263)
			(xy 63.406115 -132.890846) (xy 63.459522 -132.904443) (xy 63.510344 -132.925757) (xy 63.557473 -132.954324)
			(xy 63.578994 -132.97154) (xy 63.596218 -132.985206) (xy 63.634395 -133.007011) (xy 63.675755 -133.021919)
			(xy 63.719064 -133.029487) (xy 63.763028 -133.029487) (xy 63.806337 -133.021919) (xy 63.847697 -133.007011)
			(xy 63.885874 -132.985206) (xy 63.903098 -132.97154) (xy 63.925518 -132.953649) (xy 63.97477 -132.924252)
			(xy 64.027942 -132.902744) (xy 64.083781 -132.889633) (xy 64.140969 -132.885229) (xy 64.198157 -132.889633)
			(xy 64.253996 -132.902744) (xy 64.307168 -132.924252) (xy 64.35642 -132.953649) (xy 64.37884 -132.97154)
			(xy 64.396082 -132.985208) (xy 64.434292 -133.007013) (xy 64.475683 -133.021921) (xy 64.519022 -133.029488)
			(xy 64.563016 -133.029488) (xy 64.606355 -133.021921) (xy 64.647746 -133.007013) (xy 64.685956 -132.985208)
			(xy 64.703198 -132.97154) (xy 64.724754 -132.954407) (xy 64.771874 -132.925925) (xy 64.822672 -132.904686)
			(xy 64.876043 -132.891155) (xy 64.930824 -132.885626) (xy 64.985823 -132.888219) (xy 65.039841 -132.898878)
			(xy 65.091702 -132.91737) (xy 65.140277 -132.943294) (xy 65.184508 -132.976083) (xy 65.223431 -133.015026)
			(xy 65.2562 -133.059272) (xy 65.282101 -133.107859) (xy 65.300569 -133.159729) (xy 65.311202 -133.213752)
			(xy 65.313281 -133.258305) (xy 66.167655 -133.258305) (xy 66.172068 -133.201076) (xy 66.185204 -133.1452)
			(xy 66.206751 -133.091999) (xy 66.236201 -133.042731) (xy 66.254122 -133.020308) (xy 66.267829 -133.003115)
			(xy 66.289627 -132.96493) (xy 66.304529 -132.923564) (xy 66.31209 -132.88025) (xy 66.312084 -132.836282)
			(xy 66.304512 -132.79297) (xy 66.289599 -132.751608) (xy 66.26779 -132.713429) (xy 66.254122 -132.696204)
			(xy 66.236926 -132.674667) (xy 66.208361 -132.627539) (xy 66.187047 -132.576718) (xy 66.173451 -132.523313)
			(xy 66.167868 -132.468487) (xy 66.170421 -132.413437) (xy 66.181053 -132.359363) (xy 66.199533 -132.307445)
			(xy 66.225458 -132.258814) (xy 66.258262 -132.214532) (xy 66.29723 -132.175564) (xy 66.341512 -132.142759)
			(xy 66.390143 -132.116834) (xy 66.442061 -132.098354) (xy 66.496135 -132.087721) (xy 66.551185 -132.085168)
			(xy 66.60601 -132.090751) (xy 66.659416 -132.104347) (xy 66.710237 -132.125659) (xy 66.757365 -132.154225)
			(xy 66.778886 -132.17144) (xy 66.79611 -132.185106) (xy 66.834287 -132.206911) (xy 66.875647 -132.221819)
			(xy 66.918956 -132.229387) (xy 66.96292 -132.229387) (xy 67.006229 -132.221819) (xy 67.047589 -132.206911)
			(xy 67.085766 -132.185106) (xy 67.10299 -132.17144) (xy 67.125413 -132.153518) (xy 67.174681 -132.124066)
			(xy 67.227882 -132.102517) (xy 67.283758 -132.089381) (xy 67.340988 -132.084967) (xy 67.398218 -132.089381)
			(xy 67.454094 -132.102517) (xy 67.507295 -132.124066) (xy 67.556563 -132.153518) (xy 67.578986 -132.17144)
			(xy 67.59621 -132.185106) (xy 67.634387 -132.206911) (xy 67.675747 -132.221819) (xy 67.719056 -132.229387)
			(xy 67.76302 -132.229387) (xy 67.806329 -132.221819) (xy 67.847689 -132.206911) (xy 67.885866 -132.185106)
			(xy 67.90309 -132.17144) (xy 67.924616 -132.154229) (xy 67.971745 -132.125661) (xy 68.022568 -132.104345)
			(xy 68.075976 -132.090746) (xy 68.130804 -132.085162) (xy 68.185857 -132.087713) (xy 68.239934 -132.098345)
			(xy 68.291855 -132.116826) (xy 68.340488 -132.142751) (xy 68.384773 -132.175557) (xy 68.423743 -132.214527)
			(xy 68.456548 -132.258811) (xy 68.482474 -132.307444) (xy 68.500954 -132.359365) (xy 68.511586 -132.413442)
			(xy 68.513708 -132.459222) (xy 70.169034 -132.459222) (xy 70.17301 -132.404896) (xy 70.184853 -132.351727)
			(xy 70.204312 -132.30085) (xy 70.230972 -132.253348) (xy 70.264263 -132.210234) (xy 70.303477 -132.172427)
			(xy 70.347779 -132.140732) (xy 70.396222 -132.115826) (xy 70.447776 -132.098238) (xy 70.501342 -132.088344)
			(xy 70.555777 -132.086354) (xy 70.609922 -132.092312) (xy 70.662622 -132.10609) (xy 70.712755 -132.127394)
			(xy 70.759251 -132.15577) (xy 70.801121 -132.190614) (xy 70.83747 -132.231183) (xy 70.867526 -132.276612)
			(xy 70.890647 -132.325933) (xy 70.90634 -132.378095) (xy 70.914271 -132.431986) (xy 70.914768 -132.459222)
			(xy 70.914271 -132.486458) (xy 70.90634 -132.540349) (xy 70.890647 -132.592511) (xy 70.867526 -132.641832)
			(xy 70.83747 -132.687261) (xy 70.801121 -132.72783) (xy 70.759251 -132.762674) (xy 70.712755 -132.79105)
			(xy 70.662622 -132.812354) (xy 70.609922 -132.826132) (xy 70.555777 -132.83209) (xy 70.501342 -132.8301)
			(xy 70.447776 -132.820206) (xy 70.396222 -132.802618) (xy 70.347779 -132.777712) (xy 70.303477 -132.746017)
			(xy 70.264263 -132.70821) (xy 70.230972 -132.665096) (xy 70.204312 -132.617594) (xy 70.184853 -132.566717)
			(xy 70.17301 -132.513548) (xy 70.169034 -132.459222) (xy 68.513708 -132.459222) (xy 68.514138 -132.468495)
			(xy 68.508554 -132.523323) (xy 68.494956 -132.576731) (xy 68.47364 -132.627554) (xy 68.445071 -132.674683)
			(xy 68.427854 -132.696204) (xy 68.414229 -132.71346) (xy 68.392418 -132.751629) (xy 68.377504 -132.792982)
			(xy 68.369931 -132.836286) (xy 68.369925 -132.880247) (xy 68.377486 -132.923552) (xy 68.39239 -132.96491)
			(xy 68.41419 -133.003084) (xy 68.427854 -133.020308) (xy 68.445782 -133.042726) (xy 68.475235 -133.091995)
			(xy 68.496784 -133.145197) (xy 68.509921 -133.201074) (xy 68.514334 -133.258305) (xy 68.509919 -133.315535)
			(xy 68.496781 -133.371412) (xy 68.47523 -133.424614) (xy 68.445777 -133.473882) (xy 68.427854 -133.496304)
			(xy 68.414229 -133.51356) (xy 68.392418 -133.551729) (xy 68.377504 -133.593082) (xy 68.369931 -133.636386)
			(xy 68.369925 -133.680347) (xy 68.377486 -133.723652) (xy 68.39239 -133.76501) (xy 68.41419 -133.803184)
			(xy 68.427854 -133.820408) (xy 68.445091 -133.841914) (xy 68.473659 -133.889045) (xy 68.494975 -133.93987)
			(xy 68.508572 -133.99328) (xy 68.514156 -134.04811) (xy 68.511603 -134.103165) (xy 68.50097 -134.157243)
			(xy 68.482489 -134.209165) (xy 68.456562 -134.2578) (xy 68.423755 -134.302086) (xy 68.384784 -134.341057)
			(xy 68.340498 -134.373863) (xy 68.291863 -134.39979) (xy 68.239941 -134.418271) (xy 68.185862 -134.428904)
			(xy 68.130808 -134.431456) (xy 68.075978 -134.425872) (xy 68.022568 -134.412274) (xy 67.971743 -134.390958)
			(xy 67.924612 -134.362389) (xy 67.90309 -134.345172) (xy 67.885866 -134.331506) (xy 67.847689 -134.309701)
			(xy 67.806329 -134.294793) (xy 67.76302 -134.287225) (xy 67.719056 -134.287225) (xy 67.675747 -134.294793)
			(xy 67.634387 -134.309701) (xy 67.59621 -134.331506) (xy 67.578986 -134.345172) (xy 67.556563 -134.363094)
			(xy 67.507295 -134.392546) (xy 67.454094 -134.414095) (xy 67.398218 -134.427231) (xy 67.340988 -134.431645)
			(xy 67.283758 -134.427231) (xy 67.227882 -134.414095) (xy 67.174681 -134.392546) (xy 67.125413 -134.363094)
			(xy 67.10299 -134.345172) (xy 67.085766 -134.331506) (xy 67.047589 -134.309701) (xy 67.006229 -134.294793)
			(xy 66.96292 -134.287225) (xy 66.918956 -134.287225) (xy 66.875647 -134.294793) (xy 66.834287 -134.309701)
			(xy 66.79611 -134.331506) (xy 66.778886 -134.345172) (xy 66.75737 -134.362394) (xy 66.71024 -134.390959)
			(xy 66.659417 -134.412272) (xy 66.606009 -134.425867) (xy 66.551181 -134.431449) (xy 66.49613 -134.428896)
			(xy 66.442054 -134.418262) (xy 66.390134 -134.399781) (xy 66.341502 -134.373855) (xy 66.297219 -134.34105)
			(xy 66.25825 -134.302081) (xy 66.225444 -134.257797) (xy 66.199518 -134.209165) (xy 66.181037 -134.157245)
			(xy 66.170404 -134.10317) (xy 66.167851 -134.048118) (xy 66.173433 -133.99329) (xy 66.187028 -133.939883)
			(xy 66.208341 -133.88906) (xy 66.236906 -133.84193) (xy 66.254122 -133.820408) (xy 66.267829 -133.803215)
			(xy 66.289627 -133.76503) (xy 66.304529 -133.723664) (xy 66.31209 -133.68035) (xy 66.312084 -133.636382)
			(xy 66.304512 -133.59307) (xy 66.289599 -133.551708) (xy 66.26779 -133.513529) (xy 66.254122 -133.496304)
			(xy 66.236206 -133.473877) (xy 66.206755 -133.424609) (xy 66.185207 -133.371409) (xy 66.17207 -133.315534)
			(xy 66.167655 -133.258305) (xy 65.313281 -133.258305) (xy 65.313769 -133.268751) (xy 65.308214 -133.32353)
			(xy 65.294658 -133.376894) (xy 65.273396 -133.427683) (xy 65.244891 -133.474789) (xy 65.227708 -133.496304)
			(xy 65.214085 -133.513561) (xy 65.192278 -133.55173) (xy 65.177367 -133.593084) (xy 65.169795 -133.636386)
			(xy 65.169789 -133.680346) (xy 65.177349 -133.723651) (xy 65.19225 -133.765008) (xy 65.214046 -133.803183)
			(xy 65.227708 -133.820408) (xy 65.244852 -133.841966) (xy 65.273389 -133.889071) (xy 65.29468 -133.939865)
			(xy 65.308262 -133.993239) (xy 65.313837 -134.048032) (xy 65.311285 -134.103048) (xy 65.300661 -134.157089)
			(xy 65.282197 -134.208977) (xy 65.256295 -134.257582) (xy 65.22352 -134.301843) (xy 65.184585 -134.340797)
			(xy 65.14034 -134.373595) (xy 65.091749 -134.399521) (xy 65.03987 -134.418011) (xy 64.985834 -134.428662)
			(xy 64.930819 -134.431242) (xy 64.876024 -134.425694) (xy 64.822642 -134.41214) (xy 64.771838 -134.390874)
			(xy 64.724718 -134.362361) (xy 64.703198 -134.345172) (xy 64.685971 -134.331471) (xy 64.647773 -134.309606)
			(xy 64.606378 -134.294656) (xy 64.563025 -134.287066) (xy 64.519013 -134.287066) (xy 64.47566 -134.294656)
			(xy 64.434265 -134.309606) (xy 64.396067 -134.331471) (xy 64.37884 -134.345172) (xy 64.356433 -134.363093)
			(xy 64.307195 -134.392544) (xy 64.254022 -134.414093) (xy 64.198173 -134.427231) (xy 64.140969 -134.431644)
			(xy 64.083765 -134.427231) (xy 64.027916 -134.414093) (xy 63.974743 -134.392544) (xy 63.925505 -134.363093)
			(xy 63.903098 -134.345172) (xy 63.885874 -134.331506) (xy 63.847697 -134.309701) (xy 63.806337 -134.294793)
			(xy 63.763028 -134.287225) (xy 63.719064 -134.287225) (xy 63.675755 -134.294793) (xy 63.634395 -134.309701)
			(xy 63.596218 -134.331506) (xy 63.578994 -134.345172) (xy 63.557471 -134.362386) (xy 63.510342 -134.390951)
			(xy 63.459519 -134.412265) (xy 63.406112 -134.425861) (xy 63.351285 -134.431443) (xy 63.296233 -134.42889)
			(xy 63.242158 -134.418257) (xy 63.190238 -134.399776) (xy 63.141607 -134.373851) (xy 63.097323 -134.341046)
			(xy 63.058354 -134.302077) (xy 63.025549 -134.257793) (xy 62.999624 -134.209162) (xy 62.981143 -134.157242)
			(xy 62.97051 -134.103167) (xy 62.967957 -134.048116) (xy 61.313095 -134.048116) (xy 61.313292 -134.082048)
			(xy 61.306359 -134.133606) (xy 61.292324 -134.183699) (xy 61.271462 -134.231354) (xy 61.258196 -134.253732)
			(xy 61.242734 -134.277764) (xy 61.205671 -134.321257) (xy 61.162405 -134.358586) (xy 61.113951 -134.388876)
			(xy 61.061443 -134.41142) (xy 61.033914 -134.419086) (xy 61.005035 -134.425904) (xy 60.945953 -134.431384)
			(xy 60.916312 -134.430008) (xy 60.893811 -134.429994) (xy 60.849359 -134.436937) (xy 60.806825 -134.4516)
			(xy 60.767537 -134.473524) (xy 60.732725 -134.502025) (xy 60.703477 -134.536211) (xy 60.680706 -134.575014)
			(xy 60.665124 -134.617221) (xy 60.65722 -134.661512) (xy 60.656724 -134.684008) (xy 60.656724 -135.032242)
			(xy 60.65721 -135.054734) (xy 60.665134 -135.099015) (xy 60.680729 -135.14121) (xy 60.703507 -135.180002)
			(xy 60.732756 -135.214179) (xy 60.767565 -135.242674) (xy 60.806845 -135.264599) (xy 60.84937 -135.279267)
			(xy 60.893814 -135.286222) (xy 60.916312 -135.286242) (xy 60.943874 -135.284912) (xy 60.99887 -135.289417)
			(xy 61.052599 -135.301987) (xy 61.103886 -135.322346) (xy 61.151608 -135.350048) (xy 61.194721 -135.384488)
			(xy 61.232281 -135.424912) (xy 61.263467 -135.470434) (xy 61.275976 -135.49503) (xy 61.287441 -135.519737)
			(xy 61.303884 -135.571662) (xy 61.312596 -135.625427) (xy 61.313392 -135.679888) (xy 61.306255 -135.733885)
			(xy 61.291338 -135.786268) (xy 61.268957 -135.835924) (xy 61.239589 -135.881794) (xy 61.222128 -135.9027)
			(xy 61.207941 -135.921935) (xy 61.186287 -135.964538) (xy 61.172982 -136.010438) (xy 61.168497 -136.058017)
			(xy 61.172989 -136.105595) (xy 61.186299 -136.151493) (xy 61.207959 -136.194093) (xy 61.222128 -136.213342)
			(xy 61.239649 -136.234203) (xy 61.269038 -136.280074) (xy 61.291435 -136.329734) (xy 61.306362 -136.382127)
			(xy 61.313502 -136.436135) (xy 61.313176 -136.458319) (xy 62.967763 -136.458319) (xy 62.972174 -136.401117)
			(xy 62.98531 -136.345268) (xy 63.006858 -136.292096) (xy 63.036309 -136.24286) (xy 63.05423 -136.220454)
			(xy 63.067955 -136.203245) (xy 63.089818 -136.165044) (xy 63.104767 -136.123645) (xy 63.112353 -136.080288)
			(xy 63.11235 -136.036273) (xy 63.104757 -135.992918) (xy 63.089802 -135.951521) (xy 63.067933 -135.913323)
			(xy 63.05423 -135.896096) (xy 63.037103 -135.874536) (xy 63.008622 -135.827417) (xy 62.987385 -135.776619)
			(xy 62.973856 -135.72325) (xy 62.968328 -135.66847) (xy 62.970921 -135.613473) (xy 62.981581 -135.559456)
			(xy 63.000073 -135.507597) (xy 63.025996 -135.459023) (xy 63.058785 -135.414793) (xy 63.097726 -135.375871)
			(xy 63.141971 -135.343102) (xy 63.190557 -135.317202) (xy 63.242425 -135.298734) (xy 63.296447 -135.2881)
			(xy 63.351445 -135.285532) (xy 63.406222 -135.291086) (xy 63.459586 -135.304641) (xy 63.510373 -135.325901)
			(xy 63.557479 -135.354404) (xy 63.578994 -135.371586) (xy 63.596218 -135.385252) (xy 63.634395 -135.407057)
			(xy 63.675755 -135.421965) (xy 63.719064 -135.429533) (xy 63.763028 -135.429533) (xy 63.806337 -135.421965)
			(xy 63.847697 -135.407057) (xy 63.885874 -135.385252) (xy 63.903098 -135.371586) (xy 63.925518 -135.353695)
			(xy 63.97477 -135.324298) (xy 64.027942 -135.30279) (xy 64.083781 -135.289679) (xy 64.140969 -135.285275)
			(xy 64.198157 -135.289679) (xy 64.253996 -135.30279) (xy 64.307168 -135.324298) (xy 64.35642 -135.353695)
			(xy 64.37884 -135.371586) (xy 64.396082 -135.385254) (xy 64.434292 -135.407059) (xy 64.475683 -135.421967)
			(xy 64.519022 -135.429534) (xy 64.563016 -135.429534) (xy 64.606355 -135.421967) (xy 64.647746 -135.407059)
			(xy 64.685956 -135.385254) (xy 64.703198 -135.371586) (xy 64.724717 -135.354406) (xy 64.771822 -135.325894)
			(xy 64.822611 -135.304627) (xy 64.875977 -135.291068) (xy 64.930758 -135.285513) (xy 64.98576 -135.288082)
			(xy 65.039784 -135.29872) (xy 65.091654 -135.317195) (xy 65.14024 -135.343104) (xy 65.184482 -135.375883)
			(xy 65.223416 -135.414818) (xy 65.256195 -135.45906) (xy 65.282105 -135.507645) (xy 65.30058 -135.559515)
			(xy 65.311218 -135.613539) (xy 65.313787 -135.668541) (xy 65.308232 -135.723322) (xy 65.294673 -135.776689)
			(xy 65.273406 -135.827478) (xy 65.244895 -135.874583) (xy 65.227708 -135.896096) (xy 65.214063 -135.913355)
			(xy 65.192253 -135.951561) (xy 65.17734 -135.992949) (xy 65.169769 -136.036285) (xy 65.169766 -136.080277)
			(xy 65.17733 -136.123614) (xy 65.192237 -136.165004) (xy 65.214041 -136.203213) (xy 65.227708 -136.220454)
			(xy 65.245624 -136.242855) (xy 65.27502 -136.29211) (xy 65.296526 -136.345286) (xy 65.309635 -136.401128)
			(xy 65.314038 -136.458319) (xy 66.167657 -136.458319) (xy 66.172068 -136.401117) (xy 66.185203 -136.345269)
			(xy 66.206751 -136.292097) (xy 66.236202 -136.24286) (xy 66.254122 -136.220454) (xy 66.267848 -136.203245)
			(xy 66.289711 -136.165044) (xy 66.30466 -136.123645) (xy 66.312247 -136.080288) (xy 66.312244 -136.036273)
			(xy 66.304651 -135.992918) (xy 66.289695 -135.951521) (xy 66.267826 -135.913323) (xy 66.254122 -135.896096)
			(xy 66.236887 -135.874616) (xy 66.208392 -135.827487) (xy 66.187143 -135.776678) (xy 66.173604 -135.723295)
			(xy 66.16807 -135.668501) (xy 66.17066 -135.613489) (xy 66.18132 -135.559457) (xy 66.199815 -135.507582)
			(xy 66.225744 -135.458995) (xy 66.258542 -135.414753) (xy 66.297495 -135.37582) (xy 66.341753 -135.343044)
			(xy 66.390354 -135.317139) (xy 66.442237 -135.29867) (xy 66.496275 -135.288038) (xy 66.551288 -135.285475)
			(xy 66.60608 -135.291037) (xy 66.659456 -135.304603) (xy 66.710255 -135.325877) (xy 66.757369 -135.354396)
			(xy 66.778886 -135.371586) (xy 66.79611 -135.385252) (xy 66.834287 -135.407057) (xy 66.875647 -135.421965)
			(xy 66.918956 -135.429533) (xy 66.96292 -135.429533) (xy 67.006229 -135.421965) (xy 67.047589 -135.407057)
			(xy 67.085766 -135.385252) (xy 67.10299 -135.371586) (xy 67.125413 -135.353664) (xy 67.174681 -135.324212)
			(xy 67.227882 -135.302663) (xy 67.283758 -135.289527) (xy 67.340988 -135.285113) (xy 67.398218 -135.289527)
			(xy 67.454094 -135.302663) (xy 67.507295 -135.324212) (xy 67.556563 -135.353664) (xy 67.578986 -135.371586)
			(xy 67.59621 -135.385252) (xy 67.634387 -135.407057) (xy 67.675747 -135.421965) (xy 67.719056 -135.429533)
			(xy 67.76302 -135.429533) (xy 67.806329 -135.421965) (xy 67.847689 -135.407057) (xy 67.885866 -135.385252)
			(xy 67.90309 -135.371586) (xy 67.924582 -135.354351) (xy 67.971695 -135.325798) (xy 68.022499 -135.304493)
			(xy 68.075886 -135.290901) (xy 68.130692 -135.285318) (xy 68.185723 -135.287866) (xy 68.23978 -135.298488)
			(xy 68.291683 -135.316955) (xy 68.340301 -135.342862) (xy 68.384574 -135.375646) (xy 68.423538 -135.414591)
			(xy 68.456343 -135.458849) (xy 68.482274 -135.507455) (xy 68.500765 -135.559349) (xy 68.511413 -135.6134)
			(xy 68.513987 -135.66843) (xy 68.50843 -135.72324) (xy 68.494863 -135.776633) (xy 68.473582 -135.827447)
			(xy 68.445052 -135.874574) (xy 68.427854 -135.896096) (xy 68.414211 -135.913356) (xy 68.392406 -135.951563)
			(xy 68.377496 -135.99295) (xy 68.369927 -136.036285) (xy 68.369924 -136.080276) (xy 68.377486 -136.123612)
			(xy 68.392389 -136.165002) (xy 68.414189 -136.203212) (xy 68.427854 -136.220454) (xy 68.445768 -136.242856)
			(xy 68.47516 -136.292112) (xy 68.496664 -136.345288) (xy 68.509771 -136.401129) (xy 68.513231 -136.446085)
			(xy 70.969228 -136.446085) (xy 70.975104 -136.391994) (xy 70.988787 -136.339333) (xy 71.009985 -136.289223)
			(xy 71.038248 -136.24273) (xy 71.05523 -136.22147) (xy 71.06894 -136.204249) (xy 71.090804 -136.166051)
			(xy 71.105754 -136.124654) (xy 71.113342 -136.0813) (xy 71.113341 -136.037286) (xy 71.10575 -135.993932)
			(xy 71.090798 -135.952537) (xy 71.068932 -135.914339) (xy 71.05523 -135.897112) (xy 71.03812 -135.875539)
			(xy 71.009638 -135.828421) (xy 70.9884 -135.777625) (xy 70.974869 -135.724256) (xy 70.96934 -135.669477)
			(xy 70.971933 -135.61448) (xy 70.982591 -135.560464) (xy 71.001083 -135.508605) (xy 71.027005 -135.460032)
			(xy 71.059793 -135.415803) (xy 71.098734 -135.37688) (xy 71.142978 -135.344112) (xy 71.191564 -135.318213)
			(xy 71.243431 -135.299745) (xy 71.297452 -135.289112) (xy 71.35245 -135.286545) (xy 71.407226 -135.2921)
			(xy 71.460589 -135.305655) (xy 71.511375 -135.326916) (xy 71.55848 -135.35542) (xy 71.579994 -135.372602)
			(xy 71.597218 -135.386268) (xy 71.635395 -135.408073) (xy 71.676755 -135.422981) (xy 71.720064 -135.430549)
			(xy 71.764028 -135.430549) (xy 71.807337 -135.422981) (xy 71.848697 -135.408073) (xy 71.886874 -135.386268)
			(xy 71.904098 -135.372602) (xy 71.926521 -135.35468) (xy 71.975789 -135.325228) (xy 72.02899 -135.303679)
			(xy 72.084866 -135.290543) (xy 72.142096 -135.286129) (xy 72.199326 -135.290543) (xy 72.255202 -135.303679)
			(xy 72.308403 -135.325228) (xy 72.357671 -135.35468) (xy 72.380094 -135.372602) (xy 72.397318 -135.386268)
			(xy 72.435495 -135.408073) (xy 72.476855 -135.422981) (xy 72.520164 -135.430549) (xy 72.564128 -135.430549)
			(xy 72.607437 -135.422981) (xy 72.648797 -135.408073) (xy 72.686974 -135.386268) (xy 72.704198 -135.372602)
			(xy 72.726618 -135.354711) (xy 72.77587 -135.325314) (xy 72.829042 -135.303806) (xy 72.884881 -135.290695)
			(xy 72.942069 -135.286291) (xy 72.999257 -135.290695) (xy 73.055096 -135.303806) (xy 73.108268 -135.325314)
			(xy 73.15752 -135.354711) (xy 73.17994 -135.372602) (xy 73.197182 -135.38627) (xy 73.235392 -135.408075)
			(xy 73.276783 -135.422983) (xy 73.320122 -135.43055) (xy 73.364116 -135.43055) (xy 73.407455 -135.422983)
			(xy 73.448846 -135.408075) (xy 73.487056 -135.38627) (xy 73.504298 -135.372602) (xy 73.526718 -135.354711)
			(xy 73.57597 -135.325314) (xy 73.629142 -135.303806) (xy 73.684981 -135.290695) (xy 73.742169 -135.286291)
			(xy 73.799357 -135.290695) (xy 73.855196 -135.303806) (xy 73.908368 -135.325314) (xy 73.95762 -135.354711)
			(xy 73.98004 -135.372602) (xy 73.997264 -135.386268) (xy 74.035441 -135.408073) (xy 74.076801 -135.422981)
			(xy 74.12011 -135.430549) (xy 74.164074 -135.430549) (xy 74.207383 -135.422981) (xy 74.248743 -135.408073)
			(xy 74.28692 -135.386268) (xy 74.304144 -135.372602) (xy 74.325439 -135.355642) (xy 74.371945 -135.327348)
			(xy 74.422073 -135.306123) (xy 74.474755 -135.292418) (xy 74.528872 -135.286524) (xy 74.58327 -135.288568)
			(xy 74.636791 -135.298506) (xy 74.688297 -135.316125) (xy 74.736691 -135.341052) (xy 74.780943 -135.372755)
			(xy 74.82011 -135.41056) (xy 74.85336 -135.453662) (xy 74.879984 -135.501143) (xy 74.899416 -135.551993)
			(xy 74.911242 -135.605129) (xy 74.91521 -135.65942) (xy 74.911236 -135.713711) (xy 74.899404 -135.766846)
			(xy 74.879967 -135.817694) (xy 74.853338 -135.865172) (xy 74.820083 -135.908271) (xy 74.780911 -135.946071)
			(xy 74.736656 -135.977769) (xy 74.688259 -136.002691) (xy 74.636752 -136.020305) (xy 74.583229 -136.030236)
			(xy 74.528831 -136.032274) (xy 74.474715 -136.026375) (xy 74.422034 -136.012664) (xy 74.371908 -135.991433)
			(xy 74.325406 -135.963135) (xy 74.304144 -135.946134) (xy 74.28692 -135.932468) (xy 74.248743 -135.910663)
			(xy 74.207383 -135.895755) (xy 74.164074 -135.888187) (xy 74.12011 -135.888187) (xy 74.076801 -135.895755)
			(xy 74.035441 -135.910663) (xy 73.997264 -135.932468) (xy 73.98004 -135.946134) (xy 73.957633 -135.964055)
			(xy 73.908395 -135.993506) (xy 73.855222 -136.015055) (xy 73.799373 -136.028193) (xy 73.742169 -136.032606)
			(xy 73.684965 -136.028193) (xy 73.629116 -136.015055) (xy 73.575943 -135.993506) (xy 73.526705 -135.964055)
			(xy 73.504298 -135.946134) (xy 73.487071 -135.932433) (xy 73.448873 -135.910568) (xy 73.407478 -135.895618)
			(xy 73.364125 -135.888028) (xy 73.320113 -135.888028) (xy 73.27676 -135.895618) (xy 73.235365 -135.910568)
			(xy 73.197167 -135.932433) (xy 73.17994 -135.946134) (xy 73.157533 -135.964055) (xy 73.108295 -135.993506)
			(xy 73.055122 -136.015055) (xy 72.999273 -136.028193) (xy 72.942069 -136.032606) (xy 72.884865 -136.028193)
			(xy 72.829016 -136.015055) (xy 72.775843 -135.993506) (xy 72.726605 -135.964055) (xy 72.704198 -135.946134)
			(xy 72.686974 -135.932468) (xy 72.648797 -135.910663) (xy 72.607437 -135.895755) (xy 72.564128 -135.888187)
			(xy 72.520164 -135.888187) (xy 72.476855 -135.895755) (xy 72.435495 -135.910663) (xy 72.397318 -135.932468)
			(xy 72.380094 -135.946134) (xy 72.358605 -135.963269) (xy 72.311631 -135.991793) (xy 72.260975 -136.013108)
			(xy 72.207738 -136.026749) (xy 72.153075 -136.032422) (xy 72.098171 -136.030003) (xy 72.044219 -136.019545)
			(xy 71.992388 -136.001274) (xy 71.943803 -135.975588) (xy 71.899519 -135.943043) (xy 71.860496 -135.904345)
			(xy 71.843646 -135.882634) (xy 71.833131 -135.869442) (xy 71.806561 -135.848671) (xy 71.775474 -135.835597)
			(xy 71.742046 -135.831135) (xy 71.708618 -135.835597) (xy 71.677531 -135.848671) (xy 71.650961 -135.869442)
			(xy 71.640446 -135.882634) (xy 71.628762 -135.897112) (xy 71.615103 -135.914361) (xy 71.593298 -135.952569)
			(xy 71.57839 -135.993959) (xy 71.570822 -136.037297) (xy 71.570821 -136.08129) (xy 71.578386 -136.124627)
			(xy 71.590119 -136.157208) (xy 80.635854 -136.157208) (xy 80.639925 -136.101586) (xy 80.652051 -136.047149)
			(xy 80.671974 -135.995058) (xy 80.69927 -135.946423) (xy 80.733356 -135.90228) (xy 80.773505 -135.863571)
			(xy 80.818863 -135.83112) (xy 80.868463 -135.805619) (xy 80.921247 -135.787612) (xy 80.97609 -135.777482)
			(xy 81.031824 -135.775445) (xy 81.087261 -135.781545) (xy 81.141218 -135.795651) (xy 81.192547 -135.817463)
			(xy 81.240153 -135.846517) (xy 81.283021 -135.882192) (xy 81.320238 -135.923729) (xy 81.351011 -135.970242)
			(xy 81.374683 -136.020739) (xy 81.390751 -136.074146) (xy 81.398871 -136.129322) (xy 81.39938 -136.157208)
			(xy 81.398871 -136.185094) (xy 81.390751 -136.24027) (xy 81.374683 -136.293677) (xy 81.351011 -136.344174)
			(xy 81.320238 -136.390687) (xy 81.283021 -136.432224) (xy 81.240153 -136.467899) (xy 81.192547 -136.496953)
			(xy 81.141218 -136.518765) (xy 81.087261 -136.532871) (xy 81.031824 -136.538971) (xy 80.97609 -136.536934)
			(xy 80.921247 -136.526804) (xy 80.868463 -136.508797) (xy 80.818863 -136.483296) (xy 80.773505 -136.450845)
			(xy 80.733356 -136.412136) (xy 80.69927 -136.367993) (xy 80.671974 -136.319358) (xy 80.652051 -136.267267)
			(xy 80.639925 -136.21283) (xy 80.635854 -136.157208) (xy 71.590119 -136.157208) (xy 71.593292 -136.166018)
			(xy 71.615095 -136.204228) (xy 71.628762 -136.22147) (xy 71.645744 -136.24273) (xy 71.674007 -136.289223)
			(xy 71.695205 -136.339333) (xy 71.708888 -136.391994) (xy 71.714764 -136.446085) (xy 71.712708 -136.500456)
			(xy 71.702764 -136.553949) (xy 71.685143 -136.605426) (xy 71.660221 -136.653792) (xy 71.628528 -136.698018)
			(xy 71.590738 -136.737163) (xy 71.547655 -136.770393) (xy 71.500196 -136.797002) (xy 71.449371 -136.816424)
			(xy 71.396261 -136.828245) (xy 71.341996 -136.832213) (xy 71.287731 -136.828245) (xy 71.234621 -136.816424)
			(xy 71.183796 -136.797002) (xy 71.136337 -136.770393) (xy 71.093254 -136.737163) (xy 71.055464 -136.698018)
			(xy 71.023771 -136.653792) (xy 70.998849 -136.605426) (xy 70.981228 -136.553949) (xy 70.971284 -136.500456)
			(xy 70.969228 -136.446085) (xy 68.513231 -136.446085) (xy 68.514173 -136.458319) (xy 68.509766 -136.515509)
			(xy 68.496652 -136.571349) (xy 68.475143 -136.624522) (xy 68.445745 -136.673775) (xy 68.427854 -136.696196)
			(xy 68.41414 -136.713385) (xy 68.392335 -136.751568) (xy 68.377429 -136.792936) (xy 68.369866 -136.836251)
			(xy 68.369872 -136.880222) (xy 68.377448 -136.923536) (xy 68.392366 -136.964899) (xy 68.414182 -137.003076)
			(xy 68.427854 -137.0203) (xy 68.445082 -137.041813) (xy 68.473651 -137.088943) (xy 68.494967 -137.139767)
			(xy 68.508566 -137.193177) (xy 68.51415 -137.248007) (xy 68.511598 -137.303061) (xy 68.500965 -137.357139)
			(xy 68.482484 -137.409061) (xy 68.456558 -137.457695) (xy 68.423751 -137.501981) (xy 68.38478 -137.540952)
			(xy 68.340494 -137.573758) (xy 68.29186 -137.599685) (xy 68.239938 -137.618166) (xy 68.185859 -137.628798)
			(xy 68.130805 -137.63135) (xy 68.075976 -137.625765) (xy 68.022566 -137.612167) (xy 67.971742 -137.590851)
			(xy 67.924611 -137.562282) (xy 67.90309 -137.545064) (xy 67.885866 -137.531398) (xy 67.847689 -137.509593)
			(xy 67.806329 -137.494685) (xy 67.76302 -137.487117) (xy 67.719056 -137.487117) (xy 67.675747 -137.494685)
			(xy 67.634387 -137.509593) (xy 67.59621 -137.531398) (xy 67.578986 -137.545064) (xy 67.556563 -137.562986)
			(xy 67.507295 -137.592438) (xy 67.454094 -137.613987) (xy 67.398218 -137.627123) (xy 67.340988 -137.631537)
			(xy 67.283758 -137.627123) (xy 67.227882 -137.613987) (xy 67.174681 -137.592438) (xy 67.125413 -137.562986)
			(xy 67.10299 -137.545064) (xy 67.085766 -137.531398) (xy 67.047589 -137.509593) (xy 67.006229 -137.494685)
			(xy 66.96292 -137.487117) (xy 66.918956 -137.487117) (xy 66.875647 -137.494685) (xy 66.834287 -137.509593)
			(xy 66.79611 -137.531398) (xy 66.778886 -137.545064) (xy 66.757377 -137.562295) (xy 66.710246 -137.590862)
			(xy 66.659422 -137.612176) (xy 66.606013 -137.625772) (xy 66.551184 -137.631354) (xy 66.496131 -137.628801)
			(xy 66.442054 -137.618168) (xy 66.390133 -137.599686) (xy 66.3415 -137.57376) (xy 66.297215 -137.540954)
			(xy 66.258245 -137.501983) (xy 66.225439 -137.457699) (xy 66.199513 -137.409065) (xy 66.181032 -137.357144)
			(xy 66.170399 -137.303067) (xy 66.167846 -137.248014) (xy 66.173428 -137.193185) (xy 66.187025 -137.139777)
			(xy 66.208339 -137.088953) (xy 66.236906 -137.041822) (xy 66.254122 -137.0203) (xy 66.26774 -137.00304)
			(xy 66.289544 -136.96487) (xy 66.304454 -136.923518) (xy 66.312025 -136.880216) (xy 66.312032 -136.836258)
			(xy 66.304473 -136.792954) (xy 66.289575 -136.751597) (xy 66.267782 -136.713421) (xy 66.254122 -136.696196)
			(xy 66.236224 -136.673771) (xy 66.206768 -136.624538) (xy 66.185215 -136.571368) (xy 66.172074 -136.515521)
			(xy 66.167657 -136.458319) (xy 65.314038 -136.458319) (xy 65.30963 -136.51551) (xy 65.296515 -136.571351)
			(xy 65.275003 -136.624524) (xy 65.245601 -136.673776) (xy 65.227708 -136.696196) (xy 65.213996 -136.713386)
			(xy 65.192195 -136.75157) (xy 65.177292 -136.792937) (xy 65.16973 -136.836252) (xy 65.169737 -136.880222)
			(xy 65.177311 -136.923534) (xy 65.192226 -136.964897) (xy 65.214038 -137.003075) (xy 65.227708 -137.0203)
			(xy 65.244844 -137.041864) (xy 65.273381 -137.088969) (xy 65.294673 -137.139762) (xy 65.308255 -137.193136)
			(xy 65.313831 -137.247929) (xy 65.311279 -137.302944) (xy 65.300656 -137.356985) (xy 65.282192 -137.408873)
			(xy 65.256291 -137.457478) (xy 65.223516 -137.501739) (xy 65.184582 -137.540693) (xy 65.140337 -137.57349)
			(xy 65.091746 -137.599416) (xy 65.039867 -137.617906) (xy 64.985832 -137.628557) (xy 64.930817 -137.631136)
			(xy 64.876022 -137.625588) (xy 64.822641 -137.612033) (xy 64.771837 -137.590767) (xy 64.724718 -137.562253)
			(xy 64.703198 -137.545064) (xy 64.685971 -137.531363) (xy 64.647773 -137.509498) (xy 64.606378 -137.494548)
			(xy 64.563025 -137.486958) (xy 64.519013 -137.486958) (xy 64.47566 -137.494548) (xy 64.434265 -137.509498)
			(xy 64.396067 -137.531363) (xy 64.37884 -137.545064) (xy 64.356433 -137.562985) (xy 64.307195 -137.592436)
			(xy 64.254022 -137.613985) (xy 64.198173 -137.627123) (xy 64.140969 -137.631536) (xy 64.083765 -137.627123)
			(xy 64.027916 -137.613985) (xy 63.974743 -137.592436) (xy 63.925505 -137.562985) (xy 63.903098 -137.545064)
			(xy 63.885874 -137.531398) (xy 63.847697 -137.509593) (xy 63.806337 -137.494685) (xy 63.763028 -137.487117)
			(xy 63.719064 -137.487117) (xy 63.675755 -137.494685) (xy 63.634395 -137.509593) (xy 63.596218 -137.531398)
			(xy 63.578994 -137.545064) (xy 63.557478 -137.562287) (xy 63.510348 -137.590854) (xy 63.459524 -137.612168)
			(xy 63.406116 -137.625765) (xy 63.351287 -137.631348) (xy 63.296235 -137.628795) (xy 63.242158 -137.618163)
			(xy 63.190237 -137.599682) (xy 63.141604 -137.573755) (xy 63.09732 -137.54095) (xy 63.05835 -137.501979)
			(xy 63.025544 -137.457695) (xy 62.999618 -137.409062) (xy 62.981137 -137.357141) (xy 62.970505 -137.303065)
			(xy 62.967952 -137.248012) (xy 62.973535 -137.193183) (xy 62.987132 -137.139775) (xy 63.008446 -137.088952)
			(xy 63.037014 -137.041821) (xy 63.05423 -137.0203) (xy 63.067852 -137.003042) (xy 63.089664 -136.964874)
			(xy 63.10458 -136.923521) (xy 63.112154 -136.880217) (xy 63.112161 -136.836256) (xy 63.104599 -136.792951)
			(xy 63.089695 -136.751593) (xy 63.067894 -136.713419) (xy 63.05423 -136.696196) (xy 63.036332 -136.673772)
			(xy 63.006875 -136.624538) (xy 62.985321 -136.571368) (xy 62.97218 -136.515521) (xy 62.967763 -136.458319)
			(xy 61.313176 -136.458319) (xy 61.312701 -136.490607) (xy 61.303977 -136.544381) (xy 61.287516 -136.596313)
			(xy 61.263668 -136.645293) (xy 61.232943 -136.69028) (xy 61.195995 -136.730313) (xy 61.153611 -136.764539)
			(xy 61.106696 -136.792229) (xy 61.056248 -136.812793) (xy 61.003344 -136.825792) (xy 60.949111 -136.830949)
			(xy 60.894705 -136.828154) (xy 60.841286 -136.817467) (xy 60.789993 -136.799115) (xy 60.741918 -136.773491)
			(xy 60.698086 -136.741139) (xy 60.659433 -136.70275) (xy 60.642754 -136.68121) (xy 60.632204 -136.668037)
			(xy 60.605585 -136.647308) (xy 60.57447 -136.634263) (xy 60.541027 -136.629812) (xy 60.507584 -136.634263)
			(xy 60.476469 -136.647308) (xy 60.44985 -136.668037) (xy 60.4393 -136.68121) (xy 60.432696 -136.689846)
			(xy 60.42914 -136.694418) (xy 60.42787 -136.695942) (xy 60.414201 -136.713165) (xy 60.392391 -136.751341)
			(xy 60.377478 -136.792702) (xy 60.369909 -136.836012) (xy 60.369908 -136.879979) (xy 60.377476 -136.923289)
			(xy 60.392387 -136.96465) (xy 60.414196 -137.002827) (xy 60.42787 -137.020046) (xy 60.445788 -137.042469)
			(xy 60.475233 -137.091736) (xy 60.496775 -137.144935) (xy 60.509906 -137.200808) (xy 60.514314 -137.258034)
			(xy 60.509896 -137.315259) (xy 60.496755 -137.37113) (xy 60.475203 -137.424325) (xy 60.445749 -137.473587)
			(xy 60.42787 -137.496042) (xy 60.414201 -137.513265) (xy 60.392391 -137.551441) (xy 60.377478 -137.592802)
			(xy 60.369909 -137.636112) (xy 60.369908 -137.680079) (xy 60.377476 -137.723389) (xy 60.392387 -137.76475)
			(xy 60.414196 -137.802927) (xy 60.42787 -137.820146) (xy 60.442731 -137.838638) (xy 60.468159 -137.878689)
			(xy 60.48832 -137.921633) (xy 60.495942 -137.944098) (xy 60.504452 -137.972613) (xy 60.513353 -138.031446)
			(xy 60.513098 -138.059391) (xy 70.968852 -138.059391) (xy 70.972825 -138.005092) (xy 70.984657 -137.95195)
			(xy 71.004096 -137.901095) (xy 71.030728 -137.85361) (xy 71.063987 -137.810506) (xy 71.103164 -137.7727)
			(xy 71.147426 -137.740997) (xy 71.195829 -137.716073) (xy 71.247344 -137.698457) (xy 71.300874 -137.688525)
			(xy 71.35528 -137.686488) (xy 71.409403 -137.69239) (xy 71.462091 -137.706104) (xy 71.512222 -137.72734)
			(xy 71.55873 -137.755644) (xy 71.579994 -137.772648) (xy 71.597218 -137.786314) (xy 71.635395 -137.808119)
			(xy 71.676755 -137.823027) (xy 71.720064 -137.830595) (xy 71.764028 -137.830595) (xy 71.807337 -137.823027)
			(xy 71.848697 -137.808119) (xy 71.886874 -137.786314) (xy 71.904098 -137.772648) (xy 71.925511 -137.755416)
			(xy 71.972499 -137.726896) (xy 72.023167 -137.705589) (xy 72.076415 -137.691956) (xy 72.131088 -137.686292)
			(xy 72.186 -137.68872) (xy 72.239959 -137.699189) (xy 72.291796 -137.71747) (xy 72.340384 -137.743167)
			(xy 72.384671 -137.775723) (xy 72.423695 -137.814432) (xy 72.440546 -137.836148) (xy 72.451061 -137.84934)
			(xy 72.477631 -137.870111) (xy 72.508718 -137.883185) (xy 72.542146 -137.887647) (xy 72.575574 -137.883185)
			(xy 72.606661 -137.870111) (xy 72.633231 -137.84934) (xy 72.643746 -137.836148) (xy 72.65543 -137.821416)
			(xy 72.669133 -137.804219) (xy 72.69094 -137.766037) (xy 72.705849 -137.724672) (xy 72.713413 -137.681357)
			(xy 72.713408 -137.637387) (xy 72.705834 -137.594074) (xy 72.690917 -137.552712) (xy 72.669102 -137.514535)
			(xy 72.65543 -137.497312) (xy 72.638263 -137.47577) (xy 72.609718 -137.428663) (xy 72.588421 -137.377866)
			(xy 72.574834 -137.324487) (xy 72.569255 -137.26969) (xy 72.571804 -137.214668) (xy 72.582427 -137.160621)
			(xy 72.600891 -137.108727) (xy 72.626795 -137.060118) (xy 72.659573 -137.015851) (xy 72.698511 -136.976894)
			(xy 72.742761 -136.944094) (xy 72.791358 -136.918166) (xy 72.843243 -136.899676) (xy 72.897284 -136.889026)
			(xy 72.952305 -136.88645) (xy 73.007105 -136.892002) (xy 73.060491 -136.905562) (xy 73.111298 -136.926834)
			(xy 73.158419 -136.955355) (xy 73.17994 -136.972548) (xy 73.197182 -136.986216) (xy 73.235392 -137.008021)
			(xy 73.276783 -137.022929) (xy 73.320122 -137.030496) (xy 73.364116 -137.030496) (xy 73.407455 -137.022929)
			(xy 73.448846 -137.008021) (xy 73.487056 -136.986216) (xy 73.504298 -136.972548) (xy 73.526718 -136.954657)
			(xy 73.57597 -136.92526) (xy 73.629142 -136.903752) (xy 73.684981 -136.890641) (xy 73.742169 -136.886237)
			(xy 73.799357 -136.890641) (xy 73.855196 -136.903752) (xy 73.908368 -136.92526) (xy 73.95762 -136.954657)
			(xy 73.98004 -136.972548) (xy 73.997264 -136.986214) (xy 74.035441 -137.008019) (xy 74.076801 -137.022927)
			(xy 74.12011 -137.030495) (xy 74.164074 -137.030495) (xy 74.207383 -137.022927) (xy 74.248743 -137.008019)
			(xy 74.28692 -136.986214) (xy 74.304144 -136.972548) (xy 74.325187 -136.955766) (xy 74.371117 -136.927709)
			(xy 74.420605 -136.90655) (xy 74.472622 -136.89273) (xy 74.526086 -136.886535) (xy 74.579885 -136.888094)
			(xy 74.6329 -136.897376) (xy 74.684029 -136.914186) (xy 74.732208 -136.938176) (xy 74.776436 -136.968846)
			(xy 74.815792 -137.005558) (xy 74.849459 -137.04755) (xy 74.876735 -137.093948) (xy 74.897054 -137.143786)
			(xy 74.909994 -137.196029) (xy 74.915284 -137.24959) (xy 74.912816 -137.303355) (xy 74.90264 -137.356206)
			(xy 74.884968 -137.407043) (xy 74.872147 -137.431736) (xy 80.563066 -137.431736) (xy 80.563279 -137.37577)
			(xy 80.571665 -137.320435) (xy 80.588046 -137.266919) (xy 80.61207 -137.216371) (xy 80.64322 -137.169874)
			(xy 80.680829 -137.128428) (xy 80.72409 -137.09292) (xy 80.772074 -137.064114) (xy 80.823751 -137.042627)
			(xy 80.878013 -137.02892) (xy 80.933696 -137.023288) (xy 80.989604 -137.025851) (xy 81.044537 -137.036555)
			(xy 81.097318 -137.055169) (xy 81.146813 -137.081294) (xy 81.19196 -137.11437) (xy 81.23179 -137.153686)
			(xy 81.249012 -137.175748) (xy 81.262795 -137.193288) (xy 81.295407 -137.223717) (xy 81.332832 -137.247983)
			(xy 81.373919 -137.26534) (xy 81.417407 -137.275255) (xy 81.461958 -137.277423) (xy 81.506203 -137.271777)
			(xy 81.548781 -137.258491) (xy 81.568798 -137.248646) (xy 81.592894 -137.236699) (xy 81.643632 -137.218864)
			(xy 81.696373 -137.208339) (xy 81.75007 -137.205333) (xy 81.803657 -137.209905) (xy 81.856068 -137.221965)
			(xy 81.906263 -137.241274) (xy 81.953246 -137.267447) (xy 81.996082 -137.299966) (xy 82.01533 -137.31875)
			(xy 82.030896 -137.333838) (xy 82.066173 -137.359028) (xy 82.105214 -137.377862) (xy 82.146887 -137.389793)
			(xy 82.189981 -137.394474) (xy 82.233243 -137.391769) (xy 82.275418 -137.381757) (xy 82.315281 -137.364729)
			(xy 82.351673 -137.341179) (xy 82.383537 -137.311792) (xy 82.397092 -137.294874) (xy 82.414446 -137.273013)
			(xy 82.454583 -137.234224) (xy 82.499943 -137.201697) (xy 82.549559 -137.176126) (xy 82.602371 -137.158059)
			(xy 82.657252 -137.147879) (xy 82.71303 -137.145805) (xy 82.768516 -137.15188) (xy 82.822524 -137.165976)
			(xy 82.873902 -137.187791) (xy 82.89798 -137.20191) (xy 82.918358 -137.213677) (xy 82.962359 -137.230336)
			(xy 83.008674 -137.238621) (xy 83.055722 -137.238251) (xy 83.101901 -137.229237) (xy 83.145635 -137.211888)
			(xy 83.185434 -137.186794) (xy 83.203034 -137.171176) (xy 83.223389 -137.152965) (xy 83.268337 -137.121938)
			(xy 83.31725 -137.097639) (xy 83.369129 -137.080564) (xy 83.422913 -137.071063) (xy 83.477502 -137.069329)
			(xy 83.531781 -137.075399) (xy 83.584639 -137.089148) (xy 83.634995 -137.110295) (xy 83.681821 -137.138407)
			(xy 83.724159 -137.172911) (xy 83.761143 -137.2131) (xy 83.792017 -137.258153) (xy 83.816151 -137.307148)
			(xy 83.83305 -137.359085) (xy 83.842369 -137.4129) (xy 83.843917 -137.467495) (xy 83.837664 -137.521753)
			(xy 83.823736 -137.574564) (xy 83.802418 -137.624848) (xy 83.774147 -137.671579) (xy 83.739501 -137.713799)
			(xy 83.699187 -137.750647) (xy 83.654029 -137.781369) (xy 83.604952 -137.805336) (xy 83.552959 -137.822059)
			(xy 83.499112 -137.831196) (xy 83.444512 -137.832559) (xy 83.390276 -137.826122) (xy 83.337513 -137.812015)
			(xy 83.2873 -137.790527) (xy 83.26374 -137.776712) (xy 83.2434 -137.764878) (xy 83.199386 -137.748233)
			(xy 83.153064 -137.739961) (xy 83.106009 -137.740344) (xy 83.059827 -137.749368) (xy 83.01609 -137.766725)
			(xy 82.976288 -137.791826) (xy 82.958686 -137.807446) (xy 82.938792 -137.825217) (xy 82.894985 -137.855653)
			(xy 82.847367 -137.879692) (xy 82.796864 -137.896865) (xy 82.744463 -137.906838) (xy 82.691183 -137.909416)
			(xy 82.638063 -137.904549) (xy 82.586139 -137.892332) (xy 82.536422 -137.873003) (xy 82.489881 -137.846939)
			(xy 82.447423 -137.814648) (xy 82.428334 -137.796016) (xy 82.4128 -137.780894) (xy 82.377517 -137.755708)
			(xy 82.33847 -137.736879) (xy 82.296792 -137.724953) (xy 82.253695 -137.720276) (xy 82.21043 -137.722985)
			(xy 82.168253 -137.733) (xy 82.128388 -137.750031) (xy 82.091994 -137.773584) (xy 82.060128 -137.802973)
			(xy 82.046572 -137.819892) (xy 82.029731 -137.84102) (xy 81.991084 -137.878775) (xy 81.947496 -137.910699)
			(xy 81.899838 -137.936152) (xy 81.849066 -137.954625) (xy 81.796195 -137.965748) (xy 81.742284 -137.9693)
			(xy 81.68841 -137.965208) (xy 81.635654 -137.953554) (xy 81.585069 -137.934572) (xy 81.53767 -137.908642)
			(xy 81.494404 -137.876283) (xy 81.456138 -137.838141) (xy 81.439512 -137.816844) (xy 81.425691 -137.799335)
			(xy 81.39309 -137.768898) (xy 81.355673 -137.744624) (xy 81.314591 -137.72726) (xy 81.271107 -137.71734)
			(xy 81.226559 -137.715169) (xy 81.182317 -137.720814) (xy 81.139741 -137.7341) (xy 81.119726 -137.743946)
			(xy 81.094654 -137.756385) (xy 81.041734 -137.774597) (xy 80.986721 -137.784883) (xy 80.930795 -137.787021)
			(xy 80.875157 -137.780966) (xy 80.821 -137.766848) (xy 80.769487 -137.744968) (xy 80.721724 -137.715798)
			(xy 80.678734 -137.679963) (xy 80.641441 -137.638232) (xy 80.610645 -137.591501) (xy 80.587006 -137.540771)
			(xy 80.571032 -137.487133) (xy 80.563066 -137.431736) (xy 74.872147 -137.431736) (xy 74.860167 -137.45481)
			(xy 74.828754 -137.498513) (xy 74.791381 -137.537243) (xy 74.748826 -137.570195) (xy 74.701974 -137.596684)
			(xy 74.6518 -137.616158) (xy 74.599345 -137.628212) (xy 74.545703 -137.632597) (xy 74.491987 -137.62922)
			(xy 74.439316 -137.618152) (xy 74.388785 -137.599623) (xy 74.341444 -137.574019) (xy 74.298278 -137.541872)
			(xy 74.260185 -137.50385) (xy 74.243692 -137.48258) (xy 74.233177 -137.469388) (xy 74.206607 -137.448617)
			(xy 74.17552 -137.435543) (xy 74.142092 -137.431081) (xy 74.108664 -137.435543) (xy 74.077577 -137.448617)
			(xy 74.051007 -137.469388) (xy 74.040492 -137.48258) (xy 74.028808 -137.497312) (xy 74.015177 -137.514563)
			(xy 73.993371 -137.552734) (xy 73.97846 -137.594088) (xy 73.970889 -137.637392) (xy 73.970885 -137.681353)
			(xy 73.978446 -137.724658) (xy 73.993348 -137.766016) (xy 74.015145 -137.804191) (xy 74.028808 -137.821416)
			(xy 74.04596 -137.842967) (xy 74.074497 -137.890073) (xy 74.095788 -137.940867) (xy 74.109368 -137.994243)
			(xy 74.114943 -138.049035) (xy 74.112391 -138.104052) (xy 74.101766 -138.158093) (xy 74.083302 -138.209982)
			(xy 74.0574 -138.258586) (xy 74.024624 -138.302848) (xy 73.985689 -138.341802) (xy 73.941444 -138.3746)
			(xy 73.892852 -138.400527) (xy 73.840973 -138.419017) (xy 73.786937 -138.429668) (xy 73.731922 -138.432248)
			(xy 73.677126 -138.426701) (xy 73.623744 -138.413147) (xy 73.572939 -138.391881) (xy 73.525819 -138.363368)
			(xy 73.504298 -138.34618) (xy 73.487071 -138.332479) (xy 73.448873 -138.310614) (xy 73.407478 -138.295664)
			(xy 73.364125 -138.288074) (xy 73.320113 -138.288074) (xy 73.27676 -138.295664) (xy 73.235365 -138.310614)
			(xy 73.197167 -138.332479) (xy 73.17994 -138.34618) (xy 73.157533 -138.364101) (xy 73.108295 -138.393552)
			(xy 73.055122 -138.415101) (xy 72.999273 -138.428239) (xy 72.942069 -138.432652) (xy 72.884865 -138.428239)
			(xy 72.829016 -138.415101) (xy 72.775843 -138.393552) (xy 72.726605 -138.364101) (xy 72.704198 -138.34618)
			(xy 72.686974 -138.332514) (xy 72.648797 -138.310709) (xy 72.607437 -138.295801) (xy 72.564128 -138.288233)
			(xy 72.520164 -138.288233) (xy 72.476855 -138.295801) (xy 72.435495 -138.310709) (xy 72.397318 -138.332514)
			(xy 72.380094 -138.34618) (xy 72.357671 -138.364102) (xy 72.308403 -138.393554) (xy 72.255202 -138.415103)
			(xy 72.199326 -138.428239) (xy 72.142096 -138.432653) (xy 72.084866 -138.428239) (xy 72.02899 -138.415103)
			(xy 71.975789 -138.393554) (xy 71.926521 -138.364102) (xy 71.904098 -138.34618) (xy 71.886874 -138.332514)
			(xy 71.848697 -138.310709) (xy 71.807337 -138.295801) (xy 71.764028 -138.288233) (xy 71.720064 -138.288233)
			(xy 71.676755 -138.295801) (xy 71.635395 -138.310709) (xy 71.597218 -138.332514) (xy 71.579994 -138.34618)
			(xy 71.558716 -138.363166) (xy 71.512206 -138.391468) (xy 71.462074 -138.412701) (xy 71.409385 -138.426413)
			(xy 71.355262 -138.432313) (xy 71.300856 -138.430273) (xy 71.247327 -138.420339) (xy 71.195812 -138.40272)
			(xy 71.14741 -138.377794) (xy 71.10315 -138.346089) (xy 71.063975 -138.308281) (xy 71.030719 -138.265175)
			(xy 71.004088 -138.217689) (xy 70.984652 -138.166833) (xy 70.972822 -138.11369) (xy 70.968852 -138.059391)
			(xy 60.513098 -138.059391) (xy 60.512811 -138.090947) (xy 60.508388 -138.120374) (xy 60.503731 -138.145489)
			(xy 60.488442 -138.194227) (xy 60.466636 -138.240419) (xy 60.438723 -138.283197) (xy 60.422282 -138.302746)
			(xy 60.408062 -138.32204) (xy 60.386374 -138.364773) (xy 60.373079 -138.410814) (xy 60.368649 -138.458532)
			(xy 60.373241 -138.506233) (xy 60.386692 -138.552229) (xy 60.408525 -138.594889) (xy 60.42279 -138.61415)
			(xy 60.441847 -138.637065) (xy 60.462302 -138.670151) (xy 82.149889 -138.670151) (xy 82.156473 -138.614743)
			(xy 82.171058 -138.560886) (xy 82.193333 -138.509727) (xy 82.222824 -138.46236) (xy 82.2589 -138.419793)
			(xy 82.300792 -138.382936) (xy 82.347607 -138.352576) (xy 82.398344 -138.329358) (xy 82.451923 -138.31378)
			(xy 82.5072 -138.306173) (xy 82.562995 -138.3067) (xy 82.618118 -138.31535) (xy 82.671394 -138.331937)
			(xy 82.721684 -138.356108) (xy 82.745072 -138.371326) (xy 82.76326 -138.383179) (xy 82.802818 -138.401057)
			(xy 82.844841 -138.411947) (xy 82.888104 -138.415532) (xy 82.931346 -138.411708) (xy 82.973308 -138.400585)
			(xy 83.012767 -138.382488) (xy 83.048574 -138.357944) (xy 83.079685 -138.327668) (xy 83.092798 -138.310366)
			(xy 83.109608 -138.288096) (xy 83.148631 -138.248217) (xy 83.193048 -138.214449) (xy 83.241911 -138.187512)
			(xy 83.294176 -138.16798) (xy 83.348729 -138.156271) (xy 83.404406 -138.152634) (xy 83.460018 -138.157147)
			(xy 83.51438 -138.169713) (xy 83.566332 -138.190065) (xy 83.584817 -138.200638) (xy 84.049614 -138.200638)
			(xy 84.053685 -138.145016) (xy 84.065811 -138.090579) (xy 84.085734 -138.038488) (xy 84.11303 -137.989853)
			(xy 84.147116 -137.94571) (xy 84.187265 -137.907001) (xy 84.232623 -137.87455) (xy 84.282223 -137.849049)
			(xy 84.335007 -137.831042) (xy 84.38985 -137.820912) (xy 84.445584 -137.818875) (xy 84.501021 -137.824975)
			(xy 84.554978 -137.839081) (xy 84.606307 -137.860893) (xy 84.653913 -137.889947) (xy 84.696781 -137.925622)
			(xy 84.733998 -137.967159) (xy 84.764771 -138.013672) (xy 84.788443 -138.064169) (xy 84.804511 -138.117576)
			(xy 84.812631 -138.172752) (xy 84.81314 -138.200638) (xy 84.812631 -138.228524) (xy 84.804511 -138.2837)
			(xy 84.788443 -138.337107) (xy 84.764771 -138.387604) (xy 84.733998 -138.434117) (xy 84.696781 -138.475654)
			(xy 84.653913 -138.511329) (xy 84.606307 -138.540383) (xy 84.554978 -138.562195) (xy 84.501021 -138.576301)
			(xy 84.445584 -138.582401) (xy 84.38985 -138.580364) (xy 84.335007 -138.570234) (xy 84.282223 -138.552227)
			(xy 84.232623 -138.526726) (xy 84.187265 -138.494275) (xy 84.147116 -138.455566) (xy 84.11303 -138.411423)
			(xy 84.085734 -138.362788) (xy 84.065811 -138.310697) (xy 84.053685 -138.25626) (xy 84.049614 -138.200638)
			(xy 83.584817 -138.200638) (xy 83.614764 -138.217767) (xy 83.658644 -138.25223) (xy 83.697035 -138.292718)
			(xy 83.729119 -138.338366) (xy 83.75421 -138.388202) (xy 83.771773 -138.441161) (xy 83.781434 -138.496114)
			(xy 83.782987 -138.551888) (xy 83.776397 -138.607293) (xy 83.761807 -138.661147) (xy 83.739527 -138.712301)
			(xy 83.710032 -138.759663) (xy 83.673952 -138.802224) (xy 83.632057 -138.839074) (xy 83.585241 -138.869428)
			(xy 83.534502 -138.892638) (xy 83.480923 -138.908208) (xy 83.425647 -138.915808) (xy 83.369854 -138.915273)
			(xy 83.314735 -138.906616) (xy 83.261464 -138.890022) (xy 83.211179 -138.865845) (xy 83.187794 -138.850624)
			(xy 83.169568 -138.838832) (xy 83.130019 -138.820945) (xy 83.088003 -138.810045) (xy 83.044746 -138.806451)
			(xy 83.001508 -138.810267) (xy 82.959549 -138.821383) (xy 82.920093 -138.839474) (xy 82.884288 -138.864012)
			(xy 82.85318 -138.894284) (xy 82.840068 -138.911584) (xy 82.823323 -138.933903) (xy 82.7843 -138.973785)
			(xy 82.739883 -139.007557) (xy 82.691021 -139.034498) (xy 82.638755 -139.054034) (xy 82.584201 -139.065748)
			(xy 82.528522 -139.069389) (xy 82.472907 -139.06488) (xy 82.418542 -139.052317) (xy 82.366587 -139.031969)
			(xy 82.31815 -139.004269) (xy 82.274266 -138.969809) (xy 82.235869 -138.929323) (xy 82.20378 -138.883676)
			(xy 82.178684 -138.833841) (xy 82.161114 -138.780881) (xy 82.151448 -138.725927) (xy 82.149889 -138.670151)
			(xy 60.462302 -138.670151) (xy 60.473186 -138.687756) (xy 60.496073 -138.742783) (xy 60.503562 -138.77163)
			(xy 60.509048 -138.796426) (xy 60.514033 -138.846965) (xy 60.512102 -138.897713) (xy 60.50329 -138.947727)
			(xy 60.495942 -138.972036) (xy 60.488337 -138.99451) (xy 60.468204 -139.037472) (xy 60.442763 -139.077519)
			(xy 60.42787 -139.095988) (xy 60.414205 -139.113211) (xy 60.392403 -139.151386) (xy 60.377498 -139.192744)
			(xy 60.369935 -139.23605) (xy 60.36994 -139.280012) (xy 60.377513 -139.323316) (xy 60.392428 -139.36467)
			(xy 60.41424 -139.40284) (xy 60.42787 -139.420092) (xy 60.442729 -139.438585) (xy 60.468152 -139.478637)
			(xy 60.488308 -139.521583) (xy 60.495942 -139.544044) (xy 60.503285 -139.568354) (xy 60.512083 -139.618369)
			(xy 60.514013 -139.669115) (xy 60.50904 -139.719653) (xy 60.503562 -139.74445) (xy 60.496086 -139.773302)
			(xy 60.473209 -139.828335) (xy 60.441849 -139.879014) (xy 60.42279 -139.90193) (xy 60.408462 -139.92123)
			(xy 60.386576 -139.964021) (xy 60.373126 -140.010163) (xy 60.36859 -140.05801) (xy 60.37313 -140.105858)
			(xy 60.386584 -140.151998) (xy 60.408473 -140.194787) (xy 60.42279 -140.214096) (xy 60.42279 -140.457936)
			(xy 61.393321 -140.457936) (xy 61.397396 -140.404855) (xy 61.409526 -140.353019) (xy 61.429427 -140.303642)
			(xy 61.456632 -140.257881) (xy 61.490504 -140.216809) (xy 61.530248 -140.18139) (xy 61.574933 -140.152452)
			(xy 61.623512 -140.130674) (xy 61.674845 -140.116568) (xy 61.727731 -140.110462) (xy 61.780929 -140.112501)
			(xy 61.833192 -140.122637) (xy 61.883295 -140.140632) (xy 61.930064 -140.166064) (xy 61.972403 -140.198338)
			(xy 62.009319 -140.236696) (xy 62.039947 -140.28024) (xy 62.063569 -140.327949) (xy 62.079632 -140.378705)
			(xy 62.087759 -140.431318) (xy 62.088268 -140.457936) (xy 62.087759 -140.484554) (xy 62.079632 -140.537167)
			(xy 62.063569 -140.587923) (xy 62.039947 -140.635632) (xy 62.009319 -140.679176) (xy 61.972403 -140.717534)
			(xy 61.930064 -140.749808) (xy 61.883295 -140.77524) (xy 61.833192 -140.793235) (xy 61.780929 -140.803371)
			(xy 61.727731 -140.80541) (xy 61.674845 -140.799304) (xy 61.623512 -140.785198) (xy 61.574933 -140.76342)
			(xy 61.530248 -140.734482) (xy 61.490504 -140.699063) (xy 61.456632 -140.657991) (xy 61.429427 -140.61223)
			(xy 61.409526 -140.562853) (xy 61.397396 -140.511017) (xy 61.393321 -140.457936) (xy 60.42279 -140.457936)
			(xy 60.42279 -140.702284) (xy 60.409982 -140.719524) (xy 60.389738 -140.757398) (xy 60.376151 -140.798136)
			(xy 60.369607 -140.840579) (xy 60.370292 -140.883517) (xy 60.378188 -140.92573) (xy 60.393069 -140.966013)
			(xy 60.414512 -141.003221) (xy 60.42787 -141.020038) (xy 60.446452 -141.043371) (xy 60.476719 -141.094767)
			(xy 60.498409 -141.15033) (xy 60.510969 -141.208638) (xy 60.514076 -141.268203) (xy 60.511436 -141.297914)
			(xy 60.510318 -141.312065) (xy 60.513624 -141.340251) (xy 60.523084 -141.367008) (xy 60.538228 -141.391008)
			(xy 60.548012 -141.401292) (xy 60.751974 -141.605254) (xy 61.508386 -141.605254) (xy 61.533278 -141.594078)
			(xy 61.547271 -141.587929) (xy 61.575865 -141.577126) (xy 61.590428 -141.572488) (xy 61.610494 -141.5669)
			(xy 61.633687 -141.56102) (xy 61.680883 -141.553134) (xy 61.704728 -141.551152) (xy 61.710824 -141.550644)
			(xy 61.720984 -141.550136) (xy 61.75712 -141.549346) (xy 61.82902 -141.556742) (xy 61.86424 -141.564868)
			(xy 61.885506 -141.568917) (xy 61.928763 -141.570566) (xy 61.971675 -141.564865) (xy 62.013 -141.551977)
			(xy 62.051546 -141.532276) (xy 62.086197 -141.506331) (xy 62.115954 -141.474892) (xy 62.139955 -141.438867)
			(xy 62.157508 -141.399297) (xy 62.168105 -141.357325) (xy 62.171439 -141.314165) (xy 62.169802 -141.29258)
			(xy 62.167808 -141.266181) (xy 62.170405 -141.213305) (xy 62.18046 -141.161329) (xy 62.197771 -141.111299)
			(xy 62.221989 -141.064223) (xy 62.252626 -141.021049) (xy 62.289066 -140.982646) (xy 62.330574 -140.949787)
			(xy 62.376315 -140.923134) (xy 62.425369 -140.903224) (xy 62.476746 -140.890458) (xy 62.529414 -140.885092)
			(xy 62.555882 -140.885672) (xy 62.570461 -140.88639) (xy 62.599451 -140.88982) (xy 62.613794 -140.89253)
			(xy 62.644599 -140.899341) (xy 62.703504 -140.921921) (xy 62.757753 -140.954117) (xy 62.782196 -140.974064)
			(xy 62.800243 -140.987322) (xy 62.839986 -141.007947) (xy 62.882727 -141.021295) (xy 62.927145 -141.026953)
			(xy 62.971868 -141.024746) (xy 63.015513 -141.014743) (xy 63.056732 -140.997252) (xy 63.094252 -140.972815)
			(xy 63.110872 -140.957808) (xy 63.132462 -140.914882) (xy 63.138694 -140.901458) (xy 63.145483 -140.872658)
			(xy 63.145475 -140.843069) (xy 63.138669 -140.814273) (xy 63.132462 -140.800836) (xy 63.110872 -140.758164)
			(xy 63.091314 -140.7414) (xy 63.071984 -140.724299) (xy 63.037757 -140.685669) (xy 63.00919 -140.642685)
			(xy 62.986829 -140.59617) (xy 62.978538 -140.571728) (xy 62.971773 -140.549467) (xy 62.96319 -140.503739)
			(xy 62.960373 -140.457298) (xy 62.96152 -140.43406) (xy 62.962282 -140.423138) (xy 62.965615 -140.393838)
			(xy 62.980335 -140.336737) (xy 63.003851 -140.282661) (xy 63.035579 -140.232957) (xy 63.054738 -140.21054)
			(xy 63.067626 -140.193414) (xy 63.088068 -140.155745) (xy 63.101895 -140.115179) (xy 63.108714 -140.072867)
			(xy 63.108332 -140.030011) (xy 63.100759 -139.987828) (xy 63.08621 -139.947514) (xy 63.0651 -139.910216)
			(xy 63.051944 -139.893294) (xy 63.034095 -139.870496) (xy 63.004932 -139.820479) (xy 62.983858 -139.766553)
			(xy 62.971379 -139.710016) (xy 62.967796 -139.65223) (xy 62.973195 -139.594584) (xy 62.979808 -139.566396)
			(xy 62.991238 -139.529566) (xy 63.001913 -139.502118) (xy 63.030664 -139.450723) (xy 63.067148 -139.404495)
			(xy 63.110455 -139.364588) (xy 63.159505 -139.331997) (xy 63.186056 -139.319254) (xy 63.210565 -139.308554)
			(xy 63.261879 -139.293496) (xy 63.314818 -139.28593) (xy 63.368296 -139.28601) (xy 63.421213 -139.293735)
			(xy 63.472482 -139.308946) (xy 63.521049 -139.33133) (xy 63.565917 -139.360429) (xy 63.606164 -139.395643)
			(xy 63.640963 -139.436249) (xy 63.6696 -139.481413) (xy 63.691485 -139.530208) (xy 63.706169 -139.58163)
			(xy 63.71335 -139.634623) (xy 63.713053 -139.668603) (xy 66.167898 -139.668603) (xy 66.170448 -139.613555)
			(xy 66.181078 -139.559482) (xy 66.199556 -139.507565) (xy 66.225479 -139.458935) (xy 66.258282 -139.414654)
			(xy 66.297248 -139.375687) (xy 66.341529 -139.342883) (xy 66.390158 -139.316959) (xy 66.442075 -139.29848)
			(xy 66.496148 -139.287849) (xy 66.551196 -139.285298) (xy 66.60602 -139.290882) (xy 66.659424 -139.30448)
			(xy 66.710242 -139.325795) (xy 66.757367 -139.354362) (xy 66.778886 -139.371578) (xy 66.79611 -139.385244)
			(xy 66.834287 -139.407049) (xy 66.875647 -139.421957) (xy 66.918956 -139.429525) (xy 66.96292 -139.429525)
			(xy 67.006229 -139.421957) (xy 67.047589 -139.407049) (xy 67.085766 -139.385244) (xy 67.10299 -139.371578)
			(xy 67.124489 -139.354352) (xy 67.171601 -139.325801) (xy 67.222404 -139.304497) (xy 67.27579 -139.290906)
			(xy 67.330595 -139.285323) (xy 67.385625 -139.287871) (xy 67.43968 -139.298494) (xy 67.491581 -139.31696)
			(xy 67.540198 -139.342867) (xy 67.584471 -139.37565) (xy 67.623434 -139.414594) (xy 67.656238 -139.458851)
			(xy 67.682168 -139.507455) (xy 67.700659 -139.559348) (xy 67.711308 -139.613398) (xy 67.713882 -139.668427)
			(xy 67.708325 -139.723235) (xy 67.69476 -139.776627) (xy 67.67348 -139.82744) (xy 67.644951 -139.874566)
			(xy 67.627754 -139.896088) (xy 67.614119 -139.913354) (xy 67.592313 -139.951559) (xy 67.577403 -139.992946)
			(xy 67.569832 -140.03628) (xy 67.569828 -140.08027) (xy 67.57739 -140.123605) (xy 67.592291 -140.164994)
			(xy 67.61409 -140.203204) (xy 67.627754 -140.220446) (xy 67.644652 -140.241548) (xy 67.672779 -140.287715)
			(xy 67.693938 -140.337463) (xy 67.707683 -140.389747) (xy 67.713727 -140.443469) (xy 67.711942 -140.4975)
			(xy 67.702366 -140.550705) (xy 67.6852 -140.601968) (xy 67.660804 -140.650211) (xy 67.629691 -140.694421)
			(xy 67.592514 -140.733669) (xy 67.550054 -140.767132) (xy 67.503204 -140.794105) (xy 67.452947 -140.814024)
			(xy 67.400338 -140.826468) (xy 67.346483 -140.831178) (xy 67.292513 -140.828053) (xy 67.239561 -140.817161)
			(xy 67.18874 -140.798728) (xy 67.141117 -140.773143) (xy 67.097692 -140.740943) (xy 67.059378 -140.702805)
			(xy 67.042792 -140.681456) (xy 67.032268 -140.668239) (xy 67.005669 -140.647428) (xy 66.974541 -140.634327)
			(xy 66.941065 -140.629856) (xy 66.907589 -140.634327) (xy 66.876461 -140.647428) (xy 66.849862 -140.668239)
			(xy 66.839338 -140.681456) (xy 66.829432 -140.694156) (xy 66.815731 -140.711569) (xy 66.794058 -140.750211)
			(xy 66.779416 -140.792027) (xy 66.772248 -140.835748) (xy 66.772772 -140.880051) (xy 66.780973 -140.92359)
			(xy 66.7966 -140.965048) (xy 66.819182 -141.003167) (xy 66.833242 -141.020292) (xy 66.850651 -141.041291)
			(xy 66.879739 -141.087434) (xy 66.901788 -141.137326) (xy 66.916327 -141.189899) (xy 66.923046 -141.24403)
			(xy 66.9218 -141.298562) (xy 66.912617 -141.35233) (xy 66.895693 -141.404185) (xy 66.87139 -141.453018)
			(xy 66.840226 -141.497785) (xy 66.802868 -141.537531) (xy 66.760114 -141.571405) (xy 66.712879 -141.598684)
			(xy 66.662171 -141.618784) (xy 66.609074 -141.631276) (xy 66.554723 -141.635893) (xy 66.50028 -141.632537)
			(xy 66.446908 -141.621278) (xy 66.395748 -141.602358) (xy 66.347893 -141.576182) (xy 66.304366 -141.543307)
			(xy 66.266097 -141.504438) (xy 66.233904 -141.460405) (xy 66.208476 -141.412148) (xy 66.190354 -141.3607)
			(xy 66.179928 -141.307159) (xy 66.177419 -141.25267) (xy 66.182882 -141.198398) (xy 66.196199 -141.145502)
			(xy 66.217086 -141.095113) (xy 66.245096 -141.048308) (xy 66.261996 -141.026896) (xy 66.275644 -141.009445)
			(xy 66.297318 -140.97081) (xy 66.311964 -140.929003) (xy 66.319136 -140.885288) (xy 66.318619 -140.840993)
			(xy 66.310428 -140.797458) (xy 66.29481 -140.756004) (xy 66.27224 -140.717886) (xy 66.258186 -140.70076)
			(xy 66.241516 -140.680659) (xy 66.213394 -140.636657) (xy 66.191689 -140.58916) (xy 66.176829 -140.539099)
			(xy 66.169102 -140.487453) (xy 66.168661 -140.435234) (xy 66.175514 -140.383465) (xy 66.189528 -140.333159)
			(xy 66.210427 -140.285303) (xy 66.237802 -140.240832) (xy 66.254122 -140.220446) (xy 66.267792 -140.203225)
			(xy 66.289593 -140.165047) (xy 66.304498 -140.123686) (xy 66.312063 -140.080378) (xy 66.312063 -140.036413)
			(xy 66.304496 -139.993105) (xy 66.289589 -139.951745) (xy 66.267787 -139.913567) (xy 66.254122 -139.896342)
			(xy 66.236966 -139.874773) (xy 66.208398 -139.827649) (xy 66.187082 -139.776831) (xy 66.173483 -139.723427)
			(xy 66.167898 -139.668603) (xy 63.713053 -139.668603) (xy 63.712882 -139.688099) (xy 63.704773 -139.740958)
			(xy 63.68919 -139.792115) (xy 63.666453 -139.840518) (xy 63.63703 -139.885174) (xy 63.619634 -139.905486)
			(xy 63.606741 -139.922613) (xy 63.586289 -139.960284) (xy 63.572452 -140.000854) (xy 63.565623 -140.043172)
			(xy 63.565995 -140.086035) (xy 63.573559 -140.128228) (xy 63.588099 -140.168551) (xy 63.609203 -140.205861)
			(xy 63.622428 -140.222732) (xy 63.639993 -140.245177) (xy 63.66881 -140.294345) (xy 63.689804 -140.347328)
			(xy 63.702486 -140.40289) (xy 63.706558 -140.459735) (xy 63.701927 -140.516538) (xy 63.688699 -140.571972)
			(xy 63.667185 -140.624746) (xy 63.637885 -140.673629) (xy 63.620142 -140.695934) (xy 63.606474 -140.713158)
			(xy 63.584664 -140.751335) (xy 63.569752 -140.792695) (xy 63.562182 -140.836006) (xy 63.562181 -140.879973)
			(xy 63.569747 -140.923284) (xy 63.584655 -140.964646) (xy 63.606461 -141.002824) (xy 63.620142 -141.020038)
			(xy 63.635232 -141.038772) (xy 63.660967 -141.079413) (xy 63.67145 -141.101064) (xy 63.68282 -141.126768)
			(xy 63.698563 -141.180721) (xy 63.706026 -141.236427) (xy 63.705041 -141.292622) (xy 63.695629 -141.348031)
			(xy 63.678005 -141.4014) (xy 63.652566 -141.451517) (xy 63.619891 -141.497246) (xy 63.58072 -141.537551)
			(xy 63.535942 -141.571517) (xy 63.486571 -141.598374) (xy 63.433727 -141.617514) (xy 63.406274 -141.623542)
			(xy 63.381003 -141.62815) (xy 63.329725 -141.631187) (xy 63.278516 -141.627138) (xy 63.228352 -141.616082)
			(xy 63.180187 -141.598228) (xy 63.157354 -141.586458) (xy 63.140027 -141.576901) (xy 63.107316 -141.554629)
			(xy 63.092076 -141.542008) (xy 63.074029 -141.528753) (xy 63.034286 -141.508136) (xy 62.991547 -141.494794)
			(xy 62.947132 -141.489141) (xy 62.902414 -141.491351) (xy 62.858773 -141.501356) (xy 62.817558 -141.518847)
			(xy 62.780042 -141.543284) (xy 62.7634 -141.558264) (xy 62.74181 -141.60119) (xy 62.735498 -141.614591)
			(xy 62.728642 -141.643403) (xy 62.728645 -141.67302) (xy 62.735506 -141.701831) (xy 62.74181 -141.715236)
			(xy 62.7634 -141.757908) (xy 62.782958 -141.774672) (xy 62.80273 -141.792154) (xy 62.837634 -141.831741)
			(xy 62.866603 -141.875856) (xy 62.889058 -141.923617) (xy 62.90455 -141.974069) (xy 62.91277 -142.026202)
			(xy 62.913543 -142.078438) (xy 63.801256 -142.078438) (xy 63.803397 -142.025266) (xy 63.813627 -141.973045)
			(xy 63.831708 -141.922996) (xy 63.857214 -141.876292) (xy 63.889549 -141.834029) (xy 63.927955 -141.797195)
			(xy 63.971533 -141.766653) (xy 64.019261 -141.74312) (xy 64.070021 -141.727146) (xy 64.122624 -141.719105)
			(xy 64.175839 -141.719187) (xy 64.228417 -141.727389) (xy 64.279128 -141.743518) (xy 64.326784 -141.767198)
			(xy 64.370268 -141.797873) (xy 64.40856 -141.834824) (xy 64.425068 -141.855698) (xy 64.434596 -141.867443)
			(xy 64.458014 -141.886562) (xy 64.485273 -141.899633) (xy 64.514843 -141.90592) (xy 64.545063 -141.905072)
			(xy 64.574233 -141.897136) (xy 64.600717 -141.882557) (xy 64.623025 -141.862154) (xy 64.631824 -141.849856)
			(xy 64.654176 -141.819884) (xy 64.66787 -141.802652) (xy 64.689731 -141.764455) (xy 64.704679 -141.723061)
			(xy 64.712268 -141.679709) (xy 64.712268 -141.635699) (xy 64.704681 -141.592347) (xy 64.689734 -141.550952)
			(xy 64.667874 -141.512754) (xy 64.654176 -141.495526) (xy 64.636267 -141.473136) (xy 64.606868 -141.423913)
			(xy 64.585359 -141.370766) (xy 64.572248 -141.314951) (xy 64.567844 -141.257786) (xy 64.572252 -141.200622)
			(xy 64.585367 -141.144808) (xy 64.60688 -141.091662) (xy 64.636283 -141.042442) (xy 64.654176 -141.020038)
			(xy 64.667914 -141.00284) (xy 64.689773 -140.964635) (xy 64.704717 -140.923234) (xy 64.7123 -140.879876)
			(xy 64.712295 -140.835861) (xy 64.704701 -140.792505) (xy 64.689746 -140.751108) (xy 64.667878 -140.712908)
			(xy 64.654176 -140.69568) (xy 64.637194 -140.67442) (xy 64.608931 -140.627927) (xy 64.587733 -140.577817)
			(xy 64.57405 -140.525156) (xy 64.568174 -140.471065) (xy 64.57023 -140.416694) (xy 64.580174 -140.363201)
			(xy 64.597795 -140.311724) (xy 64.622717 -140.263358) (xy 64.65441 -140.219132) (xy 64.6922 -140.179987)
			(xy 64.735283 -140.146757) (xy 64.782742 -140.120148) (xy 64.833567 -140.100726) (xy 64.886677 -140.088905)
			(xy 64.940942 -140.084937) (xy 64.995207 -140.088905) (xy 65.048317 -140.100726) (xy 65.099142 -140.120148)
			(xy 65.146601 -140.146757) (xy 65.189684 -140.179987) (xy 65.227474 -140.219132) (xy 65.259167 -140.263358)
			(xy 65.284089 -140.311724) (xy 65.30171 -140.363201) (xy 65.311654 -140.416694) (xy 65.31371 -140.471065)
			(xy 65.307834 -140.525156) (xy 65.294151 -140.577817) (xy 65.272953 -140.627927) (xy 65.24469 -140.67442)
			(xy 65.227708 -140.69568) (xy 65.214078 -140.712951) (xy 65.192267 -140.751154) (xy 65.177353 -140.792539)
			(xy 65.16978 -140.835873) (xy 65.169775 -140.879864) (xy 65.177337 -140.9232) (xy 65.192241 -140.964589)
			(xy 65.214042 -141.002797) (xy 65.227708 -141.020038) (xy 65.245579 -141.042456) (xy 65.274973 -141.091676)
			(xy 65.29648 -141.144818) (xy 65.309591 -141.200627) (xy 65.313998 -141.257786) (xy 65.309595 -141.314946)
			(xy 65.296488 -141.370756) (xy 65.274985 -141.423899) (xy 65.245595 -141.473121) (xy 65.227708 -141.495526)
			(xy 65.214034 -141.512764) (xy 65.192226 -141.550974) (xy 65.177316 -141.592366) (xy 65.169748 -141.635706)
			(xy 65.169749 -141.679702) (xy 65.177318 -141.723041) (xy 65.192229 -141.764433) (xy 65.214038 -141.802643)
			(xy 65.227708 -141.819884) (xy 65.245623 -141.842268) (xy 65.275015 -141.891495) (xy 65.296518 -141.944643)
			(xy 65.309626 -142.000458) (xy 65.314027 -142.057622) (xy 65.313092 -142.069752) (xy 67.76803 -142.069752)
			(xy 67.770492 -142.015992) (xy 67.78066 -141.963145) (xy 67.798323 -141.91231) (xy 67.823115 -141.864544)
			(xy 67.854518 -141.820841) (xy 67.891881 -141.782108) (xy 67.934426 -141.749152) (xy 67.981269 -141.722657)
			(xy 68.031435 -141.703176) (xy 68.083882 -141.691112) (xy 68.137519 -141.686717) (xy 68.19123 -141.690082)
			(xy 68.243898 -141.701137) (xy 68.294429 -141.719652) (xy 68.341772 -141.745243) (xy 68.384942 -141.777376)
			(xy 68.423041 -141.815385) (xy 68.439538 -141.836648) (xy 68.450053 -141.84984) (xy 68.476623 -141.870611)
			(xy 68.50771 -141.883685) (xy 68.541138 -141.888147) (xy 68.574566 -141.883685) (xy 68.605653 -141.870611)
			(xy 68.632223 -141.84984) (xy 68.642738 -141.836648) (xy 68.654676 -141.821662) (xy 68.668397 -141.804398)
			(xy 68.690345 -141.766156) (xy 68.705356 -141.724697) (xy 68.712978 -141.681269) (xy 68.712982 -141.637176)
			(xy 68.705368 -141.593746) (xy 68.690364 -141.552284) (xy 68.668422 -141.514039) (xy 68.654676 -141.496796)
			(xy 68.637928 -141.476099) (xy 68.610007 -141.430765) (xy 68.588824 -141.381917) (xy 68.574811 -141.330551)
			(xy 68.568253 -141.277713) (xy 68.569284 -141.22448) (xy 68.577882 -141.171935) (xy 68.593873 -141.12115)
			(xy 68.616931 -141.073159) (xy 68.646586 -141.028939) (xy 68.664074 -141.008862) (xy 68.678876 -140.991834)
			(xy 68.702729 -140.953541) (xy 68.719443 -140.911636) (xy 68.728493 -140.867438) (xy 68.729595 -140.822337)
			(xy 68.722713 -140.77775) (xy 68.708064 -140.735079) (xy 68.686109 -140.695667) (xy 68.672202 -140.6779)
			(xy 68.655525 -140.656804) (xy 68.628313 -140.610423) (xy 68.608578 -140.560399) (xy 68.596794 -140.507931)
			(xy 68.593241 -140.454274) (xy 68.598004 -140.40071) (xy 68.610971 -140.348521) (xy 68.631831 -140.298956)
			(xy 68.660083 -140.253201) (xy 68.695054 -140.21235) (xy 68.735906 -140.17738) (xy 68.781662 -140.149128)
			(xy 68.831227 -140.128269) (xy 68.883416 -140.115303) (xy 68.93698 -140.110541) (xy 68.990637 -140.114094)
			(xy 69.043105 -140.12588) (xy 69.093128 -140.145616) (xy 69.139509 -140.172829) (xy 69.160644 -140.189458)
			(xy 69.178418 -140.203349) (xy 69.21783 -140.225282) (xy 69.260496 -140.239914) (xy 69.305075 -140.246785)
			(xy 69.350166 -140.245678) (xy 69.394354 -140.236629) (xy 69.43625 -140.219922) (xy 69.474539 -140.196081)
			(xy 69.491606 -140.18133) (xy 69.511703 -140.163875) (xy 69.555925 -140.134247) (xy 69.603912 -140.111212)
			(xy 69.654688 -140.095239) (xy 69.707221 -140.086652) (xy 69.76044 -140.085627) (xy 69.813264 -140.092184)
			(xy 69.864618 -140.10619) (xy 69.913457 -140.12736) (xy 69.958787 -140.155262) (xy 69.97954 -140.171932)
			(xy 69.996789 -140.185658) (xy 70.03501 -140.207614) (xy 70.076443 -140.222652) (xy 70.119848 -140.230322)
			(xy 70.163926 -140.230393) (xy 70.207356 -140.222865) (xy 70.248838 -140.207962) (xy 70.287129 -140.186131)
			(xy 70.304406 -140.17244) (xy 70.325882 -140.155339) (xy 70.372823 -140.12688) (xy 70.423434 -140.105619)
			(xy 70.476616 -140.092016) (xy 70.531219 -140.086367) (xy 70.586061 -140.088793) (xy 70.639952 -140.099242)
			(xy 70.691725 -140.117488) (xy 70.740261 -140.143135) (xy 70.784506 -140.175628) (xy 70.823502 -140.214263)
			(xy 70.840346 -140.23594) (xy 70.850896 -140.249113) (xy 70.877515 -140.269842) (xy 70.90863 -140.282887)
			(xy 70.942073 -140.287338) (xy 70.975516 -140.282887) (xy 71.006631 -140.269842) (xy 71.03325 -140.249113)
			(xy 71.0438 -140.23594) (xy 71.064882 -140.210032) (xy 71.079608 -140.19297) (xy 71.103386 -140.154688)
			(xy 71.120038 -140.112811) (xy 71.129041 -140.068653) (xy 71.130113 -140.0236) (xy 71.123219 -139.979064)
			(xy 71.108577 -139.936443) (xy 71.086646 -139.897074) (xy 71.072756 -139.879324) (xy 71.056262 -139.858284)
			(xy 71.029178 -139.812195) (xy 71.009478 -139.7625) (xy 70.99763 -139.710371) (xy 70.993913 -139.657043)
			(xy 70.998414 -139.603775) (xy 71.011028 -139.551827) (xy 71.031456 -139.502426) (xy 71.059215 -139.456741)
			(xy 71.09365 -139.415851) (xy 71.133945 -139.380723) (xy 71.17915 -139.352187) (xy 71.228194 -139.330917)
			(xy 71.279919 -139.317418) (xy 71.333103 -139.312007) (xy 71.386487 -139.314813) (xy 71.43881 -139.325769)
			(xy 71.488835 -139.344616) (xy 71.53538 -139.370909) (xy 71.577344 -139.404026) (xy 71.613735 -139.443185)
			(xy 71.643694 -139.487459) (xy 71.666511 -139.535803) (xy 71.681648 -139.587073) (xy 71.688747 -139.640057)
			(xy 71.688342 -139.659614) (xy 73.394059 -139.659614) (xy 73.398134 -139.606533) (xy 73.410264 -139.554697)
			(xy 73.430165 -139.50532) (xy 73.45737 -139.459559) (xy 73.491242 -139.418487) (xy 73.530986 -139.383068)
			(xy 73.575671 -139.35413) (xy 73.62425 -139.332352) (xy 73.675583 -139.318246) (xy 73.728469 -139.31214)
			(xy 73.781667 -139.314179) (xy 73.83393 -139.324315) (xy 73.884033 -139.34231) (xy 73.930802 -139.367742)
			(xy 73.973141 -139.400016) (xy 74.010057 -139.438374) (xy 74.040685 -139.481918) (xy 74.064307 -139.529627)
			(xy 74.08037 -139.580383) (xy 74.088497 -139.632996) (xy 74.089006 -139.659614) (xy 74.088497 -139.686232)
			(xy 74.08037 -139.738845) (xy 74.064307 -139.789601) (xy 74.040685 -139.83731) (xy 74.010057 -139.880854)
			(xy 73.973141 -139.919212) (xy 73.930802 -139.951486) (xy 73.884033 -139.976918) (xy 73.83393 -139.994913)
			(xy 73.781667 -140.005049) (xy 73.728469 -140.007088) (xy 73.675583 -140.000982) (xy 73.62425 -139.986876)
			(xy 73.575671 -139.965098) (xy 73.530986 -139.93616) (xy 73.491242 -139.900741) (xy 73.45737 -139.859669)
			(xy 73.430165 -139.813908) (xy 73.410264 -139.764531) (xy 73.398134 -139.712695) (xy 73.394059 -139.659614)
			(xy 71.688342 -139.659614) (xy 71.68764 -139.693503) (xy 71.678353 -139.746148) (xy 71.661105 -139.796747)
			(xy 71.636305 -139.844104) (xy 71.604539 -139.8871) (xy 71.566557 -139.924718) (xy 71.545196 -139.940792)
			(xy 71.533009 -139.950082) (xy 71.513167 -139.973427) (xy 71.499469 -140.000833) (xy 71.492707 -140.030716)
			(xy 71.493272 -140.061348) (xy 71.501131 -140.090962) (xy 71.515829 -140.117844) (xy 71.536518 -140.140442)
			(xy 71.549006 -140.149326) (xy 71.557011 -140.15475) (xy 71.572513 -140.166313) (xy 71.579994 -140.17244)
			(xy 71.597218 -140.186106) (xy 71.635395 -140.207911) (xy 71.676755 -140.222819) (xy 71.720064 -140.230387)
			(xy 71.764028 -140.230387) (xy 71.807337 -140.222819) (xy 71.848697 -140.207911) (xy 71.886874 -140.186106)
			(xy 71.904098 -140.17244) (xy 71.926521 -140.154518) (xy 71.975789 -140.125066) (xy 72.02899 -140.103517)
			(xy 72.084866 -140.090381) (xy 72.142096 -140.085967) (xy 72.199326 -140.090381) (xy 72.255202 -140.103517)
			(xy 72.308403 -140.125066) (xy 72.357671 -140.154518) (xy 72.380094 -140.17244) (xy 72.397318 -140.186106)
			(xy 72.435495 -140.207911) (xy 72.476855 -140.222819) (xy 72.520164 -140.230387) (xy 72.564128 -140.230387)
			(xy 72.607437 -140.222819) (xy 72.648797 -140.207911) (xy 72.686974 -140.186106) (xy 72.704198 -140.17244)
			(xy 72.725284 -140.155488) (xy 72.771476 -140.127316) (xy 72.821256 -140.106119) (xy 72.873577 -140.092342)
			(xy 72.927341 -140.086275) (xy 72.981417 -140.088045) (xy 73.034669 -140.097616) (xy 73.085977 -140.114785)
			(xy 73.134264 -140.139192) (xy 73.178515 -140.170325) (xy 73.217799 -140.207528) (xy 73.251292 -140.25002)
			(xy 73.278288 -140.296909) (xy 73.298222 -140.347208) (xy 73.310673 -140.39986) (xy 73.315381 -140.45376)
			(xy 73.312246 -140.507774) (xy 73.301335 -140.560767) (xy 73.282876 -140.611626) (xy 73.257257 -140.659281)
			(xy 73.225018 -140.702732) (xy 73.186835 -140.741065) (xy 73.165462 -140.757656) (xy 73.152313 -140.768222)
			(xy 73.131542 -140.794779) (xy 73.118464 -140.825855) (xy 73.113996 -140.859274) (xy 73.117579 -140.886159)
			(xy 74.586328 -140.886159) (xy 74.586328 -140.832861) (xy 74.594271 -140.780157) (xy 74.609981 -140.729227)
			(xy 74.633107 -140.681206) (xy 74.663131 -140.637169) (xy 74.699383 -140.598098) (xy 74.741054 -140.564867)
			(xy 74.787212 -140.538218) (xy 74.836826 -140.518746) (xy 74.888788 -140.506886) (xy 74.941938 -140.502903)
			(xy 74.995088 -140.506886) (xy 75.04705 -140.518746) (xy 75.096664 -140.538218) (xy 75.142822 -140.564867)
			(xy 75.184493 -140.598098) (xy 75.220745 -140.637169) (xy 75.231211 -140.65252) (xy 79.139141 -140.65252)
			(xy 79.143252 -140.597889) (xy 79.155135 -140.544407) (xy 79.174545 -140.493174) (xy 79.201082 -140.445244)
			(xy 79.217266 -140.423138) (xy 79.230621 -140.404693) (xy 79.25126 -140.364109) (xy 79.264331 -140.320494)
			(xy 79.269413 -140.275247) (xy 79.266345 -140.229819) (xy 79.255224 -140.185667) (xy 79.236407 -140.144205)
			(xy 79.22387 -140.125196) (xy 79.208402 -140.101904) (xy 79.183697 -140.051746) (xy 79.166579 -139.998519)
			(xy 79.157415 -139.943363) (xy 79.1564 -139.88746) (xy 79.163558 -139.832008) (xy 79.178733 -139.778194)
			(xy 79.201602 -139.727173) (xy 79.231674 -139.680037) (xy 79.268305 -139.637795) (xy 79.31071 -139.601354)
			(xy 79.357981 -139.571493) (xy 79.409104 -139.548853) (xy 79.462985 -139.533919) (xy 79.518469 -139.52701)
			(xy 79.574366 -139.528275) (xy 79.629481 -139.537686) (xy 79.682631 -139.555042) (xy 79.732678 -139.579971)
			(xy 79.778549 -139.611939) (xy 79.819263 -139.650261) (xy 79.853946 -139.694116) (xy 79.881855 -139.742565)
			(xy 79.902393 -139.794568) (xy 79.915119 -139.849013) (xy 79.919761 -139.904732) (xy 79.916219 -139.960532)
			(xy 79.90457 -140.015217) (xy 79.885062 -140.067615) (xy 79.858114 -140.116605) (xy 79.841598 -140.139166)
			(xy 79.828241 -140.157608) (xy 79.807604 -140.198194) (xy 79.794536 -140.24181) (xy 79.789455 -140.287056)
			(xy 79.792523 -140.332484) (xy 79.803643 -140.376636) (xy 79.822458 -140.418098) (xy 79.834994 -140.437108)
			(xy 79.851023 -140.461268) (xy 79.876384 -140.513404) (xy 79.893561 -140.568778) (xy 79.902157 -140.626114)
			(xy 79.901974 -140.684091) (xy 79.893016 -140.741372) (xy 79.87549 -140.796636) (xy 79.8498 -140.84861)
			(xy 79.816537 -140.896097) (xy 79.796894 -140.917422) (xy 79.785908 -140.929661) (xy 79.769986 -140.958423)
			(xy 79.761944 -140.990299) (xy 79.762317 -141.023172) (xy 79.77108 -141.054857) (xy 79.787651 -141.08325)
			(xy 79.798926 -141.095222) (xy 79.81728 -141.114216) (xy 79.849174 -141.156314) (xy 79.874955 -141.20241)
			(xy 79.894128 -141.251623) (xy 79.906327 -141.303011) (xy 79.911318 -141.355591) (xy 79.909006 -141.408356)
			(xy 79.899435 -141.460297) (xy 79.882789 -141.510421) (xy 79.859386 -141.557769) (xy 79.8449 -141.579854)
			(xy 79.832001 -141.599755) (xy 79.812985 -141.643191) (xy 79.802364 -141.689404) (xy 79.800509 -141.736784)
			(xy 79.807483 -141.783685) (xy 79.823044 -141.828476) (xy 79.846651 -141.869599) (xy 79.861664 -141.887956)
			(xy 79.879047 -141.909106) (xy 79.908312 -141.955371) (xy 79.930661 -142.005345) (xy 79.945638 -142.058)
			(xy 79.952933 -142.112255) (xy 79.952398 -142.166997) (xy 79.944043 -142.221099) (xy 79.928039 -142.273451)
			(xy 79.904716 -142.322978) (xy 79.874553 -142.368662) (xy 79.838168 -142.409565) (xy 79.796311 -142.444847)
			(xy 79.749839 -142.473782) (xy 79.699708 -142.495778) (xy 79.646948 -142.510381) (xy 79.592643 -142.517291)
			(xy 79.537907 -142.516368) (xy 79.483865 -142.50763) (xy 79.431627 -142.491256) (xy 79.382267 -142.467582)
			(xy 79.336798 -142.437096) (xy 79.296154 -142.400423) (xy 79.26117 -142.358316) (xy 79.232564 -142.311641)
			(xy 79.210924 -142.261355) (xy 79.196696 -142.208493) (xy 79.19017 -142.15414) (xy 79.191481 -142.099412)
			(xy 79.200602 -142.045433) (xy 79.217346 -141.993313) (xy 79.241368 -141.944122) (xy 79.256382 -141.92123)
			(xy 79.269288 -141.901335) (xy 79.288296 -141.857895) (xy 79.298911 -141.811683) (xy 79.300763 -141.764303)
			(xy 79.293789 -141.717402) (xy 79.27823 -141.672612) (xy 79.254628 -141.631487) (xy 79.239618 -141.613128)
			(xy 79.221742 -141.591496) (xy 79.191912 -141.543965) (xy 79.169363 -141.492578) (xy 79.154581 -141.438443)
			(xy 79.147885 -141.382728) (xy 79.149419 -141.326632) (xy 79.15915 -141.271366) (xy 79.176868 -141.21812)
			(xy 79.202192 -141.168042) (xy 79.234575 -141.122212) (xy 79.253588 -141.101572) (xy 79.264572 -141.089334)
			(xy 79.280484 -141.06057) (xy 79.28852 -141.028695) (xy 79.288146 -140.995826) (xy 79.279387 -140.964142)
			(xy 79.262825 -140.935747) (xy 79.251556 -140.923772) (xy 79.23252 -140.904068) (xy 79.199692 -140.860206)
			(xy 79.173476 -140.8121) (xy 79.15441 -140.760738) (xy 79.142886 -140.707178) (xy 79.139141 -140.65252)
			(xy 75.231211 -140.65252) (xy 75.250769 -140.681206) (xy 75.273895 -140.729227) (xy 75.289605 -140.780157)
			(xy 75.297548 -140.832861) (xy 75.298046 -140.85951) (xy 75.297548 -140.886159) (xy 75.289605 -140.938863)
			(xy 75.273895 -140.989793) (xy 75.250769 -141.037814) (xy 75.220745 -141.081851) (xy 75.184493 -141.120922)
			(xy 75.142822 -141.154153) (xy 75.096664 -141.180802) (xy 75.04705 -141.200274) (xy 74.995088 -141.212134)
			(xy 74.941938 -141.216118) (xy 74.888788 -141.212134) (xy 74.836826 -141.200274) (xy 74.787212 -141.180802)
			(xy 74.741054 -141.154153) (xy 74.699383 -141.120922) (xy 74.663131 -141.081851) (xy 74.633107 -141.037814)
			(xy 74.609981 -140.989793) (xy 74.594271 -140.938863) (xy 74.586328 -140.886159) (xy 73.117579 -140.886159)
			(xy 73.11845 -140.892694) (xy 73.131515 -140.923775) (xy 73.152275 -140.950341) (xy 73.165462 -140.960856)
			(xy 73.180194 -140.97254) (xy 73.197418 -140.986206) (xy 73.235595 -141.008011) (xy 73.276955 -141.022919)
			(xy 73.320264 -141.030487) (xy 73.364228 -141.030487) (xy 73.407537 -141.022919) (xy 73.448897 -141.008011)
			(xy 73.487074 -140.986206) (xy 73.504298 -140.97254) (xy 73.525401 -140.955617) (xy 73.57159 -140.927461)
			(xy 73.621364 -140.906279) (xy 73.673677 -140.892517) (xy 73.727431 -140.886464) (xy 73.781496 -140.888246)
			(xy 73.834734 -140.897827) (xy 73.886028 -140.915006) (xy 73.934298 -140.93942) (xy 73.978532 -140.970557)
			(xy 74.017798 -141.007763) (xy 74.051272 -141.050256) (xy 74.07825 -141.097142) (xy 74.098165 -141.147436)
			(xy 74.110599 -141.200081) (xy 74.115291 -141.253971) (xy 74.11214 -141.307973) (xy 74.101215 -141.360952)
			(xy 74.082744 -141.411794) (xy 74.057116 -141.459432) (xy 74.024869 -141.502863) (xy 73.986682 -141.541175)
			(xy 73.965308 -141.557756) (xy 73.952155 -141.568328) (xy 73.931432 -141.594944) (xy 73.918391 -141.626053)
			(xy 73.913939 -141.65949) (xy 73.918386 -141.692927) (xy 73.931422 -141.724038) (xy 73.952141 -141.750658)
			(xy 73.965308 -141.76121) (xy 73.98004 -141.77264) (xy 73.99728 -141.786321) (xy 74.035458 -141.808205)
			(xy 74.076837 -141.823183) (xy 74.120177 -141.830805) (xy 74.164183 -141.830843) (xy 74.207537 -141.823296)
			(xy 74.248941 -141.808391) (xy 74.287157 -141.786572) (xy 74.304398 -141.772894) (xy 74.32591 -141.755704)
			(xy 74.373016 -141.727191) (xy 74.423806 -141.705923) (xy 74.477173 -141.692364) (xy 74.531955 -141.686808)
			(xy 74.586959 -141.689377) (xy 74.640984 -141.700015) (xy 74.692856 -141.71849) (xy 74.741442 -141.7444)
			(xy 74.785685 -141.777179) (xy 74.824621 -141.816115) (xy 74.8574 -141.860358) (xy 74.88331 -141.908945)
			(xy 74.901785 -141.960816) (xy 74.912423 -142.014842) (xy 74.914992 -142.069845) (xy 74.909436 -142.124627)
			(xy 74.895877 -142.177995) (xy 74.874609 -142.228785) (xy 74.846095 -142.275891) (xy 74.828908 -142.297404)
			(xy 74.815255 -142.314658) (xy 74.793446 -142.352864) (xy 74.778534 -142.394253) (xy 74.770964 -142.43759)
			(xy 74.770961 -142.481584) (xy 74.778527 -142.524921) (xy 74.793435 -142.566312) (xy 74.81524 -142.604521)
			(xy 74.828908 -142.621762) (xy 74.840403 -142.636126) (xy 81.682652 -142.636126) (xy 81.684483 -142.581928)
			(xy 81.693966 -142.528534) (xy 81.71091 -142.47702) (xy 81.734974 -142.428423) (xy 81.765673 -142.38372)
			(xy 81.783682 -142.363444) (xy 81.793702 -142.351964) (xy 81.808404 -142.325281) (xy 81.816348 -142.29587)
			(xy 81.817081 -142.265414) (xy 81.810561 -142.235655) (xy 81.797159 -142.208296) (xy 81.787746 -142.196312)
			(xy 81.769652 -142.173618) (xy 81.739751 -142.123877) (xy 81.717722 -142.070183) (xy 81.704072 -142.013775)
			(xy 81.699116 -141.95595) (xy 81.702967 -141.898041) (xy 81.715538 -141.841382) (xy 81.736538 -141.787278)
			(xy 81.765484 -141.736975) (xy 81.783174 -141.713966) (xy 81.793415 -141.700207) (xy 81.806902 -141.668687)
			(xy 81.811512 -141.634714) (xy 81.80691 -141.60074) (xy 81.79343 -141.569217) (xy 81.783174 -141.55547)
			(xy 81.765724 -141.532796) (xy 81.737063 -141.48328) (xy 81.716118 -141.430038) (xy 81.70336 -141.374266)
			(xy 81.699074 -141.317214) (xy 81.703356 -141.260162) (xy 81.71611 -141.204388) (xy 81.737051 -141.151146)
			(xy 81.765708 -141.101627) (xy 81.783174 -141.078966) (xy 81.793415 -141.065207) (xy 81.806902 -141.033687)
			(xy 81.811512 -140.999714) (xy 81.80691 -140.96574) (xy 81.79343 -140.934217) (xy 81.783174 -140.92047)
			(xy 81.766293 -140.898573) (xy 81.738359 -140.850861) (xy 81.717605 -140.799617) (xy 81.704465 -140.745913)
			(xy 81.699216 -140.690875) (xy 81.701966 -140.635655) (xy 81.712659 -140.581411) (xy 81.73107 -140.529279)
			(xy 81.756813 -140.48035) (xy 81.789351 -140.43565) (xy 81.828 -140.396115) (xy 81.871951 -140.362573)
			(xy 81.920283 -140.335727) (xy 81.971985 -140.31614) (xy 82.025973 -140.304221) (xy 82.081116 -140.30022)
			(xy 82.136259 -140.304221) (xy 82.190247 -140.31614) (xy 82.241949 -140.335727) (xy 82.290281 -140.362573)
			(xy 82.334232 -140.396115) (xy 82.372881 -140.43565) (xy 82.405419 -140.48035) (xy 82.431162 -140.529279)
			(xy 82.449573 -140.581411) (xy 82.460266 -140.635655) (xy 82.463016 -140.690875) (xy 82.457767 -140.745913)
			(xy 82.444627 -140.799617) (xy 82.423873 -140.850861) (xy 82.395939 -140.898573) (xy 82.379058 -140.92047)
			(xy 82.368788 -140.934207) (xy 82.355312 -140.965736) (xy 82.350712 -140.999714) (xy 82.35532 -141.033691)
			(xy 82.368802 -141.065217) (xy 82.379058 -141.078966) (xy 82.396542 -141.101615) (xy 82.425198 -141.151137)
			(xy 82.446138 -141.204383) (xy 82.458892 -141.260159) (xy 82.463174 -141.317214) (xy 82.458888 -141.374269)
			(xy 82.44613 -141.430044) (xy 82.425186 -141.483288) (xy 82.396526 -141.532808) (xy 82.379058 -141.55547)
			(xy 82.368788 -141.569207) (xy 82.355312 -141.600736) (xy 82.350712 -141.634714) (xy 82.35532 -141.668691)
			(xy 82.368802 -141.700217) (xy 82.379058 -141.713966) (xy 82.395571 -141.735416) (xy 82.423052 -141.782051)
			(xy 82.443667 -141.832103) (xy 82.457 -141.884565) (xy 82.462785 -141.938386) (xy 82.460905 -141.992484)
			(xy 82.451398 -142.045773) (xy 82.434455 -142.097183) (xy 82.410416 -142.145683) (xy 82.379764 -142.190298)
			(xy 82.361786 -142.210536) (xy 82.351787 -142.222032) (xy 82.337087 -142.248711) (xy 82.329142 -142.278117)
			(xy 82.328405 -142.308569) (xy 82.33492 -142.338325) (xy 82.348313 -142.365683) (xy 82.357722 -142.377668)
			(xy 82.375003 -142.399258) (xy 82.403864 -142.446426) (xy 82.425609 -142.497268) (xy 82.439782 -142.550719)
			(xy 82.446086 -142.605656) (xy 82.444389 -142.660927) (xy 82.434725 -142.715374) (xy 82.417298 -142.767854)
			(xy 82.392473 -142.817266) (xy 82.377026 -142.840202) (xy 82.364095 -142.85966) (xy 82.344796 -142.902201)
			(xy 82.333593 -142.947552) (xy 82.330861 -142.994186) (xy 82.336693 -143.040534) (xy 82.350892 -143.085038)
			(xy 82.372981 -143.1262) (xy 82.387186 -143.144748) (xy 82.403842 -143.166327) (xy 82.431588 -143.213247)
			(xy 82.452372 -143.263638) (xy 82.465771 -143.316475) (xy 82.471512 -143.370681) (xy 82.469477 -143.425153)
			(xy 82.45971 -143.47878) (xy 82.442407 -143.53047) (xy 82.417923 -143.579171) (xy 82.386755 -143.62389)
			(xy 82.349538 -143.663717) (xy 82.307031 -143.69784) (xy 82.260099 -143.725565) (xy 82.209698 -143.746326)
			(xy 82.156855 -143.759701) (xy 82.102646 -143.765418) (xy 82.048176 -143.763359) (xy 81.994553 -143.753567)
			(xy 81.942871 -143.736241) (xy 81.894181 -143.711734) (xy 81.849476 -143.680546) (xy 81.809666 -143.643312)
			(xy 81.775562 -143.600789) (xy 81.747858 -143.553844) (xy 81.72712 -143.503434) (xy 81.713769 -143.450585)
			(xy 81.708077 -143.396374) (xy 81.71016 -143.341905) (xy 81.719976 -143.288286) (xy 81.737325 -143.236612)
			(xy 81.761854 -143.187933) (xy 81.777078 -143.165322) (xy 81.789986 -143.145849) (xy 81.809286 -143.103312)
			(xy 81.820493 -143.057965) (xy 81.823228 -143.011334) (xy 81.8174 -142.964988) (xy 81.803205 -142.920485)
			(xy 81.781121 -142.879324) (xy 81.766918 -142.860776) (xy 81.75028 -142.839362) (xy 81.722667 -142.792689)
			(xy 81.701938 -142.742578) (xy 81.68851 -142.690038) (xy 81.682652 -142.636126) (xy 74.840403 -142.636126)
			(xy 74.846831 -142.644158) (xy 74.876227 -142.693414) (xy 74.897733 -142.74659) (xy 74.910841 -142.802434)
			(xy 74.915243 -142.859625) (xy 74.910834 -142.916817) (xy 74.897718 -142.972658) (xy 74.876205 -143.025832)
			(xy 74.846802 -143.075084) (xy 74.828908 -143.097504) (xy 74.815285 -143.114761) (xy 74.793478 -143.15293)
			(xy 74.778567 -143.194284) (xy 74.770995 -143.237586) (xy 74.770989 -143.281546) (xy 74.778549 -143.324851)
			(xy 74.79345 -143.366208) (xy 74.815246 -143.404383) (xy 74.828908 -143.421608) (xy 74.846082 -143.44316)
			(xy 74.874641 -143.490286) (xy 74.89595 -143.541105) (xy 74.909542 -143.594507) (xy 74.915122 -143.649328)
			(xy 74.912568 -143.704374) (xy 74.901935 -143.758443) (xy 74.899686 -143.764762) (xy 79.345534 -143.764762)
			(xy 79.349605 -143.70914) (xy 79.361731 -143.654703) (xy 79.381654 -143.602612) (xy 79.40895 -143.553977)
			(xy 79.443036 -143.509834) (xy 79.483185 -143.471125) (xy 79.528543 -143.438674) (xy 79.578143 -143.413173)
			(xy 79.630927 -143.395166) (xy 79.68577 -143.385036) (xy 79.741504 -143.382999) (xy 79.796941 -143.389099)
			(xy 79.850898 -143.403205) (xy 79.902227 -143.425017) (xy 79.949833 -143.454071) (xy 79.992701 -143.489746)
			(xy 80.029918 -143.531283) (xy 80.060691 -143.577796) (xy 80.084363 -143.628293) (xy 80.100431 -143.6817)
			(xy 80.108551 -143.736876) (xy 80.10906 -143.764762) (xy 80.108551 -143.792648) (xy 80.100431 -143.847824)
			(xy 80.084363 -143.901231) (xy 80.060691 -143.951728) (xy 80.029918 -143.998241) (xy 79.992701 -144.039778)
			(xy 79.949833 -144.075453) (xy 79.902227 -144.104507) (xy 79.850898 -144.126319) (xy 79.796941 -144.140425)
			(xy 79.741504 -144.146525) (xy 79.68577 -144.144488) (xy 79.630927 -144.134358) (xy 79.578143 -144.116351)
			(xy 79.528543 -144.09085) (xy 79.483185 -144.058399) (xy 79.443036 -144.01969) (xy 79.40895 -143.975547)
			(xy 79.381654 -143.926912) (xy 79.361731 -143.874821) (xy 79.349605 -143.820384) (xy 79.345534 -143.764762)
			(xy 74.899686 -143.764762) (xy 74.883455 -143.810357) (xy 74.857532 -143.858983) (xy 74.82473 -143.903262)
			(xy 74.785765 -143.942227) (xy 74.741487 -143.975029) (xy 74.692861 -144.000953) (xy 74.640948 -144.019433)
			(xy 74.586879 -144.030067) (xy 74.531833 -144.032622) (xy 74.477011 -144.027043) (xy 74.423609 -144.013451)
			(xy 74.372791 -143.992144) (xy 74.325664 -143.963584) (xy 74.304144 -143.946372) (xy 74.28692 -143.932706)
			(xy 74.248743 -143.910901) (xy 74.207383 -143.895993) (xy 74.164074 -143.888425) (xy 74.12011 -143.888425)
			(xy 74.076801 -143.895993) (xy 74.035441 -143.910901) (xy 73.997264 -143.932706) (xy 73.98004 -143.946372)
			(xy 73.957617 -143.964294) (xy 73.908349 -143.993746) (xy 73.855148 -144.015295) (xy 73.799272 -144.028431)
			(xy 73.742042 -144.032845) (xy 73.684812 -144.028431) (xy 73.628936 -144.015295) (xy 73.575735 -143.993746)
			(xy 73.526467 -143.964294) (xy 73.504044 -143.946372) (xy 73.48682 -143.932706) (xy 73.448643 -143.910901)
			(xy 73.407283 -143.895993) (xy 73.363974 -143.888425) (xy 73.32001 -143.888425) (xy 73.276701 -143.895993)
			(xy 73.235341 -143.910901) (xy 73.197164 -143.932706) (xy 73.17994 -143.946372) (xy 73.157497 -143.964237)
			(xy 73.108237 -143.993622) (xy 73.055055 -144.015113) (xy 72.99921 -144.028203) (xy 72.942018 -144.032582)
			(xy 72.88483 -144.028147) (xy 72.828997 -144.015003) (xy 72.775837 -143.99346) (xy 72.726605 -143.964026)
			(xy 72.704198 -143.946118) (xy 72.686974 -143.932452) (xy 72.648797 -143.910647) (xy 72.607437 -143.895739)
			(xy 72.564128 -143.888171) (xy 72.520164 -143.888171) (xy 72.476855 -143.895739) (xy 72.435495 -143.910647)
			(xy 72.397318 -143.932452) (xy 72.380094 -143.946118) (xy 72.358958 -143.963003) (xy 72.312771 -143.991164)
			(xy 72.262999 -144.012353) (xy 72.210686 -144.026122) (xy 72.156931 -144.032184) (xy 72.102865 -144.030411)
			(xy 72.049624 -144.020839) (xy 71.998325 -144.003671) (xy 71.950048 -143.979267) (xy 71.905806 -143.948139)
			(xy 71.86653 -143.910942) (xy 71.833043 -143.868457) (xy 71.806051 -143.821578) (xy 71.786121 -143.771288)
			(xy 71.77367 -143.718645) (xy 71.768961 -143.664756) (xy 71.772092 -143.610751) (xy 71.782999 -143.557767)
			(xy 71.801451 -143.506916) (xy 71.827061 -143.459268) (xy 71.859291 -143.415822) (xy 71.897463 -143.377493)
			(xy 71.91883 -143.360902) (xy 71.932021 -143.350385) (xy 71.952794 -143.323817) (xy 71.96587 -143.29273)
			(xy 71.970333 -143.259301) (xy 71.96587 -143.225873) (xy 71.952795 -143.194786) (xy 71.932023 -143.168217)
			(xy 71.91883 -143.157702) (xy 71.904098 -143.146018) (xy 71.886874 -143.132352) (xy 71.848697 -143.110547)
			(xy 71.807337 -143.095639) (xy 71.764028 -143.088071) (xy 71.720064 -143.088071) (xy 71.676755 -143.095639)
			(xy 71.635395 -143.110547) (xy 71.597218 -143.132352) (xy 71.579994 -143.146018) (xy 71.558914 -143.162956)
			(xy 71.512742 -143.191108) (xy 71.462986 -143.21229) (xy 71.41069 -143.226057) (xy 71.356954 -143.23212)
			(xy 71.302905 -143.230351) (xy 71.24968 -143.220788) (xy 71.198396 -143.203632) (xy 71.150131 -143.179243)
			(xy 71.105898 -143.148132) (xy 71.066627 -143.110955) (xy 71.033143 -143.068491) (xy 71.006149 -143.021633)
			(xy 70.986211 -142.971365) (xy 70.97375 -142.918743) (xy 70.969026 -142.864872) (xy 70.972139 -142.810885)
			(xy 70.983023 -142.757914) (xy 71.00145 -142.707073) (xy 71.027033 -142.659429) (xy 71.059234 -142.615985)
			(xy 71.097377 -142.577651) (xy 71.11873 -142.561056) (xy 71.131919 -142.5505) (xy 71.152733 -142.523909)
			(xy 71.165837 -142.492787) (xy 71.170313 -142.459317) (xy 71.165847 -142.425846) (xy 71.152751 -142.394721)
			(xy 71.131944 -142.368125) (xy 71.11873 -142.357602) (xy 71.104252 -142.346172) (xy 71.087025 -142.332471)
			(xy 71.048827 -142.310606) (xy 71.007432 -142.295656) (xy 70.964079 -142.288066) (xy 70.920067 -142.288066)
			(xy 70.876714 -142.295656) (xy 70.835319 -142.310606) (xy 70.797121 -142.332471) (xy 70.779894 -142.346172)
			(xy 70.758791 -142.363104) (xy 70.712586 -142.391252) (xy 70.662795 -142.412421) (xy 70.610466 -142.426166)
			(xy 70.556699 -142.432197) (xy 70.502626 -142.430389) (xy 70.449382 -142.420778) (xy 70.398088 -142.403568)
			(xy 70.349823 -142.37912) (xy 70.305602 -142.347947) (xy 70.266354 -142.310707) (xy 70.232905 -142.268181)
			(xy 70.205959 -142.221265) (xy 70.186082 -142.170944) (xy 70.173692 -142.118278) (xy 70.16905 -142.064373)
			(xy 70.172253 -142.010364) (xy 70.183235 -141.957386) (xy 70.201763 -141.906554) (xy 70.227449 -141.858936)
			(xy 70.259753 -141.815533) (xy 70.297994 -141.77726) (xy 70.319392 -141.760702) (xy 70.332582 -141.750112)
			(xy 70.353427 -141.723495) (xy 70.366552 -141.692338) (xy 70.371037 -141.658829) (xy 70.366567 -141.625317)
			(xy 70.353456 -141.594155) (xy 70.332623 -141.567528) (xy 70.319392 -141.556994) (xy 70.292976 -141.535404)
			(xy 70.275899 -141.520666) (xy 70.237531 -141.496951) (xy 70.195579 -141.48038) (xy 70.151361 -141.471474)
			(xy 70.106266 -141.470511) (xy 70.061708 -141.477522) (xy 70.019087 -141.492287) (xy 69.979742 -141.514342)
			(xy 69.962014 -141.528292) (xy 69.941788 -141.54441) (xy 69.897411 -141.570973) (xy 69.849588 -141.590665)
			(xy 69.799373 -141.60305) (xy 69.747877 -141.607853) (xy 69.696238 -141.60497) (xy 69.645597 -141.594464)
			(xy 69.597074 -141.576566) (xy 69.551739 -141.551672) (xy 69.510596 -141.520333) (xy 69.474553 -141.483242)
			(xy 69.459094 -141.462506) (xy 69.449833 -141.450291) (xy 69.426546 -141.430369) (xy 69.399175 -141.416587)
			(xy 69.369303 -141.409742) (xy 69.338661 -141.410231) (xy 69.309023 -141.418026) (xy 69.282105 -141.432675)
			(xy 69.259466 -141.453331) (xy 69.25056 -141.465808) (xy 69.227446 -141.496542) (xy 69.213754 -141.513817)
			(xy 69.191863 -141.552072) (xy 69.176894 -141.593528) (xy 69.169294 -141.636943) (xy 69.169291 -141.681019)
			(xy 69.176884 -141.724435) (xy 69.191847 -141.765893) (xy 69.213732 -141.804151) (xy 69.227446 -141.821408)
			(xy 69.245388 -141.843791) (xy 69.274911 -141.892973) (xy 69.296548 -141.946099) (xy 69.309789 -142.001913)
			(xy 69.31432 -142.059096) (xy 69.310035 -142.116299) (xy 69.297035 -142.172169) (xy 69.275626 -142.225388)
			(xy 69.246316 -142.274697) (xy 69.228462 -142.29715) (xy 69.214864 -142.314394) (xy 69.193135 -142.35255)
			(xy 69.178279 -142.393869) (xy 69.170738 -142.437126) (xy 69.170734 -142.481035) (xy 69.178269 -142.524293)
			(xy 69.193119 -142.565615) (xy 69.214842 -142.603774) (xy 69.228462 -142.621) (xy 69.24626 -142.643426)
			(xy 69.275516 -142.692638) (xy 69.296901 -142.745746) (xy 69.309913 -142.801499) (xy 69.314244 -142.858586)
			(xy 69.309795 -142.915664) (xy 69.296668 -142.97139) (xy 69.275173 -143.024453) (xy 69.245816 -143.073604)
			(xy 69.227954 -143.09598) (xy 69.214327 -143.113252) (xy 69.19252 -143.151456) (xy 69.17761 -143.192841)
			(xy 69.170039 -143.236174) (xy 69.170033 -143.280163) (xy 69.177593 -143.323498) (xy 69.192494 -143.364886)
			(xy 69.214291 -143.403096) (xy 69.227954 -143.420338) (xy 69.244936 -143.441598) (xy 69.273199 -143.488091)
			(xy 69.294397 -143.538201) (xy 69.30808 -143.590862) (xy 69.313956 -143.644953) (xy 69.3119 -143.699324)
			(xy 69.301956 -143.752817) (xy 69.284335 -143.804294) (xy 69.259413 -143.85266) (xy 69.22772 -143.896886)
			(xy 69.18993 -143.936031) (xy 69.146847 -143.969261) (xy 69.099388 -143.99587) (xy 69.048563 -144.015292)
			(xy 68.995453 -144.027113) (xy 68.941188 -144.031081) (xy 68.886923 -144.027113) (xy 68.833813 -144.015292)
			(xy 68.782988 -143.99587) (xy 68.735529 -143.969261) (xy 68.692446 -143.936031) (xy 68.654656 -143.896886)
			(xy 68.622963 -143.85266) (xy 68.598041 -143.804294) (xy 68.58042 -143.752817) (xy 68.570476 -143.699324)
			(xy 68.56842 -143.644953) (xy 68.574296 -143.590862) (xy 68.587979 -143.538201) (xy 68.609177 -143.488091)
			(xy 68.63744 -143.441598) (xy 68.654422 -143.420338) (xy 68.668163 -143.403141) (xy 68.690026 -143.364937)
			(xy 68.704974 -143.323536) (xy 68.712558 -143.280177) (xy 68.712553 -143.23616) (xy 68.704957 -143.192803)
			(xy 68.689999 -143.151405) (xy 68.668127 -143.113207) (xy 68.654422 -143.09598) (xy 68.637273 -143.074589)
			(xy 68.608837 -143.027717) (xy 68.587577 -142.977182) (xy 68.573955 -142.924078) (xy 68.568265 -142.86955)
			(xy 68.570628 -142.814776) (xy 68.580995 -142.760941) (xy 68.599141 -142.709207) (xy 68.624674 -142.660692)
			(xy 68.657043 -142.616443) (xy 68.695548 -142.577417) (xy 68.71716 -142.560548) (xy 68.730334 -142.550058)
			(xy 68.751028 -142.523503) (xy 68.76405 -142.492457) (xy 68.768491 -142.459085) (xy 68.764042 -142.425714)
			(xy 68.751013 -142.394671) (xy 68.730312 -142.368121) (xy 68.71716 -142.357602) (xy 68.70319 -142.34668)
			(xy 68.685966 -142.333014) (xy 68.647789 -142.311209) (xy 68.606429 -142.296301) (xy 68.56312 -142.288733)
			(xy 68.519156 -142.288733) (xy 68.475847 -142.296301) (xy 68.434487 -142.311209) (xy 68.39631 -142.333014)
			(xy 68.379086 -142.34668) (xy 68.3581 -142.363527) (xy 68.312174 -142.391581) (xy 68.262691 -142.412737)
			(xy 68.210679 -142.426557) (xy 68.15722 -142.432752) (xy 68.103427 -142.431194) (xy 68.050416 -142.421915)
			(xy 67.999292 -142.405108) (xy 67.951116 -142.381123) (xy 67.90689 -142.350459) (xy 67.867535 -142.313752)
			(xy 67.833869 -142.271767) (xy 67.806591 -142.225376) (xy 67.786269 -142.175544) (xy 67.773326 -142.123307)
			(xy 67.76803 -142.069752) (xy 65.313092 -142.069752) (xy 65.309619 -142.114785) (xy 65.296505 -142.170599)
			(xy 65.274996 -142.223744) (xy 65.245598 -142.272967) (xy 65.227708 -142.295372) (xy 65.214086 -142.312649)
			(xy 65.192274 -142.35085) (xy 65.17736 -142.392235) (xy 65.169786 -142.435567) (xy 65.16978 -142.479557)
			(xy 65.17734 -142.522892) (xy 65.192243 -142.564281) (xy 65.214043 -142.602489) (xy 65.227708 -142.61973)
			(xy 65.245571 -142.642154) (xy 65.274966 -142.691373) (xy 65.296473 -142.744513) (xy 65.309585 -142.800322)
			(xy 65.313993 -142.857474) (xy 66.167772 -142.857474) (xy 66.171748 -142.803148) (xy 66.183591 -142.749979)
			(xy 66.20305 -142.699102) (xy 66.22971 -142.6516) (xy 66.263001 -142.608486) (xy 66.302215 -142.570679)
			(xy 66.346517 -142.538984) (xy 66.39496 -142.514078) (xy 66.446514 -142.49649) (xy 66.50008 -142.486596)
			(xy 66.554515 -142.484606) (xy 66.60866 -142.490564) (xy 66.66136 -142.504342) (xy 66.711493 -142.525646)
			(xy 66.757989 -142.554022) (xy 66.799859 -142.588866) (xy 66.836208 -142.629435) (xy 66.866264 -142.674864)
			(xy 66.889385 -142.724185) (xy 66.905078 -142.776347) (xy 66.913009 -142.830238) (xy 66.913506 -142.857474)
			(xy 66.913009 -142.88471) (xy 66.905078 -142.938601) (xy 66.889385 -142.990763) (xy 66.866264 -143.040084)
			(xy 66.836208 -143.085513) (xy 66.799859 -143.126082) (xy 66.757989 -143.160926) (xy 66.711493 -143.189302)
			(xy 66.66136 -143.210606) (xy 66.60866 -143.224384) (xy 66.554515 -143.230342) (xy 66.50008 -143.228352)
			(xy 66.446514 -143.218458) (xy 66.39496 -143.20087) (xy 66.346517 -143.175964) (xy 66.302215 -143.144269)
			(xy 66.263001 -143.106462) (xy 66.22971 -143.063348) (xy 66.20305 -143.015846) (xy 66.183591 -142.964969)
			(xy 66.171748 -142.9118) (xy 66.167772 -142.857474) (xy 65.313993 -142.857474) (xy 65.313993 -142.85748)
			(xy 65.309591 -142.914639) (xy 65.296485 -142.970448) (xy 65.274984 -143.023591) (xy 65.245594 -143.072813)
			(xy 65.227708 -143.095218) (xy 65.214042 -143.112461) (xy 65.192233 -143.15067) (xy 65.177322 -143.192061)
			(xy 65.169754 -143.2354) (xy 65.169753 -143.279395) (xy 65.177321 -143.322734) (xy 65.192231 -143.364125)
			(xy 65.214039 -143.402335) (xy 65.227708 -143.419576) (xy 65.24469 -143.440836) (xy 65.272953 -143.487329)
			(xy 65.294151 -143.537439) (xy 65.307834 -143.5901) (xy 65.31371 -143.644191) (xy 65.311654 -143.698562)
			(xy 65.30171 -143.752055) (xy 65.284089 -143.803532) (xy 65.259167 -143.851898) (xy 65.227474 -143.896124)
			(xy 65.189684 -143.935269) (xy 65.146601 -143.968499) (xy 65.099142 -143.995108) (xy 65.048317 -144.01453)
			(xy 64.995207 -144.026351) (xy 64.940942 -144.030319) (xy 64.886677 -144.026351) (xy 64.833567 -144.01453)
			(xy 64.782742 -143.995108) (xy 64.735283 -143.968499) (xy 64.6922 -143.935269) (xy 64.65441 -143.896124)
			(xy 64.622717 -143.851898) (xy 64.597795 -143.803532) (xy 64.580174 -143.752055) (xy 64.57023 -143.698562)
			(xy 64.568174 -143.644191) (xy 64.57405 -143.5901) (xy 64.587733 -143.537439) (xy 64.608931 -143.487329)
			(xy 64.637194 -143.440836) (xy 64.654176 -143.419576) (xy 64.667878 -143.40235) (xy 64.689738 -143.364151)
			(xy 64.704686 -143.322756) (xy 64.712273 -143.279403) (xy 64.712273 -143.235392) (xy 64.704685 -143.192039)
			(xy 64.689736 -143.150644) (xy 64.667875 -143.112446) (xy 64.654176 -143.095218) (xy 64.636985 -143.073811)
			(xy 64.608526 -143.026858) (xy 64.587267 -142.976237) (xy 64.573669 -142.923044) (xy 64.568025 -142.86843)
			(xy 64.57046 -142.81358) (xy 64.580919 -142.759681) (xy 64.599176 -142.707902) (xy 64.624836 -142.659363)
			(xy 64.657343 -142.615116) (xy 64.695992 -142.57612) (xy 64.717676 -142.559278) (xy 64.730939 -142.548809)
			(xy 64.751746 -142.522196) (xy 64.76484 -142.491056) (xy 64.769304 -142.457571) (xy 64.764824 -142.424087)
			(xy 64.751716 -142.392953) (xy 64.730897 -142.366349) (xy 64.717676 -142.355824) (xy 64.696594 -142.338806)
			(xy 64.679501 -142.324515) (xy 64.64127 -142.301638) (xy 64.599638 -142.285773) (xy 64.555879 -142.277404)
			(xy 64.51133 -142.276789) (xy 64.467356 -142.283945) (xy 64.425301 -142.298655) (xy 64.386454 -142.320468)
			(xy 64.368934 -142.334234) (xy 64.348007 -142.350675) (xy 64.302198 -142.377755) (xy 64.252792 -142.397526)
			(xy 64.200949 -142.409526) (xy 64.147881 -142.413473) (xy 64.094832 -142.409276) (xy 64.043045 -142.397031)
			(xy 63.993734 -142.377028) (xy 63.948053 -142.349733) (xy 63.907072 -142.315786) (xy 63.871752 -142.275983)
			(xy 63.84292 -142.231256) (xy 63.821252 -142.182653) (xy 63.807254 -142.131313) (xy 63.801256 -142.078438)
			(xy 62.913543 -142.078438) (xy 62.913551 -142.078973) (xy 62.90688 -142.131326) (xy 62.892889 -142.182214)
			(xy 62.871858 -142.23062) (xy 62.844208 -142.275574) (xy 62.827662 -142.296134) (xy 62.813993 -142.313358)
			(xy 62.792182 -142.351534) (xy 62.777268 -142.392895) (xy 62.769698 -142.436206) (xy 62.769696 -142.480173)
			(xy 62.777263 -142.523484) (xy 62.792173 -142.564847) (xy 62.81398 -142.603025) (xy 62.827662 -142.620238)
			(xy 62.845445 -142.642522) (xy 62.874742 -142.691428) (xy 62.896251 -142.744224) (xy 62.909473 -142.799679)
			(xy 62.914099 -142.856501) (xy 62.910021 -142.913364) (xy 62.897334 -142.968944) (xy 62.887352 -142.99565)
			(xy 62.873382 -143.030956) (xy 62.888876 -143.105378) (xy 63.722758 -143.93926) (xy 63.776098 -143.992854)
			(xy 63.98514 -144.201896) (xy 63.98514 -144.203928) (xy 64.29375 -144.512538)
		)
		(stroke
			(width 0)
			(type solid)
		)
		(fill yes)
		(layer "In7.Cu")
		(net "P3V3_NODE1")
	)
	(gr_poly
		(pts
			(xy 109.103668 -154.236166) (xy 109.118652 -154.235741) (xy 109.147791 -154.228732) (xy 109.174489 -154.215116)
			(xy 109.197272 -154.195646) (xy 109.214882 -154.171396) (xy 109.226347 -154.143707) (xy 109.229144 -154.128978)
			(xy 109.229144 -154.128724) (xy 109.23387 -154.101688) (xy 109.250062 -154.049248) (xy 109.2736 -153.999669)
			(xy 109.303998 -153.953973) (xy 109.340629 -153.913104) (xy 109.382738 -153.877905) (xy 109.429456 -153.849102)
			(xy 109.479818 -153.827289) (xy 109.532785 -153.812917) (xy 109.587266 -153.806281) (xy 109.642135 -153.80752)
			(xy 109.69626 -153.816607) (xy 109.748525 -153.833355) (xy 109.797852 -153.857418) (xy 109.843222 -153.888299)
			(xy 109.8837 -153.925363) (xy 109.91845 -153.967843) (xy 109.946755 -154.014864) (xy 109.968032 -154.065455)
			(xy 109.975396 -154.091894) (xy 109.975396 -154.092148) (xy 109.985556 -154.130756) (xy 110.108492 -154.236166)
			(xy 111.580676 -154.236166) (xy 111.606584 -154.223974) (xy 111.632266 -154.212339) (xy 111.686203 -154.195914)
			(xy 111.741969 -154.187612) (xy 111.798351 -154.187612) (xy 111.854117 -154.195914) (xy 111.908054 -154.212339)
			(xy 111.933736 -154.223974) (xy 111.959644 -154.236166) (xy 123.234958 -154.236166) (xy 123.947428 -153.523696)
			(xy 123.947428 -153.5176) (xy 123.953524 -153.5176) (xy 124.182632 -153.288492) (xy 124.182632 -153.032968)
			(xy 123.837192 -152.687782) (xy 123.837192 -152.213818) (xy 124.172218 -151.878792) (xy 124.646182 -151.878792)
			(xy 124.927868 -152.160732) (xy 125.310392 -152.160732) (xy 127.184658 -150.28672) (xy 127.200379 -150.270274)
			(xy 127.226294 -150.232886) (xy 127.245143 -150.191484) (xy 127.256325 -150.147388) (xy 127.259481 -150.102007)
			(xy 127.254512 -150.056788) (xy 127.241576 -150.013175) (xy 127.221086 -149.97256) (xy 127.193696 -149.936239)
			(xy 127.16028 -149.905371) (xy 127.121905 -149.880942) (xy 127.079795 -149.863731) (xy 127.057658 -149.858476)
			(xy 127.030685 -149.852255) (xy 126.978759 -149.833074) (xy 126.930149 -149.806594) (xy 126.885875 -149.77337)
			(xy 126.846864 -149.734098) (xy 126.813935 -149.689603) (xy 126.78778 -149.640818) (xy 126.768946 -149.588766)
			(xy 126.757829 -149.534539) (xy 126.754662 -149.479275) (xy 126.759512 -149.424134) (xy 126.772276 -149.370271)
			(xy 126.782068 -149.34438) (xy 126.789858 -149.32352) (xy 126.798834 -149.279909) (xy 126.800073 -149.235401)
			(xy 126.793537 -149.191359) (xy 126.779426 -149.149129) (xy 126.758172 -149.110005) (xy 126.730425 -149.075183)
			(xy 126.713996 -149.060154) (xy 126.693504 -149.04139) (xy 126.657632 -148.998962) (xy 126.628294 -148.951779)
			(xy 126.606111 -148.900839) (xy 126.591553 -148.84722) (xy 126.584926 -148.792056) (xy 126.586372 -148.736514)
			(xy 126.59586 -148.68177) (xy 126.613189 -148.628981) (xy 126.637992 -148.579264) (xy 126.669746 -148.533671)
			(xy 126.707777 -148.493167) (xy 126.751281 -148.458608) (xy 126.799339 -148.430726) (xy 126.850933 -148.41011)
			(xy 126.904972 -148.397196) (xy 126.960313 -148.392259) (xy 127.015784 -148.395401) (xy 127.070213 -148.406558)
			(xy 127.122448 -148.425492) (xy 127.171384 -148.451803) (xy 127.215985 -148.484934) (xy 127.255308 -148.524185)
			(xy 127.288521 -148.568726) (xy 127.314922 -148.617613) (xy 127.333952 -148.669813) (xy 127.345208 -148.724221)
			(xy 127.348452 -148.779687) (xy 127.343616 -148.835037) (xy 127.330801 -148.889099) (xy 127.321056 -148.91512)
			(xy 127.313266 -148.93598) (xy 127.304289 -148.97959) (xy 127.30305 -149.024098) (xy 127.309586 -149.06814)
			(xy 127.323698 -149.11037) (xy 127.344953 -149.149493) (xy 127.372702 -149.184314) (xy 127.389128 -149.199346)
			(xy 127.411574 -149.219979) (xy 127.450255 -149.267101) (xy 127.480953 -149.319774) (xy 127.502886 -149.376657)
			(xy 127.509778 -149.406356) (xy 127.514973 -149.428519) (xy 127.532155 -149.470667) (xy 127.55657 -149.509081)
			(xy 127.587437 -149.542532) (xy 127.623769 -149.569949) (xy 127.664403 -149.590457) (xy 127.70804 -149.603399)
			(xy 127.753285 -149.608362) (xy 127.79869 -149.605186) (xy 127.842804 -149.593973) (xy 127.884214 -149.575082)
			(xy 127.921598 -149.549117) (xy 127.938022 -149.533356) (xy 128.11252 -149.358858) (xy 128.11252 -140.875004)
			(xy 128.111977 -140.858354) (xy 128.103361 -140.826189) (xy 128.086713 -140.79735) (xy 128.063169 -140.773802)
			(xy 128.034333 -140.757149) (xy 128.00217 -140.748526) (xy 127.98552 -140.748004) (xy 127.611886 -140.748004)
			(xy 127.589985 -140.748464) (xy 127.546831 -140.755974) (xy 127.505604 -140.770771) (xy 127.467523 -140.792417)
			(xy 127.433717 -140.820269) (xy 127.405185 -140.853504) (xy 127.382773 -140.891139) (xy 127.367143 -140.932058)
			(xy 127.35876 -140.97505) (xy 127.35787 -141.018844) (xy 127.3645 -141.062141) (xy 127.371094 -141.08303)
			(xy 127.379591 -141.109775) (xy 127.389547 -141.165) (xy 127.391307 -141.221088) (xy 127.384835 -141.276829)
			(xy 127.370269 -141.331021) (xy 127.347924 -141.382496) (xy 127.318281 -141.430144) (xy 127.300482 -141.451838)
			(xy 127.290695 -141.464112) (xy 127.27687 -141.492286) (xy 127.270337 -141.522981) (xy 127.271492 -141.554343)
			(xy 127.280265 -141.584475) (xy 127.296125 -141.611556) (xy 127.306832 -141.623034) (xy 127.325839 -141.643015)
			(xy 127.358486 -141.687458) (xy 127.384394 -141.736139) (xy 127.403023 -141.788043) (xy 127.413984 -141.842088)
			(xy 127.41705 -141.897149) (xy 127.412156 -141.952077) (xy 127.399405 -142.005728) (xy 127.379061 -142.056984)
			(xy 127.351549 -142.104777) (xy 127.317443 -142.14811) (xy 127.277453 -142.186082) (xy 127.232412 -142.2179)
			(xy 127.183259 -142.242901) (xy 127.131019 -142.260565) (xy 127.07678 -142.270522) (xy 127.021672 -142.272567)
			(xy 126.966844 -142.266656) (xy 126.913439 -142.252912) (xy 126.862569 -142.231621) (xy 126.815294 -142.203229)
			(xy 126.7726 -142.168325) (xy 126.735376 -142.127638) (xy 126.704399 -142.082015) (xy 126.680313 -142.032407)
			(xy 126.663621 -141.979848) (xy 126.65467 -141.925434) (xy 126.653648 -141.870298) (xy 126.660574 -141.815589)
			(xy 126.675306 -141.762447) (xy 126.697535 -141.71198) (xy 126.7268 -141.66524) (xy 126.744222 -141.643862)
			(xy 126.754009 -141.631588) (xy 126.767834 -141.603414) (xy 126.774366 -141.572719) (xy 126.773211 -141.541357)
			(xy 126.764438 -141.511225) (xy 126.748579 -141.484144) (xy 126.737872 -141.472666) (xy 126.719716 -141.453611)
			(xy 126.688281 -141.411399) (xy 126.66295 -141.365265) (xy 126.644203 -141.316086) (xy 126.632397 -141.264796)
			(xy 126.627757 -141.21237) (xy 126.63037 -141.159804) (xy 126.640187 -141.108096) (xy 126.64821 -141.08303)
			(xy 126.654762 -141.062127) (xy 126.66141 -141.018831) (xy 126.660535 -140.975037) (xy 126.652162 -140.932042)
			(xy 126.63654 -140.89112) (xy 126.614131 -140.853483) (xy 126.5856 -140.820247) (xy 126.551791 -140.792396)
			(xy 126.513707 -140.770756) (xy 126.472476 -140.755968) (xy 126.42932 -140.74847) (xy 126.407418 -140.748004)
			(xy 123.741688 -140.748004) (xy 123.276868 -141.212824) (xy 123.27636 -141.264894) (xy 123.275662 -141.291841)
			(xy 123.267614 -141.345139) (xy 123.252143 -141.396774) (xy 123.229557 -141.445718) (xy 123.200306 -141.490994)
			(xy 123.164973 -141.531702) (xy 123.124262 -141.56703) (xy 123.078982 -141.596276) (xy 123.030037 -141.618857)
			(xy 122.9784 -141.634323) (xy 122.9251 -141.642365) (xy 122.898154 -141.6431) (xy 122.846084 -141.643608)
			(xy 120.652072 -143.83762) (xy 122.513528 -143.83762) (xy 122.513939 -143.783042) (xy 122.522123 -143.729079)
			(xy 122.537913 -143.676833) (xy 122.560986 -143.62737) (xy 122.590872 -143.581699) (xy 122.626962 -143.540753)
			(xy 122.668517 -143.505368) (xy 122.71469 -143.476265) (xy 122.76454 -143.454039) (xy 122.817048 -143.439142)
			(xy 122.871142 -143.43188) (xy 122.92572 -143.4324) (xy 122.952764 -143.436086) (xy 122.974426 -143.438985)
			(xy 123.01812 -143.438162) (xy 123.061029 -143.429871) (xy 123.101885 -143.414358) (xy 123.139482 -143.392081)
			(xy 123.172711 -143.363696) (xy 123.200591 -143.330043) (xy 123.222299 -143.292113) (xy 123.237193 -143.251028)
			(xy 123.244835 -143.207999) (xy 123.245372 -143.18615) (xy 123.245626 -143.170656) (xy 123.246069 -143.148201)
			(xy 123.240108 -143.103693) (xy 123.226419 -143.060925) (xy 123.205426 -143.021228) (xy 123.177783 -142.985839)
			(xy 123.144352 -142.955858) (xy 123.106171 -142.93222) (xy 123.064431 -142.915659) (xy 123.02043 -142.906691)
			(xy 122.975538 -142.905596) (xy 122.953272 -142.908528) (xy 122.925949 -142.91223) (xy 122.870816 -142.912734)
			(xy 122.816184 -142.905297) (xy 122.763192 -142.890076) (xy 122.712942 -142.867386) (xy 122.66648 -142.8377)
			(xy 122.624775 -142.801637) (xy 122.588694 -142.759946) (xy 122.558989 -142.713497) (xy 122.536279 -142.663256)
			(xy 122.521035 -142.61027) (xy 122.513576 -142.555642) (xy 122.514057 -142.500508) (xy 122.522468 -142.446018)
			(xy 122.538634 -142.393306) (xy 122.562218 -142.343469) (xy 122.592729 -142.297546) (xy 122.629531 -142.256491)
			(xy 122.67186 -142.221161) (xy 122.718832 -142.19229) (xy 122.76947 -142.170481) (xy 122.82272 -142.156186)
			(xy 122.877473 -142.149704) (xy 122.932589 -142.15117) (xy 122.98692 -142.160553) (xy 123.039335 -142.177657)
			(xy 123.088743 -142.202128) (xy 123.134114 -142.233454) (xy 123.174505 -142.270984) (xy 123.209074 -142.313937)
			(xy 123.237101 -142.361417) (xy 123.258002 -142.412437) (xy 123.271343 -142.465934) (xy 123.276846 -142.520794)
			(xy 123.276106 -142.548356) (xy 123.275615 -142.570811) (xy 123.281578 -142.615324) (xy 123.295272 -142.658096)
			(xy 123.31627 -142.697795) (xy 123.343918 -142.733187) (xy 123.377355 -142.763168) (xy 123.415542 -142.786806)
			(xy 123.457288 -142.803365) (xy 123.501295 -142.812329) (xy 123.546192 -142.813419) (xy 123.56846 -142.810484)
			(xy 123.597271 -142.806559) (xy 123.655415 -142.806474) (xy 123.7129 -142.815203) (xy 123.768398 -142.832545)
			(xy 123.820626 -142.858098) (xy 123.844812 -142.874238) (xy 123.863391 -142.886598) (xy 123.903914 -142.905273)
			(xy 123.947076 -142.916587) (xy 123.991551 -142.920191) (xy 124.035971 -142.915975) (xy 124.078973 -142.90407)
			(xy 124.119237 -142.884839) (xy 124.155524 -142.858875) (xy 124.171456 -142.84325) (xy 124.191406 -142.823608)
			(xy 124.235972 -142.789727) (xy 124.285011 -142.762721) (xy 124.33747 -142.743172) (xy 124.392223 -142.731498)
			(xy 124.448094 -142.727951) (xy 124.503883 -142.732607) (xy 124.558393 -142.745366) (xy 124.610453 -142.765953)
			(xy 124.658946 -142.793926) (xy 124.702831 -142.828686) (xy 124.741165 -142.869486) (xy 124.773125 -142.91545)
			(xy 124.798025 -142.965591) (xy 124.815331 -143.018832) (xy 124.82467 -143.07403) (xy 124.825843 -143.130001)
			(xy 124.818825 -143.185543) (xy 124.803765 -143.239462) (xy 124.780987 -143.290602) (xy 124.750981 -143.337864)
			(xy 124.71439 -143.380235) (xy 124.672001 -143.416803) (xy 124.624722 -143.446784) (xy 124.57357 -143.469534)
			(xy 124.519643 -143.484565) (xy 124.464097 -143.491554) (xy 124.408127 -143.490351) (xy 124.352934 -143.480982)
			(xy 124.299702 -143.463648) (xy 124.249574 -143.438721) (xy 124.22632 -143.423132) (xy 124.207726 -143.410794)
			(xy 124.167207 -143.392111) (xy 124.124048 -143.38079) (xy 124.079575 -143.377181) (xy 124.035155 -143.381393)
			(xy 123.992153 -143.393297) (xy 123.951891 -143.412528) (xy 123.915606 -143.438494) (xy 123.899676 -143.45412)
			(xy 123.881279 -143.472325) (xy 123.840452 -143.504131) (xy 123.795695 -143.53012) (xy 123.747834 -143.549813)
			(xy 123.697747 -143.562849) (xy 123.646358 -143.568988) (xy 123.594611 -143.568115) (xy 123.568968 -143.56461)
			(xy 123.547301 -143.561749) (xy 123.50361 -143.562567) (xy 123.460703 -143.570853) (xy 123.419849 -143.586361)
			(xy 123.382252 -143.608634) (xy 123.349023 -143.637015) (xy 123.321143 -143.670665) (xy 123.299435 -143.70859)
			(xy 123.28454 -143.749673) (xy 123.276897 -143.792698) (xy 123.27636 -143.814546) (xy 123.275779 -143.841834)
			(xy 123.267811 -143.895829) (xy 123.25223 -143.948138) (xy 123.229355 -143.997693) (xy 123.199651 -144.043483)
			(xy 123.163726 -144.084573) (xy 123.122313 -144.120124) (xy 123.076256 -144.149412) (xy 123.026496 -144.171837)
			(xy 122.974048 -144.186944) (xy 122.919983 -144.194422) (xy 122.865404 -144.194121) (xy 122.811425 -144.186045)
			(xy 122.759147 -144.170359) (xy 122.709638 -144.147385) (xy 122.663908 -144.11759) (xy 122.62289 -144.081583)
			(xy 122.587421 -144.040098) (xy 122.558226 -143.993983) (xy 122.5359 -143.944178) (xy 122.520899 -143.8917)
			(xy 122.513528 -143.83762) (xy 120.652072 -143.83762) (xy 120.253412 -144.23628) (xy 124.214727 -144.23628)
			(xy 124.217562 -144.180353) (xy 124.228543 -144.125441) (xy 124.247435 -144.072725) (xy 124.273832 -144.023338)
			(xy 124.307166 -143.978341) (xy 124.346721 -143.938701) (xy 124.391647 -143.905271) (xy 124.440977 -143.878768)
			(xy 124.493653 -143.859763) (xy 124.548541 -143.848664) (xy 124.604462 -143.84571) (xy 124.660214 -143.850963)
			(xy 124.714599 -143.864312) (xy 124.766448 -143.885469) (xy 124.814646 -143.913979) (xy 124.858157 -143.94923)
			(xy 124.896047 -143.990464) (xy 124.927501 -144.036795) (xy 124.951843 -144.087227) (xy 124.968549 -144.140676)
			(xy 124.977261 -144.195993) (xy 124.977792 -144.25199) (xy 124.970129 -144.307462) (xy 124.954438 -144.361218)
			(xy 124.931057 -144.412102) (xy 124.916184 -144.43583) (xy 124.904084 -144.455262) (xy 124.886367 -144.497466)
			(xy 124.876495 -144.542161) (xy 124.874785 -144.587902) (xy 124.881295 -144.633209) (xy 124.881594 -144.634104)
			(xy 126.703935 -144.634104) (xy 126.707812 -144.579708) (xy 126.719393 -144.526419) (xy 126.738444 -144.475321)
			(xy 126.764575 -144.427456) (xy 126.780544 -144.40535) (xy 126.794091 -144.386306) (xy 126.814824 -144.34443)
			(xy 126.827553 -144.29947) (xy 126.831849 -144.25294) (xy 126.827568 -144.206409) (xy 126.814853 -144.161445)
			(xy 126.794133 -144.119563) (xy 126.780544 -144.10055) (xy 126.764584 -144.078462) (xy 126.738463 -144.030636)
			(xy 126.719415 -143.97958) (xy 126.707827 -143.926333) (xy 126.703935 -143.871978) (xy 126.707819 -143.817623)
			(xy 126.719399 -143.764374) (xy 126.73844 -143.713315) (xy 126.764554 -143.665485) (xy 126.797209 -143.621859)
			(xy 126.83574 -143.583325) (xy 126.879364 -143.550667) (xy 126.927191 -143.52455) (xy 126.978249 -143.505505)
			(xy 127.031497 -143.493921) (xy 127.085852 -143.490033) (xy 127.140207 -143.493921) (xy 127.193455 -143.505505)
			(xy 127.244513 -143.52455) (xy 127.29234 -143.550667) (xy 127.335964 -143.583325) (xy 127.374495 -143.621859)
			(xy 127.40715 -143.665485) (xy 127.433264 -143.713315) (xy 127.452305 -143.764374) (xy 127.463885 -143.817623)
			(xy 127.467769 -143.871978) (xy 127.463877 -143.926333) (xy 127.452289 -143.97958) (xy 127.433241 -144.030636)
			(xy 127.40712 -144.078462) (xy 127.39116 -144.10055) (xy 127.37752 -144.119531) (xy 127.356795 -144.161423)
			(xy 127.344077 -144.206398) (xy 127.339794 -144.25294) (xy 127.344091 -144.299481) (xy 127.356824 -144.344451)
			(xy 127.377562 -144.386337) (xy 127.39116 -144.40535) (xy 127.406961 -144.427295) (xy 127.43294 -144.474719)
			(xy 127.45196 -144.525337) (xy 127.463639 -144.578135) (xy 127.467742 -144.632052) (xy 127.464189 -144.686009)
			(xy 127.453049 -144.738923) (xy 127.434547 -144.789733) (xy 127.409053 -144.83742) (xy 127.393446 -144.859502)
			(xy 127.38489 -144.871859) (xy 127.37331 -144.899588) (xy 127.368544 -144.929258) (xy 127.370856 -144.959219)
			(xy 127.380117 -144.987806) (xy 127.395814 -145.013431) (xy 127.406146 -145.024348) (xy 127.42568 -145.044513)
			(xy 127.459173 -145.08957) (xy 127.485699 -145.13905) (xy 127.504687 -145.191884) (xy 127.515724 -145.24693)
			(xy 127.518574 -145.303) (xy 127.513174 -145.358881) (xy 127.499641 -145.413368) (xy 127.478267 -145.465282)
			(xy 127.449515 -145.513503) (xy 127.414005 -145.556988) (xy 127.372504 -145.594799) (xy 127.32591 -145.626117)
			(xy 127.275228 -145.650268) (xy 127.221553 -145.666729) (xy 127.166045 -145.675144) (xy 127.109904 -145.675332)
			(xy 127.054341 -145.667288) (xy 127.000557 -145.651187) (xy 126.949715 -145.627376) (xy 126.902912 -145.59637)
			(xy 126.861159 -145.558838) (xy 126.825359 -145.515591) (xy 126.796285 -145.467564) (xy 126.774564 -145.415794)
			(xy 126.760667 -145.361399) (xy 126.754893 -145.305555) (xy 126.757367 -145.249468) (xy 126.768036 -145.194349)
			(xy 126.786669 -145.141389) (xy 126.812864 -145.091733) (xy 126.829058 -145.068798) (xy 126.837614 -145.056441)
			(xy 126.849193 -145.028711) (xy 126.853959 -144.999042) (xy 126.851647 -144.969081) (xy 126.842386 -144.940494)
			(xy 126.826689 -144.91487) (xy 126.816358 -144.903952) (xy 126.797391 -144.884358) (xy 126.764688 -144.840718)
			(xy 126.73853 -144.792868) (xy 126.719452 -144.74178) (xy 126.707841 -144.688497) (xy 126.703935 -144.634104)
			(xy 124.881594 -144.634104) (xy 124.895812 -144.676618) (xy 124.917869 -144.716726) (xy 124.931932 -144.734788)
			(xy 124.949263 -144.756792) (xy 124.977891 -144.804935) (xy 124.999173 -144.856746) (xy 125.012649 -144.911112)
			(xy 125.018031 -144.966865) (xy 125.015204 -145.022805) (xy 125.004227 -145.077731) (xy 124.985336 -145.130461)
			(xy 124.958939 -145.179862) (xy 124.925602 -145.224872) (xy 124.886041 -145.264524) (xy 124.841108 -145.297966)
			(xy 124.791768 -145.324477) (xy 124.739082 -145.34349) (xy 124.684182 -145.354594) (xy 124.628248 -145.357551)
			(xy 124.572483 -145.352297) (xy 124.518086 -145.338946) (xy 124.466225 -145.317785) (xy 124.418017 -145.289268)
			(xy 124.374496 -145.254008) (xy 124.336598 -145.212764) (xy 124.305139 -145.166421) (xy 124.280794 -145.115977)
			(xy 124.264087 -145.062515) (xy 124.255377 -145.007185) (xy 124.25485 -144.951176) (xy 124.262519 -144.895691)
			(xy 124.278219 -144.841925) (xy 124.301612 -144.791032) (xy 124.31649 -144.7673) (xy 124.328554 -144.747848)
			(xy 124.346268 -144.705648) (xy 124.356142 -144.660959) (xy 124.357855 -144.615223) (xy 124.351352 -144.569921)
			(xy 124.336844 -144.526514) (xy 124.314799 -144.486406) (xy 124.300742 -144.468342) (xy 124.283447 -144.446317)
			(xy 124.254833 -144.39818) (xy 124.233565 -144.346377) (xy 124.2201 -144.292021) (xy 124.214727 -144.23628)
			(xy 120.253412 -144.23628) (xy 119.819928 -144.669764) (xy 118.813584 -145.67625) (xy 121.896387 -145.67625)
			(xy 121.901642 -145.621271) (xy 121.914771 -145.567626) (xy 121.9355 -145.516434) (xy 121.963397 -145.468768)
			(xy 121.997876 -145.425624) (xy 122.038218 -145.387904) (xy 122.083579 -145.356397) (xy 122.133009 -145.331762)
			(xy 122.185476 -145.314514) (xy 122.239882 -145.305014) (xy 122.267472 -145.303748) (xy 122.291107 -145.302495)
			(xy 122.337339 -145.292395) (xy 122.380905 -145.273916) (xy 122.4203 -145.247696) (xy 122.454165 -145.214641)
			(xy 122.481329 -145.175891) (xy 122.500856 -145.132785) (xy 122.512071 -145.08681) (xy 122.513852 -145.06321)
			(xy 122.51578 -145.035652) (xy 122.526602 -144.981479) (xy 122.545125 -144.929433) (xy 122.570961 -144.880604)
			(xy 122.60357 -144.836012) (xy 122.64227 -144.79659) (xy 122.686252 -144.763162) (xy 122.734595 -144.736427)
			(xy 122.786289 -144.716946) (xy 122.840253 -144.705124) (xy 122.895357 -144.70121) (xy 122.95045 -144.705285)
			(xy 123.004379 -144.717264) (xy 123.056016 -144.736896) (xy 123.104281 -144.763771) (xy 123.148165 -144.797327)
			(xy 123.18675 -144.836862) (xy 123.219229 -144.881549) (xy 123.244922 -144.930454) (xy 123.263293 -144.982553)
			(xy 123.273957 -145.036757) (xy 123.276691 -145.091933) (xy 123.271438 -145.146926) (xy 123.258307 -145.200586)
			(xy 123.237574 -145.251791) (xy 123.209672 -145.29947) (xy 123.175184 -145.342625) (xy 123.134833 -145.380355)
			(xy 123.089461 -145.41187) (xy 123.040017 -145.436511) (xy 122.987537 -145.453763) (xy 122.933117 -145.463264)
			(xy 122.90552 -145.46453) (xy 122.881878 -145.465703) (xy 122.835637 -145.475809) (xy 122.792065 -145.494296)
			(xy 122.752666 -145.520526) (xy 122.718801 -145.553594) (xy 122.691639 -145.592357) (xy 122.672119 -145.635476)
			(xy 122.660914 -145.681463) (xy 122.65914 -145.705068) (xy 122.657133 -145.732615) (xy 122.646303 -145.786772)
			(xy 122.627775 -145.838801) (xy 122.601937 -145.887613) (xy 122.569328 -145.932188) (xy 122.530631 -145.971594)
			(xy 122.486655 -146.005006) (xy 122.43832 -146.031726) (xy 122.386636 -146.051195) (xy 122.332685 -146.063006)
			(xy 122.277594 -146.066912) (xy 122.222515 -146.062832) (xy 122.168602 -146.050849) (xy 122.11698 -146.031216)
			(xy 122.06873 -146.004343) (xy 122.02486 -145.970791) (xy 121.986289 -145.931263) (xy 121.953822 -145.886584)
			(xy 121.928138 -145.83769) (xy 121.909776 -145.785603) (xy 121.899118 -145.731412) (xy 121.896387 -145.67625)
			(xy 118.813584 -145.67625) (xy 118.017036 -146.47291) (xy 123.417074 -146.47291) (xy 123.421145 -146.417288)
			(xy 123.433271 -146.362851) (xy 123.453194 -146.31076) (xy 123.48049 -146.262125) (xy 123.514576 -146.217982)
			(xy 123.554725 -146.179273) (xy 123.600083 -146.146822) (xy 123.649683 -146.121321) (xy 123.702467 -146.103314)
			(xy 123.75731 -146.093184) (xy 123.813044 -146.091147) (xy 123.868481 -146.097247) (xy 123.922438 -146.111353)
			(xy 123.973767 -146.133165) (xy 124.021373 -146.162219) (xy 124.064241 -146.197894) (xy 124.101458 -146.239431)
			(xy 124.132231 -146.285944) (xy 124.155903 -146.336441) (xy 124.171971 -146.389848) (xy 124.180091 -146.445024)
			(xy 124.1806 -146.47291) (xy 124.180091 -146.500796) (xy 124.171971 -146.555972) (xy 124.155903 -146.609379)
			(xy 124.132231 -146.659876) (xy 124.101458 -146.706389) (xy 124.064241 -146.747926) (xy 124.021373 -146.783601)
			(xy 123.973767 -146.812655) (xy 123.922438 -146.834467) (xy 123.868481 -146.848573) (xy 123.813044 -146.854673)
			(xy 123.75731 -146.852636) (xy 123.702467 -146.842506) (xy 123.649683 -146.824499) (xy 123.600083 -146.798998)
			(xy 123.554725 -146.766547) (xy 123.514576 -146.727838) (xy 123.48049 -146.683695) (xy 123.453194 -146.63506)
			(xy 123.433271 -146.582969) (xy 123.421145 -146.528532) (xy 123.417074 -146.47291) (xy 118.017036 -146.47291)
			(xy 118.016274 -146.473672) (xy 110.098332 -146.473672) (xy 109.98708 -146.584924) (xy 105.305098 -146.584924)
			(xy 104.68229 -145.962116) (xy 102.161848 -145.962116) (xy 101.36124 -145.161508) (xy 81.091532 -145.161508)
			(xy 81.069526 -145.161974) (xy 81.026171 -145.169552) (xy 80.98477 -145.184487) (xy 80.946562 -145.206332)
			(xy 80.912689 -145.234433) (xy 80.884165 -145.267951) (xy 80.861842 -145.305883) (xy 80.84639 -145.347093)
			(xy 80.838269 -145.39035) (xy 80.837723 -145.434359) (xy 80.840834 -145.456148) (xy 80.844781 -145.483516)
			(xy 80.845673 -145.538802) (xy 80.838571 -145.593638) (xy 80.823624 -145.646873) (xy 80.801147 -145.697392)
			(xy 80.771609 -145.744135) (xy 80.73563 -145.786122) (xy 80.693966 -145.822474) (xy 80.647488 -145.852427)
			(xy 80.597172 -145.875355) (xy 80.544072 -145.890775) (xy 80.489302 -145.898366) (xy 80.434009 -145.897968)
			(xy 80.379354 -145.889588) (xy 80.326482 -145.873404) (xy 80.276502 -145.849754) (xy 80.23046 -145.819134)
			(xy 80.189324 -145.782186) (xy 80.153954 -145.739684) (xy 80.125093 -145.69252) (xy 80.103346 -145.641683)
			(xy 80.089168 -145.588238) (xy 80.082857 -145.533306) (xy 80.084545 -145.478038) (xy 80.094197 -145.423593)
			(xy 80.11161 -145.371113) (xy 80.123538 -145.346166) (xy 80.137 -145.319242) (xy 80.137 -145.288508)
			(xy 80.136506 -145.271853) (xy 80.127887 -145.239676) (xy 80.111232 -145.210828) (xy 80.087679 -145.187273)
			(xy 80.058831 -145.170617) (xy 80.026655 -145.161995) (xy 80.01 -145.161508) (xy 79.975202 -145.161508)
			(xy 79.880714 -145.204942) (xy 79.864204 -145.22196) (xy 79.844496 -145.241586) (xy 79.800412 -145.275497)
			(xy 79.751871 -145.302647) (xy 79.699903 -145.322462) (xy 79.645608 -145.334522) (xy 79.590138 -145.33857)
			(xy 79.534668 -145.334522) (xy 79.480373 -145.322462) (xy 79.428405 -145.302647) (xy 79.379864 -145.275497)
			(xy 79.33578 -145.241586) (xy 79.316072 -145.22196) (xy 79.299562 -145.204942) (xy 79.205074 -145.161508)
			(xy 77.951584 -145.161508) (xy 77.927831 -145.16207) (xy 77.88116 -145.170952) (xy 77.836952 -145.188347)
			(xy 77.796743 -145.213651) (xy 77.761934 -145.245983) (xy 77.733736 -145.284217) (xy 77.71313 -145.327024)
			(xy 77.700833 -145.372913) (xy 77.697273 -145.420287) (xy 77.699362 -145.443956) (xy 77.702001 -145.471771)
			(xy 77.700086 -145.52761) (xy 77.69005 -145.582574) (xy 77.672106 -145.635486) (xy 77.646639 -145.685216)
			(xy 77.614193 -145.730702) (xy 77.575461 -145.77097) (xy 77.531271 -145.80516) (xy 77.482569 -145.832541)
			(xy 77.430394 -145.852528) (xy 77.375863 -145.864694) (xy 77.32014 -145.868778) (xy 77.264417 -145.864694)
			(xy 77.209886 -145.852528) (xy 77.157711 -145.832541) (xy 77.109009 -145.80516) (xy 77.064819 -145.77097)
			(xy 77.026087 -145.730702) (xy 76.993641 -145.685216) (xy 76.968174 -145.635486) (xy 76.95023 -145.582574)
			(xy 76.940194 -145.52761) (xy 76.938279 -145.471771) (xy 76.940918 -145.443956) (xy 76.94305 -145.420289)
			(xy 76.939506 -145.372908) (xy 76.927216 -145.327012) (xy 76.906609 -145.284199) (xy 76.878403 -145.245964)
			(xy 76.843582 -145.213638) (xy 76.803358 -145.188347) (xy 76.759135 -145.170975) (xy 76.712452 -145.162125)
			(xy 76.688696 -145.161508) (xy 73.147428 -145.161508) (xy 73.124907 -145.161999) (xy 73.080572 -145.169949)
			(xy 73.038331 -145.185587) (xy 72.999507 -145.208423) (xy 72.965315 -145.237744) (xy 72.936825 -145.272632)
			(xy 72.914928 -145.311993) (xy 72.90031 -145.354598) (xy 72.893429 -145.399111) (xy 72.894499 -145.444141)
			(xy 72.898508 -145.466308) (xy 72.903641 -145.494026) (xy 72.906649 -145.550314) (xy 72.901344 -145.606432)
			(xy 72.88784 -145.66116) (xy 72.866432 -145.713305) (xy 72.837586 -145.761733) (xy 72.801928 -145.805391)
			(xy 72.760236 -145.843327) (xy 72.713417 -145.874717) (xy 72.662488 -145.898878) (xy 72.60856 -145.915283)
			(xy 72.552804 -145.923576) (xy 72.496436 -145.923576) (xy 72.44068 -145.915283) (xy 72.386752 -145.898878)
			(xy 72.335823 -145.874717) (xy 72.289004 -145.843327) (xy 72.247312 -145.805391) (xy 72.211654 -145.761733)
			(xy 72.182808 -145.713305) (xy 72.1614 -145.66116) (xy 72.147896 -145.606432) (xy 72.142591 -145.550314)
			(xy 72.145599 -145.494026) (xy 72.150732 -145.466308) (xy 72.154763 -145.444142) (xy 72.155851 -145.399106)
			(xy 72.148981 -145.354584) (xy 72.134368 -145.311971) (xy 72.112471 -145.272602) (xy 72.083974 -145.237711)
			(xy 72.049772 -145.208392) (xy 72.010936 -145.185563) (xy 71.968683 -145.169939) (xy 71.924337 -145.162011)
			(xy 71.901812 -145.161508) (xy 68.474336 -145.161508) (xy 68.416678 -145.193766) (xy 68.399406 -145.22196)
			(xy 68.384409 -145.245359) (xy 68.348711 -145.287957) (xy 68.307214 -145.324926) (xy 68.260792 -145.355486)
			(xy 68.21043 -145.37899) (xy 68.157191 -145.394941) (xy 68.102202 -145.403002) (xy 68.046624 -145.403002)
			(xy 67.991635 -145.394941) (xy 67.938396 -145.37899) (xy 67.888034 -145.355486) (xy 67.841612 -145.324926)
			(xy 67.800115 -145.287957) (xy 67.764417 -145.245359) (xy 67.74942 -145.22196) (xy 67.732148 -145.193766)
			(xy 67.67449 -145.161508) (xy 66.29908 -145.161508) (xy 66.281808 -145.17878) (xy 62.358524 -145.17878)
			(xy 60.93333 -143.75384) (xy 60.241434 -143.75384) (xy 60.117482 -143.871188) (xy 60.11037 -143.913098)
			(xy 60.105423 -143.939329) (xy 60.088546 -143.989968) (xy 60.064118 -144.037427) (xy 60.032716 -144.08059)
			(xy 59.99508 -144.11844) (xy 59.952094 -144.150085) (xy 59.904773 -144.17478) (xy 59.85423 -144.191942)
			(xy 59.801656 -144.201169) (xy 59.74829 -144.202243) (xy 59.695388 -144.195137) (xy 59.644196 -144.180021)
			(xy 59.59592 -144.157249) (xy 59.551697 -144.127358) (xy 59.512568 -144.091052) (xy 59.479456 -144.049186)
			(xy 59.45314 -144.002747) (xy 59.43424 -143.952828) (xy 59.423201 -143.900605) (xy 59.421268 -143.873982)
			(xy 59.418474 -143.823436) (xy 59.345068 -143.75384) (xy 59.224672 -143.75384) (xy 59.208979 -143.754307)
			(xy 59.178544 -143.761978) (xy 59.150903 -143.776848) (xy 59.12773 -143.798016) (xy 59.110427 -143.824203)
			(xy 59.100042 -143.853821) (xy 59.09818 -143.86941) (xy 59.095136 -143.89726) (xy 59.081758 -143.951662)
			(xy 59.060386 -144.003449) (xy 59.031502 -144.051452) (xy 58.995757 -144.09459) (xy 58.953957 -144.131891)
			(xy 58.907044 -144.162514) (xy 58.856076 -144.185768) (xy 58.8022 -144.20113) (xy 58.746632 -144.208254)
			(xy 58.690623 -144.206978) (xy 58.635437 -144.197332) (xy 58.582316 -144.179533) (xy 58.532459 -144.153983)
			(xy 58.486989 -144.121256) (xy 58.446931 -144.082091) (xy 58.413187 -144.03737) (xy 58.386518 -143.988102)
			(xy 58.367526 -143.935396) (xy 58.36158 -143.908018) (xy 58.353452 -143.867124) (xy 58.2295 -143.75384)
			(xy 56.071262 -143.75384) (xy 56.053419 -143.754402) (xy 56.019108 -143.764204) (xy 55.988848 -143.783115)
			(xy 55.965001 -143.809661) (xy 55.956708 -143.825468) (xy 55.94383 -143.85091) (xy 55.911662 -143.89799)
			(xy 55.872844 -143.939757) (xy 55.828239 -143.975278) (xy 55.778842 -144.003762) (xy 55.725755 -144.024573)
			(xy 55.670161 -144.037249) (xy 55.6133 -144.041505) (xy 55.556439 -144.037249) (xy 55.500845 -144.024573)
			(xy 55.447758 -144.003762) (xy 55.398361 -143.975278) (xy 55.353756 -143.939757) (xy 55.314938 -143.89799)
			(xy 55.28277 -143.85091) (xy 55.269892 -143.825468) (xy 55.261577 -143.809671) (xy 55.237744 -143.783112)
			(xy 55.207491 -143.76419) (xy 55.173181 -143.754382) (xy 55.155338 -143.75384) (xy 54.176168 -143.75384)
			(xy 54.154185 -143.754309) (xy 54.110877 -143.76188) (xy 54.069517 -143.77679) (xy 54.031339 -143.798595)
			(xy 53.997484 -143.826644) (xy 53.96896 -143.860101) (xy 53.946618 -143.897967) (xy 53.931126 -143.939112)
			(xy 53.922945 -143.98231) (xy 53.922168 -144.004284) (xy 53.921339 -144.031298) (xy 53.913 -144.084697)
			(xy 53.89721 -144.136385) (xy 53.874283 -144.185328) (xy 53.84468 -144.230545) (xy 53.808991 -144.271132)
			(xy 53.767932 -144.306277) (xy 53.722325 -144.335276) (xy 53.673082 -144.357549) (xy 53.621188 -144.37265)
			(xy 53.567683 -144.380276) (xy 53.513637 -144.380276) (xy 53.460132 -144.37265) (xy 53.408238 -144.357549)
			(xy 53.358995 -144.335276) (xy 53.313388 -144.306277) (xy 53.272329 -144.271132) (xy 53.23664 -144.230545)
			(xy 53.207037 -144.185328) (xy 53.18411 -144.136385) (xy 53.16832 -144.084697) (xy 53.159981 -144.031298)
			(xy 53.159152 -144.004284) (xy 53.158381 -143.982307) (xy 53.150212 -143.939102) (xy 53.134728 -143.897947)
			(xy 53.112389 -143.860073) (xy 53.083864 -143.826611) (xy 53.050005 -143.798558) (xy 53.011821 -143.776753)
			(xy 52.970453 -143.761848) (xy 52.927138 -143.754286) (xy 52.905152 -143.75384) (xy 50.84064 -143.75384)
			(xy 50.818103 -143.754331) (xy 50.773737 -143.762288) (xy 50.731468 -143.777941) (xy 50.692621 -143.800801)
			(xy 50.658413 -143.830152) (xy 50.629915 -143.865073) (xy 50.608019 -143.904472) (xy 50.593412 -143.947113)
			(xy 50.586551 -143.991662) (xy 50.587651 -144.036723) (xy 50.59172 -144.058894) (xy 50.596914 -144.086627)
			(xy 50.600033 -144.142961) (xy 50.594821 -144.199141) (xy 50.58139 -144.25394) (xy 50.560035 -144.306163)
			(xy 50.531221 -144.354672) (xy 50.495576 -144.398407) (xy 50.453879 -144.436415) (xy 50.407038 -144.467867)
			(xy 50.356075 -144.492077) (xy 50.302102 -144.508516) (xy 50.246296 -144.516826) (xy 50.189876 -144.516826)
			(xy 50.13407 -144.508516) (xy 50.080097 -144.492077) (xy 50.029134 -144.467867) (xy 49.982293 -144.436415)
			(xy 49.940596 -144.398407) (xy 49.904951 -144.354672) (xy 49.876137 -144.306163) (xy 49.854782 -144.25394)
			(xy 49.841351 -144.199141) (xy 49.836139 -144.142961) (xy 49.839258 -144.086627) (xy 49.844452 -144.058894)
			(xy 49.84851 -144.036716) (xy 49.849645 -143.991647) (xy 49.842809 -143.947086) (xy 49.828216 -143.90443)
			(xy 49.806324 -143.865019) (xy 49.777821 -143.83009) (xy 49.743602 -143.800739) (xy 49.704739 -143.777888)
			(xy 49.662454 -143.762254) (xy 49.618074 -143.754327) (xy 49.595532 -143.75384) (xy 43.573954 -143.75384)
			(xy 43.041824 -143.22171) (xy 42.991024 -143.22044) (xy 42.964637 -143.219344) (xy 42.912523 -143.210779)
			(xy 42.862088 -143.195111) (xy 42.814295 -143.172639) (xy 42.770057 -143.143791) (xy 42.730219 -143.10912)
			(xy 42.695542 -143.069287) (xy 42.666688 -143.025053) (xy 42.644209 -142.977263) (xy 42.628533 -142.926831)
			(xy 42.619961 -142.874718) (xy 42.618914 -142.84833) (xy 42.617644 -142.79753) (xy 41.78554 -141.965426)
			(xy 41.77423 -141.954714) (xy 41.747545 -141.938659) (xy 41.717756 -141.92958) (xy 41.702228 -141.928342)
			(xy 41.674269 -141.926411) (xy 41.619324 -141.91538) (xy 41.566583 -141.896431) (xy 41.517181 -141.86997)
			(xy 41.472182 -141.836567) (xy 41.432552 -141.796941) (xy 41.399146 -141.751944) (xy 41.372681 -141.702544)
			(xy 41.353727 -141.649805) (xy 41.342692 -141.59486) (xy 41.340786 -141.5669) (xy 41.338246 -141.518132)
			(xy 40.64762 -140.827506) (xy 40.64762 -138.78941) (xy 40.647069 -138.765454) (xy 40.638095 -138.718391)
			(xy 40.620462 -138.673842) (xy 40.594795 -138.633386) (xy 40.562003 -138.598454) (xy 40.523247 -138.570285)
			(xy 40.4799 -138.549875) (xy 40.433497 -138.537948) (xy 40.409622 -138.535918) (xy 40.382938 -138.533776)
			(xy 40.330543 -138.522805) (xy 40.280257 -138.504448) (xy 40.233117 -138.479082) (xy 40.190093 -138.44723)
			(xy 40.15207 -138.409549) (xy 40.119832 -138.366813) (xy 40.094043 -138.319903) (xy 40.075233 -138.269785)
			(xy 40.06379 -138.217491) (xy 40.059949 -138.164098) (xy 40.06379 -138.110704) (xy 40.075234 -138.05841)
			(xy 40.094045 -138.008292) (xy 40.119835 -137.961383) (xy 40.152073 -137.918648) (xy 40.190096 -137.880966)
			(xy 40.233121 -137.849115) (xy 40.280262 -137.82375) (xy 40.330547 -137.805394) (xy 40.382943 -137.794423)
			(xy 40.409622 -137.792206) (xy 40.433493 -137.790144) (xy 40.479892 -137.778219) (xy 40.523236 -137.757812)
			(xy 40.561989 -137.729647) (xy 40.59478 -137.694721) (xy 40.620447 -137.654269) (xy 40.638081 -137.609726)
			(xy 40.647059 -137.562668) (xy 40.64762 -137.538714) (xy 40.64762 -137.40765) (xy 39.732204 -136.492234)
			(xy 39.719536 -136.480425) (xy 39.689356 -136.463468) (xy 39.655729 -136.455244) (xy 39.621129 -136.456359)
			(xy 39.604442 -136.460992) (xy 39.567612 -136.472422) (xy 39.553388 -136.481058) (xy 39.55288 -136.481312)
			(xy 39.530478 -136.494756) (xy 39.482714 -136.515925) (xy 39.432462 -136.530214) (xy 39.380705 -136.537343)
			(xy 39.328461 -136.537173) (xy 39.276752 -136.529705) (xy 39.226594 -136.515088) (xy 39.17897 -136.493606)
			(xy 39.15664 -136.480042) (xy 39.156386 -136.479788) (xy 39.142162 -136.470898) (xy 39.10457 -136.45896)
			(xy 39.087839 -136.454316) (xy 39.05315 -136.453219) (xy 39.019451 -136.461517) (xy 38.989239 -136.478598)
			(xy 38.976554 -136.490456) (xy 38.71468 -136.75233) (xy 38.71468 -137.791819) (xy 38.983972 -137.791819)
			(xy 38.984071 -137.737424) (xy 38.992079 -137.683621) (xy 39.007825 -137.631555) (xy 39.030976 -137.582332)
			(xy 39.061038 -137.536999) (xy 39.097373 -137.496519) (xy 39.139208 -137.461753) (xy 39.185653 -137.43344)
			(xy 39.235723 -137.412182) (xy 39.288351 -137.398431) (xy 39.342419 -137.392479) (xy 39.396779 -137.394452)
			(xy 39.450273 -137.404309) (xy 39.501766 -137.421841) (xy 39.550162 -137.446673) (xy 39.594432 -137.47828)
			(xy 39.633636 -137.515988) (xy 39.66694 -137.558996) (xy 39.693636 -137.60639) (xy 39.713156 -137.657162)
			(xy 39.725086 -137.710232) (xy 39.729171 -137.764474) (xy 39.725326 -137.818733) (xy 39.713631 -137.871856)
			(xy 39.694336 -137.922714) (xy 39.66785 -137.970226) (xy 39.651686 -137.992104) (xy 39.638628 -138.009767)
			(xy 39.618254 -138.04868) (xy 39.604876 -138.090518) (xy 39.598893 -138.134033) (xy 39.600484 -138.177928)
			(xy 39.609601 -138.220896) (xy 39.625972 -138.261655) (xy 39.64911 -138.298991) (xy 39.66337 -138.3157)
			(xy 39.6811 -138.336333) (xy 39.711003 -138.381778) (xy 39.73398 -138.431088) (xy 39.749542 -138.483216)
			(xy 39.757359 -138.537052) (xy 39.757263 -138.591452) (xy 39.749258 -138.645261) (xy 39.733514 -138.697333)
			(xy 39.710364 -138.746562) (xy 39.680302 -138.791902) (xy 39.643966 -138.832388) (xy 39.602129 -138.86716)
			(xy 39.55568 -138.895479) (xy 39.505607 -138.916742) (xy 39.452974 -138.930497) (xy 39.398901 -138.936453)
			(xy 39.344536 -138.934482) (xy 39.291035 -138.924626) (xy 39.239537 -138.907096) (xy 39.191135 -138.882262)
			(xy 39.146859 -138.850655) (xy 39.107649 -138.812944) (xy 39.074341 -138.769933) (xy 39.047641 -138.722536)
			(xy 39.028117 -138.671759) (xy 39.016184 -138.618683) (xy 39.012096 -138.564437) (xy 39.015941 -138.510172)
			(xy 39.027635 -138.457043) (xy 39.046931 -138.40618) (xy 39.073418 -138.358663) (xy 39.089584 -138.336782)
			(xy 39.10256 -138.319061) (xy 39.122942 -138.280162) (xy 39.13633 -138.238336) (xy 39.142324 -138.194832)
			(xy 39.140745 -138.150944) (xy 39.13164 -138.107983) (xy 39.115281 -138.067228) (xy 39.092155 -138.029894)
			(xy 39.0779 -138.013186) (xy 39.060207 -137.992523) (xy 39.030311 -137.94708) (xy 39.00734 -137.897773)
			(xy 38.991783 -137.84565) (xy 38.983972 -137.791819) (xy 38.71468 -137.791819) (xy 38.71468 -140.165328)
			(xy 38.971484 -140.165328) (xy 38.97546 -140.111002) (xy 38.987303 -140.057833) (xy 39.006762 -140.006956)
			(xy 39.033422 -139.959454) (xy 39.066713 -139.91634) (xy 39.105927 -139.878533) (xy 39.150229 -139.846838)
			(xy 39.198672 -139.821932) (xy 39.250226 -139.804344) (xy 39.303792 -139.79445) (xy 39.358227 -139.79246)
			(xy 39.412372 -139.798418) (xy 39.465072 -139.812196) (xy 39.515205 -139.8335) (xy 39.561701 -139.861876)
			(xy 39.603571 -139.89672) (xy 39.63992 -139.937289) (xy 39.669976 -139.982718) (xy 39.693097 -140.032039)
			(xy 39.70879 -140.084201) (xy 39.716721 -140.138092) (xy 39.717218 -140.165328) (xy 39.716721 -140.192564)
			(xy 39.70879 -140.246455) (xy 39.693097 -140.298617) (xy 39.669976 -140.347938) (xy 39.63992 -140.393367)
			(xy 39.603571 -140.433936) (xy 39.561701 -140.46878) (xy 39.515205 -140.497156) (xy 39.465072 -140.51846)
			(xy 39.412372 -140.532238) (xy 39.358227 -140.538196) (xy 39.303792 -140.536206) (xy 39.250226 -140.526312)
			(xy 39.198672 -140.508724) (xy 39.150229 -140.483818) (xy 39.105927 -140.452123) (xy 39.066713 -140.414316)
			(xy 39.033422 -140.371202) (xy 39.006762 -140.3237) (xy 38.987303 -140.272823) (xy 38.97546 -140.219654)
			(xy 38.971484 -140.165328) (xy 38.71468 -140.165328) (xy 38.71468 -140.49121) (xy 38.680898 -140.524992)
			(xy 35.56508 -140.524992) (xy 35.56508 -131.854956) (xy 35.564578 -131.832206) (xy 35.55648 -131.787432)
			(xy 35.540531 -131.744818) (xy 35.517244 -131.705729) (xy 35.487364 -131.671415) (xy 35.451846 -131.642976)
			(xy 35.411829 -131.621322) (xy 35.368594 -131.607145) (xy 35.346132 -131.603496) (xy 35.318242 -131.599096)
			(xy 35.264079 -131.58315) (xy 35.212856 -131.559399) (xy 35.165692 -131.52836) (xy 35.123615 -131.490711)
			(xy 35.087544 -131.447273) (xy 35.058267 -131.398996) (xy 35.036422 -131.346932) (xy 35.022486 -131.292217)
			(xy 35.016763 -131.236046) (xy 35.019378 -131.179646) (xy 35.030274 -131.124246) (xy 35.049214 -131.071055)
			(xy 35.075783 -131.021236) (xy 35.092132 -130.998214) (xy 35.105232 -130.979682) (xy 35.125332 -130.938998)
			(xy 35.137892 -130.895392) (xy 35.142512 -130.850249) (xy 35.139045 -130.805003) (xy 35.127602 -130.761091)
			(xy 35.108547 -130.719907) (xy 35.095942 -130.701034) (xy 35.08042 -130.678108) (xy 35.05545 -130.628696)
			(xy 35.037886 -130.576193) (xy 35.028097 -130.521702) (xy 35.02629 -130.466369) (xy 35.032501 -130.411355)
			(xy 35.046602 -130.357818) (xy 35.068294 -130.306882) (xy 35.097123 -130.259617) (xy 35.132483 -130.217017)
			(xy 35.173631 -130.179977) (xy 35.219701 -130.149276) (xy 35.269726 -130.125557) (xy 35.322655 -130.109321)
			(xy 35.349942 -130.104642) (xy 35.372125 -130.10071) (xy 35.414725 -130.086067) (xy 35.454078 -130.064143)
			(xy 35.488949 -130.035627) (xy 35.518249 -130.00141) (xy 35.541058 -129.962564) (xy 35.556662 -129.920307)
			(xy 35.564574 -129.87596) (xy 35.56508 -129.853436) (xy 35.56508 -128.08966) (xy 35.564532 -128.073016)
			(xy 35.555907 -128.040865) (xy 35.539255 -128.012041) (xy 35.515712 -127.988508) (xy 35.48688 -127.97187)
			(xy 35.454724 -127.96326) (xy 35.43808 -127.96266) (xy 30.62478 -127.96266) (xy 30.608131 -127.963205)
			(xy 30.57597 -127.971826) (xy 30.547133 -127.988475) (xy 30.523587 -128.012017) (xy 30.506934 -128.040851)
			(xy 30.498308 -128.073012) (xy 30.49778 -128.08966) (xy 30.49778 -130.565652) (xy 30.498272 -130.588292)
			(xy 30.50629 -130.632857) (xy 30.52208 -130.675295) (xy 30.545143 -130.714262) (xy 30.574748 -130.748523)
			(xy 30.609958 -130.776994) (xy 30.649656 -130.798773) (xy 30.692587 -130.813171) (xy 30.73739 -130.81973)
			(xy 30.782645 -130.818244) (xy 30.826921 -130.808759) (xy 30.848046 -130.800602) (xy 30.87387 -130.790565)
			(xy 30.927639 -130.777211) (xy 30.982775 -130.771774) (xy 31.038117 -130.774369) (xy 31.092502 -130.784941)
			(xy 31.144786 -130.803267) (xy 31.19387 -130.828963) (xy 31.238721 -130.861487) (xy 31.278396 -130.900157)
			(xy 31.312062 -130.944158) (xy 31.33901 -130.992565) (xy 31.358672 -131.044362) (xy 31.370637 -131.098457)
			(xy 31.374652 -131.153714) (xy 31.370633 -131.208971) (xy 31.358664 -131.263066) (xy 31.338997 -131.314861)
			(xy 31.312046 -131.363266) (xy 31.278377 -131.407265) (xy 31.238699 -131.445932) (xy 31.193845 -131.478453)
			(xy 31.144759 -131.504145) (xy 31.092474 -131.522467) (xy 31.038088 -131.533035) (xy 30.982746 -131.535625)
			(xy 30.927611 -131.530184) (xy 30.873842 -131.516826) (xy 30.848046 -131.506722) (xy 30.826912 -131.498604)
			(xy 30.782644 -131.489145) (xy 30.737401 -131.487676) (xy 30.692613 -131.494246) (xy 30.649697 -131.508646)
			(xy 30.61001 -131.530419) (xy 30.574808 -131.558879) (xy 30.545204 -131.593125) (xy 30.522135 -131.632073)
			(xy 30.50633 -131.674491) (xy 30.498289 -131.719039) (xy 30.49778 -131.741672) (xy 30.49778 -133.017514)
			(xy 31.184848 -133.017514) (xy 31.188919 -132.961892) (xy 31.201045 -132.907455) (xy 31.220968 -132.855364)
			(xy 31.248264 -132.806729) (xy 31.28235 -132.762586) (xy 31.322499 -132.723877) (xy 31.367857 -132.691426)
			(xy 31.417457 -132.665925) (xy 31.470241 -132.647918) (xy 31.525084 -132.637788) (xy 31.580818 -132.635751)
			(xy 31.636255 -132.641851) (xy 31.690212 -132.655957) (xy 31.741541 -132.677769) (xy 31.789147 -132.706823)
			(xy 31.832015 -132.742498) (xy 31.869232 -132.784035) (xy 31.900005 -132.830548) (xy 31.923677 -132.881045)
			(xy 31.939745 -132.934452) (xy 31.947865 -132.989628) (xy 31.948374 -133.017514) (xy 31.947865 -133.0454)
			(xy 31.939745 -133.100576) (xy 31.923677 -133.153983) (xy 31.900005 -133.20448) (xy 31.869232 -133.250993)
			(xy 31.832015 -133.29253) (xy 31.789147 -133.328205) (xy 31.741541 -133.357259) (xy 31.690212 -133.379071)
			(xy 31.636255 -133.393177) (xy 31.580818 -133.399277) (xy 31.525084 -133.39724) (xy 31.470241 -133.38711)
			(xy 31.417457 -133.369103) (xy 31.367857 -133.343602) (xy 31.322499 -133.311151) (xy 31.28235 -133.272442)
			(xy 31.248264 -133.228299) (xy 31.220968 -133.179664) (xy 31.201045 -133.127573) (xy 31.188919 -133.073136)
			(xy 31.184848 -133.017514) (xy 30.49778 -133.017514) (xy 30.49778 -139.70127) (xy 33.389822 -139.70127)
			(xy 33.393893 -139.645648) (xy 33.406019 -139.591211) (xy 33.425942 -139.53912) (xy 33.453238 -139.490485)
			(xy 33.487324 -139.446342) (xy 33.527473 -139.407633) (xy 33.572831 -139.375182) (xy 33.622431 -139.349681)
			(xy 33.675215 -139.331674) (xy 33.730058 -139.321544) (xy 33.785792 -139.319507) (xy 33.841229 -139.325607)
			(xy 33.895186 -139.339713) (xy 33.946515 -139.361525) (xy 33.994121 -139.390579) (xy 34.036989 -139.426254)
			(xy 34.074206 -139.467791) (xy 34.104979 -139.514304) (xy 34.128651 -139.564801) (xy 34.144719 -139.618208)
			(xy 34.152839 -139.673384) (xy 34.153348 -139.70127) (xy 34.152839 -139.729156) (xy 34.144719 -139.784332)
			(xy 34.128651 -139.837739) (xy 34.104979 -139.888236) (xy 34.074206 -139.934749) (xy 34.036989 -139.976286)
			(xy 33.994121 -140.011961) (xy 33.946515 -140.041015) (xy 33.895186 -140.062827) (xy 33.841229 -140.076933)
			(xy 33.785792 -140.083033) (xy 33.730058 -140.080996) (xy 33.675215 -140.070866) (xy 33.622431 -140.052859)
			(xy 33.572831 -140.027358) (xy 33.527473 -139.994907) (xy 33.487324 -139.956198) (xy 33.453238 -139.912055)
			(xy 33.425942 -139.86342) (xy 33.406019 -139.811329) (xy 33.393893 -139.756892) (xy 33.389822 -139.70127)
			(xy 30.49778 -139.70127) (xy 30.49778 -141.75486) (xy 31.454342 -141.75486) (xy 31.458413 -141.699238)
			(xy 31.470539 -141.644801) (xy 31.490462 -141.59271) (xy 31.517758 -141.544075) (xy 31.551844 -141.499932)
			(xy 31.591993 -141.461223) (xy 31.637351 -141.428772) (xy 31.686951 -141.403271) (xy 31.739735 -141.385264)
			(xy 31.794578 -141.375134) (xy 31.850312 -141.373097) (xy 31.905749 -141.379197) (xy 31.959706 -141.393303)
			(xy 32.011035 -141.415115) (xy 32.058641 -141.444169) (xy 32.101509 -141.479844) (xy 32.138726 -141.521381)
			(xy 32.169499 -141.567894) (xy 32.193171 -141.618391) (xy 32.209239 -141.671798) (xy 32.217359 -141.726974)
			(xy 32.217868 -141.75486) (xy 32.217359 -141.782746) (xy 32.209239 -141.837922) (xy 32.193171 -141.891329)
			(xy 32.169499 -141.941826) (xy 32.138726 -141.988339) (xy 32.101509 -142.029876) (xy 32.058641 -142.065551)
			(xy 32.011035 -142.094605) (xy 31.959706 -142.116417) (xy 31.905749 -142.130523) (xy 31.850312 -142.136623)
			(xy 31.794578 -142.134586) (xy 31.739735 -142.124456) (xy 31.686951 -142.106449) (xy 31.637351 -142.080948)
			(xy 31.591993 -142.048497) (xy 31.551844 -142.009788) (xy 31.517758 -141.965645) (xy 31.490462 -141.91701)
			(xy 31.470539 -141.864919) (xy 31.458413 -141.810482) (xy 31.454342 -141.75486) (xy 30.49778 -141.75486)
			(xy 30.49778 -142.472918) (xy 30.557721 -142.532862) (xy 39.015668 -142.532862) (xy 39.019739 -142.47724)
			(xy 39.031865 -142.422803) (xy 39.051788 -142.370712) (xy 39.079084 -142.322077) (xy 39.11317 -142.277934)
			(xy 39.153319 -142.239225) (xy 39.198677 -142.206774) (xy 39.248277 -142.181273) (xy 39.301061 -142.163266)
			(xy 39.355904 -142.153136) (xy 39.411638 -142.151099) (xy 39.467075 -142.157199) (xy 39.521032 -142.171305)
			(xy 39.572361 -142.193117) (xy 39.619967 -142.222171) (xy 39.662835 -142.257846) (xy 39.700052 -142.299383)
			(xy 39.730825 -142.345896) (xy 39.754497 -142.396393) (xy 39.770565 -142.4498) (xy 39.778685 -142.504976)
			(xy 39.779194 -142.532862) (xy 39.778685 -142.560748) (xy 39.770565 -142.615924) (xy 39.754497 -142.669331)
			(xy 39.730825 -142.719828) (xy 39.700052 -142.766341) (xy 39.662835 -142.807878) (xy 39.619967 -142.843553)
			(xy 39.572361 -142.872607) (xy 39.521032 -142.894419) (xy 39.467075 -142.908525) (xy 39.411638 -142.914625)
			(xy 39.355904 -142.912588) (xy 39.301061 -142.902458) (xy 39.248277 -142.884451) (xy 39.198677 -142.85895)
			(xy 39.153319 -142.826499) (xy 39.11317 -142.78779) (xy 39.079084 -142.743647) (xy 39.051788 -142.695012)
			(xy 39.031865 -142.642921) (xy 39.019739 -142.588484) (xy 39.015668 -142.532862) (xy 30.557721 -142.532862)
			(xy 32.407766 -144.382998) (xy 39.859202 -144.382998) (xy 39.863273 -144.327376) (xy 39.875399 -144.272939)
			(xy 39.895322 -144.220848) (xy 39.922618 -144.172213) (xy 39.956704 -144.12807) (xy 39.996853 -144.089361)
			(xy 40.042211 -144.05691) (xy 40.091811 -144.031409) (xy 40.144595 -144.013402) (xy 40.199438 -144.003272)
			(xy 40.255172 -144.001235) (xy 40.310609 -144.007335) (xy 40.364566 -144.021441) (xy 40.415895 -144.043253)
			(xy 40.463501 -144.072307) (xy 40.506369 -144.107982) (xy 40.543586 -144.149519) (xy 40.574359 -144.196032)
			(xy 40.598031 -144.246529) (xy 40.614099 -144.299936) (xy 40.622219 -144.355112) (xy 40.622728 -144.382998)
			(xy 40.622219 -144.410884) (xy 40.620267 -144.424146) (xy 40.965626 -144.424146) (xy 40.969697 -144.368524)
			(xy 40.981823 -144.314087) (xy 41.001746 -144.261996) (xy 41.029042 -144.213361) (xy 41.063128 -144.169218)
			(xy 41.103277 -144.130509) (xy 41.148635 -144.098058) (xy 41.198235 -144.072557) (xy 41.251019 -144.05455)
			(xy 41.305862 -144.04442) (xy 41.361596 -144.042383) (xy 41.417033 -144.048483) (xy 41.47099 -144.062589)
			(xy 41.522319 -144.084401) (xy 41.569925 -144.113455) (xy 41.612793 -144.14913) (xy 41.65001 -144.190667)
			(xy 41.680783 -144.23718) (xy 41.704455 -144.287677) (xy 41.720523 -144.341084) (xy 41.728643 -144.39626)
			(xy 41.729152 -144.424146) (xy 41.728643 -144.452032) (xy 41.720523 -144.507208) (xy 41.71059 -144.540224)
			(xy 41.981626 -144.540224) (xy 41.985697 -144.484602) (xy 41.997823 -144.430165) (xy 42.017746 -144.378074)
			(xy 42.045042 -144.329439) (xy 42.079128 -144.285296) (xy 42.119277 -144.246587) (xy 42.164635 -144.214136)
			(xy 42.214235 -144.188635) (xy 42.267019 -144.170628) (xy 42.321862 -144.160498) (xy 42.377596 -144.158461)
			(xy 42.433033 -144.164561) (xy 42.48699 -144.178667) (xy 42.538319 -144.200479) (xy 42.585925 -144.229533)
			(xy 42.628793 -144.265208) (xy 42.66601 -144.306745) (xy 42.696783 -144.353258) (xy 42.720455 -144.403755)
			(xy 42.736523 -144.457162) (xy 42.744643 -144.512338) (xy 42.745152 -144.540224) (xy 42.744643 -144.56811)
			(xy 42.736523 -144.623286) (xy 42.734384 -144.630394) (xy 43.065444 -144.630394) (xy 43.069515 -144.574772)
			(xy 43.081641 -144.520335) (xy 43.101564 -144.468244) (xy 43.12886 -144.419609) (xy 43.162946 -144.375466)
			(xy 43.203095 -144.336757) (xy 43.248453 -144.304306) (xy 43.298053 -144.278805) (xy 43.350837 -144.260798)
			(xy 43.40568 -144.250668) (xy 43.461414 -144.248631) (xy 43.516851 -144.254731) (xy 43.570808 -144.268837)
			(xy 43.622137 -144.290649) (xy 43.669743 -144.319703) (xy 43.712611 -144.355378) (xy 43.749828 -144.396915)
			(xy 43.780601 -144.443428) (xy 43.804273 -144.493925) (xy 43.820341 -144.547332) (xy 43.828461 -144.602508)
			(xy 43.82897 -144.630394) (xy 43.828461 -144.65828) (xy 43.825911 -144.675606) (xy 44.166026 -144.675606)
			(xy 44.170097 -144.619984) (xy 44.182223 -144.565547) (xy 44.202146 -144.513456) (xy 44.229442 -144.464821)
			(xy 44.263528 -144.420678) (xy 44.303677 -144.381969) (xy 44.349035 -144.349518) (xy 44.398635 -144.324017)
			(xy 44.451419 -144.30601) (xy 44.506262 -144.29588) (xy 44.561996 -144.293843) (xy 44.617433 -144.299943)
			(xy 44.67139 -144.314049) (xy 44.722719 -144.335861) (xy 44.770325 -144.364915) (xy 44.813193 -144.40059)
			(xy 44.85041 -144.442127) (xy 44.881183 -144.48864) (xy 44.892862 -144.513554) (xy 45.271942 -144.513554)
			(xy 45.276013 -144.457932) (xy 45.288139 -144.403495) (xy 45.308062 -144.351404) (xy 45.335358 -144.302769)
			(xy 45.369444 -144.258626) (xy 45.409593 -144.219917) (xy 45.454951 -144.187466) (xy 45.504551 -144.161965)
			(xy 45.557335 -144.143958) (xy 45.612178 -144.133828) (xy 45.667912 -144.131791) (xy 45.723349 -144.137891)
			(xy 45.777306 -144.151997) (xy 45.828635 -144.173809) (xy 45.876241 -144.202863) (xy 45.919109 -144.238538)
			(xy 45.956326 -144.280075) (xy 45.987099 -144.326588) (xy 46.010771 -144.377085) (xy 46.026839 -144.430492)
			(xy 46.034959 -144.485668) (xy 46.035468 -144.513554) (xy 46.034959 -144.54144) (xy 46.026839 -144.596616)
			(xy 46.010771 -144.650023) (xy 45.987099 -144.70052) (xy 45.956326 -144.747033) (xy 45.919109 -144.78857)
			(xy 45.876241 -144.824245) (xy 45.828635 -144.853299) (xy 45.777306 -144.875111) (xy 45.723349 -144.889217)
			(xy 45.667912 -144.895317) (xy 45.612178 -144.89328) (xy 45.557335 -144.88315) (xy 45.504551 -144.865143)
			(xy 45.454951 -144.839642) (xy 45.409593 -144.807191) (xy 45.369444 -144.768482) (xy 45.335358 -144.724339)
			(xy 45.308062 -144.675704) (xy 45.288139 -144.623613) (xy 45.276013 -144.569176) (xy 45.271942 -144.513554)
			(xy 44.892862 -144.513554) (xy 44.904855 -144.539137) (xy 44.920923 -144.592544) (xy 44.929043 -144.64772)
			(xy 44.929552 -144.675606) (xy 44.929043 -144.703492) (xy 44.920923 -144.758668) (xy 44.904855 -144.812075)
			(xy 44.881183 -144.862572) (xy 44.85041 -144.909085) (xy 44.813193 -144.950622) (xy 44.770325 -144.986297)
			(xy 44.722719 -145.015351) (xy 44.67139 -145.037163) (xy 44.617433 -145.051269) (xy 44.561996 -145.057369)
			(xy 44.506262 -145.055332) (xy 44.451419 -145.045202) (xy 44.398635 -145.027195) (xy 44.349035 -145.001694)
			(xy 44.303677 -144.969243) (xy 44.263528 -144.930534) (xy 44.229442 -144.886391) (xy 44.202146 -144.837756)
			(xy 44.182223 -144.785665) (xy 44.170097 -144.731228) (xy 44.166026 -144.675606) (xy 43.825911 -144.675606)
			(xy 43.820341 -144.713456) (xy 43.804273 -144.766863) (xy 43.780601 -144.81736) (xy 43.749828 -144.863873)
			(xy 43.712611 -144.90541) (xy 43.669743 -144.941085) (xy 43.622137 -144.970139) (xy 43.570808 -144.991951)
			(xy 43.516851 -145.006057) (xy 43.461414 -145.012157) (xy 43.40568 -145.01012) (xy 43.350837 -144.99999)
			(xy 43.298053 -144.981983) (xy 43.248453 -144.956482) (xy 43.203095 -144.924031) (xy 43.162946 -144.885322)
			(xy 43.12886 -144.841179) (xy 43.101564 -144.792544) (xy 43.081641 -144.740453) (xy 43.069515 -144.686016)
			(xy 43.065444 -144.630394) (xy 42.734384 -144.630394) (xy 42.720455 -144.676693) (xy 42.696783 -144.72719)
			(xy 42.66601 -144.773703) (xy 42.628793 -144.81524) (xy 42.585925 -144.850915) (xy 42.538319 -144.879969)
			(xy 42.48699 -144.901781) (xy 42.433033 -144.915887) (xy 42.377596 -144.921987) (xy 42.321862 -144.91995)
			(xy 42.267019 -144.90982) (xy 42.214235 -144.891813) (xy 42.164635 -144.866312) (xy 42.119277 -144.833861)
			(xy 42.079128 -144.795152) (xy 42.045042 -144.751009) (xy 42.017746 -144.702374) (xy 41.997823 -144.650283)
			(xy 41.985697 -144.595846) (xy 41.981626 -144.540224) (xy 41.71059 -144.540224) (xy 41.704455 -144.560615)
			(xy 41.680783 -144.611112) (xy 41.65001 -144.657625) (xy 41.612793 -144.699162) (xy 41.569925 -144.734837)
			(xy 41.522319 -144.763891) (xy 41.47099 -144.785703) (xy 41.417033 -144.799809) (xy 41.361596 -144.805909)
			(xy 41.305862 -144.803872) (xy 41.251019 -144.793742) (xy 41.198235 -144.775735) (xy 41.148635 -144.750234)
			(xy 41.103277 -144.717783) (xy 41.063128 -144.679074) (xy 41.029042 -144.634931) (xy 41.001746 -144.586296)
			(xy 40.981823 -144.534205) (xy 40.969697 -144.479768) (xy 40.965626 -144.424146) (xy 40.620267 -144.424146)
			(xy 40.614099 -144.46606) (xy 40.598031 -144.519467) (xy 40.574359 -144.569964) (xy 40.543586 -144.616477)
			(xy 40.506369 -144.658014) (xy 40.463501 -144.693689) (xy 40.415895 -144.722743) (xy 40.364566 -144.744555)
			(xy 40.310609 -144.758661) (xy 40.255172 -144.764761) (xy 40.199438 -144.762724) (xy 40.144595 -144.752594)
			(xy 40.091811 -144.734587) (xy 40.042211 -144.709086) (xy 39.996853 -144.676635) (xy 39.956704 -144.637926)
			(xy 39.922618 -144.593783) (xy 39.895322 -144.545148) (xy 39.875399 -144.493057) (xy 39.863273 -144.43862)
			(xy 39.859202 -144.382998) (xy 32.407766 -144.382998) (xy 33.617483 -145.592775) (xy 36.004739 -145.592775)
			(xy 36.005267 -145.537539) (xy 36.013756 -145.482956) (xy 36.030028 -145.430168) (xy 36.053744 -145.380278)
			(xy 36.084406 -145.334331) (xy 36.121374 -145.293286) (xy 36.163876 -145.258002) (xy 36.211022 -145.229216)
			(xy 36.261826 -145.20753) (xy 36.315227 -145.193399) (xy 36.370108 -145.187117) (xy 36.425321 -145.188815)
			(xy 36.479712 -145.198459) (xy 36.532143 -145.215846) (xy 36.581519 -145.240612) (xy 36.626807 -145.272241)
			(xy 36.667059 -145.310071) (xy 36.701435 -145.353311) (xy 36.729215 -145.401056) (xy 36.749819 -145.452309)
			(xy 36.762816 -145.505997) (xy 36.767934 -145.560999) (xy 36.765067 -145.616163) (xy 36.76015 -145.643346)
			(xy 36.758256 -145.654094) (xy 47.536273 -145.654094) (xy 47.538632 -145.598436) (xy 47.549058 -145.543713)
			(xy 47.567331 -145.491087) (xy 47.593061 -145.441678) (xy 47.625702 -145.396535) (xy 47.66456 -145.356618)
			(xy 47.708809 -145.322775) (xy 47.757509 -145.295725) (xy 47.809624 -145.276045) (xy 47.864048 -145.264151)
			(xy 47.919622 -145.260297) (xy 47.975166 -145.264564) (xy 48.002444 -145.27022) (xy 48.02395 -145.274608)
			(xy 48.067783 -145.276795) (xy 48.11134 -145.271418) (xy 48.153325 -145.258636) (xy 48.19249 -145.238831)
			(xy 48.227669 -145.21259) (xy 48.257816 -145.180695) (xy 48.282033 -145.144094) (xy 48.291242 -145.12417)
			(xy 48.302884 -145.098861) (xy 48.332352 -145.051586) (xy 48.368381 -145.009099) (xy 48.410205 -144.972303)
			(xy 48.456935 -144.94198) (xy 48.507577 -144.918773) (xy 48.561056 -144.903177) (xy 48.616235 -144.895524)
			(xy 48.671939 -144.895975) (xy 48.726986 -144.904522) (xy 48.780205 -144.920982) (xy 48.830465 -144.945005)
			(xy 48.876698 -144.976082) (xy 48.898501 -144.9959) (xy 54.631842 -144.9959) (xy 54.635913 -144.940278)
			(xy 54.648039 -144.885841) (xy 54.667962 -144.83375) (xy 54.695258 -144.785115) (xy 54.729344 -144.740972)
			(xy 54.769493 -144.702263) (xy 54.814851 -144.669812) (xy 54.864451 -144.644311) (xy 54.917235 -144.626304)
			(xy 54.972078 -144.616174) (xy 55.027812 -144.614137) (xy 55.083249 -144.620237) (xy 55.137206 -144.634343)
			(xy 55.188535 -144.656155) (xy 55.236141 -144.685209) (xy 55.279009 -144.720884) (xy 55.316226 -144.762421)
			(xy 55.346999 -144.808934) (xy 55.370671 -144.859431) (xy 55.386739 -144.912838) (xy 55.394859 -144.968014)
			(xy 55.395368 -144.9959) (xy 55.394859 -145.023786) (xy 55.386739 -145.078962) (xy 55.370671 -145.132369)
			(xy 55.346999 -145.182866) (xy 55.316226 -145.229379) (xy 55.279009 -145.270916) (xy 55.236141 -145.306591)
			(xy 55.188535 -145.335645) (xy 55.137206 -145.357457) (xy 55.083249 -145.371563) (xy 55.027812 -145.377663)
			(xy 54.972078 -145.375626) (xy 54.917235 -145.365496) (xy 54.864451 -145.347489) (xy 54.814851 -145.321988)
			(xy 54.769493 -145.289537) (xy 54.729344 -145.250828) (xy 54.695258 -145.206685) (xy 54.667962 -145.15805)
			(xy 54.648039 -145.105959) (xy 54.635913 -145.051522) (xy 54.631842 -144.9959) (xy 48.898501 -144.9959)
			(xy 48.91792 -145.013551) (xy 48.953256 -145.056616) (xy 48.981954 -145.104362) (xy 49.003405 -145.155773)
			(xy 49.017151 -145.209756) (xy 49.022902 -145.265165) (xy 49.020535 -145.320821) (xy 49.0101 -145.375542)
			(xy 48.991819 -145.428163) (xy 48.96608 -145.477567) (xy 48.939133 -145.514822) (xy 49.841402 -145.514822)
			(xy 49.845473 -145.4592) (xy 49.857599 -145.404763) (xy 49.877522 -145.352672) (xy 49.904818 -145.304037)
			(xy 49.938904 -145.259894) (xy 49.979053 -145.221185) (xy 50.024411 -145.188734) (xy 50.074011 -145.163233)
			(xy 50.126795 -145.145226) (xy 50.181638 -145.135096) (xy 50.237372 -145.133059) (xy 50.292809 -145.139159)
			(xy 50.346766 -145.153265) (xy 50.398095 -145.175077) (xy 50.445701 -145.204131) (xy 50.488569 -145.239806)
			(xy 50.525786 -145.281343) (xy 50.556559 -145.327856) (xy 50.580231 -145.378353) (xy 50.596299 -145.43176)
			(xy 50.604419 -145.486936) (xy 50.604928 -145.514822) (xy 53.272942 -145.514822) (xy 53.277013 -145.4592)
			(xy 53.289139 -145.404763) (xy 53.309062 -145.352672) (xy 53.336358 -145.304037) (xy 53.370444 -145.259894)
			(xy 53.410593 -145.221185) (xy 53.455951 -145.188734) (xy 53.505551 -145.163233) (xy 53.558335 -145.145226)
			(xy 53.613178 -145.135096) (xy 53.668912 -145.133059) (xy 53.724349 -145.139159) (xy 53.778306 -145.153265)
			(xy 53.829635 -145.175077) (xy 53.877241 -145.204131) (xy 53.920109 -145.239806) (xy 53.957326 -145.281343)
			(xy 53.988099 -145.327856) (xy 54.011771 -145.378353) (xy 54.027839 -145.43176) (xy 54.035959 -145.486936)
			(xy 54.036468 -145.514822) (xy 54.035959 -145.542708) (xy 54.027839 -145.597884) (xy 54.011771 -145.651291)
			(xy 53.988099 -145.701788) (xy 53.957326 -145.748301) (xy 53.920109 -145.789838) (xy 53.877241 -145.825513)
			(xy 53.829635 -145.854567) (xy 53.778306 -145.876379) (xy 53.724349 -145.890485) (xy 53.668912 -145.896585)
			(xy 53.613178 -145.894548) (xy 53.558335 -145.884418) (xy 53.505551 -145.866411) (xy 53.455951 -145.84091)
			(xy 53.410593 -145.808459) (xy 53.370444 -145.76975) (xy 53.336358 -145.725607) (xy 53.309062 -145.676972)
			(xy 53.289139 -145.624881) (xy 53.277013 -145.570444) (xy 53.272942 -145.514822) (xy 50.604928 -145.514822)
			(xy 50.604419 -145.542708) (xy 50.596299 -145.597884) (xy 50.580231 -145.651291) (xy 50.556559 -145.701788)
			(xy 50.525786 -145.748301) (xy 50.488569 -145.789838) (xy 50.445701 -145.825513) (xy 50.398095 -145.854567)
			(xy 50.346766 -145.876379) (xy 50.292809 -145.890485) (xy 50.237372 -145.896585) (xy 50.181638 -145.894548)
			(xy 50.126795 -145.884418) (xy 50.074011 -145.866411) (xy 50.024411 -145.84091) (xy 49.979053 -145.808459)
			(xy 49.938904 -145.76975) (xy 49.904818 -145.725607) (xy 49.877522 -145.676972) (xy 49.857599 -145.624881)
			(xy 49.845473 -145.570444) (xy 49.841402 -145.514822) (xy 48.939133 -145.514822) (xy 48.933432 -145.522703)
			(xy 48.894567 -145.562612) (xy 48.850312 -145.596446) (xy 48.801607 -145.623484) (xy 48.749489 -145.643154)
			(xy 48.695064 -145.655035) (xy 48.63949 -145.658877) (xy 48.583948 -145.654596) (xy 48.556672 -145.648934)
			(xy 48.535159 -145.644589) (xy 48.49133 -145.642401) (xy 48.447778 -145.647774) (xy 48.405796 -145.660551)
			(xy 48.366633 -145.680351) (xy 48.331455 -145.706584) (xy 48.301307 -145.738471) (xy 48.277085 -145.775064)
			(xy 48.267874 -145.794984) (xy 48.256344 -145.820343) (xy 48.226877 -145.867619) (xy 48.190849 -145.910108)
			(xy 48.149025 -145.946907) (xy 48.102296 -145.977234) (xy 48.051654 -146.000443) (xy 47.998175 -146.016043)
			(xy 47.942996 -146.0237) (xy 47.88729 -146.023254) (xy 47.832241 -146.014712) (xy 47.779019 -145.998256)
			(xy 47.728756 -145.974237) (xy 47.682519 -145.943165) (xy 47.641292 -145.905699) (xy 47.60595 -145.862638)
			(xy 47.577245 -145.814895) (xy 47.555787 -145.763486) (xy 47.542032 -145.709503) (xy 47.536273 -145.654094)
			(xy 36.758256 -145.654094) (xy 36.756041 -145.666665) (xy 36.755562 -145.714007) (xy 36.763856 -145.760619)
			(xy 36.780637 -145.80489) (xy 36.805324 -145.845288) (xy 36.837063 -145.880418) (xy 36.874758 -145.909064)
			(xy 36.917105 -145.930236) (xy 36.939728 -145.937224) (xy 36.966139 -145.945335) (xy 37.016528 -145.967987)
			(xy 37.063123 -145.99767) (xy 37.10495 -146.033762) (xy 37.141134 -146.07551) (xy 37.170918 -146.122041)
			(xy 37.193679 -146.17238) (xy 37.208942 -146.225476) (xy 37.216388 -146.280218) (xy 37.21586 -146.335462)
			(xy 37.20737 -146.390052) (xy 37.191095 -146.442847) (xy 37.167376 -146.492742) (xy 37.136708 -146.538695)
			(xy 37.099734 -146.579744) (xy 37.057225 -146.615031) (xy 37.010071 -146.643818) (xy 36.959259 -146.665503)
			(xy 36.90585 -146.679633) (xy 36.850962 -146.685912) (xy 36.795742 -146.684208) (xy 36.741345 -146.674558)
			(xy 36.688908 -146.657164) (xy 36.639529 -146.632388) (xy 36.594239 -146.600749) (xy 36.553986 -146.56291)
			(xy 36.519612 -146.51966) (xy 36.491835 -146.471904) (xy 36.471236 -146.420642) (xy 36.458246 -146.366944)
			(xy 36.453137 -146.311935) (xy 36.456015 -146.256763) (xy 36.460938 -146.229578) (xy 36.46503 -146.206257)
			(xy 36.465513 -146.158916) (xy 36.457222 -146.112304) (xy 36.440444 -146.068033) (xy 36.41576 -146.027635)
			(xy 36.384022 -145.992505) (xy 36.346329 -145.963859) (xy 36.303983 -145.942688) (xy 36.28136 -145.9357)
			(xy 36.254941 -145.927629) (xy 36.20456 -145.904976) (xy 36.157974 -145.875294) (xy 36.116154 -145.839204)
			(xy 36.079978 -145.797459) (xy 36.050199 -145.750934) (xy 36.027443 -145.7006) (xy 36.012183 -145.647511)
			(xy 36.004739 -145.592775) (xy 33.617483 -145.592775) (xy 34.78966 -146.76501) (xy 38.769542 -146.76501)
			(xy 38.773613 -146.709388) (xy 38.785739 -146.654951) (xy 38.805662 -146.60286) (xy 38.832958 -146.554225)
			(xy 38.867044 -146.510082) (xy 38.907193 -146.471373) (xy 38.952551 -146.438922) (xy 39.002151 -146.413421)
			(xy 39.054935 -146.395414) (xy 39.109778 -146.385284) (xy 39.165512 -146.383247) (xy 39.220949 -146.389347)
			(xy 39.274906 -146.403453) (xy 39.326235 -146.425265) (xy 39.373841 -146.454319) (xy 39.416709 -146.489994)
			(xy 39.45147 -146.52879) (xy 50.801522 -146.52879) (xy 50.805593 -146.473168) (xy 50.817719 -146.418731)
			(xy 50.837642 -146.36664) (xy 50.864938 -146.318005) (xy 50.899024 -146.273862) (xy 50.939173 -146.235153)
			(xy 50.984531 -146.202702) (xy 51.034131 -146.177201) (xy 51.086915 -146.159194) (xy 51.141758 -146.149064)
			(xy 51.197492 -146.147027) (xy 51.252929 -146.153127) (xy 51.306886 -146.167233) (xy 51.358215 -146.189045)
			(xy 51.405821 -146.218099) (xy 51.448689 -146.253774) (xy 51.485906 -146.295311) (xy 51.516679 -146.341824)
			(xy 51.540351 -146.392321) (xy 51.556419 -146.445728) (xy 51.564539 -146.500904) (xy 51.565048 -146.52879)
			(xy 51.565011 -146.530822) (xy 52.968142 -146.530822) (xy 52.972213 -146.4752) (xy 52.984339 -146.420763)
			(xy 53.004262 -146.368672) (xy 53.031558 -146.320037) (xy 53.065644 -146.275894) (xy 53.105793 -146.237185)
			(xy 53.151151 -146.204734) (xy 53.200751 -146.179233) (xy 53.253535 -146.161226) (xy 53.308378 -146.151096)
			(xy 53.364112 -146.149059) (xy 53.419549 -146.155159) (xy 53.473506 -146.169265) (xy 53.524835 -146.191077)
			(xy 53.572441 -146.220131) (xy 53.615309 -146.255806) (xy 53.652526 -146.297343) (xy 53.683299 -146.343856)
			(xy 53.706971 -146.394353) (xy 53.718823 -146.433748) (xy 61.318455 -146.433748) (xy 61.32334 -146.379585)
			(xy 61.335868 -146.326665) (xy 61.355782 -146.27606) (xy 61.382681 -146.228796) (xy 61.416018 -146.18583)
			(xy 61.435234 -146.166586) (xy 61.447424 -146.154035) (xy 61.465093 -146.123853) (xy 61.473902 -146.090007)
			(xy 61.473189 -146.055041) (xy 61.463008 -146.021582) (xy 61.45403 -146.006566) (xy 61.439628 -145.983244)
			(xy 61.416928 -145.933353) (xy 61.401602 -145.880727) (xy 61.393965 -145.826449) (xy 61.394174 -145.771637)
			(xy 61.402226 -145.71742) (xy 61.417954 -145.664912) (xy 61.441035 -145.615196) (xy 61.470992 -145.569295)
			(xy 61.507211 -145.528153) (xy 61.548944 -145.492619) (xy 61.595334 -145.463422) (xy 61.645424 -145.441165)
			(xy 61.698184 -145.426306) (xy 61.752527 -145.41915) (xy 61.807335 -145.419845) (xy 61.861479 -145.428377)
			(xy 61.913846 -145.444569) (xy 61.963355 -145.468089) (xy 62.008989 -145.498452) (xy 62.049809 -145.535033)
			(xy 62.084972 -145.57708) (xy 62.113757 -145.623726) (xy 62.125098 -145.64868) (xy 62.132188 -145.663868)
			(xy 62.153083 -145.690067) (xy 62.180085 -145.709914) (xy 62.211327 -145.722035) (xy 62.244649 -145.725593)
			(xy 62.277746 -145.720341) (xy 62.293246 -145.713958) (xy 62.319016 -145.703028) (xy 62.372927 -145.687967)
			(xy 62.42846 -145.680944) (xy 62.484423 -145.682111) (xy 62.539615 -145.691442) (xy 62.592851 -145.708736)
			(xy 62.64299 -145.733623) (xy 62.688954 -145.765569) (xy 62.729757 -145.803887) (xy 62.76437 -145.847562)
			(xy 66.62115 -145.847562) (xy 66.625221 -145.79194) (xy 66.637347 -145.737503) (xy 66.65727 -145.685412)
			(xy 66.684566 -145.636777) (xy 66.718652 -145.592634) (xy 66.758801 -145.553925) (xy 66.804159 -145.521474)
			(xy 66.853759 -145.495973) (xy 66.906543 -145.477966) (xy 66.961386 -145.467836) (xy 67.01712 -145.465799)
			(xy 67.072557 -145.471899) (xy 67.126514 -145.486005) (xy 67.177843 -145.507817) (xy 67.225449 -145.536871)
			(xy 67.268317 -145.572546) (xy 67.305534 -145.614083) (xy 67.336307 -145.660596) (xy 67.359979 -145.711093)
			(xy 67.376047 -145.7645) (xy 67.384167 -145.819676) (xy 67.384676 -145.847562) (xy 67.384167 -145.875448)
			(xy 67.376047 -145.930624) (xy 67.366649 -145.961862) (xy 69.292468 -145.961862) (xy 69.296539 -145.90624)
			(xy 69.308665 -145.851803) (xy 69.328588 -145.799712) (xy 69.355884 -145.751077) (xy 69.38997 -145.706934)
			(xy 69.430119 -145.668225) (xy 69.475477 -145.635774) (xy 69.525077 -145.610273) (xy 69.577861 -145.592266)
			(xy 69.632704 -145.582136) (xy 69.688438 -145.580099) (xy 69.743875 -145.586199) (xy 69.797832 -145.600305)
			(xy 69.849161 -145.622117) (xy 69.896767 -145.651171) (xy 69.939635 -145.686846) (xy 69.976852 -145.728383)
			(xy 70.007625 -145.774896) (xy 70.031297 -145.825393) (xy 70.047365 -145.8788) (xy 70.051739 -145.908522)
			(xy 70.651114 -145.908522) (xy 70.655185 -145.8529) (xy 70.667311 -145.798463) (xy 70.687234 -145.746372)
			(xy 70.71453 -145.697737) (xy 70.748616 -145.653594) (xy 70.788765 -145.614885) (xy 70.834123 -145.582434)
			(xy 70.883723 -145.556933) (xy 70.936507 -145.538926) (xy 70.99135 -145.528796) (xy 71.047084 -145.526759)
			(xy 71.102521 -145.532859) (xy 71.156478 -145.546965) (xy 71.207807 -145.568777) (xy 71.255413 -145.597831)
			(xy 71.298281 -145.633506) (xy 71.335498 -145.675043) (xy 71.366271 -145.721556) (xy 71.389943 -145.772053)
			(xy 71.406011 -145.82546) (xy 71.414131 -145.880636) (xy 71.41464 -145.908522) (xy 71.414131 -145.936408)
			(xy 71.406011 -145.991584) (xy 71.389943 -146.044991) (xy 71.366271 -146.095488) (xy 71.335498 -146.142001)
			(xy 71.298281 -146.183538) (xy 71.258219 -146.216878) (xy 84.97646 -146.216878) (xy 84.980531 -146.161256)
			(xy 84.992657 -146.106819) (xy 85.01258 -146.054728) (xy 85.039876 -146.006093) (xy 85.073962 -145.96195)
			(xy 85.114111 -145.923241) (xy 85.159469 -145.89079) (xy 85.209069 -145.865289) (xy 85.261853 -145.847282)
			(xy 85.316696 -145.837152) (xy 85.37243 -145.835115) (xy 85.427867 -145.841215) (xy 85.481824 -145.855321)
			(xy 85.533153 -145.877133) (xy 85.580759 -145.906187) (xy 85.623627 -145.941862) (xy 85.660844 -145.983399)
			(xy 85.691617 -146.029912) (xy 85.715289 -146.080409) (xy 85.731357 -146.133816) (xy 85.739477 -146.188992)
			(xy 85.739986 -146.216878) (xy 85.739477 -146.244764) (xy 85.731357 -146.29994) (xy 85.715289 -146.353347)
			(xy 85.691617 -146.403844) (xy 85.660844 -146.450357) (xy 85.623627 -146.491894) (xy 85.580759 -146.527569)
			(xy 85.533153 -146.556623) (xy 85.481824 -146.578435) (xy 85.427867 -146.592541) (xy 85.37243 -146.598641)
			(xy 85.316696 -146.596604) (xy 85.261853 -146.586474) (xy 85.209069 -146.568467) (xy 85.159469 -146.542966)
			(xy 85.114111 -146.510515) (xy 85.073962 -146.471806) (xy 85.039876 -146.427663) (xy 85.01258 -146.379028)
			(xy 84.992657 -146.326937) (xy 84.980531 -146.2725) (xy 84.97646 -146.216878) (xy 71.258219 -146.216878)
			(xy 71.255413 -146.219213) (xy 71.207807 -146.248267) (xy 71.156478 -146.270079) (xy 71.102521 -146.284185)
			(xy 71.047084 -146.290285) (xy 70.99135 -146.288248) (xy 70.936507 -146.278118) (xy 70.883723 -146.260111)
			(xy 70.834123 -146.23461) (xy 70.788765 -146.202159) (xy 70.748616 -146.16345) (xy 70.71453 -146.119307)
			(xy 70.687234 -146.070672) (xy 70.667311 -146.018581) (xy 70.655185 -145.964144) (xy 70.651114 -145.908522)
			(xy 70.051739 -145.908522) (xy 70.055485 -145.933976) (xy 70.055994 -145.961862) (xy 70.055485 -145.989748)
			(xy 70.047365 -146.044924) (xy 70.031297 -146.098331) (xy 70.007625 -146.148828) (xy 69.976852 -146.195341)
			(xy 69.939635 -146.236878) (xy 69.896767 -146.272553) (xy 69.849161 -146.301607) (xy 69.797832 -146.323419)
			(xy 69.743875 -146.337525) (xy 69.688438 -146.343625) (xy 69.632704 -146.341588) (xy 69.577861 -146.331458)
			(xy 69.525077 -146.313451) (xy 69.475477 -146.28795) (xy 69.430119 -146.255499) (xy 69.38997 -146.21679)
			(xy 69.355884 -146.172647) (xy 69.328588 -146.124012) (xy 69.308665 -146.071921) (xy 69.296539 -146.017484)
			(xy 69.292468 -145.961862) (xy 67.366649 -145.961862) (xy 67.359979 -145.984031) (xy 67.336307 -146.034528)
			(xy 67.305534 -146.081041) (xy 67.268317 -146.122578) (xy 67.225449 -146.158253) (xy 67.177843 -146.187307)
			(xy 67.126514 -146.209119) (xy 67.072557 -146.223225) (xy 67.01712 -146.229325) (xy 66.961386 -146.227288)
			(xy 66.906543 -146.217158) (xy 66.853759 -146.199151) (xy 66.804159 -146.17365) (xy 66.758801 -146.141199)
			(xy 66.718652 -146.10249) (xy 66.684566 -146.058347) (xy 66.65727 -146.009712) (xy 66.637347 -145.957621)
			(xy 66.625221 -145.903184) (xy 66.62115 -145.847562) (xy 62.76437 -145.847562) (xy 62.764524 -145.847756)
			(xy 62.792509 -145.896234) (xy 62.81311 -145.94828) (xy 62.825885 -146.002778) (xy 62.830561 -146.058558)
			(xy 62.827037 -146.114422) (xy 62.815389 -146.169172) (xy 62.795866 -146.221632) (xy 62.768888 -146.270677)
			(xy 62.735034 -146.315254) (xy 62.69503 -146.354406) (xy 62.649735 -146.387293) (xy 62.608368 -146.408902)
			(xy 68.098668 -146.408902) (xy 68.102739 -146.35328) (xy 68.114865 -146.298843) (xy 68.134788 -146.246752)
			(xy 68.162084 -146.198117) (xy 68.19617 -146.153974) (xy 68.236319 -146.115265) (xy 68.281677 -146.082814)
			(xy 68.331277 -146.057313) (xy 68.384061 -146.039306) (xy 68.438904 -146.029176) (xy 68.494638 -146.027139)
			(xy 68.550075 -146.033239) (xy 68.604032 -146.047345) (xy 68.655361 -146.069157) (xy 68.702967 -146.098211)
			(xy 68.745835 -146.133886) (xy 68.783052 -146.175423) (xy 68.813825 -146.221936) (xy 68.837497 -146.272433)
			(xy 68.853565 -146.32584) (xy 68.861685 -146.381016) (xy 68.862194 -146.408902) (xy 68.861685 -146.436788)
			(xy 68.853565 -146.491964) (xy 68.837497 -146.545371) (xy 68.813825 -146.595868) (xy 68.783052 -146.642381)
			(xy 68.745835 -146.683918) (xy 68.702967 -146.719593) (xy 68.655361 -146.748647) (xy 68.604032 -146.770459)
			(xy 68.550075 -146.784565) (xy 68.494638 -146.790665) (xy 68.438904 -146.788628) (xy 68.384061 -146.778498)
			(xy 68.331277 -146.760491) (xy 68.281677 -146.73499) (xy 68.236319 -146.702539) (xy 68.19617 -146.66383)
			(xy 68.162084 -146.619687) (xy 68.134788 -146.571052) (xy 68.114865 -146.518961) (xy 68.102739 -146.464524)
			(xy 68.098668 -146.408902) (xy 62.608368 -146.408902) (xy 62.600121 -146.41321) (xy 62.547252 -146.431599)
			(xy 62.492265 -146.442067) (xy 62.436338 -146.444388) (xy 62.380672 -146.438513) (xy 62.353444 -146.432016)
			(xy 62.331162 -146.426772) (xy 62.285512 -146.423438) (xy 62.240005 -146.428345) (xy 62.196116 -146.441334)
			(xy 62.155267 -146.461982) (xy 62.118783 -146.489621) (xy 62.087847 -146.523354) (xy 62.063462 -146.562088)
			(xy 62.054486 -146.583146) (xy 62.043843 -146.608174) (xy 62.01661 -146.655246) (xy 61.98297 -146.697975)
			(xy 61.943603 -146.735494) (xy 61.899307 -146.767043) (xy 61.850981 -146.791982) (xy 61.799602 -146.809807)
			(xy 61.746214 -146.820155) (xy 61.691896 -146.822818) (xy 61.637752 -146.81774) (xy 61.584876 -146.805026)
			(xy 61.534342 -146.784932) (xy 61.487174 -146.757867) (xy 61.444326 -146.724378) (xy 61.406668 -146.685144)
			(xy 61.374963 -146.64096) (xy 61.349852 -146.592722) (xy 61.331846 -146.541407) (xy 61.321309 -146.488055)
			(xy 61.318455 -146.433748) (xy 53.718823 -146.433748) (xy 53.723039 -146.44776) (xy 53.731159 -146.502936)
			(xy 53.731668 -146.530822) (xy 53.731159 -146.558708) (xy 53.723039 -146.613884) (xy 53.706971 -146.667291)
			(xy 53.683299 -146.717788) (xy 53.652526 -146.764301) (xy 53.615309 -146.805838) (xy 53.572441 -146.841513)
			(xy 53.524835 -146.870567) (xy 53.473506 -146.892379) (xy 53.419549 -146.906485) (xy 53.364112 -146.912585)
			(xy 53.308378 -146.910548) (xy 53.253535 -146.900418) (xy 53.200751 -146.882411) (xy 53.151151 -146.85691)
			(xy 53.105793 -146.824459) (xy 53.065644 -146.78575) (xy 53.031558 -146.741607) (xy 53.004262 -146.692972)
			(xy 52.984339 -146.640881) (xy 52.972213 -146.586444) (xy 52.968142 -146.530822) (xy 51.565011 -146.530822)
			(xy 51.564539 -146.556676) (xy 51.556419 -146.611852) (xy 51.540351 -146.665259) (xy 51.516679 -146.715756)
			(xy 51.485906 -146.762269) (xy 51.448689 -146.803806) (xy 51.405821 -146.839481) (xy 51.358215 -146.868535)
			(xy 51.306886 -146.890347) (xy 51.252929 -146.904453) (xy 51.197492 -146.910553) (xy 51.141758 -146.908516)
			(xy 51.086915 -146.898386) (xy 51.034131 -146.880379) (xy 50.984531 -146.854878) (xy 50.939173 -146.822427)
			(xy 50.899024 -146.783718) (xy 50.864938 -146.739575) (xy 50.837642 -146.69094) (xy 50.817719 -146.638849)
			(xy 50.805593 -146.584412) (xy 50.801522 -146.52879) (xy 39.45147 -146.52879) (xy 39.453926 -146.531531)
			(xy 39.484699 -146.578044) (xy 39.508371 -146.628541) (xy 39.524439 -146.681948) (xy 39.532559 -146.737124)
			(xy 39.533068 -146.76501) (xy 39.532559 -146.792896) (xy 39.524439 -146.848072) (xy 39.508371 -146.901479)
			(xy 39.498521 -146.92249) (xy 42.018202 -146.92249) (xy 42.022273 -146.866868) (xy 42.034399 -146.812431)
			(xy 42.054322 -146.76034) (xy 42.081618 -146.711705) (xy 42.115704 -146.667562) (xy 42.155853 -146.628853)
			(xy 42.201211 -146.596402) (xy 42.250811 -146.570901) (xy 42.303595 -146.552894) (xy 42.358438 -146.542764)
			(xy 42.414172 -146.540727) (xy 42.469609 -146.546827) (xy 42.523566 -146.560933) (xy 42.574895 -146.582745)
			(xy 42.622501 -146.611799) (xy 42.665369 -146.647474) (xy 42.702586 -146.689011) (xy 42.733359 -146.735524)
			(xy 42.757031 -146.786021) (xy 42.773099 -146.839428) (xy 42.781219 -146.894604) (xy 42.781728 -146.92249)
			(xy 42.781264 -146.94789) (xy 44.151802 -146.94789) (xy 44.155873 -146.892268) (xy 44.167999 -146.837831)
			(xy 44.187922 -146.78574) (xy 44.215218 -146.737105) (xy 44.249304 -146.692962) (xy 44.289453 -146.654253)
			(xy 44.334811 -146.621802) (xy 44.384411 -146.596301) (xy 44.437195 -146.578294) (xy 44.492038 -146.568164)
			(xy 44.547772 -146.566127) (xy 44.603209 -146.572227) (xy 44.657166 -146.586333) (xy 44.708495 -146.608145)
			(xy 44.756101 -146.637199) (xy 44.798969 -146.672874) (xy 44.836186 -146.714411) (xy 44.866959 -146.760924)
			(xy 44.890631 -146.811421) (xy 44.906699 -146.864828) (xy 44.914819 -146.920004) (xy 44.915328 -146.94789)
			(xy 44.914819 -146.975776) (xy 44.906699 -147.030952) (xy 44.890631 -147.084359) (xy 44.866959 -147.134856)
			(xy 44.836186 -147.181369) (xy 44.798969 -147.222906) (xy 44.756101 -147.258581) (xy 44.708495 -147.287635)
			(xy 44.657166 -147.309447) (xy 44.603209 -147.323553) (xy 44.547772 -147.329653) (xy 44.492038 -147.327616)
			(xy 44.437195 -147.317486) (xy 44.384411 -147.299479) (xy 44.334811 -147.273978) (xy 44.289453 -147.241527)
			(xy 44.249304 -147.202818) (xy 44.215218 -147.158675) (xy 44.187922 -147.11004) (xy 44.167999 -147.057949)
			(xy 44.155873 -147.003512) (xy 44.151802 -146.94789) (xy 42.781264 -146.94789) (xy 42.781219 -146.950376)
			(xy 42.773099 -147.005552) (xy 42.757031 -147.058959) (xy 42.733359 -147.109456) (xy 42.702586 -147.155969)
			(xy 42.665369 -147.197506) (xy 42.622501 -147.233181) (xy 42.574895 -147.262235) (xy 42.523566 -147.284047)
			(xy 42.469609 -147.298153) (xy 42.414172 -147.304253) (xy 42.358438 -147.302216) (xy 42.303595 -147.292086)
			(xy 42.250811 -147.274079) (xy 42.201211 -147.248578) (xy 42.155853 -147.216127) (xy 42.115704 -147.177418)
			(xy 42.081618 -147.133275) (xy 42.054322 -147.08464) (xy 42.034399 -147.032549) (xy 42.022273 -146.978112)
			(xy 42.018202 -146.92249) (xy 39.498521 -146.92249) (xy 39.484699 -146.951976) (xy 39.453926 -146.998489)
			(xy 39.416709 -147.040026) (xy 39.373841 -147.075701) (xy 39.326235 -147.104755) (xy 39.274906 -147.126567)
			(xy 39.220949 -147.140673) (xy 39.165512 -147.146773) (xy 39.109778 -147.144736) (xy 39.054935 -147.134606)
			(xy 39.002151 -147.116599) (xy 38.952551 -147.091098) (xy 38.907193 -147.058647) (xy 38.867044 -147.019938)
			(xy 38.832958 -146.975795) (xy 38.805662 -146.92716) (xy 38.785739 -146.875069) (xy 38.773613 -146.820632)
			(xy 38.769542 -146.76501) (xy 34.78966 -146.76501) (xy 35.640264 -147.615656) (xy 35.652413 -147.627004)
			(xy 35.681209 -147.643591) (xy 35.71331 -147.652185) (xy 35.729926 -147.65274) (xy 39.243508 -147.65274)
			(xy 39.313358 -147.72259) (xy 40.583102 -147.72259) (xy 40.587173 -147.666968) (xy 40.599299 -147.612531)
			(xy 40.619222 -147.56044) (xy 40.646518 -147.511805) (xy 40.680604 -147.467662) (xy 40.720753 -147.428953)
			(xy 40.766111 -147.396502) (xy 40.815711 -147.371001) (xy 40.868495 -147.352994) (xy 40.923338 -147.342864)
			(xy 40.979072 -147.340827) (xy 41.034509 -147.346927) (xy 41.088466 -147.361033) (xy 41.139795 -147.382845)
			(xy 41.187401 -147.411899) (xy 41.230269 -147.447574) (xy 41.267486 -147.489111) (xy 41.298259 -147.535624)
			(xy 41.321931 -147.586121) (xy 41.336243 -147.63369) (xy 48.660302 -147.63369) (xy 48.664373 -147.578068)
			(xy 48.676499 -147.523631) (xy 48.696422 -147.47154) (xy 48.723718 -147.422905) (xy 48.757804 -147.378762)
			(xy 48.797953 -147.340053) (xy 48.843311 -147.307602) (xy 48.892911 -147.282101) (xy 48.945695 -147.264094)
			(xy 49.000538 -147.253964) (xy 49.056272 -147.251927) (xy 49.111709 -147.258027) (xy 49.165666 -147.272133)
			(xy 49.216995 -147.293945) (xy 49.264601 -147.322999) (xy 49.307469 -147.358674) (xy 49.344686 -147.400211)
			(xy 49.375459 -147.446724) (xy 49.399131 -147.497221) (xy 49.414054 -147.546822) (xy 52.853842 -147.546822)
			(xy 52.857913 -147.4912) (xy 52.870039 -147.436763) (xy 52.889962 -147.384672) (xy 52.917258 -147.336037)
			(xy 52.951344 -147.291894) (xy 52.991493 -147.253185) (xy 53.036851 -147.220734) (xy 53.086451 -147.195233)
			(xy 53.139235 -147.177226) (xy 53.194078 -147.167096) (xy 53.249812 -147.165059) (xy 53.305249 -147.171159)
			(xy 53.359206 -147.185265) (xy 53.410535 -147.207077) (xy 53.458141 -147.236131) (xy 53.501009 -147.271806)
			(xy 53.538226 -147.313343) (xy 53.568999 -147.359856) (xy 53.589891 -147.404422) (xy 55.606925 -147.404422)
			(xy 55.608736 -147.34864) (xy 55.618655 -147.293717) (xy 55.636469 -147.240824) (xy 55.661798 -147.191091)
			(xy 55.694102 -147.145578) (xy 55.732692 -147.105257) (xy 55.776744 -147.070988) (xy 55.825318 -147.043502)
			(xy 55.877379 -147.023386) (xy 55.931814 -147.011068) (xy 55.987463 -147.006811) (xy 56.043139 -147.010708)
			(xy 56.0705 -147.016216) (xy 56.093821 -147.020833) (xy 56.141339 -147.022205) (xy 56.188283 -147.014722)
			(xy 56.233019 -146.998643) (xy 56.273986 -146.974529) (xy 56.309758 -146.943221) (xy 56.339087 -146.905809)
			(xy 56.360951 -146.863598) (xy 56.374588 -146.818059) (xy 56.377586 -146.794474) (xy 56.380971 -146.766778)
			(xy 56.394788 -146.71272) (xy 56.416333 -146.661252) (xy 56.445146 -146.613471) (xy 56.480611 -146.570397)
			(xy 56.521972 -146.532949) (xy 56.568348 -146.501925) (xy 56.618747 -146.477987) (xy 56.672097 -146.461646)
			(xy 56.727257 -146.453251) (xy 56.783052 -146.452981) (xy 56.838292 -146.460841) (xy 56.891797 -146.476664)
			(xy 56.942426 -146.500113) (xy 56.9891 -146.530686) (xy 57.030822 -146.567732) (xy 57.066703 -146.610461)
			(xy 57.095976 -146.65796) (xy 57.118019 -146.709217) (xy 57.13236 -146.763139) (xy 57.138693 -146.818574)
			(xy 57.136883 -146.87434) (xy 57.126969 -146.929248) (xy 57.109163 -146.982126) (xy 57.083844 -147.031846)
			(xy 57.055099 -147.07235) (xy 124.245114 -147.07235) (xy 124.249185 -147.016728) (xy 124.261311 -146.962291)
			(xy 124.281234 -146.9102) (xy 124.30853 -146.861565) (xy 124.342616 -146.817422) (xy 124.382765 -146.778713)
			(xy 124.428123 -146.746262) (xy 124.477723 -146.720761) (xy 124.530507 -146.702754) (xy 124.58535 -146.692624)
			(xy 124.641084 -146.690587) (xy 124.696521 -146.696687) (xy 124.750478 -146.710793) (xy 124.801807 -146.732605)
			(xy 124.849413 -146.761659) (xy 124.892281 -146.797334) (xy 124.929498 -146.838871) (xy 124.960271 -146.885384)
			(xy 124.983943 -146.935881) (xy 124.995886 -146.975576) (xy 126.724408 -146.975576) (xy 126.728479 -146.919954)
			(xy 126.740605 -146.865517) (xy 126.760528 -146.813426) (xy 126.787824 -146.764791) (xy 126.82191 -146.720648)
			(xy 126.862059 -146.681939) (xy 126.907417 -146.649488) (xy 126.957017 -146.623987) (xy 127.009801 -146.60598)
			(xy 127.064644 -146.59585) (xy 127.120378 -146.593813) (xy 127.175815 -146.599913) (xy 127.229772 -146.614019)
			(xy 127.281101 -146.635831) (xy 127.328707 -146.664885) (xy 127.371575 -146.70056) (xy 127.408792 -146.742097)
			(xy 127.439565 -146.78861) (xy 127.463237 -146.839107) (xy 127.479305 -146.892514) (xy 127.487425 -146.94769)
			(xy 127.487934 -146.975576) (xy 127.487425 -147.003462) (xy 127.479305 -147.058638) (xy 127.463237 -147.112045)
			(xy 127.439565 -147.162542) (xy 127.408792 -147.209055) (xy 127.371575 -147.250592) (xy 127.328707 -147.286267)
			(xy 127.281101 -147.315321) (xy 127.229772 -147.337133) (xy 127.175815 -147.351239) (xy 127.120378 -147.357339)
			(xy 127.064644 -147.355302) (xy 127.009801 -147.345172) (xy 126.957017 -147.327165) (xy 126.907417 -147.301664)
			(xy 126.862059 -147.269213) (xy 126.82191 -147.230504) (xy 126.787824 -147.186361) (xy 126.760528 -147.137726)
			(xy 126.740605 -147.085635) (xy 126.728479 -147.031198) (xy 126.724408 -146.975576) (xy 124.995886 -146.975576)
			(xy 125.000011 -146.989288) (xy 125.008131 -147.044464) (xy 125.00864 -147.07235) (xy 125.008131 -147.100236)
			(xy 125.000011 -147.155412) (xy 124.983943 -147.208819) (xy 124.960271 -147.259316) (xy 124.929498 -147.305829)
			(xy 124.892281 -147.347366) (xy 124.849413 -147.383041) (xy 124.801807 -147.412095) (xy 124.750478 -147.433907)
			(xy 124.696521 -147.448013) (xy 124.641084 -147.454113) (xy 124.58535 -147.452076) (xy 124.530507 -147.441946)
			(xy 124.477723 -147.423939) (xy 124.428123 -147.398438) (xy 124.382765 -147.365987) (xy 124.342616 -147.327278)
			(xy 124.30853 -147.283135) (xy 124.281234 -147.2345) (xy 124.261311 -147.182409) (xy 124.249185 -147.127972)
			(xy 124.245114 -147.07235) (xy 57.055099 -147.07235) (xy 57.051552 -147.077348) (xy 57.012976 -147.11766)
			(xy 56.96894 -147.151923) (xy 56.920382 -147.179406) (xy 56.868339 -147.199523) (xy 56.813921 -147.211844)
			(xy 56.758288 -147.216106) (xy 56.702628 -147.212219) (xy 56.675274 -147.206716) (xy 56.651943 -147.202153)
			(xy 56.604428 -147.200768) (xy 56.557485 -147.20824) (xy 56.512749 -147.22431) (xy 56.471781 -147.248417)
			(xy 56.436009 -147.279721) (xy 56.406681 -147.317129) (xy 56.384819 -147.359337) (xy 56.371185 -147.404874)
			(xy 56.368188 -147.428458) (xy 56.364823 -147.456164) (xy 56.351012 -147.51024) (xy 56.332545 -147.554377)
			(xy 57.30145 -147.554377) (xy 57.305134 -147.499653) (xy 57.316617 -147.446021) (xy 57.335664 -147.394586)
			(xy 57.361882 -147.346409) (xy 57.394729 -147.302485) (xy 57.433529 -147.263718) (xy 57.477481 -147.230908)
			(xy 57.52568 -147.204731) (xy 57.577131 -147.185728) (xy 57.630773 -147.174289) (xy 57.6855 -147.170652)
			(xy 57.740184 -147.174891) (xy 57.793697 -147.186918) (xy 57.844936 -147.206486) (xy 57.892844 -147.233191)
			(xy 57.936433 -147.266483) (xy 57.974804 -147.305674) (xy 58.007166 -147.349957) (xy 58.032852 -147.398419)
			(xy 58.051332 -147.45006) (xy 58.062225 -147.503816) (xy 58.065307 -147.558577) (xy 58.063384 -147.585938)
			(xy 58.061953 -147.608082) (xy 58.065783 -147.652286) (xy 58.077234 -147.695152) (xy 58.095957 -147.735377)
			(xy 58.121383 -147.771738) (xy 58.152739 -147.803129) (xy 58.189071 -147.828597) (xy 58.229274 -147.847366)
			(xy 58.272127 -147.858866) (xy 58.316326 -147.862748) (xy 58.338466 -147.861274) (xy 58.365829 -147.859376)
			(xy 58.42059 -147.862502) (xy 58.474338 -147.873438) (xy 58.525966 -147.89196) (xy 58.574408 -147.917686)
			(xy 58.618667 -147.950085) (xy 58.657828 -147.988488) (xy 58.691086 -148.032105) (xy 58.717754 -148.080035)
			(xy 58.733828 -148.122227) (xy 63.001404 -148.122227) (xy 63.005192 -148.068035) (xy 63.016629 -148.014928)
			(xy 63.035483 -147.963981) (xy 63.061374 -147.916223) (xy 63.093778 -147.872621) (xy 63.132039 -147.834056)
			(xy 63.175384 -147.801308) (xy 63.222935 -147.775041) (xy 63.273732 -147.755784) (xy 63.326747 -147.743928)
			(xy 63.380908 -147.739711) (xy 63.435119 -147.743221) (xy 63.488284 -147.754384) (xy 63.51397 -147.76323)
			(xy 63.528856 -147.768121) (xy 63.560013 -147.771329) (xy 63.591012 -147.766847) (xy 63.619985 -147.754946)
			(xy 63.645184 -147.736344) (xy 63.66509 -147.712161) (xy 63.672212 -147.698206) (xy 63.684402 -147.673493)
			(xy 63.71487 -147.627579) (xy 63.751627 -147.586526) (xy 63.793908 -147.551188) (xy 63.840833 -147.522302)
			(xy 63.891426 -147.500467) (xy 63.944635 -147.486139) (xy 63.999351 -147.479615) (xy 64.054437 -147.481032)
			(xy 64.108745 -147.490359) (xy 64.161147 -147.507403) (xy 64.210551 -147.531809) (xy 64.25593 -147.563069)
			(xy 64.296339 -147.600532) (xy 64.330938 -147.64342) (xy 64.359006 -147.69084) (xy 64.368718 -147.714462)
			(xy 65.576194 -147.714462) (xy 65.580265 -147.65884) (xy 65.592391 -147.604403) (xy 65.612314 -147.552312)
			(xy 65.63961 -147.503677) (xy 65.673696 -147.459534) (xy 65.713845 -147.420825) (xy 65.759203 -147.388374)
			(xy 65.808803 -147.362873) (xy 65.861587 -147.344866) (xy 65.91643 -147.334736) (xy 65.972164 -147.332699)
			(xy 66.027601 -147.338799) (xy 66.081558 -147.352905) (xy 66.132887 -147.374717) (xy 66.180493 -147.403771)
			(xy 66.223361 -147.439446) (xy 66.260578 -147.480983) (xy 66.291351 -147.527496) (xy 66.315023 -147.577993)
			(xy 66.331091 -147.6314) (xy 66.339211 -147.686576) (xy 66.33972 -147.714462) (xy 66.339211 -147.742348)
			(xy 66.338605 -147.746466) (xy 116.517926 -147.746466) (xy 116.521997 -147.690844) (xy 116.534123 -147.636407)
			(xy 116.554046 -147.584316) (xy 116.581342 -147.535681) (xy 116.615428 -147.491538) (xy 116.655577 -147.452829)
			(xy 116.700935 -147.420378) (xy 116.750535 -147.394877) (xy 116.803319 -147.37687) (xy 116.858162 -147.36674)
			(xy 116.913896 -147.364703) (xy 116.969333 -147.370803) (xy 117.02329 -147.384909) (xy 117.074619 -147.406721)
			(xy 117.122225 -147.435775) (xy 117.165093 -147.47145) (xy 117.20231 -147.512987) (xy 117.233083 -147.5595)
			(xy 117.256755 -147.609997) (xy 117.272823 -147.663404) (xy 117.280943 -147.71858) (xy 117.281452 -147.746466)
			(xy 117.280943 -147.774352) (xy 117.272823 -147.829528) (xy 117.256755 -147.882935) (xy 117.233083 -147.933432)
			(xy 117.20231 -147.979945) (xy 117.165093 -148.021482) (xy 117.122225 -148.057157) (xy 117.074619 -148.086211)
			(xy 117.02329 -148.108023) (xy 116.969333 -148.122129) (xy 116.913896 -148.128229) (xy 116.858162 -148.126192)
			(xy 116.803319 -148.116062) (xy 116.750535 -148.098055) (xy 116.700935 -148.072554) (xy 116.655577 -148.040103)
			(xy 116.615428 -148.001394) (xy 116.581342 -147.957251) (xy 116.554046 -147.908616) (xy 116.534123 -147.856525)
			(xy 116.521997 -147.802088) (xy 116.517926 -147.746466) (xy 66.338605 -147.746466) (xy 66.331091 -147.797524)
			(xy 66.315023 -147.850931) (xy 66.291351 -147.901428) (xy 66.260578 -147.947941) (xy 66.223361 -147.989478)
			(xy 66.180493 -148.025153) (xy 66.132887 -148.054207) (xy 66.081558 -148.076019) (xy 66.027601 -148.090125)
			(xy 65.972164 -148.096225) (xy 65.91643 -148.094188) (xy 65.861587 -148.084058) (xy 65.808803 -148.066051)
			(xy 65.759203 -148.04055) (xy 65.713845 -148.008099) (xy 65.673696 -147.96939) (xy 65.63961 -147.925247)
			(xy 65.612314 -147.876612) (xy 65.592391 -147.824521) (xy 65.580265 -147.770084) (xy 65.576194 -147.714462)
			(xy 64.368718 -147.714462) (xy 64.379959 -147.741804) (xy 64.393362 -147.795253) (xy 64.398935 -147.850074)
			(xy 64.396563 -147.905127) (xy 64.386295 -147.959266) (xy 64.368345 -148.011364) (xy 64.343085 -148.060337)
			(xy 64.311043 -148.105167) (xy 64.272883 -148.14492) (xy 64.229402 -148.178769) (xy 64.181502 -148.20601)
			(xy 64.130182 -148.226076) (xy 64.076509 -148.23855) (xy 64.021599 -148.243171) (xy 63.966596 -148.239844)
			(xy 63.912643 -148.228638) (xy 63.886588 -148.219668) (xy 63.871716 -148.214733) (xy 63.840552 -148.211533)
			(xy 63.809548 -148.216023) (xy 63.780573 -148.227933) (xy 63.755373 -148.246543) (xy 63.735468 -148.270733)
			(xy 63.728346 -148.284692) (xy 63.714608 -148.312331) (xy 63.679581 -148.363147) (xy 63.636839 -148.407669)
			(xy 63.612522 -148.426678) (xy 63.594002 -148.441206) (xy 63.562243 -148.475946) (xy 63.537424 -148.515938)
			(xy 63.520391 -148.559816) (xy 63.511728 -148.60608) (xy 63.511731 -148.653148) (xy 63.520399 -148.699412)
			(xy 63.537437 -148.743288) (xy 63.562261 -148.783277) (xy 63.594023 -148.818013) (xy 63.612522 -148.83257)
			(xy 63.634643 -148.849803) (xy 63.661051 -148.876512) (xy 64.060068 -148.876512) (xy 64.064139 -148.82089)
			(xy 64.076265 -148.766453) (xy 64.096188 -148.714362) (xy 64.123484 -148.665727) (xy 64.15757 -148.621584)
			(xy 64.197719 -148.582875) (xy 64.243077 -148.550424) (xy 64.292677 -148.524923) (xy 64.345461 -148.506916)
			(xy 64.400304 -148.496786) (xy 64.456038 -148.494749) (xy 64.511475 -148.500849) (xy 64.565432 -148.514955)
			(xy 64.616761 -148.536767) (xy 64.664367 -148.565821) (xy 64.707235 -148.601496) (xy 64.744452 -148.643033)
			(xy 64.775225 -148.689546) (xy 64.798897 -148.740043) (xy 64.814965 -148.79345) (xy 64.823085 -148.848626)
			(xy 64.823594 -148.876512) (xy 73.62266 -148.876512) (xy 73.626731 -148.82089) (xy 73.638857 -148.766453)
			(xy 73.65878 -148.714362) (xy 73.686076 -148.665727) (xy 73.720162 -148.621584) (xy 73.760311 -148.582875)
			(xy 73.805669 -148.550424) (xy 73.855269 -148.524923) (xy 73.908053 -148.506916) (xy 73.962896 -148.496786)
			(xy 74.01863 -148.494749) (xy 74.074067 -148.500849) (xy 74.128024 -148.514955) (xy 74.179353 -148.536767)
			(xy 74.226959 -148.565821) (xy 74.269827 -148.601496) (xy 74.307044 -148.643033) (xy 74.337817 -148.689546)
			(xy 74.361489 -148.740043) (xy 74.377557 -148.79345) (xy 74.385677 -148.848626) (xy 74.386186 -148.876512)
			(xy 74.385677 -148.904398) (xy 74.377557 -148.959574) (xy 74.361489 -149.012981) (xy 74.337817 -149.063478)
			(xy 74.307044 -149.109991) (xy 74.304739 -149.112563) (xy 100.808339 -149.112563) (xy 100.81483 -149.05777)
			(xy 100.829147 -149.004483) (xy 100.85099 -148.953815) (xy 100.879903 -148.906821) (xy 100.915284 -148.864481)
			(xy 100.956394 -148.82768) (xy 101.002377 -148.797183) (xy 101.052273 -148.773629) (xy 101.105041 -148.757507)
			(xy 101.159582 -148.749154) (xy 101.214757 -148.748744) (xy 101.269415 -148.756285) (xy 101.322417 -148.771622)
			(xy 101.372658 -148.794433) (xy 101.419088 -148.824242) (xy 101.440234 -148.841968) (xy 101.452415 -148.851955)
			(xy 101.480504 -148.866188) (xy 101.511226 -148.873096) (xy 101.542704 -148.872258) (xy 101.573015 -148.863725)
			(xy 101.600306 -148.848018) (xy 101.611938 -148.837396) (xy 101.632102 -148.818566) (xy 101.676878 -148.786334)
			(xy 101.72583 -148.760888) (xy 101.777936 -148.742758) (xy 101.83211 -148.732322) (xy 101.887223 -148.729798)
			(xy 101.942125 -148.735238) (xy 101.99567 -148.748529) (xy 102.046743 -148.769394) (xy 102.094278 -148.797398)
			(xy 102.137283 -148.831957) (xy 102.174863 -148.872349) (xy 102.204954 -148.915882) (xy 107.543598 -148.915882)
			(xy 107.547669 -148.86026) (xy 107.559795 -148.805823) (xy 107.579718 -148.753732) (xy 107.607014 -148.705097)
			(xy 107.6411 -148.660954) (xy 107.681249 -148.622245) (xy 107.726607 -148.589794) (xy 107.776207 -148.564293)
			(xy 107.828991 -148.546286) (xy 107.883834 -148.536156) (xy 107.939568 -148.534119) (xy 107.995005 -148.540219)
			(xy 108.048962 -148.554325) (xy 108.100291 -148.576137) (xy 108.147897 -148.605191) (xy 108.190765 -148.640866)
			(xy 108.227982 -148.682403) (xy 108.258755 -148.728916) (xy 108.282427 -148.779413) (xy 108.293988 -148.817838)
			(xy 118.677942 -148.817838) (xy 118.682013 -148.762216) (xy 118.694139 -148.707779) (xy 118.714062 -148.655688)
			(xy 118.741358 -148.607053) (xy 118.775444 -148.56291) (xy 118.815593 -148.524201) (xy 118.860951 -148.49175)
			(xy 118.910551 -148.466249) (xy 118.963335 -148.448242) (xy 119.018178 -148.438112) (xy 119.073912 -148.436075)
			(xy 119.129349 -148.442175) (xy 119.183306 -148.456281) (xy 119.234635 -148.478093) (xy 119.282241 -148.507147)
			(xy 119.325109 -148.542822) (xy 119.362326 -148.584359) (xy 119.393099 -148.630872) (xy 119.416771 -148.681369)
			(xy 119.432839 -148.734776) (xy 119.440959 -148.789952) (xy 119.441468 -148.817838) (xy 119.440959 -148.845724)
			(xy 119.432839 -148.9009) (xy 119.416771 -148.954307) (xy 119.393099 -149.004804) (xy 119.362326 -149.051317)
			(xy 119.325109 -149.092854) (xy 119.282241 -149.128529) (xy 119.279265 -149.130345) (xy 122.995445 -149.130345)
			(xy 122.999393 -149.074917) (xy 123.011339 -149.020648) (xy 123.031031 -148.968686) (xy 123.058053 -148.92013)
			(xy 123.091832 -148.876007) (xy 123.131654 -148.837251) (xy 123.176678 -148.804682) (xy 123.225949 -148.778988)
			(xy 123.278427 -148.760714) (xy 123.333 -148.750245) (xy 123.388515 -148.747803) (xy 123.443796 -148.753441)
			(xy 123.497676 -148.767037) (xy 123.549012 -148.788306) (xy 123.596721 -148.816797) (xy 123.639792 -148.851907)
			(xy 123.677315 -148.892894) (xy 123.708495 -148.93889) (xy 123.732673 -148.988922) (xy 123.749338 -149.041933)
			(xy 123.758136 -149.0968) (xy 123.758883 -149.152364) (xy 123.751561 -149.207448) (xy 123.736326 -149.260887)
			(xy 123.713501 -149.311551) (xy 123.683567 -149.358368) (xy 123.665742 -149.379686) (xy 123.652068 -149.396168)
			(xy 123.629867 -149.432785) (xy 123.614118 -149.472605) (xy 123.605265 -149.514502) (xy 123.603559 -149.557289)
			(xy 123.609049 -149.599758) (xy 123.621579 -149.640705) (xy 123.640795 -149.678974) (xy 123.666152 -149.71348)
			(xy 123.681236 -149.728682) (xy 123.703588 -149.752304) (xy 123.718292 -149.768518) (xy 123.752298 -149.796073)
			(xy 123.79052 -149.817397) (xy 123.83183 -149.83186) (xy 123.875007 -149.839034) (xy 123.918774 -149.838708)
			(xy 123.961839 -149.830891) (xy 124.002929 -149.815814) (xy 124.040829 -149.793923) (xy 124.057918 -149.780244)
			(xy 124.077052 -149.764773) (xy 124.118563 -149.738354) (xy 124.163123 -149.717484) (xy 124.186442 -149.709632)
			(xy 124.20834 -149.702098) (xy 124.249158 -149.680235) (xy 124.285343 -149.651341) (xy 124.315698 -149.616374)
			(xy 124.33922 -149.576488) (xy 124.355131 -149.533003) (xy 124.362905 -149.487355) (xy 124.362285 -149.441055)
			(xy 124.353291 -149.395632) (xy 124.336222 -149.352588) (xy 124.324364 -149.332696) (xy 124.310026 -149.3088)
			(xy 124.287575 -149.257799) (xy 124.272783 -149.204074) (xy 124.265964 -149.148769) (xy 124.267264 -149.09306)
			(xy 124.276654 -149.038133) (xy 124.293936 -148.985157) (xy 124.31874 -148.935258) (xy 124.35054 -148.889499)
			(xy 124.388659 -148.848853) (xy 124.432286 -148.814186) (xy 124.480492 -148.786234) (xy 124.532252 -148.765592)
			(xy 124.586464 -148.752701) (xy 124.641975 -148.747833) (xy 124.697603 -148.751093) (xy 124.752166 -148.762411)
			(xy 124.804501 -148.781547) (xy 124.853495 -148.808093) (xy 124.898106 -148.841485) (xy 124.937385 -148.881011)
			(xy 124.970495 -148.925831) (xy 124.996733 -148.974991) (xy 125.015539 -149.027446) (xy 125.026514 -149.082078)
			(xy 125.029425 -149.137726) (xy 125.024208 -149.193205) (xy 125.010976 -149.247335) (xy 124.99001 -149.298964)
			(xy 124.961755 -149.346993) (xy 124.926814 -149.390401) (xy 124.885929 -149.428264) (xy 124.839971 -149.459776)
			(xy 124.789918 -149.484267) (xy 124.76353 -149.493224) (xy 124.741651 -149.500806) (xy 124.700839 -149.522667)
			(xy 124.664659 -149.551556) (xy 124.634307 -149.586518) (xy 124.610787 -149.626397) (xy 124.594875 -149.669875)
			(xy 124.587097 -149.715515) (xy 124.587711 -149.76181) (xy 124.596696 -149.807228) (xy 124.613755 -149.850269)
			(xy 124.625608 -149.87016) (xy 124.639553 -149.893433) (xy 124.661608 -149.942999) (xy 124.676418 -149.995189)
			(xy 124.683685 -150.048951) (xy 124.683261 -150.1032) (xy 124.675156 -150.156842) (xy 124.659532 -150.208794)
			(xy 124.636706 -150.258009) (xy 124.607137 -150.303494) (xy 124.571422 -150.34433) (xy 124.530282 -150.379695)
			(xy 124.484547 -150.408874) (xy 124.435139 -150.431279) (xy 124.383055 -150.446458) (xy 124.329345 -150.454105)
			(xy 124.275095 -150.454065) (xy 124.221397 -150.446339) (xy 124.169335 -150.431084) (xy 124.11996 -150.408606)
			(xy 124.074267 -150.37936) (xy 124.033179 -150.343935) (xy 124.014992 -150.323804) (xy 124.000211 -150.307664)
			(xy 123.966219 -150.280107) (xy 123.928009 -150.258779) (xy 123.886712 -150.24431) (xy 123.843546 -150.237128)
			(xy 123.799788 -150.237444) (xy 123.756731 -150.24525) (xy 123.715647 -150.260314) (xy 123.67775 -150.282192)
			(xy 123.660662 -150.295864) (xy 123.63959 -150.312927) (xy 123.593503 -150.34149) (xy 123.543836 -150.363241)
			(xy 123.49159 -150.377742) (xy 123.437817 -150.3847) (xy 123.383601 -150.383976) (xy 123.330034 -150.375583)
			(xy 123.278194 -150.359692) (xy 123.229126 -150.336622) (xy 123.183818 -150.306838) (xy 123.143183 -150.270939)
			(xy 123.10804 -150.22965) (xy 123.079095 -150.183801) (xy 123.056933 -150.134316) (xy 123.042 -150.082192)
			(xy 123.034596 -150.02848) (xy 123.034871 -149.974259) (xy 123.042818 -149.920624) (xy 123.058279 -149.868654)
			(xy 123.080942 -149.819397) (xy 123.110349 -149.773844) (xy 123.12777 -149.753066) (xy 123.141492 -149.736623)
			(xy 123.163689 -149.699997) (xy 123.179435 -149.66017) (xy 123.188282 -149.618267) (xy 123.189982 -149.575474)
			(xy 123.184486 -149.533002) (xy 123.171949 -149.492051) (xy 123.152727 -149.45378) (xy 123.127363 -149.419272)
			(xy 123.112276 -149.40407) (xy 123.09269 -149.384356) (xy 123.058762 -149.340347) (xy 123.031577 -149.291883)
			(xy 123.011709 -149.239987) (xy 122.99958 -149.185759) (xy 122.995445 -149.130345) (xy 119.279265 -149.130345)
			(xy 119.234635 -149.157583) (xy 119.183306 -149.179395) (xy 119.129349 -149.193501) (xy 119.073912 -149.199601)
			(xy 119.018178 -149.197564) (xy 118.963335 -149.187434) (xy 118.910551 -149.169427) (xy 118.860951 -149.143926)
			(xy 118.815593 -149.111475) (xy 118.775444 -149.072766) (xy 118.741358 -149.028623) (xy 118.714062 -148.979988)
			(xy 118.694139 -148.927897) (xy 118.682013 -148.87346) (xy 118.677942 -148.817838) (xy 108.293988 -148.817838)
			(xy 108.298495 -148.83282) (xy 108.306615 -148.887996) (xy 108.307124 -148.915882) (xy 108.306615 -148.943768)
			(xy 108.298495 -148.998944) (xy 108.282427 -149.052351) (xy 108.258755 -149.102848) (xy 108.227982 -149.149361)
			(xy 108.190765 -149.190898) (xy 108.147897 -149.226573) (xy 108.117596 -149.245066) (xy 110.747046 -149.245066)
			(xy 110.751117 -149.189444) (xy 110.763243 -149.135007) (xy 110.783166 -149.082916) (xy 110.810462 -149.034281)
			(xy 110.844548 -148.990138) (xy 110.884697 -148.951429) (xy 110.930055 -148.918978) (xy 110.979655 -148.893477)
			(xy 111.032439 -148.87547) (xy 111.087282 -148.86534) (xy 111.143016 -148.863303) (xy 111.198453 -148.869403)
			(xy 111.25241 -148.883509) (xy 111.303739 -148.905321) (xy 111.351345 -148.934375) (xy 111.394213 -148.97005)
			(xy 111.43143 -149.011587) (xy 111.462203 -149.0581) (xy 111.485875 -149.108597) (xy 111.501943 -149.162004)
			(xy 111.510063 -149.21718) (xy 111.510572 -149.245066) (xy 111.510063 -149.272952) (xy 111.501943 -149.328128)
			(xy 111.485875 -149.381535) (xy 111.462203 -149.432032) (xy 111.43143 -149.478545) (xy 111.394213 -149.520082)
			(xy 111.351345 -149.555757) (xy 111.303739 -149.584811) (xy 111.25241 -149.606623) (xy 111.198453 -149.620729)
			(xy 111.143016 -149.626829) (xy 111.087282 -149.624792) (xy 111.032439 -149.614662) (xy 110.979655 -149.596655)
			(xy 110.930055 -149.571154) (xy 110.884697 -149.538703) (xy 110.844548 -149.499994) (xy 110.810462 -149.455851)
			(xy 110.783166 -149.407216) (xy 110.763243 -149.355125) (xy 110.751117 -149.300688) (xy 110.747046 -149.245066)
			(xy 108.117596 -149.245066) (xy 108.100291 -149.255627) (xy 108.048962 -149.277439) (xy 107.995005 -149.291545)
			(xy 107.939568 -149.297645) (xy 107.883834 -149.295608) (xy 107.828991 -149.285478) (xy 107.776207 -149.267471)
			(xy 107.726607 -149.24197) (xy 107.681249 -149.209519) (xy 107.6411 -149.17081) (xy 107.607014 -149.126667)
			(xy 107.579718 -149.078032) (xy 107.559795 -149.025941) (xy 107.547669 -148.971504) (xy 107.543598 -148.915882)
			(xy 102.204954 -148.915882) (xy 102.206233 -148.917733) (xy 102.230739 -148.967162) (xy 102.24787 -149.019605)
			(xy 102.257269 -149.073969) (xy 102.258739 -149.12912) (xy 102.25225 -149.183907) (xy 102.237938 -149.237189)
			(xy 102.216101 -149.287854) (xy 102.187194 -149.334845) (xy 102.15182 -149.377182) (xy 102.110717 -149.413983)
			(xy 102.064742 -149.44448) (xy 102.014853 -149.468037) (xy 101.962092 -149.484162) (xy 101.907559 -149.49252)
			(xy 101.85239 -149.492936) (xy 101.797736 -149.485402) (xy 101.744738 -149.470074) (xy 101.6945 -149.447273)
			(xy 101.64807 -149.417473) (xy 101.626924 -149.399752) (xy 101.614776 -149.389721) (xy 101.586678 -149.37549)
			(xy 101.555947 -149.368586) (xy 101.524461 -149.369432) (xy 101.494145 -149.377976) (xy 101.466851 -149.393696)
			(xy 101.45522 -149.404324) (xy 101.435033 -149.423135) (xy 101.390254 -149.455373) (xy 101.341299 -149.480825)
			(xy 101.289188 -149.498959) (xy 101.235008 -149.509399) (xy 101.17989 -149.511926) (xy 101.124982 -149.506486)
			(xy 101.07143 -149.493195) (xy 101.020352 -149.472329) (xy 100.972812 -149.444322) (xy 100.929801 -149.40976)
			(xy 100.892217 -149.369363) (xy 100.860845 -149.323974) (xy 100.836337 -149.27454) (xy 100.819205 -149.22209)
			(xy 100.809807 -149.16772) (xy 100.808339 -149.112563) (xy 74.304739 -149.112563) (xy 74.269827 -149.151528)
			(xy 74.226959 -149.187203) (xy 74.179353 -149.216257) (xy 74.128024 -149.238069) (xy 74.074067 -149.252175)
			(xy 74.01863 -149.258275) (xy 73.962896 -149.256238) (xy 73.908053 -149.246108) (xy 73.855269 -149.228101)
			(xy 73.805669 -149.2026) (xy 73.760311 -149.170149) (xy 73.720162 -149.13144) (xy 73.686076 -149.087297)
			(xy 73.65878 -149.038662) (xy 73.638857 -148.986571) (xy 73.626731 -148.932134) (xy 73.62266 -148.876512)
			(xy 64.823594 -148.876512) (xy 64.823085 -148.904398) (xy 64.814965 -148.959574) (xy 64.798897 -149.012981)
			(xy 64.775225 -149.063478) (xy 64.744452 -149.109991) (xy 64.707235 -149.151528) (xy 64.664367 -149.187203)
			(xy 64.616761 -149.216257) (xy 64.565432 -149.238069) (xy 64.511475 -149.252175) (xy 64.456038 -149.258275)
			(xy 64.400304 -149.256238) (xy 64.345461 -149.246108) (xy 64.292677 -149.228101) (xy 64.243077 -149.2026)
			(xy 64.197719 -149.170149) (xy 64.15757 -149.13144) (xy 64.123484 -149.087297) (xy 64.096188 -149.038662)
			(xy 64.076265 -148.986571) (xy 64.064139 -148.932134) (xy 64.060068 -148.876512) (xy 63.661051 -148.876512)
			(xy 63.674068 -148.889678) (xy 63.707232 -148.934895) (xy 63.733419 -148.984479) (xy 63.752066 -149.037362)
			(xy 63.762772 -149.092405) (xy 63.765304 -149.148422) (xy 63.75961 -149.204207) (xy 63.745812 -149.258557)
			(xy 63.724206 -149.310302) (xy 63.695259 -149.358327) (xy 63.659593 -149.401598) (xy 63.617978 -149.439181)
			(xy 63.571309 -149.470268) (xy 63.524825 -149.492193) (xy 68.099535 -149.492193) (xy 68.107275 -149.437335)
			(xy 68.122868 -149.384174) (xy 68.145986 -149.333827) (xy 68.176143 -149.287353) (xy 68.212704 -149.245729)
			(xy 68.254901 -149.209831) (xy 68.301847 -149.180414) (xy 68.352553 -149.158095) (xy 68.405955 -149.143345)
			(xy 68.460928 -149.136474) (xy 68.516317 -149.137626) (xy 68.570957 -149.146777) (xy 68.623699 -149.163734)
			(xy 68.673433 -149.188141) (xy 68.719115 -149.219485) (xy 68.759783 -149.257106) (xy 68.794583 -149.300214)
			(xy 68.809108 -149.323806) (xy 68.821145 -149.343165) (xy 68.850948 -149.377653) (xy 68.886426 -149.40627)
			(xy 68.92644 -149.428098) (xy 68.969706 -149.442437) (xy 69.014837 -149.448827) (xy 69.060383 -149.447062)
			(xy 69.104884 -149.4372) (xy 69.146912 -149.419557) (xy 69.185117 -149.394699) (xy 69.202046 -149.379432)
			(xy 69.222523 -149.360771) (xy 69.267891 -149.328974) (xy 69.31738 -149.304073) (xy 69.369951 -149.286591)
			(xy 69.424497 -149.276897) (xy 69.479872 -149.275193) (xy 69.534911 -149.281517) (xy 69.588457 -149.295734)
			(xy 69.639383 -149.317546) (xy 69.686619 -149.346495) (xy 69.729172 -149.381971) (xy 69.766146 -149.423229)
			(xy 69.796765 -149.4694) (xy 69.820383 -149.519514) (xy 69.836505 -149.572517) (xy 69.844792 -149.627295)
			(xy 69.844988 -149.666452) (xy 70.257668 -149.666452) (xy 70.261739 -149.61083) (xy 70.273865 -149.556393)
			(xy 70.293788 -149.504302) (xy 70.321084 -149.455667) (xy 70.35517 -149.411524) (xy 70.395319 -149.372815)
			(xy 70.440677 -149.340364) (xy 70.490277 -149.314863) (xy 70.543061 -149.296856) (xy 70.597904 -149.286726)
			(xy 70.653638 -149.284689) (xy 70.709075 -149.290789) (xy 70.763032 -149.304895) (xy 70.814361 -149.326707)
			(xy 70.861967 -149.355761) (xy 70.904835 -149.391436) (xy 70.942052 -149.432973) (xy 70.972825 -149.479486)
			(xy 70.996497 -149.529983) (xy 71.012565 -149.58339) (xy 71.017537 -149.617176) (xy 71.665082 -149.617176)
			(xy 71.669153 -149.561554) (xy 71.681279 -149.507117) (xy 71.701202 -149.455026) (xy 71.728498 -149.406391)
			(xy 71.762584 -149.362248) (xy 71.802733 -149.323539) (xy 71.848091 -149.291088) (xy 71.897691 -149.265587)
			(xy 71.950475 -149.24758) (xy 72.005318 -149.23745) (xy 72.061052 -149.235413) (xy 72.116489 -149.241513)
			(xy 72.170446 -149.255619) (xy 72.221775 -149.277431) (xy 72.269381 -149.306485) (xy 72.312249 -149.34216)
			(xy 72.349466 -149.383697) (xy 72.380239 -149.43021) (xy 72.403911 -149.480707) (xy 72.419979 -149.534114)
			(xy 72.428099 -149.58929) (xy 72.428608 -149.617176) (xy 72.428099 -149.645062) (xy 72.419979 -149.700238)
			(xy 72.403911 -149.753645) (xy 72.380239 -149.804142) (xy 72.349466 -149.850655) (xy 72.312249 -149.892192)
			(xy 72.269381 -149.927867) (xy 72.221775 -149.956921) (xy 72.170446 -149.978733) (xy 72.116489 -149.992839)
			(xy 72.061052 -149.998939) (xy 72.005318 -149.996902) (xy 71.950475 -149.986772) (xy 71.897691 -149.968765)
			(xy 71.848091 -149.943264) (xy 71.802733 -149.910813) (xy 71.762584 -149.872104) (xy 71.728498 -149.827961)
			(xy 71.701202 -149.779326) (xy 71.681279 -149.727235) (xy 71.669153 -149.672798) (xy 71.665082 -149.617176)
			(xy 71.017537 -149.617176) (xy 71.020685 -149.638566) (xy 71.021194 -149.666452) (xy 71.020685 -149.694338)
			(xy 71.012565 -149.749514) (xy 70.996497 -149.802921) (xy 70.972825 -149.853418) (xy 70.942052 -149.899931)
			(xy 70.904835 -149.941468) (xy 70.861967 -149.977143) (xy 70.814361 -150.006197) (xy 70.763032 -150.028009)
			(xy 70.709075 -150.042115) (xy 70.653638 -150.048215) (xy 70.597904 -150.046178) (xy 70.543061 -150.036048)
			(xy 70.490277 -150.018041) (xy 70.440677 -149.99254) (xy 70.395319 -149.960089) (xy 70.35517 -149.92138)
			(xy 70.321084 -149.877237) (xy 70.293788 -149.828602) (xy 70.273865 -149.776511) (xy 70.261739 -149.722074)
			(xy 70.257668 -149.666452) (xy 69.844988 -149.666452) (xy 69.845069 -149.682696) (xy 69.83733 -149.737554)
			(xy 69.821739 -149.790715) (xy 69.798622 -149.841063) (xy 69.768467 -149.887538) (xy 69.731907 -149.929163)
			(xy 69.689711 -149.965063) (xy 69.642767 -149.994482) (xy 69.592061 -150.016803) (xy 69.53866 -150.031555)
			(xy 69.483687 -150.038428) (xy 69.428298 -150.037278) (xy 69.373657 -150.02813) (xy 69.320915 -150.011174)
			(xy 69.271179 -149.986769) (xy 69.225496 -149.955427) (xy 69.184826 -149.917808) (xy 69.150024 -149.874701)
			(xy 69.135498 -149.85111) (xy 69.123452 -149.831756) (xy 69.093651 -149.797268) (xy 69.058175 -149.76865)
			(xy 69.018162 -149.74682) (xy 68.974896 -149.73248) (xy 68.929766 -149.726089) (xy 68.88422 -149.727853)
			(xy 68.83972 -149.737715) (xy 68.797693 -149.755358) (xy 68.759488 -149.780217) (xy 68.74256 -149.795484)
			(xy 68.72207 -149.814131) (xy 68.676702 -149.845927) (xy 68.627212 -149.870827) (xy 68.574641 -149.888308)
			(xy 68.520095 -149.898001) (xy 68.46472 -149.899703) (xy 68.409681 -149.893379) (xy 68.356136 -149.87916)
			(xy 68.30521 -149.857347) (xy 68.257975 -149.828397) (xy 68.215423 -149.79292) (xy 68.17845 -149.751662)
			(xy 68.147833 -149.70549) (xy 68.124216 -149.655375) (xy 68.108095 -149.602371) (xy 68.09981 -149.547593)
			(xy 68.099535 -149.492193) (xy 63.524825 -149.492193) (xy 63.520593 -149.494189) (xy 63.466922 -149.510429)
			(xy 63.411451 -149.518637) (xy 63.355377 -149.518637) (xy 63.299906 -149.510429) (xy 63.246235 -149.494189)
			(xy 63.195519 -149.470268) (xy 63.14885 -149.439181) (xy 63.107235 -149.401598) (xy 63.071569 -149.358327)
			(xy 63.042622 -149.310302) (xy 63.021016 -149.258557) (xy 63.007218 -149.204207) (xy 63.001524 -149.148422)
			(xy 63.004056 -149.092405) (xy 63.014762 -149.037362) (xy 63.033409 -148.984479) (xy 63.059596 -148.934895)
			(xy 63.09276 -148.889678) (xy 63.132185 -148.849803) (xy 63.154306 -148.83257) (xy 63.172784 -148.817988)
			(xy 63.20455 -148.78326) (xy 63.229377 -148.743277) (xy 63.246418 -148.699406) (xy 63.255087 -148.653147)
			(xy 63.25509 -148.606082) (xy 63.246425 -148.559822) (xy 63.22939 -148.515949) (xy 63.204567 -148.475963)
			(xy 63.172805 -148.441232) (xy 63.154306 -148.426678) (xy 63.132834 -148.410037) (xy 63.094467 -148.371578)
			(xy 63.061943 -148.328066) (xy 63.03592 -148.280379) (xy 63.016925 -148.229484) (xy 63.005341 -148.176409)
			(xy 63.001404 -148.122227) (xy 58.733828 -148.122227) (xy 58.737281 -148.131291) (xy 58.749266 -148.184815)
			(xy 58.753461 -148.239504) (xy 58.749781 -148.29423) (xy 58.738299 -148.347865) (xy 58.719254 -148.399302)
			(xy 58.693039 -148.447481) (xy 58.660193 -148.491408) (xy 58.621394 -148.530179) (xy 58.577442 -148.562992)
			(xy 58.529244 -148.589172) (xy 58.477792 -148.608178) (xy 58.424149 -148.61962) (xy 58.369421 -148.62326)
			(xy 58.314735 -148.619024) (xy 58.261219 -148.606999) (xy 58.209978 -148.587434) (xy 58.162068 -148.560731)
			(xy 58.118476 -148.527441) (xy 58.080101 -148.48825) (xy 58.047735 -148.443968) (xy 58.022046 -148.395506)
			(xy 58.003562 -148.343865) (xy 57.992666 -148.290108) (xy 57.989581 -148.235346) (xy 57.991502 -148.207984)
			(xy 57.993027 -148.185844) (xy 57.989184 -148.141635) (xy 57.97772 -148.098766) (xy 57.958986 -148.058538)
			(xy 57.933549 -148.022176) (xy 57.902183 -147.990785) (xy 57.865842 -147.965318) (xy 57.82563 -147.946551)
			(xy 57.78277 -147.935052) (xy 57.738564 -147.931173) (xy 57.71642 -147.932648) (xy 57.689055 -147.934512)
			(xy 57.634296 -147.931384) (xy 57.580549 -147.920446) (xy 57.528924 -147.901922) (xy 57.480484 -147.876195)
			(xy 57.436228 -147.843795) (xy 57.397069 -147.805391) (xy 57.363814 -147.761774) (xy 57.33715 -147.713844)
			(xy 57.317625 -147.662588) (xy 57.305643 -147.609065) (xy 57.30145 -147.554377) (xy 56.332545 -147.554377)
			(xy 56.32947 -147.561727) (xy 56.300657 -147.609526) (xy 56.265188 -147.652618) (xy 56.22382 -147.690084)
			(xy 56.177436 -147.721123) (xy 56.127024 -147.745073) (xy 56.073662 -147.761425) (xy 56.018486 -147.769828)
			(xy 55.962675 -147.770103) (xy 55.907419 -147.762245) (xy 55.853898 -147.746421) (xy 55.803252 -147.722969)
			(xy 55.756564 -147.69239) (xy 55.714828 -147.655334) (xy 55.678936 -147.612595) (xy 55.649653 -147.565082)
			(xy 55.627604 -147.51381) (xy 55.613259 -147.459873) (xy 55.606925 -147.404422) (xy 53.589891 -147.404422)
			(xy 53.592671 -147.410353) (xy 53.608739 -147.46376) (xy 53.616859 -147.518936) (xy 53.617368 -147.546822)
			(xy 53.616859 -147.574708) (xy 53.608739 -147.629884) (xy 53.592671 -147.683291) (xy 53.568999 -147.733788)
			(xy 53.538226 -147.780301) (xy 53.501009 -147.821838) (xy 53.458141 -147.857513) (xy 53.410535 -147.886567)
			(xy 53.359206 -147.908379) (xy 53.305249 -147.922485) (xy 53.249812 -147.928585) (xy 53.194078 -147.926548)
			(xy 53.139235 -147.916418) (xy 53.086451 -147.898411) (xy 53.036851 -147.87291) (xy 52.991493 -147.840459)
			(xy 52.951344 -147.80175) (xy 52.917258 -147.757607) (xy 52.889962 -147.708972) (xy 52.870039 -147.656881)
			(xy 52.857913 -147.602444) (xy 52.853842 -147.546822) (xy 49.414054 -147.546822) (xy 49.415199 -147.550628)
			(xy 49.423319 -147.605804) (xy 49.423828 -147.63369) (xy 49.423319 -147.661576) (xy 49.415199 -147.716752)
			(xy 49.399131 -147.770159) (xy 49.375459 -147.820656) (xy 49.344686 -147.867169) (xy 49.307469 -147.908706)
			(xy 49.264601 -147.944381) (xy 49.216995 -147.973435) (xy 49.165666 -147.995247) (xy 49.111709 -148.009353)
			(xy 49.056272 -148.015453) (xy 49.000538 -148.013416) (xy 48.945695 -148.003286) (xy 48.892911 -147.985279)
			(xy 48.843311 -147.959778) (xy 48.797953 -147.927327) (xy 48.757804 -147.888618) (xy 48.723718 -147.844475)
			(xy 48.696422 -147.79584) (xy 48.676499 -147.743749) (xy 48.664373 -147.689312) (xy 48.660302 -147.63369)
			(xy 41.336243 -147.63369) (xy 41.337999 -147.639528) (xy 41.346119 -147.694704) (xy 41.346628 -147.72259)
			(xy 41.346119 -147.750476) (xy 41.337999 -147.805652) (xy 41.321931 -147.859059) (xy 41.298259 -147.909556)
			(xy 41.267486 -147.956069) (xy 41.230269 -147.997606) (xy 41.187401 -148.033281) (xy 41.139795 -148.062335)
			(xy 41.088466 -148.084147) (xy 41.034509 -148.098253) (xy 40.979072 -148.104353) (xy 40.923338 -148.102316)
			(xy 40.868495 -148.092186) (xy 40.815711 -148.074179) (xy 40.766111 -148.048678) (xy 40.720753 -148.016227)
			(xy 40.680604 -147.977518) (xy 40.646518 -147.933375) (xy 40.619222 -147.88474) (xy 40.599299 -147.832649)
			(xy 40.587173 -147.778212) (xy 40.583102 -147.72259) (xy 39.313358 -147.72259) (xy 39.402004 -147.811236)
			(xy 39.41413 -147.822681) (xy 39.442985 -147.839369) (xy 39.475177 -147.848016) (xy 39.508511 -147.84803)
			(xy 39.540711 -147.839412) (xy 39.55542 -147.831556) (xy 39.579698 -147.818137) (xy 39.631263 -147.797688)
			(xy 39.685245 -147.784924) (xy 39.740507 -147.780115) (xy 39.795883 -147.783362) (xy 39.850205 -147.794596)
			(xy 39.902326 -147.813581) (xy 39.951148 -147.839915) (xy 39.995639 -147.873044) (xy 40.034863 -147.912269)
			(xy 40.067991 -147.956762) (xy 40.094324 -148.005584) (xy 40.113307 -148.057706) (xy 40.12454 -148.112027)
			(xy 40.127785 -148.167404) (xy 40.122974 -148.222666) (xy 40.110209 -148.276648) (xy 40.089759 -148.328212)
			(xy 40.076374 -148.35251) (xy 40.068526 -148.367181) (xy 40.059907 -148.399305) (xy 40.059889 -148.432564)
			(xy 40.068475 -148.464697) (xy 40.08508 -148.493515) (xy 40.09644 -148.505672) (xy 40.536876 -148.946108)
			(xy 40.547674 -148.956356) (xy 40.573011 -148.971973) (xy 40.601281 -148.981281) (xy 40.63094 -148.983773)
			(xy 40.660367 -148.979313) (xy 40.67429 -148.974048) (xy 40.699511 -148.964339) (xy 40.751962 -148.951323)
			(xy 40.805725 -148.945839) (xy 40.859724 -148.947999) (xy 40.912877 -148.957758) (xy 40.964121 -148.974921)
			(xy 41.01243 -148.999145) (xy 41.056836 -149.029945) (xy 41.09645 -149.066704) (xy 41.13048 -149.108686)
			(xy 41.158244 -149.155051) (xy 41.179187 -149.20487) (xy 41.192888 -149.257146) (xy 41.196514 -149.283928)
			(xy 41.199686 -149.30683) (xy 41.213237 -149.351029) (xy 41.234556 -149.39205) (xy 41.262941 -149.42854)
			(xy 41.297455 -149.459296) (xy 41.336962 -149.483305) (xy 41.380159 -149.499774) (xy 41.425621 -149.508162)
			(xy 41.448736 -149.508718) (xy 41.68521 -149.508718) (xy 41.70862 -149.50819) (xy 41.754651 -149.499625)
			(xy 41.798331 -149.482768) (xy 41.838182 -149.45819) (xy 41.872853 -149.426725) (xy 41.901169 -149.389437)
			(xy 41.922171 -149.347592) (xy 41.935148 -149.302605) (xy 41.93794 -149.279356) (xy 41.940912 -149.25359)
			(xy 41.952936 -149.203136) (xy 41.971685 -149.154776) (xy 41.996813 -149.109403) (xy 42.027857 -149.067852)
			(xy 42.064244 -149.03089) (xy 42.084498 -149.014688) (xy 42.102723 -148.999934) (xy 42.133945 -148.96496)
			(xy 42.158227 -148.924854) (xy 42.174742 -148.880976) (xy 42.182933 -148.834813) (xy 42.182521 -148.787931)
			(xy 42.173521 -148.74192) (xy 42.156236 -148.698339) (xy 42.131254 -148.658665) (xy 42.099421 -148.624245)
			(xy 42.080942 -148.609812) (xy 42.058806 -148.592706) (xy 42.01931 -148.553086) (xy 41.986026 -148.508121)
			(xy 41.959669 -148.458776) (xy 41.940803 -148.406111) (xy 41.929834 -148.351253) (xy 41.926996 -148.295382)
			(xy 41.932352 -148.239696) (xy 41.945785 -148.18539) (xy 41.967008 -148.133629) (xy 41.995565 -148.085524)
			(xy 42.030843 -148.042106) (xy 42.072086 -148.004309) (xy 42.118408 -147.972942) (xy 42.168816 -147.948679)
			(xy 42.222228 -147.932041) (xy 42.277497 -147.923384) (xy 42.333438 -147.922895) (xy 42.38885 -147.930583)
			(xy 42.442544 -147.946284) (xy 42.493369 -147.969661) (xy 42.540233 -148.000212) (xy 42.582131 -148.037282)
			(xy 42.618164 -148.080075) (xy 42.647558 -148.127674) (xy 42.669684 -148.179055) (xy 42.684065 -148.233118)
			(xy 42.690394 -148.288702) (xy 42.688535 -148.344614) (xy 42.688485 -148.34489) (xy 43.415202 -148.34489)
			(xy 43.419273 -148.289268) (xy 43.431399 -148.234831) (xy 43.451322 -148.18274) (xy 43.478618 -148.134105)
			(xy 43.512704 -148.089962) (xy 43.552853 -148.051253) (xy 43.598211 -148.018802) (xy 43.647811 -147.993301)
			(xy 43.700595 -147.975294) (xy 43.755438 -147.965164) (xy 43.811172 -147.963127) (xy 43.866609 -147.969227)
			(xy 43.920566 -147.983333) (xy 43.971895 -148.005145) (xy 44.019501 -148.034199) (xy 44.062369 -148.069874)
			(xy 44.099586 -148.111411) (xy 44.130359 -148.157924) (xy 44.154031 -148.208421) (xy 44.15688 -148.21789)
			(xy 44.786802 -148.21789) (xy 44.790873 -148.162268) (xy 44.802999 -148.107831) (xy 44.822922 -148.05574)
			(xy 44.850218 -148.007105) (xy 44.884304 -147.962962) (xy 44.924453 -147.924253) (xy 44.969811 -147.891802)
			(xy 45.019411 -147.866301) (xy 45.072195 -147.848294) (xy 45.127038 -147.838164) (xy 45.182772 -147.836127)
			(xy 45.238209 -147.842227) (xy 45.292166 -147.856333) (xy 45.343495 -147.878145) (xy 45.391101 -147.907199)
			(xy 45.433969 -147.942874) (xy 45.471186 -147.984411) (xy 45.501959 -148.030924) (xy 45.525631 -148.081421)
			(xy 45.541699 -148.134828) (xy 45.549819 -148.190004) (xy 45.550328 -148.21789) (xy 45.549819 -148.245776)
			(xy 45.541699 -148.300952) (xy 45.525631 -148.354359) (xy 45.521735 -148.36267) (xy 50.136042 -148.36267)
			(xy 50.140113 -148.307048) (xy 50.152239 -148.252611) (xy 50.172162 -148.20052) (xy 50.199458 -148.151885)
			(xy 50.233544 -148.107742) (xy 50.273693 -148.069033) (xy 50.319051 -148.036582) (xy 50.368651 -148.011081)
			(xy 50.421435 -147.993074) (xy 50.476278 -147.982944) (xy 50.532012 -147.980907) (xy 50.587449 -147.987007)
			(xy 50.641406 -148.001113) (xy 50.692735 -148.022925) (xy 50.740341 -148.051979) (xy 50.783209 -148.087654)
			(xy 50.820426 -148.129191) (xy 50.851199 -148.175704) (xy 50.874871 -148.226201) (xy 50.890939 -148.279608)
			(xy 50.899059 -148.334784) (xy 50.899568 -148.36267) (xy 50.899059 -148.390556) (xy 50.890939 -148.445732)
			(xy 50.874871 -148.499139) (xy 50.851199 -148.549636) (xy 50.842475 -148.562822) (xy 52.942742 -148.562822)
			(xy 52.946813 -148.5072) (xy 52.958939 -148.452763) (xy 52.978862 -148.400672) (xy 53.006158 -148.352037)
			(xy 53.040244 -148.307894) (xy 53.080393 -148.269185) (xy 53.125751 -148.236734) (xy 53.175351 -148.211233)
			(xy 53.228135 -148.193226) (xy 53.282978 -148.183096) (xy 53.338712 -148.181059) (xy 53.394149 -148.187159)
			(xy 53.448106 -148.201265) (xy 53.499435 -148.223077) (xy 53.547041 -148.252131) (xy 53.589909 -148.287806)
			(xy 53.627126 -148.329343) (xy 53.657899 -148.375856) (xy 53.681571 -148.426353) (xy 53.697639 -148.47976)
			(xy 53.705759 -148.534936) (xy 53.706268 -148.562822) (xy 53.705759 -148.590708) (xy 53.697639 -148.645884)
			(xy 53.681571 -148.699291) (xy 53.657899 -148.749788) (xy 53.627126 -148.796301) (xy 53.589909 -148.837838)
			(xy 53.547041 -148.873513) (xy 53.499435 -148.902567) (xy 53.448106 -148.924379) (xy 53.394149 -148.938485)
			(xy 53.338712 -148.944585) (xy 53.282978 -148.942548) (xy 53.228135 -148.932418) (xy 53.175351 -148.914411)
			(xy 53.125751 -148.88891) (xy 53.080393 -148.856459) (xy 53.040244 -148.81775) (xy 53.006158 -148.773607)
			(xy 52.978862 -148.724972) (xy 52.958939 -148.672881) (xy 52.946813 -148.618444) (xy 52.942742 -148.562822)
			(xy 50.842475 -148.562822) (xy 50.820426 -148.596149) (xy 50.783209 -148.637686) (xy 50.740341 -148.673361)
			(xy 50.692735 -148.702415) (xy 50.641406 -148.724227) (xy 50.587449 -148.738333) (xy 50.532012 -148.744433)
			(xy 50.476278 -148.742396) (xy 50.421435 -148.732266) (xy 50.368651 -148.714259) (xy 50.319051 -148.688758)
			(xy 50.273693 -148.656307) (xy 50.233544 -148.617598) (xy 50.199458 -148.573455) (xy 50.172162 -148.52482)
			(xy 50.152239 -148.472729) (xy 50.140113 -148.418292) (xy 50.136042 -148.36267) (xy 45.521735 -148.36267)
			(xy 45.501959 -148.404856) (xy 45.471186 -148.451369) (xy 45.433969 -148.492906) (xy 45.391101 -148.528581)
			(xy 45.343495 -148.557635) (xy 45.292166 -148.579447) (xy 45.238209 -148.593553) (xy 45.182772 -148.599653)
			(xy 45.127038 -148.597616) (xy 45.072195 -148.587486) (xy 45.019411 -148.569479) (xy 44.969811 -148.543978)
			(xy 44.924453 -148.511527) (xy 44.884304 -148.472818) (xy 44.850218 -148.428675) (xy 44.822922 -148.38004)
			(xy 44.802999 -148.327949) (xy 44.790873 -148.273512) (xy 44.786802 -148.21789) (xy 44.15688 -148.21789)
			(xy 44.170099 -148.261828) (xy 44.178219 -148.317004) (xy 44.178728 -148.34489) (xy 44.178219 -148.372776)
			(xy 44.170099 -148.427952) (xy 44.154031 -148.481359) (xy 44.130359 -148.531856) (xy 44.099586 -148.578369)
			(xy 44.062369 -148.619906) (xy 44.019501 -148.655581) (xy 43.971895 -148.684635) (xy 43.920566 -148.706447)
			(xy 43.866609 -148.720553) (xy 43.811172 -148.726653) (xy 43.755438 -148.724616) (xy 43.700595 -148.714486)
			(xy 43.647811 -148.696479) (xy 43.598211 -148.670978) (xy 43.552853 -148.638527) (xy 43.512704 -148.599818)
			(xy 43.478618 -148.555675) (xy 43.451322 -148.50704) (xy 43.431399 -148.454949) (xy 43.419273 -148.400512)
			(xy 43.415202 -148.34489) (xy 42.688485 -148.34489) (xy 42.678527 -148.399655) (xy 42.660586 -148.452643)
			(xy 42.635096 -148.502441) (xy 42.602605 -148.547982) (xy 42.563809 -148.588287) (xy 42.541952 -148.605748)
			(xy 42.523728 -148.6205) (xy 42.492505 -148.65547) (xy 42.468226 -148.695574) (xy 42.451712 -148.73945)
			(xy 42.443524 -148.78561) (xy 42.44394 -148.832489) (xy 42.452946 -148.878496) (xy 42.470235 -148.922072)
			(xy 42.495223 -148.961738) (xy 42.527061 -148.996149) (xy 42.545508 -149.010624) (xy 42.566491 -149.026807)
			(xy 42.604211 -149.064022) (xy 42.63642 -149.106099) (xy 42.662495 -149.152228) (xy 42.681937 -149.201522)
			(xy 42.694371 -149.253032) (xy 42.6974 -149.279356) (xy 42.700203 -149.302603) (xy 42.7132 -149.347581)
			(xy 42.734212 -149.389419) (xy 42.762528 -149.426703) (xy 42.797192 -149.458173) (xy 42.837032 -149.482765)
			(xy 42.8807 -149.499647) (xy 42.926721 -149.50825) (xy 42.95013 -149.508718) (xy 44.68495 -149.508718)
			(xy 44.708407 -149.508148) (xy 44.754514 -149.499478) (xy 44.798248 -149.482497) (xy 44.838125 -149.457782)
			(xy 44.872792 -149.426171) (xy 44.901072 -149.388738) (xy 44.922005 -149.346752) (xy 44.934881 -149.301638)
			(xy 44.93768 -149.27834) (xy 44.940677 -149.251282) (xy 44.953361 -149.198342) (xy 44.973441 -149.147742)
			(xy 45.000508 -149.100509) (xy 45.034015 -149.057604) (xy 45.073279 -149.019896) (xy 45.117504 -148.988152)
			(xy 45.165792 -148.963016) (xy 45.217163 -148.944998) (xy 45.270573 -148.934465) (xy 45.324938 -148.93163)
			(xy 45.379153 -148.936551) (xy 45.432119 -148.949128) (xy 45.48276 -148.969105) (xy 45.50664 -148.982176)
			(xy 45.526624 -148.993009) (xy 45.569473 -149.008168) (xy 45.614334 -149.015465) (xy 45.659778 -149.014666)
			(xy 45.704356 -149.005796) (xy 45.746645 -148.98914) (xy 45.785297 -148.965228) (xy 45.80255 -148.950426)
			(xy 45.823597 -148.932158) (xy 45.869996 -148.901291) (xy 45.920393 -148.877503) (xy 45.973715 -148.861302)
			(xy 46.028826 -148.853033) (xy 46.084555 -148.85287) (xy 46.139714 -148.860819) (xy 46.193129 -148.876709)
			(xy 46.243663 -148.900202) (xy 46.290242 -148.930799) (xy 46.331872 -148.967847) (xy 46.367668 -149.010559)
			(xy 46.396869 -149.058025) (xy 46.418851 -149.109235) (xy 46.433149 -149.163099) (xy 46.439456 -149.218469)
			(xy 46.439074 -149.246336) (xy 46.438816 -149.268995) (xy 46.445364 -149.31383) (xy 46.459762 -149.356793)
			(xy 46.481554 -149.396519) (xy 46.510048 -149.431749) (xy 46.54434 -149.461364) (xy 46.583342 -149.484426)
			(xy 46.625818 -149.500203) (xy 46.670418 -149.508194) (xy 46.693074 -149.508718) (xy 49.713642 -149.508718)
			(xy 49.74717 -149.484334) (xy 49.769026 -149.468955) (xy 49.81618 -149.443808) (xy 49.866382 -149.425485)
			(xy 49.91865 -149.414346) (xy 49.97196 -149.410609) (xy 50.02527 -149.414346) (xy 50.077538 -149.425485)
			(xy 50.12774 -149.443808) (xy 50.174894 -149.468955) (xy 50.19675 -149.484334) (xy 50.230278 -149.508718)
			(xy 55.546498 -149.508718) (xy 55.834026 -149.796246) (xy 61.288166 -149.796246) (xy 61.292237 -149.740624)
			(xy 61.304363 -149.686187) (xy 61.324286 -149.634096) (xy 61.351582 -149.585461) (xy 61.385668 -149.541318)
			(xy 61.425817 -149.502609) (xy 61.471175 -149.470158) (xy 61.520775 -149.444657) (xy 61.573559 -149.42665)
			(xy 61.628402 -149.41652) (xy 61.684136 -149.414483) (xy 61.739573 -149.420583) (xy 61.79353 -149.434689)
			(xy 61.844859 -149.456501) (xy 61.892465 -149.485555) (xy 61.935333 -149.52123) (xy 61.97255 -149.562767)
			(xy 62.003323 -149.60928) (xy 62.026995 -149.659777) (xy 62.043063 -149.713184) (xy 62.051183 -149.76836)
			(xy 62.051692 -149.796246) (xy 62.051183 -149.824132) (xy 62.043063 -149.879308) (xy 62.026995 -149.932715)
			(xy 62.003323 -149.983212) (xy 61.97255 -150.029725) (xy 61.935333 -150.071262) (xy 61.892465 -150.106937)
			(xy 61.844859 -150.135991) (xy 61.79353 -150.157803) (xy 61.739573 -150.171909) (xy 61.684136 -150.178009)
			(xy 61.628402 -150.175972) (xy 61.573559 -150.165842) (xy 61.520775 -150.147835) (xy 61.471175 -150.122334)
			(xy 61.425817 -150.089883) (xy 61.385668 -150.051174) (xy 61.351582 -150.007031) (xy 61.324286 -149.958396)
			(xy 61.304363 -149.906305) (xy 61.292237 -149.851868) (xy 61.288166 -149.796246) (xy 55.834026 -149.796246)
			(xy 56.721248 -150.683468) (xy 59.147962 -150.683468) (xy 59.152033 -150.627846) (xy 59.164159 -150.573409)
			(xy 59.184082 -150.521318) (xy 59.211378 -150.472683) (xy 59.245464 -150.42854) (xy 59.285613 -150.389831)
			(xy 59.330971 -150.35738) (xy 59.380571 -150.331879) (xy 59.433355 -150.313872) (xy 59.488198 -150.303742)
			(xy 59.543932 -150.301705) (xy 59.599369 -150.307805) (xy 59.653326 -150.321911) (xy 59.704655 -150.343723)
			(xy 59.752261 -150.372777) (xy 59.795129 -150.408452) (xy 59.832346 -150.449989) (xy 59.863119 -150.496502)
			(xy 59.886791 -150.546999) (xy 59.902859 -150.600406) (xy 59.906771 -150.62699) (xy 73.549219 -150.62699)
			(xy 73.555872 -150.571316) (xy 73.570605 -150.517217) (xy 73.593099 -150.465858) (xy 73.62287 -150.418345)
			(xy 73.640696 -150.396702) (xy 73.650173 -150.385068) (xy 73.663801 -150.358339) (xy 73.670804 -150.329165)
			(xy 73.670796 -150.299162) (xy 73.663776 -150.269992) (xy 73.650133 -150.243271) (xy 73.640696 -150.231602)
			(xy 73.62287 -150.209959) (xy 73.593099 -150.162446) (xy 73.570605 -150.111087) (xy 73.555872 -150.056988)
			(xy 73.549219 -150.001314) (xy 73.550788 -149.945267) (xy 73.560546 -149.890053) (xy 73.578283 -149.836863)
			(xy 73.603616 -149.786843) (xy 73.635999 -149.741071) (xy 73.674734 -149.700532) (xy 73.718987 -149.666102)
			(xy 73.767804 -149.638522) (xy 73.820133 -149.618386) (xy 73.874846 -149.606128) (xy 73.930764 -149.602012)
			(xy 73.986682 -149.606128) (xy 74.041395 -149.618386) (xy 74.093724 -149.638522) (xy 74.142541 -149.666102)
			(xy 74.186794 -149.700532) (xy 74.225529 -149.741071) (xy 74.257912 -149.786843) (xy 74.283245 -149.836863)
			(xy 74.300982 -149.890053) (xy 74.305601 -149.91619) (xy 78.517343 -149.91619) (xy 78.521841 -149.860484)
			(xy 78.53442 -149.80603) (xy 78.554811 -149.753995) (xy 78.582576 -149.705493) (xy 78.617122 -149.661561)
			(xy 78.657709 -149.62314) (xy 78.703467 -149.591053) (xy 78.753419 -149.565987) (xy 78.806493 -149.548479)
			(xy 78.861554 -149.538902) (xy 78.917423 -149.537462) (xy 78.972904 -149.544191) (xy 79.026809 -149.558943)
			(xy 79.077985 -149.581404) (xy 79.125335 -149.611092) (xy 79.146908 -149.62886) (xy 79.158578 -149.638289)
			(xy 79.185297 -149.651919) (xy 79.214461 -149.658927) (xy 79.244455 -149.658927) (xy 79.273619 -149.651919)
			(xy 79.300338 -149.638289) (xy 79.312008 -149.62886) (xy 79.333672 -149.610938) (xy 79.381326 -149.581095)
			(xy 79.432844 -149.558571) (xy 79.48711 -149.543853) (xy 79.542949 -149.53726) (xy 79.599151 -149.538936)
			(xy 79.654498 -149.548842) (xy 79.707792 -149.566766) (xy 79.757877 -149.592319) (xy 79.803668 -149.624946)
			(xy 79.844175 -149.663942) (xy 79.878518 -149.708462) (xy 79.905955 -149.75754) (xy 79.919091 -149.792182)
			(xy 81.896456 -149.792182) (xy 81.900527 -149.73656) (xy 81.912653 -149.682123) (xy 81.932576 -149.630032)
			(xy 81.959872 -149.581397) (xy 81.993958 -149.537254) (xy 82.034107 -149.498545) (xy 82.079465 -149.466094)
			(xy 82.129065 -149.440593) (xy 82.181849 -149.422586) (xy 82.236692 -149.412456) (xy 82.292426 -149.410419)
			(xy 82.347863 -149.416519) (xy 82.40182 -149.430625) (xy 82.453149 -149.452437) (xy 82.500755 -149.481491)
			(xy 82.543623 -149.517166) (xy 82.58084 -149.558703) (xy 82.611613 -149.605216) (xy 82.635285 -149.655713)
			(xy 82.651353 -149.70912) (xy 82.659473 -149.764296) (xy 82.659982 -149.792182) (xy 82.659473 -149.820068)
			(xy 82.651353 -149.875244) (xy 82.635285 -149.928651) (xy 82.611613 -149.979148) (xy 82.58084 -150.025661)
			(xy 82.543623 -150.067198) (xy 82.500755 -150.102873) (xy 82.453149 -150.131927) (xy 82.40182 -150.153739)
			(xy 82.347863 -150.167845) (xy 82.292426 -150.173945) (xy 82.236692 -150.171908) (xy 82.181849 -150.161778)
			(xy 82.129065 -150.143771) (xy 82.079465 -150.11827) (xy 82.034107 -150.085819) (xy 81.993958 -150.04711)
			(xy 81.959872 -150.002967) (xy 81.932576 -149.954332) (xy 81.912653 -149.902241) (xy 81.900527 -149.847804)
			(xy 81.896456 -149.792182) (xy 79.919091 -149.792182) (xy 79.92589 -149.810114) (xy 79.937892 -149.865045)
			(xy 79.9417 -149.921143) (xy 79.937233 -149.977192) (xy 79.924587 -150.031978) (xy 79.904036 -150.084314)
			(xy 79.876025 -150.133067) (xy 79.841162 -150.17718) (xy 79.821024 -150.196804) (xy 79.805302 -150.212234)
			(xy 79.801448 -150.217378) (xy 80.678272 -150.217378) (xy 80.682343 -150.161756) (xy 80.694469 -150.107319)
			(xy 80.714392 -150.055228) (xy 80.741688 -150.006593) (xy 80.775774 -149.96245) (xy 80.815923 -149.923741)
			(xy 80.861281 -149.89129) (xy 80.910881 -149.865789) (xy 80.963665 -149.847782) (xy 81.018508 -149.837652)
			(xy 81.074242 -149.835615) (xy 81.129679 -149.841715) (xy 81.183636 -149.855821) (xy 81.234965 -149.877633)
			(xy 81.282571 -149.906687) (xy 81.325439 -149.942362) (xy 81.362656 -149.983899) (xy 81.393429 -150.030412)
			(xy 81.417101 -150.080909) (xy 81.433169 -150.134316) (xy 81.441289 -150.189492) (xy 81.441798 -150.217378)
			(xy 81.441289 -150.245264) (xy 81.433169 -150.30044) (xy 81.417101 -150.353847) (xy 81.393429 -150.404344)
			(xy 81.362656 -150.450857) (xy 81.325439 -150.492394) (xy 81.282571 -150.528069) (xy 81.234965 -150.557123)
			(xy 81.183636 -150.578935) (xy 81.129679 -150.593041) (xy 81.074242 -150.599141) (xy 81.018508 -150.597104)
			(xy 80.963665 -150.586974) (xy 80.910881 -150.568967) (xy 80.861281 -150.543466) (xy 80.815923 -150.511015)
			(xy 80.775774 -150.472306) (xy 80.741688 -150.428163) (xy 80.714392 -150.379528) (xy 80.694469 -150.327437)
			(xy 80.682343 -150.273) (xy 80.678272 -150.217378) (xy 79.801448 -150.217378) (xy 79.778892 -150.247485)
			(xy 79.75896 -150.286763) (xy 79.746102 -150.328891) (xy 79.740705 -150.372606) (xy 79.74293 -150.416596)
			(xy 79.75271 -150.459543) (xy 79.769753 -150.500159) (xy 79.793548 -150.537226) (xy 79.82338 -150.569632)
			(xy 79.840582 -150.583392) (xy 79.860394 -150.599648) (xy 79.871596 -150.608948) (xy 79.897256 -150.622689)
			(xy 79.925364 -150.63025) (xy 79.939896 -150.631144) (xy 79.95446 -150.631226) (xy 79.983033 -150.62564)
			(xy 80.009599 -150.613728) (xy 80.02143 -150.605236) (xy 80.043786 -150.588704) (xy 80.092393 -150.561706)
			(xy 80.144405 -150.54205) (xy 80.198718 -150.530151) (xy 80.254184 -150.526263) (xy 80.309626 -150.530466)
			(xy 80.363872 -150.542673) (xy 80.415771 -150.562624) (xy 80.464224 -150.589897) (xy 80.508205 -150.623915)
			(xy 80.546783 -150.663956) (xy 80.551957 -150.671186) (xy 96.987831 -150.671186) (xy 96.994484 -150.615512)
			(xy 97.009217 -150.561413) (xy 97.031711 -150.510054) (xy 97.061482 -150.462541) (xy 97.079308 -150.440898)
			(xy 97.088692 -150.429194) (xy 97.102327 -150.402485) (xy 97.109343 -150.37333) (xy 97.109352 -150.343343)
			(xy 97.102352 -150.314183) (xy 97.088733 -150.287467) (xy 97.079308 -150.275798) (xy 97.061482 -150.254155)
			(xy 97.031711 -150.206642) (xy 97.009217 -150.155283) (xy 96.994484 -150.101184) (xy 96.987831 -150.04551)
			(xy 96.9894 -149.989463) (xy 96.999158 -149.934249) (xy 97.016895 -149.881059) (xy 97.042228 -149.831039)
			(xy 97.074611 -149.785267) (xy 97.113346 -149.744728) (xy 97.157599 -149.710298) (xy 97.206416 -149.682718)
			(xy 97.258745 -149.662582) (xy 97.313458 -149.650324) (xy 97.369376 -149.646208) (xy 97.425294 -149.650324)
			(xy 97.480007 -149.662582) (xy 97.532336 -149.682718) (xy 97.581153 -149.710298) (xy 97.625406 -149.744728)
			(xy 97.664141 -149.785267) (xy 97.696524 -149.831039) (xy 97.721857 -149.881059) (xy 97.739594 -149.934249)
			(xy 97.749352 -149.989463) (xy 97.750921 -150.04551) (xy 97.744268 -150.101184) (xy 97.729535 -150.155283)
			(xy 97.707041 -150.206642) (xy 97.67727 -150.254155) (xy 97.659444 -150.275798) (xy 97.649971 -150.287434)
			(xy 97.636349 -150.314164) (xy 97.62935 -150.343336) (xy 97.629358 -150.373337) (xy 97.636375 -150.402505)
			(xy 97.650011 -150.429227) (xy 97.659444 -150.440898) (xy 97.67727 -150.462541) (xy 97.707041 -150.510054)
			(xy 97.729535 -150.561413) (xy 97.744268 -150.615512) (xy 97.750921 -150.671186) (xy 97.749352 -150.727233)
			(xy 97.739594 -150.782447) (xy 97.721857 -150.835637) (xy 97.696524 -150.885657) (xy 97.664141 -150.931429)
			(xy 97.625406 -150.971968) (xy 97.581153 -151.006398) (xy 97.532336 -151.033978) (xy 97.480007 -151.054114)
			(xy 97.425294 -151.066372) (xy 97.369376 -151.070488) (xy 97.313458 -151.066372) (xy 97.258745 -151.054114)
			(xy 97.206416 -151.033978) (xy 97.157599 -151.006398) (xy 97.113346 -150.971968) (xy 97.074611 -150.931429)
			(xy 97.042228 -150.885657) (xy 97.016895 -150.835637) (xy 96.999158 -150.782447) (xy 96.9894 -150.727233)
			(xy 96.987831 -150.671186) (xy 80.551957 -150.671186) (xy 80.57914 -150.709173) (xy 80.604591 -150.758608)
			(xy 80.622597 -150.811213) (xy 80.632776 -150.865875) (xy 80.634913 -150.921436) (xy 80.628963 -150.976718)
			(xy 80.615051 -151.030552) (xy 80.593472 -151.081795) (xy 80.564684 -151.129364) (xy 80.529296 -151.17225)
			(xy 80.488057 -151.209546) (xy 80.441842 -151.24046) (xy 80.391629 -151.264339) (xy 80.338481 -151.280676)
			(xy 80.283525 -151.289126) (xy 80.227925 -151.289509) (xy 80.172858 -151.281817) (xy 80.11949 -151.266214)
			(xy 80.068953 -151.243029) (xy 80.022316 -151.212755) (xy 80.00111 -151.19477) (xy 79.989904 -151.185475)
			(xy 79.964247 -151.171731) (xy 79.936139 -151.164169) (xy 79.921608 -151.163274) (xy 79.907044 -151.163191)
			(xy 79.878471 -151.168777) (xy 79.851904 -151.18069) (xy 79.840074 -151.189182) (xy 79.817436 -151.205908)
			(xy 79.768188 -151.233162) (xy 79.715469 -151.252881) (xy 79.660424 -151.264637) (xy 79.604249 -151.268175)
			(xy 79.548164 -151.263417) (xy 79.493387 -151.250467) (xy 79.441109 -151.229607) (xy 79.392465 -151.201289)
			(xy 79.370174 -151.184102) (xy 79.335376 -151.156416) (xy 79.246476 -151.156416) (xy 79.211678 -151.184102)
			(xy 79.189833 -151.200983) (xy 79.142199 -151.228893) (xy 79.09104 -151.249645) (xy 79.037424 -151.262806)
			(xy 78.98247 -151.268102) (xy 78.927328 -151.265421) (xy 78.873147 -151.25482) (xy 78.82106 -151.23652)
			(xy 78.772156 -151.210903) (xy 78.727454 -151.178505) (xy 78.687889 -151.140001) (xy 78.654287 -151.096196)
			(xy 78.62735 -151.048006) (xy 78.607641 -150.996436) (xy 78.595571 -150.942564) (xy 78.591392 -150.887514)
			(xy 78.595192 -150.832437) (xy 78.606891 -150.778483) (xy 78.626245 -150.726779) (xy 78.65285 -150.678404)
			(xy 78.68615 -150.634369) (xy 78.705456 -150.614634) (xy 78.720824 -150.598784) (xy 78.746411 -150.562812)
			(xy 78.765394 -150.522959) (xy 78.777202 -150.480424) (xy 78.78148 -150.436488) (xy 78.778097 -150.392474)
			(xy 78.767157 -150.349707) (xy 78.748988 -150.309476) (xy 78.724138 -150.272991) (xy 78.693355 -150.241351)
			(xy 78.675738 -150.228046) (xy 78.653382 -150.211274) (xy 78.613365 -150.17226) (xy 78.579469 -150.127825)
			(xy 78.552421 -150.078919) (xy 78.532798 -150.026589) (xy 78.521021 -149.971957) (xy 78.517343 -149.91619)
			(xy 74.305601 -149.91619) (xy 74.31074 -149.945267) (xy 74.312309 -150.001314) (xy 74.305656 -150.056988)
			(xy 74.290923 -150.111087) (xy 74.268429 -150.162446) (xy 74.238658 -150.209959) (xy 74.220832 -150.231602)
			(xy 74.211452 -150.243308) (xy 74.197823 -150.270017) (xy 74.190811 -150.299171) (xy 74.190802 -150.329156)
			(xy 74.197798 -150.358314) (xy 74.211411 -150.385031) (xy 74.220832 -150.396702) (xy 74.238658 -150.418345)
			(xy 74.268429 -150.465858) (xy 74.290923 -150.517217) (xy 74.305656 -150.571316) (xy 74.312309 -150.62699)
			(xy 74.31074 -150.683037) (xy 74.300982 -150.738251) (xy 74.283245 -150.791441) (xy 74.257912 -150.841461)
			(xy 74.225529 -150.887233) (xy 74.186794 -150.927772) (xy 74.142541 -150.962202) (xy 74.093724 -150.989782)
			(xy 74.041395 -151.009918) (xy 73.986682 -151.022176) (xy 73.930764 -151.026292) (xy 73.874846 -151.022176)
			(xy 73.820133 -151.009918) (xy 73.767804 -150.989782) (xy 73.718987 -150.962202) (xy 73.674734 -150.927772)
			(xy 73.635999 -150.887233) (xy 73.603616 -150.841461) (xy 73.578283 -150.791441) (xy 73.560546 -150.738251)
			(xy 73.550788 -150.683037) (xy 73.549219 -150.62699) (xy 59.906771 -150.62699) (xy 59.910979 -150.655582)
			(xy 59.911488 -150.683468) (xy 59.910979 -150.711354) (xy 59.902859 -150.76653) (xy 59.886791 -150.819937)
			(xy 59.863119 -150.870434) (xy 59.832346 -150.916947) (xy 59.795129 -150.958484) (xy 59.752261 -150.994159)
			(xy 59.704655 -151.023213) (xy 59.653326 -151.045025) (xy 59.599369 -151.059131) (xy 59.543932 -151.065231)
			(xy 59.488198 -151.063194) (xy 59.433355 -151.053064) (xy 59.380571 -151.035057) (xy 59.330971 -151.009556)
			(xy 59.285613 -150.977105) (xy 59.245464 -150.938396) (xy 59.211378 -150.894253) (xy 59.184082 -150.845618)
			(xy 59.164159 -150.793527) (xy 59.152033 -150.73909) (xy 59.147962 -150.683468) (xy 56.721248 -150.683468)
			(xy 57.592468 -151.554688) (xy 57.608801 -151.570312) (xy 57.645915 -151.596101) (xy 57.687003 -151.614923)
			(xy 57.730771 -151.626186) (xy 57.775841 -151.629534) (xy 57.820793 -151.624863) (xy 57.864212 -151.61232)
			(xy 57.904729 -151.592299) (xy 57.94107 -151.565431) (xy 57.956958 -151.549354) (xy 57.976367 -151.529523)
			(xy 58.019904 -151.495121) (xy 58.067966 -151.467391) (xy 58.11954 -151.446918) (xy 58.173535 -151.434134)
			(xy 58.228813 -151.429309) (xy 58.284207 -151.432544) (xy 58.338547 -151.443771) (xy 58.390687 -151.462754)
			(xy 58.439526 -151.489092) (xy 58.484034 -151.522229) (xy 58.52327 -151.561465) (xy 58.556407 -151.605972)
			(xy 58.582745 -151.654811) (xy 58.59721 -151.694541) (xy 60.393124 -151.694541) (xy 60.393601 -151.639825)
			(xy 60.401891 -151.585738) (xy 60.417825 -151.533392) (xy 60.441076 -151.483859) (xy 60.471167 -151.438157)
			(xy 60.507479 -151.397225) (xy 60.549268 -151.361901) (xy 60.595676 -151.332911) (xy 60.64575 -151.310851)
			(xy 60.698463 -151.296172) (xy 60.752732 -151.289177) (xy 60.807444 -151.290008) (xy 60.861475 -151.298649)
			(xy 60.913717 -151.314922) (xy 60.963098 -151.338494) (xy 61.008604 -151.36888) (xy 61.0493 -151.405457)
			(xy 61.067188 -151.426164) (xy 61.081895 -151.443163) (xy 61.116293 -151.472096) (xy 61.155244 -151.494528)
			(xy 61.197533 -151.509758) (xy 61.241841 -151.517313) (xy 61.286788 -151.516955) (xy 61.330971 -151.508698)
			(xy 61.373013 -151.492797) (xy 61.411602 -151.469749) (xy 61.428884 -151.455374) (xy 61.449812 -151.437751)
			(xy 61.495837 -151.408167) (xy 61.545617 -151.385463) (xy 61.598131 -151.370105) (xy 61.6523 -151.362409)
			(xy 61.707013 -151.362532) (xy 61.761147 -151.370472) (xy 61.813591 -151.386065) (xy 61.863268 -151.408993)
			(xy 61.90916 -151.438784) (xy 61.950323 -151.474827) (xy 61.955634 -151.481028) (xy 63.92748 -151.481028)
			(xy 63.931551 -151.425406) (xy 63.943677 -151.370969) (xy 63.9636 -151.318878) (xy 63.990896 -151.270243)
			(xy 64.024982 -151.2261) (xy 64.065131 -151.187391) (xy 64.110489 -151.15494) (xy 64.160089 -151.129439)
			(xy 64.212873 -151.111432) (xy 64.267716 -151.101302) (xy 64.32345 -151.099265) (xy 64.378887 -151.105365)
			(xy 64.432844 -151.119471) (xy 64.484173 -151.141283) (xy 64.531779 -151.170337) (xy 64.574647 -151.206012)
			(xy 64.611864 -151.247549) (xy 64.642637 -151.294062) (xy 64.666309 -151.344559) (xy 64.682377 -151.397966)
			(xy 64.690497 -151.453142) (xy 64.691006 -151.481028) (xy 64.690497 -151.508914) (xy 64.682377 -151.56409)
			(xy 64.666309 -151.617497) (xy 64.642637 -151.667994) (xy 64.611864 -151.714507) (xy 64.574647 -151.756044)
			(xy 64.551066 -151.775668) (xy 75.594716 -151.775668) (xy 75.598787 -151.720046) (xy 75.610913 -151.665609)
			(xy 75.630836 -151.613518) (xy 75.658132 -151.564883) (xy 75.692218 -151.52074) (xy 75.732367 -151.482031)
			(xy 75.777725 -151.44958) (xy 75.827325 -151.424079) (xy 75.880109 -151.406072) (xy 75.934952 -151.395942)
			(xy 75.990686 -151.393905) (xy 76.046123 -151.400005) (xy 76.10008 -151.414111) (xy 76.151409 -151.435923)
			(xy 76.199015 -151.464977) (xy 76.241883 -151.500652) (xy 76.2791 -151.542189) (xy 76.309873 -151.588702)
			(xy 76.333545 -151.639199) (xy 76.349613 -151.692606) (xy 76.357733 -151.747782) (xy 76.358242 -151.775668)
			(xy 76.357733 -151.803554) (xy 76.349613 -151.85873) (xy 76.333545 -151.912137) (xy 76.309873 -151.962634)
			(xy 76.2791 -152.009147) (xy 76.241883 -152.050684) (xy 76.199015 -152.086359) (xy 76.151409 -152.115413)
			(xy 76.10008 -152.137225) (xy 76.046123 -152.151331) (xy 75.990686 -152.157431) (xy 75.934952 -152.155394)
			(xy 75.880109 -152.145264) (xy 75.827325 -152.127257) (xy 75.777725 -152.101756) (xy 75.732367 -152.069305)
			(xy 75.692218 -152.030596) (xy 75.658132 -151.986453) (xy 75.630836 -151.937818) (xy 75.610913 -151.885727)
			(xy 75.598787 -151.83129) (xy 75.594716 -151.775668) (xy 64.551066 -151.775668) (xy 64.531779 -151.791719)
			(xy 64.484173 -151.820773) (xy 64.432844 -151.842585) (xy 64.378887 -151.856691) (xy 64.32345 -151.862791)
			(xy 64.267716 -151.860754) (xy 64.212873 -151.850624) (xy 64.160089 -151.832617) (xy 64.110489 -151.807116)
			(xy 64.065131 -151.774665) (xy 64.024982 -151.735956) (xy 63.990896 -151.691813) (xy 63.9636 -151.643178)
			(xy 63.943677 -151.591087) (xy 63.931551 -151.53665) (xy 63.92748 -151.481028) (xy 61.955634 -151.481028)
			(xy 61.985914 -151.516382) (xy 62.015202 -151.562596) (xy 62.037586 -151.612521) (xy 62.052606 -151.665132)
			(xy 62.059954 -151.719349) (xy 62.059479 -151.77406) (xy 62.051191 -151.828142) (xy 62.035261 -151.880485)
			(xy 62.012014 -151.930014) (xy 61.981929 -151.975713) (xy 61.945623 -152.016644) (xy 61.90384 -152.051967)
			(xy 61.857438 -152.080957) (xy 61.80737 -152.10302) (xy 61.754664 -152.117701) (xy 61.7004 -152.1247)
			(xy 61.645693 -152.123874) (xy 61.591666 -152.115239) (xy 61.539427 -152.098972) (xy 61.490048 -152.075408)
			(xy 61.444544 -152.04503) (xy 61.403847 -152.008461) (xy 61.385958 -151.987758) (xy 61.371203 -151.970802)
			(xy 61.336815 -151.941866) (xy 61.297872 -151.919431) (xy 61.255591 -151.904196) (xy 61.211288 -151.896637)
			(xy 61.166347 -151.896988) (xy 61.122168 -151.90524) (xy 61.08013 -151.921134) (xy 61.041543 -151.944176)
			(xy 61.024262 -151.958548) (xy 61.003316 -151.976154) (xy 60.957288 -152.005743) (xy 60.907505 -152.028452)
			(xy 60.854987 -152.043813) (xy 60.800813 -152.051512) (xy 60.746095 -152.05139) (xy 60.691956 -152.043451)
			(xy 60.639507 -152.027856) (xy 60.589824 -152.004927) (xy 60.543928 -151.975134) (xy 60.502761 -151.939088)
			(xy 60.467167 -151.897529) (xy 60.437877 -151.85131) (xy 60.415492 -151.80138) (xy 60.400472 -151.748764)
			(xy 60.393124 -151.694541) (xy 58.59721 -151.694541) (xy 58.601728 -151.706951) (xy 58.612956 -151.761291)
			(xy 58.616192 -151.816685) (xy 58.611366 -151.871963) (xy 58.598583 -151.925958) (xy 58.57811 -151.977532)
			(xy 58.55038 -152.025594) (xy 58.515978 -152.069131) (xy 58.4962 -152.088596) (xy 58.480086 -152.104454)
			(xy 58.453188 -152.140786) (xy 58.433144 -152.181306) (xy 58.420589 -152.224733) (xy 58.415918 -152.269697)
			(xy 58.419278 -152.314777) (xy 58.430564 -152.358552) (xy 58.449419 -152.399637) (xy 58.475249 -152.436737)
			(xy 58.490866 -152.453086) (xy 58.825638 -152.787858) (xy 63.06947 -152.787858) (xy 63.154052 -152.7556)
			(xy 63.175157 -152.737383) (xy 63.221659 -152.706634) (xy 63.272142 -152.68298) (xy 63.325529 -152.666925)
			(xy 63.380685 -152.658812) (xy 63.436435 -152.658812) (xy 63.491591 -152.666925) (xy 63.544978 -152.68298)
			(xy 63.595461 -152.706634) (xy 63.641963 -152.737383) (xy 63.663068 -152.7556) (xy 63.74765 -152.787858)
			(xy 65.972182 -152.787858) (xy 65.98412 -152.785572) (xy 66.007954 -152.781365) (xy 66.056256 -152.778298)
			(xy 66.104558 -152.781365) (xy 66.128392 -152.785572) (xy 66.14033 -152.787858) (xy 77.150214 -152.787858)
			(xy 77.173898 -152.787339) (xy 77.220449 -152.778574) (xy 77.264568 -152.761333) (xy 77.304727 -152.736212)
			(xy 77.339533 -152.704083) (xy 77.367781 -152.666059) (xy 77.388491 -152.623457) (xy 77.400945 -152.577756)
			(xy 77.404712 -152.530537) (xy 77.40269 -152.506934) (xy 77.400265 -152.479214) (xy 77.402512 -152.423616)
			(xy 77.41281 -152.368933) (xy 77.43094 -152.316327) (xy 77.456519 -152.266911) (xy 77.489003 -152.221734)
			(xy 77.527705 -152.181755) (xy 77.571803 -152.14782) (xy 77.620361 -152.120649) (xy 77.672351 -152.100819)
			(xy 77.72667 -152.088751) (xy 77.782166 -152.084699) (xy 77.837662 -152.088751) (xy 77.891981 -152.100819)
			(xy 77.943971 -152.120649) (xy 77.992529 -152.14782) (xy 78.036627 -152.181755) (xy 78.075329 -152.221734)
			(xy 78.107813 -152.266911) (xy 78.133392 -152.316327) (xy 78.151522 -152.368933) (xy 78.16182 -152.423616)
			(xy 78.164067 -152.479214) (xy 78.161642 -152.506934) (xy 78.159661 -152.530534) (xy 78.163459 -152.577737)
			(xy 78.17593 -152.623421) (xy 78.196645 -152.666005) (xy 78.224886 -152.704018) (xy 78.259677 -152.736145)
			(xy 78.299814 -152.761275) (xy 78.34391 -152.778539) (xy 78.390441 -152.78734) (xy 78.414118 -152.787858)
			(xy 81.491328 -152.787858) (xy 81.528412 -152.824942) (xy 86.548468 -152.824942) (xy 86.571819 -152.824416)
			(xy 86.617735 -152.815891) (xy 86.661321 -152.799122) (xy 86.701112 -152.774674) (xy 86.735766 -152.743368)
			(xy 86.76412 -152.706259) (xy 86.785217 -152.664596) (xy 86.79835 -152.619779) (xy 86.803075 -152.573318)
			(xy 86.799233 -152.526775) (xy 86.786954 -152.481717) (xy 86.766652 -152.43966) (xy 86.753192 -152.420574)
			(xy 86.737016 -152.397677) (xy 86.71084 -152.348103) (xy 86.692202 -152.295232) (xy 86.681504 -152.240202)
			(xy 86.678976 -152.184199) (xy 86.684672 -152.128429) (xy 86.698471 -152.074093) (xy 86.720074 -152.022362)
			(xy 86.749016 -151.974351) (xy 86.784674 -151.931093) (xy 86.82628 -151.89352) (xy 86.872938 -151.862442)
			(xy 86.923641 -151.838529) (xy 86.977299 -151.822294) (xy 87.032756 -151.814088) (xy 87.088816 -151.814088)
			(xy 87.144273 -151.822294) (xy 87.197931 -151.838529) (xy 87.248634 -151.862442) (xy 87.295292 -151.89352)
			(xy 87.336898 -151.931093) (xy 87.372556 -151.974351) (xy 87.401498 -152.022362) (xy 87.423101 -152.074093)
			(xy 87.4369 -152.128429) (xy 87.442596 -152.184199) (xy 87.440068 -152.240202) (xy 87.42937 -152.295232)
			(xy 87.410732 -152.348103) (xy 87.384556 -152.397677) (xy 87.36838 -152.420574) (xy 87.35499 -152.439702)
			(xy 87.334696 -152.481748) (xy 87.322422 -152.526792) (xy 87.318583 -152.573321) (xy 87.323307 -152.619768)
			(xy 87.336434 -152.664571) (xy 87.357525 -152.706223) (xy 87.385868 -152.743321) (xy 87.420511 -152.774619)
			(xy 87.460287 -152.799062) (xy 87.503859 -152.81583) (xy 87.549761 -152.824356) (xy 87.573104 -152.824942)
			(xy 88.862408 -152.824942) (xy 88.885033 -152.824446) (xy 88.929566 -152.81643) (xy 88.971975 -152.800653)
			(xy 89.01092 -152.777614) (xy 89.045167 -152.748041) (xy 89.073636 -152.712869) (xy 89.095424 -152.673211)
			(xy 89.109844 -152.630321) (xy 89.116438 -152.585556) (xy 89.115 -152.540329) (xy 89.105573 -152.496073)
			(xy 89.088457 -152.454186) (xy 89.076784 -152.434798) (xy 89.062516 -152.411452) (xy 89.040084 -152.361548)
			(xy 89.025013 -152.308951) (xy 89.01761 -152.254741) (xy 89.018029 -152.200028) (xy 89.02626 -152.145937)
			(xy 89.042135 -152.093577) (xy 89.065328 -152.044023) (xy 89.095362 -151.99829) (xy 89.131623 -151.957317)
			(xy 89.173366 -151.921946) (xy 89.219734 -151.892901) (xy 89.269775 -151.870778) (xy 89.322465 -151.856033)
			(xy 89.37672 -151.848966) (xy 89.431428 -151.849723) (xy 89.485467 -151.858289) (xy 89.537728 -151.874488)
			(xy 89.587138 -151.897987) (xy 89.632684 -151.928305) (xy 89.673432 -151.964818) (xy 89.708544 -152.006779)
			(xy 89.737301 -152.053326) (xy 89.759113 -152.103504) (xy 89.773533 -152.156283) (xy 89.780263 -152.210581)
			(xy 89.779167 -152.265284) (xy 89.770267 -152.319269) (xy 89.753745 -152.371428) (xy 89.72994 -152.420692)
			(xy 89.699341 -152.46605) (xy 89.662576 -152.50657) (xy 89.620399 -152.541422) (xy 89.573675 -152.569891)
			(xy 89.548716 -152.581102) (xy 89.50706 -152.598882) (xy 89.485978 -152.639268) (xy 89.478403 -152.654963)
			(xy 89.471244 -152.689058) (xy 89.473569 -152.723819) (xy 89.485203 -152.756657) (xy 89.505282 -152.785127)
			(xy 89.51849 -152.796494) (xy 89.553542 -152.824942) (xy 89.803478 -152.824942) (xy 89.891616 -152.788112)
			(xy 89.907872 -152.773634) (xy 89.908126 -152.77338) (xy 89.929241 -152.755073) (xy 89.975821 -152.724196)
			(xy 90.026405 -152.700441) (xy 90.079913 -152.684317) (xy 90.1352 -152.676168) (xy 90.191084 -152.676168)
			(xy 90.246371 -152.684317) (xy 90.299879 -152.700441) (xy 90.350463 -152.724196) (xy 90.397043 -152.755073)
			(xy 90.418158 -152.77338) (xy 90.418412 -152.773634) (xy 90.434668 -152.788112) (xy 90.522806 -152.824942)
			(xy 91.25712 -152.824942) (xy 91.342464 -152.79116) (xy 91.358466 -152.777952) (xy 91.379192 -152.761064)
			(xy 91.424478 -152.732645) (xy 91.473288 -152.710829) (xy 91.524666 -152.696043) (xy 91.577606 -152.688577)
			(xy 91.63107 -152.688577) (xy 91.68401 -152.696043) (xy 91.735388 -152.710829) (xy 91.784198 -152.732645)
			(xy 91.829484 -152.761064) (xy 91.85021 -152.777952) (xy 91.866212 -152.79116) (xy 91.951556 -152.824942)
			(xy 98.693732 -152.824942) (xy 98.71038 -152.824395) (xy 98.742539 -152.815773) (xy 98.771373 -152.799123)
			(xy 98.794917 -152.775581) (xy 98.811569 -152.746748) (xy 98.820194 -152.71459) (xy 98.820732 -152.697942)
			(xy 98.820732 -151.734774) (xy 99.434904 -151.120856) (xy 102.715314 -151.120856) (xy 102.738932 -151.120342)
			(xy 102.785356 -151.111623) (xy 102.829366 -151.09447) (xy 102.869446 -151.069474) (xy 102.904212 -151.037497)
			(xy 102.932466 -150.999643) (xy 102.953232 -150.957217) (xy 102.965795 -150.911683) (xy 102.968298 -150.888192)
			(xy 102.97108 -150.861356) (xy 102.983236 -150.808793) (xy 103.00267 -150.758463) (xy 103.028996 -150.711371)
			(xy 103.061689 -150.668454) (xy 103.080566 -150.649178) (xy 103.092175 -150.636991) (xy 103.109119 -150.607923)
			(xy 103.117898 -150.575442) (xy 103.117903 -150.541796) (xy 103.109134 -150.509312) (xy 103.092198 -150.480239)
			(xy 103.080566 -150.468076) (xy 103.061379 -150.448586) (xy 103.028218 -150.405097) (xy 103.001607 -150.357318)
			(xy 102.982091 -150.306229) (xy 102.97007 -150.252876) (xy 102.965791 -150.198354) (xy 102.969341 -150.143779)
			(xy 102.980647 -150.090271) (xy 102.999479 -150.038925) (xy 103.025449 -149.990794) (xy 103.058026 -149.946865)
			(xy 103.096541 -149.908038) (xy 103.140207 -149.875109) (xy 103.188126 -149.848752) (xy 103.239319 -149.829508)
			(xy 103.292735 -149.817772) (xy 103.347279 -149.813783) (xy 103.401834 -149.817623) (xy 103.455282 -149.829214)
			(xy 103.506526 -149.848318) (xy 103.554518 -149.874544) (xy 103.598273 -149.907354) (xy 103.636894 -149.946076)
			(xy 103.669591 -149.989916) (xy 103.695692 -150.037975) (xy 103.714664 -150.089269) (xy 103.726116 -150.142747)
			(xy 103.729815 -150.197312) (xy 103.725684 -150.251845) (xy 103.713809 -150.305231) (xy 103.694432 -150.356373)
			(xy 103.667951 -150.404224) (xy 103.634909 -150.447804) (xy 103.615744 -150.467314) (xy 103.604087 -150.479478)
			(xy 103.587059 -150.508534) (xy 103.578233 -150.541036) (xy 103.578227 -150.574715) (xy 103.58704 -150.60722)
			(xy 103.604057 -150.636284) (xy 103.615744 -150.648416) (xy 103.631287 -150.664117) (xy 103.65904 -150.698495)
			(xy 103.671116 -150.716996) (xy 103.687372 -150.74265) (xy 103.72725 -150.766526) (xy 103.739933 -150.773651)
			(xy 103.767621 -150.782549) (xy 103.796605 -150.784953) (xy 103.825381 -150.780737) (xy 103.852457 -150.77012)
			(xy 103.864664 -150.762208) (xy 103.913686 -150.728426) (xy 103.928418 -150.697946) (xy 103.928418 -150.697692)
			(xy 103.941234 -150.672103) (xy 103.973377 -150.624754) (xy 104.012233 -150.582738) (xy 104.056929 -150.546997)
			(xy 104.106462 -150.518334) (xy 104.159721 -150.497392) (xy 104.215511 -150.484641) (xy 104.27258 -150.480366)
			(xy 104.329647 -150.484664) (xy 104.385431 -150.497439) (xy 104.438681 -150.518404) (xy 104.488203 -150.547087)
			(xy 104.51084 -150.564596) (xy 104.545384 -150.592282) (xy 104.634792 -150.592282) (xy 104.669336 -150.564596)
			(xy 104.690601 -150.54818) (xy 104.73685 -150.52085) (xy 104.786476 -150.500278) (xy 104.838496 -150.48687)
			(xy 104.891883 -150.480892) (xy 104.945581 -150.482461) (xy 104.998527 -150.491547) (xy 105.049676 -150.50797)
			(xy 105.098016 -150.531405) (xy 105.133413 -150.555216) (xy 115.414297 -150.555216) (xy 115.420397 -150.499779)
			(xy 115.434503 -150.445822) (xy 115.456315 -150.394493) (xy 115.485369 -150.346887) (xy 115.521044 -150.304019)
			(xy 115.562581 -150.266802) (xy 115.609094 -150.236029) (xy 115.659591 -150.212357) (xy 115.712998 -150.196289)
			(xy 115.768174 -150.188169) (xy 115.79606 -150.18766) (xy 115.823946 -150.188169) (xy 115.879122 -150.196289)
			(xy 115.932529 -150.212357) (xy 115.983026 -150.236029) (xy 116.029539 -150.266802) (xy 116.071076 -150.304019)
			(xy 116.106751 -150.346887) (xy 116.135805 -150.394493) (xy 116.157617 -150.445822) (xy 116.171723 -150.499779)
			(xy 116.177823 -150.555216) (xy 116.175786 -150.61095) (xy 116.165656 -150.665793) (xy 116.147649 -150.718577)
			(xy 116.122148 -150.768177) (xy 116.089697 -150.813535) (xy 116.050988 -150.853684) (xy 116.006845 -150.88777)
			(xy 115.95821 -150.915066) (xy 115.906119 -150.934989) (xy 115.851682 -150.947115) (xy 115.79606 -150.951186)
			(xy 115.740438 -150.947115) (xy 115.686001 -150.934989) (xy 115.63391 -150.915066) (xy 115.585275 -150.88777)
			(xy 115.541132 -150.853684) (xy 115.502423 -150.813535) (xy 115.469972 -150.768177) (xy 115.444471 -150.718577)
			(xy 115.426464 -150.665793) (xy 115.416334 -150.61095) (xy 115.414297 -150.555216) (xy 105.133413 -150.555216)
			(xy 105.14259 -150.561389) (xy 105.182517 -150.597329) (xy 105.217009 -150.638514) (xy 105.245382 -150.684131)
			(xy 105.267077 -150.733276) (xy 105.281663 -150.784978) (xy 105.288853 -150.838216) (xy 105.289096 -150.865078)
			(xy 105.2894 -150.887365) (xy 105.296859 -150.931304) (xy 105.311868 -150.973269) (xy 105.333967 -151.011972)
			(xy 105.362479 -151.046228) (xy 105.396528 -151.074984) (xy 105.435071 -151.097361) (xy 105.476927 -151.112672)
			(xy 105.520812 -151.120446) (xy 105.543096 -151.120856) (xy 105.693718 -151.120856) (xy 106.17896 -151.605996)
			(xy 108.670342 -151.605996) (xy 108.674413 -151.550374) (xy 108.686539 -151.495937) (xy 108.706462 -151.443846)
			(xy 108.733758 -151.395211) (xy 108.767844 -151.351068) (xy 108.807993 -151.312359) (xy 108.853351 -151.279908)
			(xy 108.902951 -151.254407) (xy 108.955735 -151.2364) (xy 109.010578 -151.22627) (xy 109.066312 -151.224233)
			(xy 109.121749 -151.230333) (xy 109.175706 -151.244439) (xy 109.227035 -151.266251) (xy 109.274641 -151.295305)
			(xy 109.317509 -151.33098) (xy 109.354726 -151.372517) (xy 109.385499 -151.41903) (xy 109.409171 -151.469527)
			(xy 109.425239 -151.522934) (xy 109.427175 -151.536088) (xy 118.97 -151.536088) (xy 118.973383 -151.480354)
			(xy 118.984853 -151.425707) (xy 119.004167 -151.373317) (xy 119.030911 -151.324302) (xy 119.064514 -151.279708)
			(xy 119.104259 -151.240489) (xy 119.149296 -151.207483) (xy 119.173752 -151.194008) (xy 119.193542 -151.18302)
			(xy 119.229196 -151.155139) (xy 119.259345 -151.12138) (xy 119.283032 -151.082812) (xy 119.29951 -151.040656)
			(xy 119.308255 -150.996248) (xy 119.308991 -150.950993) (xy 119.305832 -150.928578) (xy 119.301803 -150.900949)
			(xy 119.300903 -150.845123) (xy 119.308151 -150.789762) (xy 119.323391 -150.736048) (xy 119.346298 -150.68513)
			(xy 119.376382 -150.638095) (xy 119.413001 -150.595947) (xy 119.455372 -150.559587) (xy 119.502591 -150.529791)
			(xy 119.553649 -150.507197) (xy 119.607454 -150.492286) (xy 119.662859 -150.485377) (xy 119.718679 -150.486618)
			(xy 119.773721 -150.495983) (xy 119.826811 -150.51327) (xy 119.876814 -150.538111) (xy 119.922662 -150.569976)
			(xy 119.963375 -150.608183) (xy 119.998085 -150.651917) (xy 120.016206 -150.683232) (xy 121.878597 -150.683232)
			(xy 121.884697 -150.627795) (xy 121.898803 -150.573838) (xy 121.920615 -150.522509) (xy 121.949669 -150.474903)
			(xy 121.985344 -150.432035) (xy 122.026881 -150.394818) (xy 122.073394 -150.364045) (xy 122.123891 -150.340373)
			(xy 122.177298 -150.324305) (xy 122.232474 -150.316185) (xy 122.26036 -150.315676) (xy 122.288246 -150.316185)
			(xy 122.343422 -150.324305) (xy 122.396829 -150.340373) (xy 122.447326 -150.364045) (xy 122.493839 -150.394818)
			(xy 122.535376 -150.432035) (xy 122.571051 -150.474903) (xy 122.600105 -150.522509) (xy 122.621917 -150.573838)
			(xy 122.636023 -150.627795) (xy 122.642123 -150.683232) (xy 122.640086 -150.738966) (xy 122.629956 -150.793809)
			(xy 122.611949 -150.846593) (xy 122.586448 -150.896193) (xy 122.553997 -150.941551) (xy 122.515288 -150.9817)
			(xy 122.471145 -151.015786) (xy 122.42251 -151.043082) (xy 122.370419 -151.063005) (xy 122.315982 -151.075131)
			(xy 122.26036 -151.079202) (xy 122.204738 -151.075131) (xy 122.150301 -151.063005) (xy 122.09821 -151.043082)
			(xy 122.049575 -151.015786) (xy 122.005432 -150.9817) (xy 121.966723 -150.941551) (xy 121.934272 -150.896193)
			(xy 121.908771 -150.846593) (xy 121.890764 -150.793809) (xy 121.880634 -150.738966) (xy 121.878597 -150.683232)
			(xy 120.016206 -150.683232) (xy 120.026049 -150.700243) (xy 120.04667 -150.752129) (xy 120.059508 -150.806467)
			(xy 120.064288 -150.862096) (xy 120.060908 -150.917827) (xy 120.049441 -150.97247) (xy 120.030132 -151.024858)
			(xy 120.003392 -151.073872) (xy 119.969793 -151.118465) (xy 119.930054 -151.157685) (xy 119.885022 -151.190692)
			(xy 119.860568 -151.204168) (xy 119.840795 -151.215184) (xy 119.80514 -151.24306) (xy 119.77499 -151.276814)
			(xy 119.7513 -151.315376) (xy 119.73482 -151.357528) (xy 119.726071 -151.401932) (xy 119.725331 -151.447185)
			(xy 119.728488 -151.469598) (xy 119.732508 -151.49723) (xy 119.732526 -151.498318) (xy 122.904757 -151.498318)
			(xy 122.910857 -151.442881) (xy 122.924963 -151.388924) (xy 122.946775 -151.337595) (xy 122.975829 -151.289989)
			(xy 123.011504 -151.247121) (xy 123.053041 -151.209904) (xy 123.099554 -151.179131) (xy 123.150051 -151.155459)
			(xy 123.203458 -151.139391) (xy 123.258634 -151.131271) (xy 123.28652 -151.130762) (xy 123.314406 -151.131271)
			(xy 123.369582 -151.139391) (xy 123.422989 -151.155459) (xy 123.473486 -151.179131) (xy 123.519999 -151.209904)
			(xy 123.561536 -151.247121) (xy 123.597211 -151.289989) (xy 123.626265 -151.337595) (xy 123.648077 -151.388924)
			(xy 123.662183 -151.442881) (xy 123.668283 -151.498318) (xy 123.666246 -151.554052) (xy 123.656116 -151.608895)
			(xy 123.638109 -151.661679) (xy 123.612608 -151.711279) (xy 123.580157 -151.756637) (xy 123.541448 -151.796786)
			(xy 123.497305 -151.830872) (xy 123.44867 -151.858168) (xy 123.396579 -151.878091) (xy 123.342142 -151.890217)
			(xy 123.28652 -151.894288) (xy 123.230898 -151.890217) (xy 123.176461 -151.878091) (xy 123.12437 -151.858168)
			(xy 123.075735 -151.830872) (xy 123.031592 -151.796786) (xy 122.992883 -151.756637) (xy 122.960432 -151.711279)
			(xy 122.934931 -151.661679) (xy 122.916924 -151.608895) (xy 122.906794 -151.554052) (xy 122.904757 -151.498318)
			(xy 119.732526 -151.498318) (xy 119.73341 -151.55306) (xy 119.726164 -151.608425) (xy 119.710925 -151.662142)
			(xy 119.688019 -151.713064) (xy 119.657934 -151.760103) (xy 119.621314 -151.802255) (xy 119.578941 -151.838618)
			(xy 119.53172 -151.868416) (xy 119.48066 -151.891013) (xy 119.426851 -151.905925) (xy 119.371443 -151.912835)
			(xy 119.31562 -151.911594) (xy 119.260574 -151.902229) (xy 119.207481 -151.88494) (xy 119.157475 -151.860096)
			(xy 119.111625 -151.828229) (xy 119.07091 -151.790018) (xy 119.0362 -151.746281) (xy 119.008235 -151.697951)
			(xy 118.987615 -151.646062) (xy 118.974778 -151.59172) (xy 118.97 -151.536088) (xy 109.427175 -151.536088)
			(xy 109.433359 -151.57811) (xy 109.433868 -151.605996) (xy 109.433359 -151.633882) (xy 109.425239 -151.689058)
			(xy 109.409171 -151.742465) (xy 109.385499 -151.792962) (xy 109.354726 -151.839475) (xy 109.317509 -151.881012)
			(xy 109.274641 -151.916687) (xy 109.227035 -151.945741) (xy 109.175706 -151.967553) (xy 109.121749 -151.981659)
			(xy 109.066312 -151.987759) (xy 109.010578 -151.985722) (xy 108.955735 -151.975592) (xy 108.902951 -151.957585)
			(xy 108.853351 -151.932084) (xy 108.807993 -151.899633) (xy 108.767844 -151.860924) (xy 108.733758 -151.816781)
			(xy 108.706462 -151.768146) (xy 108.686539 -151.716055) (xy 108.674413 -151.661618) (xy 108.670342 -151.605996)
			(xy 106.17896 -151.605996) (xy 106.904028 -152.330912) (xy 106.904028 -152.431242) (xy 110.189008 -152.431242)
			(xy 110.193079 -152.37562) (xy 110.205205 -152.321183) (xy 110.225128 -152.269092) (xy 110.252424 -152.220457)
			(xy 110.28651 -152.176314) (xy 110.326659 -152.137605) (xy 110.372017 -152.105154) (xy 110.421617 -152.079653)
			(xy 110.474401 -152.061646) (xy 110.529244 -152.051516) (xy 110.584978 -152.049479) (xy 110.640415 -152.055579)
			(xy 110.694372 -152.069685) (xy 110.745701 -152.091497) (xy 110.793307 -152.120551) (xy 110.836175 -152.156226)
			(xy 110.873392 -152.197763) (xy 110.904165 -152.244276) (xy 110.927837 -152.294773) (xy 110.943905 -152.34818)
			(xy 110.952025 -152.403356) (xy 110.952534 -152.431242) (xy 110.952025 -152.459128) (xy 110.943905 -152.514304)
			(xy 110.935571 -152.542004) (xy 114.877087 -152.542004) (xy 114.883187 -152.486567) (xy 114.897293 -152.43261)
			(xy 114.919105 -152.381281) (xy 114.948159 -152.333675) (xy 114.983834 -152.290807) (xy 115.025371 -152.25359)
			(xy 115.071884 -152.222817) (xy 115.122381 -152.199145) (xy 115.175788 -152.183077) (xy 115.230964 -152.174957)
			(xy 115.25885 -152.174448) (xy 115.286736 -152.174957) (xy 115.341912 -152.183077) (xy 115.387525 -152.1968)
			(xy 116.102128 -152.1968) (xy 116.106201 -152.141141) (xy 116.118336 -152.086668) (xy 116.138272 -152.034542)
			(xy 116.165586 -151.985874) (xy 116.199694 -151.941702) (xy 116.239871 -151.902967) (xy 116.285259 -151.870495)
			(xy 116.334891 -151.844977) (xy 116.387711 -151.826958) (xy 116.44259 -151.816821) (xy 116.498361 -151.814783)
			(xy 116.553835 -151.820886) (xy 116.607828 -151.835002) (xy 116.659191 -151.856829) (xy 116.706829 -151.885902)
			(xy 116.749725 -151.921601) (xy 116.786967 -151.963165) (xy 116.817761 -152.009709) (xy 116.841449 -152.06024)
			(xy 116.857527 -152.113682) (xy 116.865653 -152.168896) (xy 116.866162 -152.1968) (xy 116.865653 -152.224704)
			(xy 116.857527 -152.279918) (xy 116.841449 -152.33336) (xy 116.817761 -152.383891) (xy 116.786967 -152.430435)
			(xy 116.749725 -152.471999) (xy 116.706829 -152.507698) (xy 116.659191 -152.536771) (xy 116.607828 -152.558598)
			(xy 116.553835 -152.572714) (xy 116.498361 -152.578817) (xy 116.44259 -152.576779) (xy 116.387711 -152.566642)
			(xy 116.334891 -152.548623) (xy 116.285259 -152.523105) (xy 116.239871 -152.490633) (xy 116.199694 -152.451898)
			(xy 116.165586 -152.407726) (xy 116.138272 -152.359058) (xy 116.118336 -152.306932) (xy 116.106201 -152.252459)
			(xy 116.102128 -152.1968) (xy 115.387525 -152.1968) (xy 115.395319 -152.199145) (xy 115.445816 -152.222817)
			(xy 115.492329 -152.25359) (xy 115.533866 -152.290807) (xy 115.569541 -152.333675) (xy 115.598595 -152.381281)
			(xy 115.620407 -152.43261) (xy 115.634513 -152.486567) (xy 115.640613 -152.542004) (xy 115.638576 -152.597738)
			(xy 115.628446 -152.652581) (xy 115.610439 -152.705365) (xy 115.584938 -152.754965) (xy 115.552487 -152.800323)
			(xy 115.513778 -152.840472) (xy 115.469635 -152.874558) (xy 115.421 -152.901854) (xy 115.368909 -152.921777)
			(xy 115.314472 -152.933903) (xy 115.25885 -152.937974) (xy 115.203228 -152.933903) (xy 115.148791 -152.921777)
			(xy 115.0967 -152.901854) (xy 115.048065 -152.874558) (xy 115.003922 -152.840472) (xy 114.965213 -152.800323)
			(xy 114.932762 -152.754965) (xy 114.907261 -152.705365) (xy 114.889254 -152.652581) (xy 114.879124 -152.597738)
			(xy 114.877087 -152.542004) (xy 110.935571 -152.542004) (xy 110.927837 -152.567711) (xy 110.904165 -152.618208)
			(xy 110.873392 -152.664721) (xy 110.836175 -152.706258) (xy 110.793307 -152.741933) (xy 110.745701 -152.770987)
			(xy 110.694372 -152.792799) (xy 110.640415 -152.806905) (xy 110.584978 -152.813005) (xy 110.529244 -152.810968)
			(xy 110.474401 -152.800838) (xy 110.421617 -152.782831) (xy 110.372017 -152.75733) (xy 110.326659 -152.724879)
			(xy 110.28651 -152.68617) (xy 110.252424 -152.642027) (xy 110.225128 -152.593392) (xy 110.205205 -152.541301)
			(xy 110.193079 -152.486864) (xy 110.189008 -152.431242) (xy 106.904028 -152.431242) (xy 106.904028 -152.723088)
			(xy 106.904521 -152.739742) (xy 106.913141 -152.771917) (xy 106.929796 -152.800763) (xy 106.95335 -152.824314)
			(xy 106.982198 -152.840965) (xy 107.014373 -152.849581) (xy 107.031028 -152.850088) (xy 107.381802 -152.850088)
			(xy 108.76788 -154.236166)
		)
		(stroke
			(width 0)
			(type solid)
		)
		(fill yes)
		(layer "In7.Cu")
		(net "P1V538_BMC_NODE1")
	)
	(gr_poly
		(pts
			(xy 50.20056 -199.103742) (xy 50.20056 -187.056268) (xy 50.18786 -187.029852) (xy 50.183796 -187.02147)
			(xy 50.183034 -187.0202) (xy 50.183034 -187.019946) (xy 50.182272 -187.018168) (xy 50.171838 -186.993642)
			(xy 50.157148 -186.942407) (xy 50.149733 -186.889626) (xy 50.149736 -186.836327) (xy 50.157158 -186.783547)
			(xy 50.171854 -186.732313) (xy 50.182272 -186.70778) (xy 50.183034 -186.706002) (xy 50.183034 -186.705748)
			(xy 50.183796 -186.704478) (xy 50.18786 -186.696096) (xy 50.20056 -186.66968) (xy 50.20056 -184.500774)
			(xy 50.200083 -184.477941) (xy 50.191929 -184.43301) (xy 50.175871 -184.390261) (xy 50.152426 -184.351073)
			(xy 50.122351 -184.316711) (xy 50.086615 -184.288281) (xy 50.046371 -184.2667) (xy 50.002916 -184.252665)
			(xy 49.957651 -184.246628) (xy 49.912037 -184.248784) (xy 49.889664 -184.253378) (xy 49.862864 -184.259059)
			(xy 49.808267 -184.263582) (xy 49.753585 -184.260251) (xy 49.699941 -184.249135) (xy 49.648439 -184.230461)
			(xy 49.600136 -184.204614) (xy 49.556025 -184.172126) (xy 49.517014 -184.133663) (xy 49.483905 -184.090017)
			(xy 49.457377 -184.042085) (xy 49.447196 -184.01665) (xy 49.438635 -183.995495) (xy 49.415114 -183.956391)
			(xy 49.384992 -183.922113) (xy 49.349237 -183.89376) (xy 49.308996 -183.872243) (xy 49.265562 -183.858251)
			(xy 49.220328 -183.852235) (xy 49.197514 -183.85282) (xy 49.166272 -183.85409) (xy 49.162462 -183.85409)
			(xy 49.139481 -183.854381) (xy 49.094203 -183.862243) (xy 49.051077 -183.878121) (xy 49.011511 -183.901497)
			(xy 48.976794 -183.931608) (xy 48.948059 -183.967472) (xy 48.926243 -184.00792) (xy 48.918622 -184.029604)
			(xy 48.910594 -184.055681) (xy 48.888118 -184.105398) (xy 48.858788 -184.151405) (xy 48.823202 -184.192764)
			(xy 48.782086 -184.22863) (xy 48.73628 -184.258273) (xy 48.686717 -184.281086) (xy 48.634409 -184.296605)
			(xy 48.580424 -184.304513) (xy 48.525863 -184.304648) (xy 48.47184 -184.297008) (xy 48.419456 -184.281748)
			(xy 48.369781 -184.259181) (xy 48.323828 -184.229766) (xy 48.302926 -184.21223) (xy 48.283023 -184.194485)
			(xy 48.247878 -184.154384) (xy 48.21866 -184.109779) (xy 48.195938 -184.061539) (xy 48.18761 -184.036208)
			(xy 48.179987 -184.013402) (xy 48.157426 -183.970946) (xy 48.127286 -183.933488) (xy 48.09064 -183.902364)
			(xy 48.048796 -183.878686) (xy 48.003247 -183.863297) (xy 47.955617 -183.856746) (xy 47.931578 -183.857392)
			(xy 47.895002 -183.85917) (xy 47.894748 -183.85917) (xy 47.871794 -183.859621) (xy 47.826619 -183.867779)
			(xy 47.783642 -183.883911) (xy 47.744257 -183.907494) (xy 47.709743 -183.937761) (xy 47.681221 -183.973731)
			(xy 47.659616 -184.014235) (xy 47.652178 -184.035954) (xy 47.644026 -184.062398) (xy 47.621147 -184.112782)
			(xy 47.591221 -184.159327) (xy 47.55488 -184.201056) (xy 47.512887 -184.23709) (xy 47.466123 -184.266674)
			(xy 47.415574 -184.289184) (xy 47.362301 -184.304149) (xy 47.334932 -184.308242) (xy 47.308165 -184.311257)
			(xy 47.254305 -184.310626) (xy 47.201069 -184.30243) (xy 47.149513 -184.286832) (xy 47.100662 -184.264142)
			(xy 47.055486 -184.234809) (xy 47.014881 -184.199417) (xy 46.979655 -184.158669) (xy 46.950507 -184.113374)
			(xy 46.928016 -184.06443) (xy 46.919896 -184.038748) (xy 46.913386 -184.018369) (xy 46.894512 -183.97998)
			(xy 46.869471 -183.945297) (xy 46.838972 -183.915301) (xy 46.803878 -183.890841) (xy 46.765181 -183.872607)
			(xy 46.723975 -183.861117) (xy 46.681426 -183.856695) (xy 46.660054 -183.857646) (xy 46.63331 -183.8596)
			(xy 46.579756 -183.856889) (xy 46.527109 -183.846708) (xy 46.476405 -183.829256) (xy 46.428645 -183.804877)
			(xy 46.384767 -183.774052) (xy 46.345638 -183.737388) (xy 46.312026 -183.695606) (xy 46.284596 -183.649531)
			(xy 46.263886 -183.600069) (xy 46.250304 -183.548194) (xy 46.244119 -183.494929) (xy 46.245452 -183.441323)
			(xy 46.254277 -183.388431) (xy 46.270419 -183.337296) (xy 46.293562 -183.288924) (xy 46.30801 -183.266334)
			(xy 46.323368 -183.244087) (xy 46.359357 -183.20375) (xy 46.400679 -183.168896) (xy 46.446506 -183.140225)
			(xy 46.495923 -183.118309) (xy 46.547938 -183.103587) (xy 46.60151 -183.096356) (xy 46.655566 -183.096758)
			(xy 46.709025 -183.104787) (xy 46.760814 -183.120281) (xy 46.809899 -183.142931) (xy 46.855294 -183.172282)
			(xy 46.896093 -183.207748) (xy 46.931476 -183.248616) (xy 46.960737 -183.294071) (xy 46.983288 -183.3432)
			(xy 46.991524 -183.36895) (xy 46.998035 -183.389328) (xy 47.016909 -183.427715) (xy 47.04195 -183.462397)
			(xy 47.072449 -183.492391) (xy 47.107543 -183.516849) (xy 47.14624 -183.535079) (xy 47.187446 -183.546567)
			(xy 47.229993 -183.550986) (xy 47.251366 -183.550052) (xy 47.28591 -183.548528) (xy 47.286672 -183.548528)
			(xy 47.309625 -183.548075) (xy 47.354797 -183.539914) (xy 47.397771 -183.52378) (xy 47.437153 -183.500196)
			(xy 47.471664 -183.469928) (xy 47.500183 -183.433959) (xy 47.521785 -183.393456) (xy 47.529242 -183.371744)
			(xy 47.537669 -183.344496) (xy 47.561483 -183.292674) (xy 47.592751 -183.244976) (xy 47.630773 -183.202467)
			(xy 47.674702 -183.166094) (xy 47.723558 -183.13667) (xy 47.776251 -183.11485) (xy 47.831607 -183.101121)
			(xy 47.88839 -183.095789) (xy 47.945333 -183.098973) (xy 48.001167 -183.110603) (xy 48.054647 -183.130418)
			(xy 48.079914 -183.143652) (xy 48.105297 -183.158239) (xy 48.151662 -183.193982) (xy 48.192021 -183.236389)
			(xy 48.225427 -183.284465) (xy 48.251096 -183.337079) (xy 48.260254 -183.364886) (xy 48.267876 -183.387694)
			(xy 48.290435 -183.430155) (xy 48.320574 -183.467619) (xy 48.35722 -183.498748) (xy 48.399064 -183.522432)
			(xy 48.444615 -183.537828) (xy 48.492248 -183.544385) (xy 48.516286 -183.543702) (xy 48.5521 -183.541924)
			(xy 48.555402 -183.541924) (xy 48.578386 -183.541636) (xy 48.623669 -183.533779) (xy 48.6668 -183.517905)
			(xy 48.706373 -183.494532) (xy 48.741097 -183.464422) (xy 48.769838 -183.428558) (xy 48.79166 -183.388109)
			(xy 48.799242 -183.36641) (xy 48.807461 -183.339741) (xy 48.830615 -183.288966) (xy 48.860925 -183.24211)
			(xy 48.897744 -183.200175) (xy 48.940283 -183.164056) (xy 48.987634 -183.134526) (xy 49.038786 -183.112215)
			(xy 49.092643 -183.097602) (xy 49.120298 -183.093868) (xy 49.148327 -183.090986) (xy 49.204651 -183.092524)
			(xy 49.260136 -183.102336) (xy 49.313571 -183.120208) (xy 49.363793 -183.145752) (xy 49.409709 -183.17841)
			(xy 49.450316 -183.217471) (xy 49.484731 -183.262085) (xy 49.512205 -183.311278) (xy 49.522634 -183.337454)
			(xy 49.531195 -183.358608) (xy 49.554718 -183.397707) (xy 49.584841 -183.431981) (xy 49.620596 -183.460329)
			(xy 49.660836 -183.481842) (xy 49.70427 -183.495829) (xy 49.749502 -183.50184) (xy 49.772316 -183.501284)
			(xy 49.7869 -183.50023) (xy 49.816143 -183.500101) (xy 49.830736 -183.50103) (xy 49.853436 -183.50167)
			(xy 49.898467 -183.495852) (xy 49.941746 -183.482117) (xy 49.981891 -183.460903) (xy 50.017624 -183.432887)
			(xy 50.047803 -183.398962) (xy 50.071468 -183.36021) (xy 50.080164 -183.339232) (xy 50.092674 -183.308964)
			(xy 50.126526 -183.252903) (xy 50.147474 -183.227726) (xy 50.163984 -183.209946) (xy 50.175199 -183.197832)
			(xy 50.191574 -183.169182) (xy 50.200057 -183.137291) (xy 50.20056 -183.120792) (xy 50.20056 -181.623716)
			(xy 50.2001 -181.601372) (xy 50.1923 -181.557369) (xy 50.176919 -181.515411) (xy 50.154433 -181.476792)
			(xy 50.125536 -181.442704) (xy 50.091119 -181.414199) (xy 50.052245 -181.392157) (xy 50.010113 -181.377258)
			(xy 49.966024 -181.369962) (xy 49.921339 -181.370494) (xy 49.899316 -181.374288) (xy 49.872642 -181.379422)
			(xy 49.818439 -181.382976) (xy 49.76428 -181.378809) (xy 49.711259 -181.367003) (xy 49.660449 -181.347799)
			(xy 49.612875 -181.321582) (xy 49.569499 -181.288885) (xy 49.531198 -181.250367) (xy 49.498747 -181.206807)
			(xy 49.472801 -181.159085) (xy 49.453884 -181.108167) (xy 49.442378 -181.05508) (xy 49.438517 -181.000898)
			(xy 49.442379 -180.946717) (xy 49.453884 -180.89363) (xy 49.472802 -180.842712) (xy 49.498749 -180.79499)
			(xy 49.531201 -180.75143) (xy 49.569501 -180.712913) (xy 49.612877 -180.680216) (xy 49.660452 -180.654)
			(xy 49.711263 -180.634796) (xy 49.764283 -180.622991) (xy 49.818442 -180.618824) (xy 49.872645 -180.622379)
			(xy 49.899316 -180.627528) (xy 49.921347 -180.631216) (xy 49.966008 -180.631713) (xy 50.010069 -180.624397)
			(xy 50.052174 -180.609492) (xy 50.091025 -180.587457) (xy 50.125426 -180.558972) (xy 50.15432 -180.524912)
			(xy 50.176816 -180.486326) (xy 50.192221 -180.444403) (xy 50.200063 -180.400432) (xy 50.20056 -180.3781)
			(xy 50.20056 -179.178458) (xy 50.199985 -179.161323) (xy 50.190845 -179.128292) (xy 50.173259 -179.098876)
			(xy 50.148491 -179.075188) (xy 50.11832 -179.05893) (xy 50.101754 -179.054506) (xy 50.1015 -179.054506)
			(xy 50.086258 -179.050889) (xy 50.056375 -179.041478) (xy 50.04181 -179.03571) (xy 50.0211 -179.027745)
			(xy 49.977737 -179.01836) (xy 49.933402 -179.01665) (xy 49.889444 -179.022667) (xy 49.847199 -179.036228)
			(xy 49.807953 -179.056921) (xy 49.772897 -179.084117) (xy 49.743098 -179.116989) (xy 49.730914 -179.135532)
			(xy 49.716595 -179.158172) (xy 49.682603 -179.199576) (xy 49.643154 -179.235817) (xy 49.599022 -179.266183)
			(xy 49.551077 -179.290077) (xy 49.50026 -179.307028) (xy 49.447571 -179.316702) (xy 49.394047 -179.318911)
			(xy 49.340741 -179.31361) (xy 49.2887 -179.300903) (xy 49.238949 -179.281041) (xy 49.192466 -179.254414)
			(xy 49.150165 -179.221546) (xy 49.112878 -179.183084) (xy 49.081339 -179.139783) (xy 49.056167 -179.092495)
			(xy 49.046638 -179.06746) (xy 49.037674 -179.04144) (xy 49.026466 -178.987561) (xy 49.023116 -178.93263)
			(xy 49.027693 -178.877788) (xy 49.040103 -178.824173) (xy 49.060088 -178.772897) (xy 49.087233 -178.725025)
			(xy 49.120975 -178.68155) (xy 49.160614 -178.643375) (xy 49.205327 -178.611291) (xy 49.254186 -178.585965)
			(xy 49.306177 -178.567922) (xy 49.36022 -178.557537) (xy 49.415196 -178.555025) (xy 49.469962 -178.560438)
			(xy 49.523381 -178.573665) (xy 49.54905 -178.58359) (xy 49.569761 -178.591559) (xy 49.613128 -178.600951)
			(xy 49.657467 -178.602667) (xy 49.70143 -178.596654) (xy 49.743681 -178.583097) (xy 49.782934 -178.562406)
			(xy 49.817996 -178.535211) (xy 49.8478 -178.502338) (xy 49.859946 -178.483768) (xy 49.872772 -178.463514)
			(xy 49.902706 -178.426066) (xy 49.919636 -178.409092) (xy 49.938716 -178.391115) (xy 49.98092 -178.36002)
			(xy 50.026981 -178.33499) (xy 50.076032 -178.316495) (xy 50.1015 -178.310286) (xy 50.101754 -178.310286)
			(xy 50.118353 -178.305944) (xy 50.148565 -178.289712) (xy 50.173353 -178.26601) (xy 50.190923 -178.236556)
			(xy 50.2 -178.203483) (xy 50.20056 -178.186334) (xy 50.20056 -177.774092) (xy 50.200098 -177.757991)
			(xy 50.192047 -177.726812) (xy 50.176436 -177.698648) (xy 50.154263 -177.675297) (xy 50.126943 -177.658251)
			(xy 50.096222 -177.648599) (xy 50.080164 -177.647346) (xy 50.052604 -177.645443) (xy 49.998418 -177.634688)
			(xy 49.946349 -177.61623) (xy 49.897487 -177.590456) (xy 49.852852 -177.557905) (xy 49.813378 -177.519257)
			(xy 49.779891 -177.475321) (xy 49.75309 -177.427014) (xy 49.733536 -177.375348) (xy 49.721637 -177.321401)
			(xy 49.717643 -177.266302) (xy 49.721637 -177.211204) (xy 49.733535 -177.157257) (xy 49.753088 -177.10559)
			(xy 49.779888 -177.057283) (xy 49.813375 -177.013346) (xy 49.852848 -176.974698) (xy 49.897483 -176.942146)
			(xy 49.946345 -176.916372) (xy 49.998413 -176.897914) (xy 50.052599 -176.887158) (xy 50.080164 -176.885346)
			(xy 50.096207 -176.884032) (xy 50.126896 -176.874356) (xy 50.154189 -176.857309) (xy 50.176347 -176.833974)
			(xy 50.191961 -176.805838) (xy 50.200038 -176.774689) (xy 50.20056 -176.7586) (xy 50.20056 -176.356264)
			(xy 48.998632 -175.154336) (xy 48.845216 -175.154336) (xy 48.829859 -175.155536) (xy 48.800369 -175.164404)
			(xy 48.773861 -175.180078) (xy 48.751878 -175.201645) (xy 48.735702 -175.22785) (xy 48.726273 -175.257166)
			(xy 48.724141 -175.287887) (xy 48.729429 -175.318225) (xy 48.74183 -175.346413) (xy 48.760621 -175.37081)
			(xy 48.78471 -175.389997) (xy 48.79848 -175.396906) (xy 48.822607 -175.407447) (xy 48.867954 -175.434201)
			(xy 48.909192 -175.466935) (xy 48.945538 -175.505028) (xy 48.976301 -175.547756) (xy 49.000899 -175.594308)
			(xy 49.018863 -175.6438) (xy 49.029852 -175.695291) (xy 49.03216 -175.721518) (xy 49.03363 -175.748292)
			(xy 49.029954 -175.801786) (xy 49.018829 -175.854239) (xy 49.000473 -175.904619) (xy 48.975247 -175.951935)
			(xy 48.943649 -175.995256) (xy 48.906299 -176.033728) (xy 48.863933 -176.066595) (xy 48.817385 -176.09321)
			(xy 48.792638 -176.103534) (xy 48.77201 -176.11224) (xy 48.733947 -176.135809) (xy 48.700604 -176.165684)
			(xy 48.673014 -176.200942) (xy 48.652031 -176.240489) (xy 48.638304 -176.283103) (xy 48.63226 -176.327462)
			(xy 48.634085 -176.372195) (xy 48.643721 -176.415914) (xy 48.660873 -176.457268) (xy 48.672496 -176.476406)
			(xy 48.687119 -176.499111) (xy 48.710513 -176.547786) (xy 48.726808 -176.599274) (xy 48.73568 -176.652545)
			(xy 48.73695 -176.706535) (xy 48.730593 -176.760165) (xy 48.716736 -176.812362) (xy 48.695657 -176.862083)
			(xy 48.667776 -176.908334) (xy 48.63365 -176.950191) (xy 48.593963 -176.986817) (xy 48.549508 -177.01748)
			(xy 48.501172 -177.041567) (xy 48.449922 -177.058596) (xy 48.396783 -177.068228) (xy 48.342816 -177.070269)
			(xy 48.289102 -177.064678) (xy 48.262794 -177.058574) (xy 48.235489 -177.051222) (xy 48.183255 -177.029568)
			(xy 48.134789 -177.000441) (xy 48.091152 -176.964481) (xy 48.0533 -176.922474) (xy 48.022062 -176.875341)
			(xy 47.998122 -176.824114) (xy 47.982004 -176.769915) (xy 47.974061 -176.713931) (xy 47.974468 -176.657387)
			(xy 47.983215 -176.601523) (xy 48.000111 -176.547561) (xy 48.024786 -176.496684) (xy 48.056699 -176.450006)
			(xy 48.095151 -176.408548) (xy 48.139301 -176.373219) (xy 48.188181 -176.344793) (xy 48.21428 -176.333912)
			(xy 48.23491 -176.325206) (xy 48.272977 -176.301636) (xy 48.306324 -176.271759) (xy 48.333919 -176.2365)
			(xy 48.354907 -176.19695) (xy 48.368638 -176.154334) (xy 48.374688 -176.109972) (xy 48.37287 -176.065235)
			(xy 48.363239 -176.02151) (xy 48.346093 -175.980149) (xy 48.334422 -175.96104) (xy 48.319467 -175.937752)
			(xy 48.295708 -175.887766) (xy 48.279417 -175.834874) (xy 48.270935 -175.780184) (xy 48.270439 -175.724842)
			(xy 48.277941 -175.670008) (xy 48.285146 -175.643286) (xy 48.293931 -175.614883) (xy 48.319063 -175.561005)
			(xy 48.352237 -175.51167) (xy 48.392654 -175.46807) (xy 48.439337 -175.431258) (xy 48.464978 -175.41621)
			(xy 48.485152 -175.40426) (xy 48.521122 -175.37419) (xy 48.550966 -175.338031) (xy 48.57367 -175.297012)
			(xy 48.588465 -175.252524) (xy 48.594847 -175.206077) (xy 48.592602 -175.159247) (xy 48.581804 -175.113624)
			(xy 48.56282 -175.070755) (xy 48.536295 -175.032097) (xy 48.520096 -175.015144) (xy 47.285656 -173.780704)
			(xy 47.234602 -173.779688) (xy 47.208053 -173.7787) (xy 47.155596 -173.770284) (xy 47.104815 -173.754671)
			(xy 47.05669 -173.732165) (xy 47.012153 -173.7032) (xy 46.972065 -173.668336) (xy 46.937201 -173.628249)
			(xy 46.908236 -173.583712) (xy 46.885729 -173.535587) (xy 46.870117 -173.484806) (xy 46.8617 -173.432349)
			(xy 46.860714 -173.4058) (xy 46.859698 -173.354746) (xy 45.355764 -171.850812) (xy 45.337984 -171.841668)
			(xy 45.3117 -171.827574) (xy 45.26348 -171.79248) (xy 45.221311 -171.750309) (xy 45.186219 -171.702089)
			(xy 45.172122 -171.675806) (xy 45.162978 -171.658026) (xy 43.351704 -169.846752) (xy 43.335039 -169.830794)
			(xy 43.297066 -169.80459) (xy 43.254986 -169.785673) (xy 43.210183 -169.774663) (xy 43.164128 -169.771922)
			(xy 43.118335 -169.777541) (xy 43.074309 -169.791335) (xy 43.033497 -169.81285) (xy 42.997239 -169.84138)
			(xy 42.966728 -169.875987) (xy 42.954448 -169.89552) (xy 42.940057 -169.919554) (xy 42.90533 -169.963508)
			(xy 42.864549 -170.001911) (xy 42.818591 -170.03394) (xy 42.768444 -170.058904) (xy 42.715186 -170.076267)
			(xy 42.659961 -170.085657) (xy 42.603957 -170.086871) (xy 42.548378 -170.079884) (xy 42.494417 -170.064845)
			(xy 42.443235 -170.042077) (xy 42.395933 -170.012071) (xy 42.353526 -169.975471) (xy 42.316926 -169.933063)
			(xy 42.28692 -169.88576) (xy 42.264154 -169.834578) (xy 42.249115 -169.780617) (xy 42.242128 -169.725038)
			(xy 42.243343 -169.669034) (xy 42.252734 -169.613809) (xy 42.270098 -169.560551) (xy 42.295063 -169.510405)
			(xy 42.327092 -169.464447) (xy 42.365496 -169.423667) (xy 42.40945 -169.38894) (xy 42.433494 -169.374566)
			(xy 42.453005 -169.362255) (xy 42.487607 -169.331747) (xy 42.516133 -169.295494) (xy 42.537646 -169.254687)
			(xy 42.551439 -169.210667) (xy 42.557059 -169.16488) (xy 42.55432 -169.118831) (xy 42.543314 -169.074033)
			(xy 42.524401 -169.031957) (xy 42.498204 -168.993988) (xy 42.482262 -168.97731) (xy 42.169842 -168.66489)
			(xy 42.158478 -168.654154) (xy 42.131682 -168.63807) (xy 42.10178 -168.628981) (xy 42.070566 -168.627433)
			(xy 42.039911 -168.633519) (xy 42.02557 -168.639744) (xy 42.000454 -168.651112) (xy 41.947757 -168.667308)
			(xy 41.893278 -168.675748) (xy 41.838151 -168.676256) (xy 41.783525 -168.668823) (xy 41.730539 -168.653602)
			(xy 41.680295 -168.630911) (xy 41.633843 -168.601223) (xy 41.592148 -168.565157) (xy 41.556081 -168.523463)
			(xy 41.526392 -168.47701) (xy 41.5037 -168.426768) (xy 41.488479 -168.373781) (xy 41.481044 -168.319156)
			(xy 41.481552 -168.264029) (xy 41.489991 -168.209549) (xy 41.506186 -168.156852) (xy 41.51757 -168.131744)
			(xy 41.534842 -168.095168) (xy 41.520872 -168.01592) (xy 41.492424 -167.987472) (xy 41.434004 -167.929052)
			(xy 39.930832 -167.929052) (xy 39.930832 -166.42588) (xy 22.32914 -148.824188) (xy 22.313201 -148.808923)
			(xy 22.277073 -148.783584) (xy 22.237112 -148.764864) (xy 22.194518 -148.753326) (xy 22.150573 -148.749317)
			(xy 22.106594 -148.752956) (xy 22.063905 -148.764135) (xy 22.023788 -148.782517) (xy 21.987447 -148.807551)
			(xy 21.955976 -148.838484) (xy 21.942806 -148.856192) (xy 21.927111 -148.878799) (xy 21.890267 -148.919679)
			(xy 21.847932 -148.954842) (xy 21.800985 -148.983559) (xy 21.7504 -149.005234) (xy 21.697225 -149.019416)
			(xy 21.642565 -149.025813) (xy 21.587552 -149.024291) (xy 21.533329 -149.014881) (xy 21.48102 -148.99778)
			(xy 21.431711 -148.973341) (xy 21.386423 -148.942072) (xy 21.346098 -148.904621) (xy 21.311571 -148.861766)
			(xy 21.283559 -148.814395) (xy 21.262642 -148.763491) (xy 21.249256 -148.710111) (xy 21.243676 -148.655361)
			(xy 21.244306 -148.627846) (xy 21.244341 -148.605038) (xy 21.237211 -148.559992) (xy 21.222147 -148.516946)
			(xy 21.199634 -148.477283) (xy 21.170396 -148.442282) (xy 21.135375 -148.413068) (xy 21.095697 -148.390582)
			(xy 21.05264 -148.375547) (xy 21.030184 -148.37156) (xy 21.004086 -148.366983) (xy 20.953394 -148.35156)
			(xy 20.905326 -148.329267) (xy 20.860808 -148.300534) (xy 20.820696 -148.265915) (xy 20.785764 -148.226075)
			(xy 20.77085 -148.204174) (xy 20.75615 -148.180942) (xy 20.732855 -148.131146) (xy 20.716952 -148.078521)
			(xy 20.708768 -148.024158) (xy 20.708475 -147.969183) (xy 20.716079 -147.914735) (xy 20.73142 -147.861944)
			(xy 20.754183 -147.811902) (xy 20.783895 -147.765647) (xy 20.81994 -147.724137) (xy 20.840446 -147.705826)
			(xy 20.856608 -147.689978) (xy 20.883599 -147.653647) (xy 20.903725 -147.613108) (xy 20.916349 -147.569644)
			(xy 20.921071 -147.524631) (xy 20.917742 -147.479494) (xy 20.906467 -147.435661) (xy 20.887604 -147.394519)
			(xy 20.861748 -147.357372) (xy 20.846034 -147.341082) (xy 20.675092 -147.17014) (xy 20.63623 -147.163028)
			(xy 20.607992 -147.157308) (xy 20.553534 -147.138499) (xy 20.502524 -147.111714) (xy 20.456124 -147.077561)
			(xy 20.415389 -147.036817) (xy 20.381245 -146.99041) (xy 20.35447 -146.939396) (xy 20.335672 -146.884934)
			(xy 20.329906 -146.856704) (xy 20.322794 -146.817842) (xy 17.483074 -143.978122) (xy 17.467498 -143.963191)
			(xy 17.432277 -143.938275) (xy 17.393355 -143.919664) (xy 17.351849 -143.907893) (xy 17.308951 -143.903301)
			(xy 17.265894 -143.906018) (xy 17.223914 -143.915968) (xy 17.184217 -143.932864) (xy 17.147944 -143.956221)
			(xy 17.116136 -143.985368) (xy 17.089706 -144.019468) (xy 17.079214 -144.03832) (xy 17.066025 -144.063303)
			(xy 17.033403 -144.109422) (xy 16.994338 -144.150228) (xy 16.949684 -144.184829) (xy 16.900416 -144.212469)
			(xy 16.847612 -144.232543) (xy 16.792426 -144.244612) (xy 16.736063 -144.248414) (xy 16.679755 -144.243864)
			(xy 16.624734 -144.231063) (xy 16.572201 -144.210289) (xy 16.523305 -144.181998) (xy 16.479114 -144.146807)
			(xy 16.440594 -144.105486) (xy 16.424148 -144.082516) (xy 16.408586 -144.058983) (xy 16.383819 -144.008293)
			(xy 16.366787 -143.954508) (xy 16.357861 -143.898801) (xy 16.357235 -143.842387) (xy 16.364924 -143.786496)
			(xy 16.38076 -143.732347) (xy 16.404396 -143.68112) (xy 16.435319 -143.633932) (xy 16.472854 -143.591812)
			(xy 16.516182 -143.555679) (xy 16.564359 -143.526321) (xy 16.616333 -143.504376) (xy 16.670973 -143.490325)
			(xy 16.698976 -143.486886) (xy 16.743934 -143.482314) (xy 16.775684 -143.45031) (xy 16.787043 -143.438141)
			(xy 16.803642 -143.4093) (xy 16.812235 -143.377153) (xy 16.812239 -143.343877) (xy 16.803654 -143.311727)
			(xy 16.787061 -143.282883) (xy 16.775684 -143.270732) (xy 16.624554 -143.119602) (xy 16.6116 -143.111728)
			(xy 16.585977 -143.095438) (xy 16.539776 -143.056046) (xy 16.500397 -143.009834) (xy 16.484092 -142.98422)
			(xy 16.476218 -142.971266) (xy 16.167354 -142.662402) (xy 16.13535 -142.653258) (xy 16.108587 -142.645256)
			(xy 16.057571 -142.622508) (xy 16.010418 -142.592561) (xy 15.968138 -142.556057) (xy 15.931634 -142.513776)
			(xy 15.901689 -142.466623) (xy 15.878941 -142.415606) (xy 15.870936 -142.388844) (xy 15.861792 -142.35684)
			(xy 13.473684 -139.968732) (xy 13.45677 -139.952576) (xy 13.418204 -139.926119) (xy 13.375452 -139.907159)
			(xy 13.329953 -139.896335) (xy 13.283243 -139.894012) (xy 13.236895 -139.900268) (xy 13.192472 -139.914893)
			(xy 13.151472 -139.937394) (xy 13.115277 -139.967011) (xy 13.085108 -140.002747) (xy 13.073126 -140.022834)
			(xy 13.059914 -140.046924) (xy 13.027624 -140.091375) (xy 12.989291 -140.130734) (xy 12.945706 -140.164184)
			(xy 12.897772 -140.191034) (xy 12.846481 -140.210727) (xy 12.792895 -140.222856) (xy 12.738123 -140.22717)
			(xy 12.683299 -140.22358) (xy 12.629558 -140.21216) (xy 12.578011 -140.193146) (xy 12.529727 -140.166933)
			(xy 12.485704 -140.134061) (xy 12.446853 -140.095213) (xy 12.413979 -140.051192) (xy 12.387763 -140.002909)
			(xy 12.368746 -139.951363) (xy 12.357323 -139.897622) (xy 12.353729 -139.842799) (xy 12.358041 -139.788026)
			(xy 12.370167 -139.73444) (xy 12.389857 -139.683148) (xy 12.416704 -139.635213) (xy 12.450152 -139.591626)
			(xy 12.489508 -139.55329) (xy 12.533958 -139.520998) (xy 12.558014 -139.507722) (xy 12.578091 -139.495715)
			(xy 12.613859 -139.465573) (xy 12.643505 -139.429392) (xy 12.666026 -139.388396) (xy 12.680663 -139.343969)
			(xy 12.68692 -139.297615) (xy 12.684586 -139.250898) (xy 12.673739 -139.205398) (xy 12.654747 -139.162652)
			(xy 12.628251 -139.124105) (xy 12.612116 -139.107164) (xy 11.458702 -137.95375) (xy 11.442386 -137.938132)
			(xy 11.405307 -137.912348) (xy 11.364256 -137.893524) (xy 11.320524 -137.88225) (xy 11.275487 -137.878883)
			(xy 11.230565 -137.883527) (xy 11.18717 -137.896037) (xy 11.146669 -137.91602) (xy 11.110337 -137.942845)
			(xy 11.079318 -137.975669) (xy 11.054587 -138.013457) (xy 11.036924 -138.055022) (xy 11.031474 -138.07694)
			(xy 11.025507 -138.104693) (xy 11.00646 -138.158167) (xy 10.9797 -138.208228) (xy 10.945817 -138.253772)
			(xy 10.905559 -138.293791) (xy 10.859816 -138.327404) (xy 10.809598 -138.353868) (xy 10.756012 -138.372598)
			(xy 10.700242 -138.383181) (xy 10.64352 -138.385384) (xy 10.587098 -138.379157) (xy 10.559542 -138.372342)
			(xy 10.526964 -138.362963) (xy 10.465514 -138.334344) (xy 10.437368 -138.315446) (xy 10.419381 -138.30331)
			(xy 10.380184 -138.284707) (xy 10.338396 -138.273035) (xy 10.295232 -138.268633) (xy 10.251949 -138.27163)
			(xy 10.209804 -138.281939) (xy 10.170023 -138.299259) (xy 10.133764 -138.323087) (xy 10.117582 -138.337544)
			(xy 10.095867 -138.3571) (xy 10.047606 -138.39005) (xy 9.994882 -138.415248) (xy 9.93893 -138.432105)
			(xy 9.881061 -138.440225) (xy 9.822631 -138.439419) (xy 9.793732 -138.43508) (xy 9.765766 -138.429849)
			(xy 9.711682 -138.412194) (xy 9.660821 -138.3867) (xy 9.614312 -138.353933) (xy 9.573187 -138.314619)
			(xy 9.538359 -138.269632) (xy 9.510601 -138.219971) (xy 9.500108 -138.193526) (xy 9.491026 -138.168117)
			(xy 9.479293 -138.115449) (xy 9.475098 -138.061653) (xy 9.478526 -138.007803) (xy 9.489507 -137.954974)
			(xy 9.507822 -137.904218) (xy 9.533107 -137.85655) (xy 9.564856 -137.81292) (xy 9.602436 -137.7742)
			(xy 9.645097 -137.741161) (xy 9.691989 -137.714462) (xy 9.742174 -137.694638) (xy 9.794652 -137.682083)
			(xy 9.848375 -137.677048) (xy 9.902272 -137.679633) (xy 9.955267 -137.689786) (xy 10.006303 -137.707306)
			(xy 10.05436 -137.731842) (xy 10.076688 -137.746994) (xy 10.094676 -137.759132) (xy 10.133875 -137.77774)
			(xy 10.175666 -137.789417) (xy 10.218833 -137.793824) (xy 10.262122 -137.790833) (xy 10.304272 -137.78053)
			(xy 10.34406 -137.763216) (xy 10.380327 -137.739393) (xy 10.396474 -137.724896) (xy 10.409936 -137.712958)
			(xy 10.428763 -137.697457) (xy 10.469636 -137.670851) (xy 10.513559 -137.649658) (xy 10.55982 -137.634222)
			(xy 10.583672 -137.629138) (xy 10.605582 -137.623648) (xy 10.647153 -137.605996) (xy 10.68495 -137.581275)
			(xy 10.717782 -137.550261) (xy 10.744614 -137.513931) (xy 10.764602 -137.473431) (xy 10.777115 -137.430036)
			(xy 10.781761 -137.385112) (xy 10.778392 -137.340074) (xy 10.767115 -137.29634) (xy 10.748285 -137.255289)
			(xy 10.722495 -137.218213) (xy 10.706862 -137.20191) (xy 10.603738 -137.098786) (xy 10.587352 -137.083098)
			(xy 10.550096 -137.057222) (xy 10.508834 -137.03838) (xy 10.46488 -137.027172) (xy 10.419635 -137.023954)
			(xy 10.374537 -137.02883) (xy 10.331024 -137.041644) (xy 10.290482 -137.061988) (xy 10.272014 -137.075164)
			(xy 10.249919 -137.091145) (xy 10.202075 -137.117305) (xy 10.150993 -137.136386) (xy 10.097715 -137.148)
			(xy 10.043327 -137.15191) (xy 9.988936 -137.148036) (xy 9.93565 -137.136457) (xy 9.884556 -137.11741)
			(xy 9.836694 -137.091282) (xy 9.79304 -137.058606) (xy 9.754483 -137.020047) (xy 9.721809 -136.976392)
			(xy 9.695683 -136.928529) (xy 9.676638 -136.877434) (xy 9.665062 -136.824148) (xy 9.66119 -136.769756)
			(xy 9.665103 -136.715368) (xy 9.676719 -136.66209) (xy 9.695802 -136.61101) (xy 9.721964 -136.563166)
			(xy 9.737852 -136.541002) (xy 9.751035 -136.522548) (xy 9.771327 -136.481993) (xy 9.784102 -136.438482)
			(xy 9.788955 -136.393395) (xy 9.785732 -136.348161) (xy 9.774536 -136.304217) (xy 9.755721 -136.262957)
			(xy 9.729884 -136.225689) (xy 9.71423 -136.209278) (xy 7.37362 -133.868668) (xy 7.37362 -120.540272)
			(xy 7.373092 -120.516954) (xy 7.364583 -120.471101) (xy 7.347854 -120.427568) (xy 7.323467 -120.387816)
			(xy 7.292241 -120.353178) (xy 7.255221 -120.324815) (xy 7.213649 -120.303678) (xy 7.168921 -120.290477)
			(xy 7.145782 -120.287542) (xy 7.118778 -120.284953) (xy 7.065839 -120.273105) (xy 7.015114 -120.253876)
			(xy 6.967625 -120.227654) (xy 6.92433 -120.194967) (xy 6.886104 -120.156476) (xy 6.853717 -120.112957)
			(xy 6.827824 -120.065287) (xy 6.808946 -120.01443) (xy 6.797464 -119.961411) (xy 6.793611 -119.9073)
			(xy 6.797464 -119.853189) (xy 6.808946 -119.80017) (xy 6.827823 -119.749313) (xy 6.853717 -119.701644)
			(xy 6.886103 -119.658124) (xy 6.92433 -119.619633) (xy 6.967624 -119.586946) (xy 7.015113 -119.560724)
			(xy 7.065839 -119.541495) (xy 7.118777 -119.529648) (xy 7.145782 -119.527066) (xy 7.168926 -119.524146)
			(xy 7.213669 -119.510966) (xy 7.255255 -119.48984) (xy 7.292285 -119.461478) (xy 7.323516 -119.426834)
			(xy 7.347898 -119.38707) (xy 7.364612 -119.343524) (xy 7.373097 -119.297658) (xy 7.37362 -119.274336)
			(xy 7.37362 -112.072928) (xy 7.373088 -112.049613) (xy 7.364573 -112.003765) (xy 7.34784 -111.96024)
			(xy 7.323451 -111.920495) (xy 7.292224 -111.885863) (xy 7.255206 -111.857506) (xy 7.213638 -111.836374)
			(xy 7.168914 -111.823175) (xy 7.145782 -111.820198) (xy 7.118778 -111.817609) (xy 7.06584 -111.805761)
			(xy 7.015115 -111.786533) (xy 6.967627 -111.76031) (xy 6.924332 -111.727624) (xy 6.886107 -111.689133)
			(xy 6.85372 -111.645614) (xy 6.827827 -111.597945) (xy 6.80895 -111.547089) (xy 6.797468 -111.49407)
			(xy 6.793615 -111.43996) (xy 6.797468 -111.38585) (xy 6.80895 -111.332831) (xy 6.827827 -111.281975)
			(xy 6.85372 -111.234306) (xy 6.886107 -111.190787) (xy 6.924332 -111.152296) (xy 6.967627 -111.11961)
			(xy 7.015115 -111.093387) (xy 7.06584 -111.074159) (xy 7.118778 -111.062311) (xy 7.145782 -111.059722)
			(xy 7.168928 -111.056802) (xy 7.213676 -111.043623) (xy 7.255266 -111.022499) (xy 7.292302 -110.994138)
			(xy 7.32354 -110.959494) (xy 7.34793 -110.919731) (xy 7.364653 -110.876184) (xy 7.373148 -110.830316)
			(xy 7.37362 -110.806992) (xy 7.37362 -104.44353) (xy 7.4676 -104.44353) (xy 10.360406 -101.550724)
			(xy 12.22121 -101.550724) (xy 12.293854 -101.514402) (xy 13.25372 -100.554536) (xy 13.64996 -100.099368)
			(xy 13.776706 -99.778566) (xy 13.818616 -99.521264) (xy 13.82268 -99.49561) (xy 13.82268 -96.776032)
			(xy 13.822189 -96.759375) (xy 13.813573 -96.727196) (xy 13.79692 -96.698344) (xy 13.773365 -96.674787)
			(xy 13.744515 -96.658132) (xy 13.712337 -96.649512) (xy 13.69568 -96.649032) (xy 1.77038 -96.649032)
			(xy 1.753729 -96.649529) (xy 1.721562 -96.658154) (xy 1.692723 -96.674811) (xy 1.669179 -96.698365)
			(xy 1.652534 -96.72721) (xy 1.643922 -96.75938) (xy 1.64338 -96.776032) (xy 1.64338 -137.256615)
			(xy 8.289605 -137.256615) (xy 8.292295 -137.20152) (xy 8.302893 -137.147386) (xy 8.321176 -137.095344)
			(xy 8.346764 -137.046477) (xy 8.379123 -137.001804) (xy 8.398002 -136.981692) (xy 8.414103 -136.964453)
			(xy 8.440203 -136.925165) (xy 8.458604 -136.881736) (xy 8.468674 -136.835656) (xy 8.470067 -136.78851)
			(xy 8.462735 -136.741916) (xy 8.44693 -136.697476) (xy 8.423195 -136.656716) (xy 8.408162 -136.638538)
			(xy 8.390516 -136.617335) (xy 8.360875 -136.570814) (xy 8.338243 -136.520509) (xy 8.323092 -136.467469)
			(xy 8.315738 -136.4128) (xy 8.316334 -136.357642) (xy 8.324869 -136.303145) (xy 8.341163 -136.250445)
			(xy 8.364877 -136.200641) (xy 8.395517 -136.154772) (xy 8.432444 -136.113794) (xy 8.474887 -136.078561)
			(xy 8.521963 -136.049809) (xy 8.572688 -136.028137) (xy 8.626006 -136.013996) (xy 8.680805 -136.007681)
			(xy 8.735942 -136.009325) (xy 8.790268 -136.018893) (xy 8.842649 -136.036185) (xy 8.891993 -136.060841)
			(xy 8.937272 -136.092346) (xy 8.977541 -136.130045) (xy 9.011961 -136.17315) (xy 9.039814 -136.220763)
			(xy 9.06052 -136.271891) (xy 9.073645 -136.325468) (xy 9.078918 -136.380377) (xy 9.076227 -136.435473)
			(xy 9.065629 -136.489607) (xy 9.047346 -136.54165) (xy 9.021757 -136.590517) (xy 8.989397 -136.635189)
			(xy 8.970518 -136.655302) (xy 8.954423 -136.672546) (xy 8.92832 -136.711832) (xy 8.909917 -136.755261)
			(xy 8.899846 -136.801339) (xy 8.898452 -136.848486) (xy 8.905784 -136.895079) (xy 8.921589 -136.939519)
			(xy 8.945324 -136.980278) (xy 8.960358 -136.998456) (xy 8.978003 -137.019659) (xy 9.007644 -137.066179)
			(xy 9.030275 -137.116484) (xy 9.045426 -137.169523) (xy 9.052779 -137.224192) (xy 9.052183 -137.27935)
			(xy 9.043648 -137.333846) (xy 9.027354 -137.386546) (xy 9.00364 -137.436349) (xy 8.973 -137.482217)
			(xy 8.936074 -137.523195) (xy 8.89363 -137.558427) (xy 8.846555 -137.587179) (xy 8.79583 -137.608851)
			(xy 8.742513 -137.622992) (xy 8.687714 -137.629306) (xy 8.632578 -137.627662) (xy 8.578253 -137.618095)
			(xy 8.525873 -137.600803) (xy 8.476529 -137.576147) (xy 8.43125 -137.544642) (xy 8.390981 -137.506944)
			(xy 8.356561 -137.463839) (xy 8.328709 -137.416227) (xy 8.308003 -137.3651) (xy 8.294878 -137.311523)
			(xy 8.289605 -137.256615) (xy 1.64338 -137.256615) (xy 1.64338 -138.745722) (xy 4.863082 -138.745722)
			(xy 4.867153 -138.6901) (xy 4.879279 -138.635663) (xy 4.899202 -138.583572) (xy 4.926498 -138.534937)
			(xy 4.960584 -138.490794) (xy 5.000733 -138.452085) (xy 5.046091 -138.419634) (xy 5.095691 -138.394133)
			(xy 5.148475 -138.376126) (xy 5.203318 -138.365996) (xy 5.259052 -138.363959) (xy 5.314489 -138.370059)
			(xy 5.368446 -138.384165) (xy 5.419775 -138.405977) (xy 5.467381 -138.435031) (xy 5.510249 -138.470706)
			(xy 5.547466 -138.512243) (xy 5.578239 -138.558756) (xy 5.601911 -138.609253) (xy 5.617979 -138.66266)
			(xy 5.626099 -138.717836) (xy 5.626608 -138.745722) (xy 5.626099 -138.773608) (xy 5.617979 -138.828784)
			(xy 5.601911 -138.882191) (xy 5.578239 -138.932688) (xy 5.547466 -138.979201) (xy 5.510249 -139.020738)
			(xy 5.467381 -139.056413) (xy 5.419775 -139.085467) (xy 5.368446 -139.107279) (xy 5.314489 -139.121385)
			(xy 5.259052 -139.127485) (xy 5.203318 -139.125448) (xy 5.148475 -139.115318) (xy 5.095691 -139.097311)
			(xy 5.046091 -139.07181) (xy 5.000733 -139.039359) (xy 4.960584 -139.00065) (xy 4.926498 -138.956507)
			(xy 4.899202 -138.907872) (xy 4.879279 -138.855781) (xy 4.867153 -138.801344) (xy 4.863082 -138.745722)
			(xy 1.64338 -138.745722) (xy 1.64338 -139.775438) (xy 4.558282 -139.775438) (xy 4.562353 -139.719816)
			(xy 4.574479 -139.665379) (xy 4.594402 -139.613288) (xy 4.621698 -139.564653) (xy 4.655784 -139.52051)
			(xy 4.695933 -139.481801) (xy 4.741291 -139.44935) (xy 4.790891 -139.423849) (xy 4.843675 -139.405842)
			(xy 4.898518 -139.395712) (xy 4.954252 -139.393675) (xy 5.009689 -139.399775) (xy 5.063646 -139.413881)
			(xy 5.114975 -139.435693) (xy 5.162581 -139.464747) (xy 5.205449 -139.500422) (xy 5.242666 -139.541959)
			(xy 5.273439 -139.588472) (xy 5.297111 -139.638969) (xy 5.313179 -139.692376) (xy 5.321299 -139.747552)
			(xy 5.321808 -139.775438) (xy 5.321299 -139.803324) (xy 5.313179 -139.8585) (xy 5.297111 -139.911907)
			(xy 5.273439 -139.962404) (xy 5.242666 -140.008917) (xy 5.236114 -140.01623) (xy 7.40867 -140.01623)
			(xy 7.412741 -139.960608) (xy 7.424867 -139.906171) (xy 7.44479 -139.85408) (xy 7.472086 -139.805445)
			(xy 7.506172 -139.761302) (xy 7.546321 -139.722593) (xy 7.591679 -139.690142) (xy 7.641279 -139.664641)
			(xy 7.694063 -139.646634) (xy 7.748906 -139.636504) (xy 7.80464 -139.634467) (xy 7.860077 -139.640567)
			(xy 7.914034 -139.654673) (xy 7.965363 -139.676485) (xy 8.012969 -139.705539) (xy 8.055837 -139.741214)
			(xy 8.093054 -139.782751) (xy 8.123827 -139.829264) (xy 8.147499 -139.879761) (xy 8.163567 -139.933168)
			(xy 8.171687 -139.988344) (xy 8.172196 -140.01623) (xy 8.171687 -140.044116) (xy 8.163567 -140.099292)
			(xy 8.147499 -140.152699) (xy 8.123827 -140.203196) (xy 8.093054 -140.249709) (xy 8.055837 -140.291246)
			(xy 8.012969 -140.326921) (xy 7.965363 -140.355975) (xy 7.914034 -140.377787) (xy 7.860077 -140.391893)
			(xy 7.80464 -140.397993) (xy 7.748906 -140.395956) (xy 7.694063 -140.385826) (xy 7.641279 -140.367819)
			(xy 7.591679 -140.342318) (xy 7.546321 -140.309867) (xy 7.506172 -140.271158) (xy 7.472086 -140.227015)
			(xy 7.44479 -140.17838) (xy 7.424867 -140.126289) (xy 7.412741 -140.071852) (xy 7.40867 -140.01623)
			(xy 5.236114 -140.01623) (xy 5.205449 -140.050454) (xy 5.162581 -140.086129) (xy 5.114975 -140.115183)
			(xy 5.063646 -140.136995) (xy 5.009689 -140.151101) (xy 4.954252 -140.157201) (xy 4.898518 -140.155164)
			(xy 4.843675 -140.145034) (xy 4.790891 -140.127027) (xy 4.741291 -140.101526) (xy 4.695933 -140.069075)
			(xy 4.655784 -140.030366) (xy 4.621698 -139.986223) (xy 4.594402 -139.937588) (xy 4.574479 -139.885497)
			(xy 4.562353 -139.83106) (xy 4.558282 -139.775438) (xy 1.64338 -139.775438) (xy 1.64338 -141.174978)
			(xy 4.786882 -141.174978) (xy 4.790953 -141.119356) (xy 4.803079 -141.064919) (xy 4.823002 -141.012828)
			(xy 4.850298 -140.964193) (xy 4.884384 -140.92005) (xy 4.924533 -140.881341) (xy 4.969891 -140.84889)
			(xy 5.019491 -140.823389) (xy 5.072275 -140.805382) (xy 5.127118 -140.795252) (xy 5.182852 -140.793215)
			(xy 5.238289 -140.799315) (xy 5.292246 -140.813421) (xy 5.343575 -140.835233) (xy 5.391181 -140.864287)
			(xy 5.434049 -140.899962) (xy 5.471266 -140.941499) (xy 5.502039 -140.988012) (xy 5.525711 -141.038509)
			(xy 5.541779 -141.091916) (xy 5.549899 -141.147092) (xy 5.550408 -141.174978) (xy 5.549899 -141.202864)
			(xy 5.541779 -141.25804) (xy 5.525711 -141.311447) (xy 5.525506 -141.311884) (xy 8.058656 -141.311884)
			(xy 8.062727 -141.256262) (xy 8.074853 -141.201825) (xy 8.094776 -141.149734) (xy 8.122072 -141.101099)
			(xy 8.156158 -141.056956) (xy 8.196307 -141.018247) (xy 8.241665 -140.985796) (xy 8.291265 -140.960295)
			(xy 8.344049 -140.942288) (xy 8.398892 -140.932158) (xy 8.454626 -140.930121) (xy 8.510063 -140.936221)
			(xy 8.56402 -140.950327) (xy 8.615349 -140.972139) (xy 8.662955 -141.001193) (xy 8.705823 -141.036868)
			(xy 8.74304 -141.078405) (xy 8.773813 -141.124918) (xy 8.788112 -141.15542) (xy 9.358628 -141.15542)
			(xy 9.362699 -141.099798) (xy 9.374825 -141.045361) (xy 9.394748 -140.99327) (xy 9.422044 -140.944635)
			(xy 9.45613 -140.900492) (xy 9.496279 -140.861783) (xy 9.541637 -140.829332) (xy 9.591237 -140.803831)
			(xy 9.644021 -140.785824) (xy 9.698864 -140.775694) (xy 9.754598 -140.773657) (xy 9.810035 -140.779757)
			(xy 9.863992 -140.793863) (xy 9.915321 -140.815675) (xy 9.962927 -140.844729) (xy 10.005795 -140.880404)
			(xy 10.043012 -140.921941) (xy 10.073785 -140.968454) (xy 10.097457 -141.018951) (xy 10.113525 -141.072358)
			(xy 10.121645 -141.127534) (xy 10.122154 -141.15542) (xy 10.121645 -141.183306) (xy 10.117974 -141.208252)
			(xy 10.6586 -141.208252) (xy 10.662671 -141.15263) (xy 10.674797 -141.098193) (xy 10.69472 -141.046102)
			(xy 10.722016 -140.997467) (xy 10.756102 -140.953324) (xy 10.796251 -140.914615) (xy 10.841609 -140.882164)
			(xy 10.891209 -140.856663) (xy 10.943993 -140.838656) (xy 10.998836 -140.828526) (xy 11.05457 -140.826489)
			(xy 11.110007 -140.832589) (xy 11.163964 -140.846695) (xy 11.215293 -140.868507) (xy 11.262899 -140.897561)
			(xy 11.305767 -140.933236) (xy 11.342984 -140.974773) (xy 11.373757 -141.021286) (xy 11.397429 -141.071783)
			(xy 11.413497 -141.12519) (xy 11.421617 -141.180366) (xy 11.422126 -141.208252) (xy 11.421617 -141.236138)
			(xy 11.413497 -141.291314) (xy 11.397429 -141.344721) (xy 11.373757 -141.395218) (xy 11.342984 -141.441731)
			(xy 11.305767 -141.483268) (xy 11.262899 -141.518943) (xy 11.215293 -141.547997) (xy 11.163964 -141.569809)
			(xy 11.110007 -141.583915) (xy 11.05457 -141.590015) (xy 10.998836 -141.587978) (xy 10.943993 -141.577848)
			(xy 10.891209 -141.559841) (xy 10.841609 -141.53434) (xy 10.796251 -141.501889) (xy 10.756102 -141.46318)
			(xy 10.722016 -141.419037) (xy 10.69472 -141.370402) (xy 10.674797 -141.318311) (xy 10.662671 -141.263874)
			(xy 10.6586 -141.208252) (xy 10.117974 -141.208252) (xy 10.113525 -141.238482) (xy 10.097457 -141.291889)
			(xy 10.073785 -141.342386) (xy 10.043012 -141.388899) (xy 10.005795 -141.430436) (xy 9.962927 -141.466111)
			(xy 9.915321 -141.495165) (xy 9.863992 -141.516977) (xy 9.810035 -141.531083) (xy 9.754598 -141.537183)
			(xy 9.698864 -141.535146) (xy 9.644021 -141.525016) (xy 9.591237 -141.507009) (xy 9.541637 -141.481508)
			(xy 9.496279 -141.449057) (xy 9.45613 -141.410348) (xy 9.422044 -141.366205) (xy 9.394748 -141.31757)
			(xy 9.374825 -141.265479) (xy 9.362699 -141.211042) (xy 9.358628 -141.15542) (xy 8.788112 -141.15542)
			(xy 8.797485 -141.175415) (xy 8.813553 -141.228822) (xy 8.821673 -141.283998) (xy 8.822182 -141.311884)
			(xy 8.821673 -141.33977) (xy 8.813553 -141.394946) (xy 8.797485 -141.448353) (xy 8.773813 -141.49885)
			(xy 8.74304 -141.545363) (xy 8.705823 -141.5869) (xy 8.662955 -141.622575) (xy 8.615349 -141.651629)
			(xy 8.56402 -141.673441) (xy 8.510063 -141.687547) (xy 8.454626 -141.693647) (xy 8.398892 -141.69161)
			(xy 8.344049 -141.68148) (xy 8.291265 -141.663473) (xy 8.241665 -141.637972) (xy 8.196307 -141.605521)
			(xy 8.156158 -141.566812) (xy 8.122072 -141.522669) (xy 8.094776 -141.474034) (xy 8.074853 -141.421943)
			(xy 8.062727 -141.367506) (xy 8.058656 -141.311884) (xy 5.525506 -141.311884) (xy 5.502039 -141.361944)
			(xy 5.471266 -141.408457) (xy 5.434049 -141.449994) (xy 5.391181 -141.485669) (xy 5.343575 -141.514723)
			(xy 5.292246 -141.536535) (xy 5.238289 -141.550641) (xy 5.182852 -141.556741) (xy 5.127118 -141.554704)
			(xy 5.072275 -141.544574) (xy 5.019491 -141.526567) (xy 4.969891 -141.501066) (xy 4.924533 -141.468615)
			(xy 4.884384 -141.429906) (xy 4.850298 -141.385763) (xy 4.823002 -141.337128) (xy 4.803079 -141.285037)
			(xy 4.790953 -141.2306) (xy 4.786882 -141.174978) (xy 1.64338 -141.174978) (xy 1.64338 -143.258032)
			(xy 12.538962 -143.258032) (xy 12.543033 -143.20241) (xy 12.555159 -143.147973) (xy 12.575082 -143.095882)
			(xy 12.602378 -143.047247) (xy 12.636464 -143.003104) (xy 12.676613 -142.964395) (xy 12.721971 -142.931944)
			(xy 12.771571 -142.906443) (xy 12.824355 -142.888436) (xy 12.879198 -142.878306) (xy 12.934932 -142.876269)
			(xy 12.990369 -142.882369) (xy 13.044326 -142.896475) (xy 13.095655 -142.918287) (xy 13.143261 -142.947341)
			(xy 13.186129 -142.983016) (xy 13.223346 -143.024553) (xy 13.254119 -143.071066) (xy 13.277791 -143.121563)
			(xy 13.293859 -143.17497) (xy 13.301979 -143.230146) (xy 13.302488 -143.258032) (xy 13.301979 -143.285918)
			(xy 13.293859 -143.341094) (xy 13.277791 -143.394501) (xy 13.254119 -143.444998) (xy 13.223346 -143.491511)
			(xy 13.186129 -143.533048) (xy 13.143261 -143.568723) (xy 13.095655 -143.597777) (xy 13.044326 -143.619589)
			(xy 12.990369 -143.633695) (xy 12.934932 -143.639795) (xy 12.879198 -143.637758) (xy 12.824355 -143.627628)
			(xy 12.771571 -143.609621) (xy 12.721971 -143.58412) (xy 12.676613 -143.551669) (xy 12.636464 -143.51296)
			(xy 12.602378 -143.468817) (xy 12.575082 -143.420182) (xy 12.555159 -143.368091) (xy 12.543033 -143.313654)
			(xy 12.538962 -143.258032) (xy 1.64338 -143.258032) (xy 1.64338 -143.997934) (xy 3.732782 -143.997934)
			(xy 3.736853 -143.942312) (xy 3.748979 -143.887875) (xy 3.768902 -143.835784) (xy 3.796198 -143.787149)
			(xy 3.830284 -143.743006) (xy 3.870433 -143.704297) (xy 3.915791 -143.671846) (xy 3.965391 -143.646345)
			(xy 4.018175 -143.628338) (xy 4.073018 -143.618208) (xy 4.128752 -143.616171) (xy 4.184189 -143.622271)
			(xy 4.238146 -143.636377) (xy 4.289475 -143.658189) (xy 4.337081 -143.687243) (xy 4.379949 -143.722918)
			(xy 4.417166 -143.764455) (xy 4.447939 -143.810968) (xy 4.471611 -143.861465) (xy 4.487679 -143.914872)
			(xy 4.495799 -143.970048) (xy 4.496308 -143.997934) (xy 4.495799 -144.02582) (xy 4.487679 -144.080996)
			(xy 4.471611 -144.134403) (xy 4.447939 -144.1849) (xy 4.417166 -144.231413) (xy 4.379949 -144.27295)
			(xy 4.347212 -144.300194) (xy 5.614922 -144.300194) (xy 5.618993 -144.244572) (xy 5.631119 -144.190135)
			(xy 5.651042 -144.138044) (xy 5.678338 -144.089409) (xy 5.712424 -144.045266) (xy 5.752573 -144.006557)
			(xy 5.797931 -143.974106) (xy 5.847531 -143.948605) (xy 5.900315 -143.930598) (xy 5.955158 -143.920468)
			(xy 6.010892 -143.918431) (xy 6.066329 -143.924531) (xy 6.120286 -143.938637) (xy 6.171615 -143.960449)
			(xy 6.219221 -143.989503) (xy 6.262089 -144.025178) (xy 6.299306 -144.066715) (xy 6.330079 -144.113228)
			(xy 6.353751 -144.163725) (xy 6.369819 -144.217132) (xy 6.377939 -144.272308) (xy 6.378448 -144.300194)
			(xy 6.377939 -144.32808) (xy 6.369819 -144.383256) (xy 6.353751 -144.436663) (xy 6.341877 -144.461992)
			(xy 13.330934 -144.461992) (xy 13.335005 -144.40637) (xy 13.347131 -144.351933) (xy 13.367054 -144.299842)
			(xy 13.39435 -144.251207) (xy 13.428436 -144.207064) (xy 13.468585 -144.168355) (xy 13.513943 -144.135904)
			(xy 13.563543 -144.110403) (xy 13.616327 -144.092396) (xy 13.67117 -144.082266) (xy 13.726904 -144.080229)
			(xy 13.782341 -144.086329) (xy 13.836298 -144.100435) (xy 13.887627 -144.122247) (xy 13.935233 -144.151301)
			(xy 13.978101 -144.186976) (xy 14.015318 -144.228513) (xy 14.046091 -144.275026) (xy 14.069763 -144.325523)
			(xy 14.085831 -144.37893) (xy 14.093951 -144.434106) (xy 14.09446 -144.461992) (xy 14.093951 -144.489878)
			(xy 14.085831 -144.545054) (xy 14.069763 -144.598461) (xy 14.046091 -144.648958) (xy 14.015318 -144.695471)
			(xy 13.978101 -144.737008) (xy 13.935233 -144.772683) (xy 13.887627 -144.801737) (xy 13.836298 -144.823549)
			(xy 13.782341 -144.837655) (xy 13.726904 -144.843755) (xy 13.67117 -144.841718) (xy 13.616327 -144.831588)
			(xy 13.563543 -144.813581) (xy 13.513943 -144.78808) (xy 13.468585 -144.755629) (xy 13.428436 -144.71692)
			(xy 13.39435 -144.672777) (xy 13.367054 -144.624142) (xy 13.347131 -144.572051) (xy 13.335005 -144.517614)
			(xy 13.330934 -144.461992) (xy 6.341877 -144.461992) (xy 6.330079 -144.48716) (xy 6.299306 -144.533673)
			(xy 6.262089 -144.57521) (xy 6.219221 -144.610885) (xy 6.171615 -144.639939) (xy 6.120286 -144.661751)
			(xy 6.066329 -144.675857) (xy 6.010892 -144.681957) (xy 5.955158 -144.67992) (xy 5.900315 -144.66979)
			(xy 5.847531 -144.651783) (xy 5.797931 -144.626282) (xy 5.752573 -144.593831) (xy 5.712424 -144.555122)
			(xy 5.678338 -144.510979) (xy 5.651042 -144.462344) (xy 5.631119 -144.410253) (xy 5.618993 -144.355816)
			(xy 5.614922 -144.300194) (xy 4.347212 -144.300194) (xy 4.337081 -144.308625) (xy 4.289475 -144.337679)
			(xy 4.238146 -144.359491) (xy 4.184189 -144.373597) (xy 4.128752 -144.379697) (xy 4.073018 -144.37766)
			(xy 4.018175 -144.36753) (xy 3.965391 -144.349523) (xy 3.915791 -144.324022) (xy 3.870433 -144.291571)
			(xy 3.830284 -144.252862) (xy 3.796198 -144.208719) (xy 3.768902 -144.160084) (xy 3.748979 -144.107993)
			(xy 3.736853 -144.053556) (xy 3.732782 -143.997934) (xy 1.64338 -143.997934) (xy 1.64338 -145.303494)
			(xy 4.433822 -145.303494) (xy 4.437893 -145.247872) (xy 4.450019 -145.193435) (xy 4.469942 -145.141344)
			(xy 4.497238 -145.092709) (xy 4.531324 -145.048566) (xy 4.571473 -145.009857) (xy 4.616831 -144.977406)
			(xy 4.666431 -144.951905) (xy 4.719215 -144.933898) (xy 4.774058 -144.923768) (xy 4.829792 -144.921731)
			(xy 4.885229 -144.927831) (xy 4.939186 -144.941937) (xy 4.990515 -144.963749) (xy 5.038121 -144.992803)
			(xy 5.080989 -145.028478) (xy 5.118206 -145.070015) (xy 5.148979 -145.116528) (xy 5.172651 -145.167025)
			(xy 5.188719 -145.220432) (xy 5.196839 -145.275608) (xy 5.197348 -145.303494) (xy 5.196839 -145.33138)
			(xy 5.188719 -145.386556) (xy 5.172651 -145.439963) (xy 5.148979 -145.49046) (xy 5.118206 -145.536973)
			(xy 5.080989 -145.57851) (xy 5.038121 -145.614185) (xy 4.990515 -145.643239) (xy 4.939186 -145.665051)
			(xy 4.885229 -145.679157) (xy 4.829792 -145.685257) (xy 4.774058 -145.68322) (xy 4.719215 -145.67309)
			(xy 4.666431 -145.655083) (xy 4.616831 -145.629582) (xy 4.571473 -145.597131) (xy 4.531324 -145.558422)
			(xy 4.497238 -145.514279) (xy 4.469942 -145.465644) (xy 4.450019 -145.413553) (xy 4.437893 -145.359116)
			(xy 4.433822 -145.303494) (xy 1.64338 -145.303494) (xy 1.64338 -145.849848) (xy 12.221462 -145.849848)
			(xy 12.225533 -145.794226) (xy 12.237659 -145.739789) (xy 12.257582 -145.687698) (xy 12.284878 -145.639063)
			(xy 12.318964 -145.59492) (xy 12.359113 -145.556211) (xy 12.404471 -145.52376) (xy 12.454071 -145.498259)
			(xy 12.506855 -145.480252) (xy 12.561698 -145.470122) (xy 12.617432 -145.468085) (xy 12.672869 -145.474185)
			(xy 12.726826 -145.488291) (xy 12.778155 -145.510103) (xy 12.796292 -145.521172) (xy 14.276322 -145.521172)
			(xy 14.280393 -145.46555) (xy 14.292519 -145.411113) (xy 14.312442 -145.359022) (xy 14.339738 -145.310387)
			(xy 14.373824 -145.266244) (xy 14.413973 -145.227535) (xy 14.459331 -145.195084) (xy 14.508931 -145.169583)
			(xy 14.561715 -145.151576) (xy 14.616558 -145.141446) (xy 14.672292 -145.139409) (xy 14.727729 -145.145509)
			(xy 14.781686 -145.159615) (xy 14.833015 -145.181427) (xy 14.880621 -145.210481) (xy 14.923489 -145.246156)
			(xy 14.960706 -145.287693) (xy 14.991479 -145.334206) (xy 15.015151 -145.384703) (xy 15.031219 -145.43811)
			(xy 15.039339 -145.493286) (xy 15.039848 -145.521172) (xy 15.039339 -145.549058) (xy 15.031219 -145.604234)
			(xy 15.015151 -145.657641) (xy 14.991479 -145.708138) (xy 14.960706 -145.754651) (xy 14.923489 -145.796188)
			(xy 14.880621 -145.831863) (xy 14.833015 -145.860917) (xy 14.781686 -145.882729) (xy 14.727729 -145.896835)
			(xy 14.672292 -145.902935) (xy 14.616558 -145.900898) (xy 14.561715 -145.890768) (xy 14.508931 -145.872761)
			(xy 14.459331 -145.84726) (xy 14.413973 -145.814809) (xy 14.373824 -145.7761) (xy 14.339738 -145.731957)
			(xy 14.312442 -145.683322) (xy 14.292519 -145.631231) (xy 14.280393 -145.576794) (xy 14.276322 -145.521172)
			(xy 12.796292 -145.521172) (xy 12.825761 -145.539157) (xy 12.868629 -145.574832) (xy 12.905846 -145.616369)
			(xy 12.936619 -145.662882) (xy 12.960291 -145.713379) (xy 12.976359 -145.766786) (xy 12.984479 -145.821962)
			(xy 12.984988 -145.849848) (xy 12.984479 -145.877734) (xy 12.976359 -145.93291) (xy 12.960291 -145.986317)
			(xy 12.936619 -146.036814) (xy 12.905846 -146.083327) (xy 12.868629 -146.124864) (xy 12.825761 -146.160539)
			(xy 12.778155 -146.189593) (xy 12.726826 -146.211405) (xy 12.672869 -146.225511) (xy 12.617432 -146.231611)
			(xy 12.561698 -146.229574) (xy 12.506855 -146.219444) (xy 12.454071 -146.201437) (xy 12.404471 -146.175936)
			(xy 12.359113 -146.143485) (xy 12.318964 -146.104776) (xy 12.284878 -146.060633) (xy 12.257582 -146.011998)
			(xy 12.237659 -145.959907) (xy 12.225533 -145.90547) (xy 12.221462 -145.849848) (xy 1.64338 -145.849848)
			(xy 1.64338 -146.307583) (xy 15.790139 -146.307583) (xy 15.79513 -146.252212) (xy 15.808105 -146.198152)
			(xy 15.828789 -146.146547) (xy 15.856744 -146.098491) (xy 15.891379 -146.055002) (xy 15.931958 -146.017)
			(xy 15.977624 -145.985291) (xy 16.027409 -145.960545) (xy 16.080259 -145.943288) (xy 16.135053 -145.933884)
			(xy 16.190632 -145.932534) (xy 16.245819 -145.939264) (xy 16.272764 -145.946114) (xy 16.287492 -145.949728)
			(xy 16.317798 -145.950604) (xy 16.347453 -145.944295) (xy 16.374779 -145.931159) (xy 16.398227 -145.91194)
			(xy 16.416471 -145.887724) (xy 16.422878 -145.873978) (xy 16.434153 -145.848984) (xy 16.462821 -145.802243)
			(xy 16.497886 -145.760088) (xy 16.538624 -145.723388) (xy 16.584196 -145.692898) (xy 16.633664 -145.669246)
			(xy 16.686009 -145.652919) (xy 16.740152 -145.644255) (xy 16.794977 -145.643431) (xy 16.849356 -145.650464)
			(xy 16.902168 -145.66521) (xy 16.952324 -145.687365) (xy 16.998793 -145.716473) (xy 17.040615 -145.751932)
			(xy 17.07693 -145.793015) (xy 17.10699 -145.838872) (xy 17.130174 -145.888561) (xy 17.146007 -145.941057)
			(xy 17.154161 -145.99528) (xy 17.154468 -146.05011) (xy 17.146922 -146.10442) (xy 17.131679 -146.157091)
			(xy 17.109053 -146.207036) (xy 17.079509 -146.253228) (xy 17.061942 -146.274282) (xy 17.047796 -146.291339)
			(xy 17.025089 -146.329388) (xy 17.00933 -146.370801) (xy 17.000998 -146.41432) (xy 17.000347 -146.458625)
			(xy 17.007394 -146.502371) (xy 17.021928 -146.544229) (xy 17.043506 -146.58293) (xy 17.057116 -146.600418)
			(xy 17.074275 -146.622415) (xy 17.102805 -146.670353) (xy 17.124048 -146.721935) (xy 17.137551 -146.776062)
			(xy 17.143025 -146.831577) (xy 17.140354 -146.887299) (xy 17.129595 -146.942036) (xy 17.110977 -146.994623)
			(xy 17.084898 -147.043937) (xy 17.051914 -147.088926) (xy 17.012728 -147.128631) (xy 16.968177 -147.162204)
			(xy 16.91921 -147.188929) (xy 16.866873 -147.208237) (xy 16.812281 -147.219715) (xy 16.7566 -147.223119)
			(xy 16.701017 -147.218375) (xy 16.646718 -147.205585) (xy 16.594861 -147.185023) (xy 16.546552 -147.157126)
			(xy 16.502822 -147.122489) (xy 16.464604 -147.081853) (xy 16.432713 -147.036082) (xy 16.407829 -146.986154)
			(xy 16.390483 -146.933134) (xy 16.385286 -146.905726) (xy 16.381209 -146.884783) (xy 16.367115 -146.844517)
			(xy 16.34649 -146.807173) (xy 16.319914 -146.7738) (xy 16.288136 -146.745338) (xy 16.252048 -146.722587)
			(xy 16.212665 -146.706185) (xy 16.171096 -146.696596) (xy 16.149828 -146.694906) (xy 16.122104 -146.69283)
			(xy 16.067662 -146.681563) (xy 16.015432 -146.662513) (xy 15.966521 -146.636084) (xy 15.921963 -146.602835)
			(xy 15.882703 -146.563471) (xy 15.849573 -146.518825) (xy 15.823273 -146.469844) (xy 15.804362 -146.417564)
			(xy 15.793238 -146.363092) (xy 15.790139 -146.307583) (xy 1.64338 -146.307583) (xy 1.64338 -146.919188)
			(xy 4.158486 -146.919188) (xy 4.162557 -146.863566) (xy 4.174683 -146.809129) (xy 4.194606 -146.757038)
			(xy 4.221902 -146.708403) (xy 4.255988 -146.66426) (xy 4.296137 -146.625551) (xy 4.341495 -146.5931)
			(xy 4.391095 -146.567599) (xy 4.443879 -146.549592) (xy 4.498722 -146.539462) (xy 4.554456 -146.537425)
			(xy 4.609893 -146.543525) (xy 4.66385 -146.557631) (xy 4.715179 -146.579443) (xy 4.762785 -146.608497)
			(xy 4.805653 -146.644172) (xy 4.84287 -146.685709) (xy 4.873643 -146.732222) (xy 4.897315 -146.782719)
			(xy 4.913383 -146.836126) (xy 4.921503 -146.891302) (xy 4.922012 -146.919188) (xy 4.921503 -146.947074)
			(xy 4.913383 -147.00225) (xy 4.897315 -147.055657) (xy 4.873643 -147.106154) (xy 4.84287 -147.152667)
			(xy 4.805653 -147.194204) (xy 4.762785 -147.229879) (xy 4.736229 -147.246086) (xy 12.236702 -147.246086)
			(xy 12.240773 -147.190464) (xy 12.252899 -147.136027) (xy 12.272822 -147.083936) (xy 12.300118 -147.035301)
			(xy 12.334204 -146.991158) (xy 12.374353 -146.952449) (xy 12.419711 -146.919998) (xy 12.469311 -146.894497)
			(xy 12.522095 -146.87649) (xy 12.576938 -146.86636) (xy 12.632672 -146.864323) (xy 12.688109 -146.870423)
			(xy 12.742066 -146.884529) (xy 12.793395 -146.906341) (xy 12.841001 -146.935395) (xy 12.883869 -146.97107)
			(xy 12.921086 -147.012607) (xy 12.951859 -147.05912) (xy 12.975531 -147.109617) (xy 12.991599 -147.163024)
			(xy 12.999719 -147.2182) (xy 13.000228 -147.246086) (xy 12.999719 -147.273972) (xy 12.991599 -147.329148)
			(xy 12.988696 -147.338796) (xy 14.113762 -147.338796) (xy 14.117833 -147.283174) (xy 14.129959 -147.228737)
			(xy 14.149882 -147.176646) (xy 14.177178 -147.128011) (xy 14.211264 -147.083868) (xy 14.251413 -147.045159)
			(xy 14.296771 -147.012708) (xy 14.346371 -146.987207) (xy 14.399155 -146.9692) (xy 14.453998 -146.95907)
			(xy 14.509732 -146.957033) (xy 14.565169 -146.963133) (xy 14.619126 -146.977239) (xy 14.670455 -146.999051)
			(xy 14.718061 -147.028105) (xy 14.760929 -147.06378) (xy 14.798146 -147.105317) (xy 14.828919 -147.15183)
			(xy 14.852591 -147.202327) (xy 14.868659 -147.255734) (xy 14.876779 -147.31091) (xy 14.877288 -147.338796)
			(xy 14.876779 -147.366682) (xy 14.868659 -147.421858) (xy 14.852591 -147.475265) (xy 14.828919 -147.525762)
			(xy 14.798146 -147.572275) (xy 14.760929 -147.613812) (xy 14.718061 -147.649487) (xy 14.670455 -147.678541)
			(xy 14.619126 -147.700353) (xy 14.565169 -147.714459) (xy 14.509732 -147.720559) (xy 14.453998 -147.718522)
			(xy 14.399155 -147.708392) (xy 14.346371 -147.690385) (xy 14.296771 -147.664884) (xy 14.251413 -147.632433)
			(xy 14.211264 -147.593724) (xy 14.177178 -147.549581) (xy 14.149882 -147.500946) (xy 14.129959 -147.448855)
			(xy 14.117833 -147.394418) (xy 14.113762 -147.338796) (xy 12.988696 -147.338796) (xy 12.975531 -147.382555)
			(xy 12.951859 -147.433052) (xy 12.921086 -147.479565) (xy 12.883869 -147.521102) (xy 12.841001 -147.556777)
			(xy 12.793395 -147.585831) (xy 12.742066 -147.607643) (xy 12.688109 -147.621749) (xy 12.632672 -147.627849)
			(xy 12.576938 -147.625812) (xy 12.522095 -147.615682) (xy 12.469311 -147.597675) (xy 12.419711 -147.572174)
			(xy 12.374353 -147.539723) (xy 12.334204 -147.501014) (xy 12.300118 -147.456871) (xy 12.272822 -147.408236)
			(xy 12.252899 -147.356145) (xy 12.240773 -147.301708) (xy 12.236702 -147.246086) (xy 4.736229 -147.246086)
			(xy 4.715179 -147.258933) (xy 4.66385 -147.280745) (xy 4.609893 -147.294851) (xy 4.554456 -147.300951)
			(xy 4.498722 -147.298914) (xy 4.443879 -147.288784) (xy 4.391095 -147.270777) (xy 4.341495 -147.245276)
			(xy 4.296137 -147.212825) (xy 4.255988 -147.174116) (xy 4.221902 -147.129973) (xy 4.194606 -147.081338)
			(xy 4.174683 -147.029247) (xy 4.162557 -146.97481) (xy 4.158486 -146.919188) (xy 1.64338 -146.919188)
			(xy 1.64338 -147.96135) (xy 17.338546 -147.96135) (xy 17.342617 -147.905728) (xy 17.354743 -147.851291)
			(xy 17.374666 -147.7992) (xy 17.401962 -147.750565) (xy 17.436048 -147.706422) (xy 17.476197 -147.667713)
			(xy 17.521555 -147.635262) (xy 17.571155 -147.609761) (xy 17.623939 -147.591754) (xy 17.678782 -147.581624)
			(xy 17.734516 -147.579587) (xy 17.789953 -147.585687) (xy 17.84391 -147.599793) (xy 17.895239 -147.621605)
			(xy 17.942845 -147.650659) (xy 17.985713 -147.686334) (xy 18.02293 -147.727871) (xy 18.053703 -147.774384)
			(xy 18.077375 -147.824881) (xy 18.093443 -147.878288) (xy 18.101563 -147.933464) (xy 18.102072 -147.96135)
			(xy 18.101563 -147.989236) (xy 18.093443 -148.044412) (xy 18.077375 -148.097819) (xy 18.053703 -148.148316)
			(xy 18.02293 -148.194829) (xy 17.985713 -148.236366) (xy 17.942845 -148.272041) (xy 17.895239 -148.301095)
			(xy 17.84391 -148.322907) (xy 17.789953 -148.337013) (xy 17.734516 -148.343113) (xy 17.678782 -148.341076)
			(xy 17.623939 -148.330946) (xy 17.571155 -148.312939) (xy 17.521555 -148.287438) (xy 17.476197 -148.254987)
			(xy 17.436048 -148.216278) (xy 17.401962 -148.172135) (xy 17.374666 -148.1235) (xy 17.354743 -148.071409)
			(xy 17.342617 -148.016972) (xy 17.338546 -147.96135) (xy 1.64338 -147.96135) (xy 1.64338 -148.744178)
			(xy 14.207742 -148.744178) (xy 14.211813 -148.688556) (xy 14.223939 -148.634119) (xy 14.243862 -148.582028)
			(xy 14.271158 -148.533393) (xy 14.305244 -148.48925) (xy 14.345393 -148.450541) (xy 14.390751 -148.41809)
			(xy 14.440351 -148.392589) (xy 14.493135 -148.374582) (xy 14.547978 -148.364452) (xy 14.603712 -148.362415)
			(xy 14.659149 -148.368515) (xy 14.713106 -148.382621) (xy 14.764435 -148.404433) (xy 14.812041 -148.433487)
			(xy 14.854909 -148.469162) (xy 14.892126 -148.510699) (xy 14.922899 -148.557212) (xy 14.946571 -148.607709)
			(xy 14.962639 -148.661116) (xy 14.970759 -148.716292) (xy 14.971268 -148.744178) (xy 14.970759 -148.772064)
			(xy 14.962639 -148.82724) (xy 14.946571 -148.880647) (xy 14.922899 -148.931144) (xy 14.892126 -148.977657)
			(xy 14.854909 -149.019194) (xy 14.812041 -149.054869) (xy 14.764435 -149.083923) (xy 14.713106 -149.105735)
			(xy 14.659149 -149.119841) (xy 14.603712 -149.125941) (xy 14.547978 -149.123904) (xy 14.493135 -149.113774)
			(xy 14.440351 -149.095767) (xy 14.390751 -149.070266) (xy 14.345393 -149.037815) (xy 14.305244 -148.999106)
			(xy 14.271158 -148.954963) (xy 14.243862 -148.906328) (xy 14.223939 -148.854237) (xy 14.211813 -148.7998)
			(xy 14.207742 -148.744178) (xy 1.64338 -148.744178) (xy 1.64338 -149.781514) (xy 10.008614 -149.781514)
			(xy 10.012685 -149.725892) (xy 10.024811 -149.671455) (xy 10.044734 -149.619364) (xy 10.07203 -149.570729)
			(xy 10.106116 -149.526586) (xy 10.146265 -149.487877) (xy 10.191623 -149.455426) (xy 10.241223 -149.429925)
			(xy 10.294007 -149.411918) (xy 10.34885 -149.401788) (xy 10.404584 -149.399751) (xy 10.460021 -149.405851)
			(xy 10.513978 -149.419957) (xy 10.565307 -149.441769) (xy 10.612913 -149.470823) (xy 10.655781 -149.506498)
			(xy 10.692998 -149.548035) (xy 10.723771 -149.594548) (xy 10.725686 -149.598634) (xy 11.69746 -149.598634)
			(xy 11.701531 -149.543012) (xy 11.713657 -149.488575) (xy 11.73358 -149.436484) (xy 11.760876 -149.387849)
			(xy 11.794962 -149.343706) (xy 11.835111 -149.304997) (xy 11.880469 -149.272546) (xy 11.930069 -149.247045)
			(xy 11.982853 -149.229038) (xy 12.037696 -149.218908) (xy 12.09343 -149.216871) (xy 12.148867 -149.222971)
			(xy 12.202824 -149.237077) (xy 12.254153 -149.258889) (xy 12.301759 -149.287943) (xy 12.344627 -149.323618)
			(xy 12.381844 -149.365155) (xy 12.412617 -149.411668) (xy 12.436289 -149.462165) (xy 12.452357 -149.515572)
			(xy 12.460477 -149.570748) (xy 12.460986 -149.598634) (xy 12.460477 -149.62652) (xy 12.452357 -149.681696)
			(xy 12.436289 -149.735103) (xy 12.412617 -149.7856) (xy 12.381844 -149.832113) (xy 12.344627 -149.87365)
			(xy 12.301759 -149.909325) (xy 12.254153 -149.938379) (xy 12.202824 -149.960191) (xy 12.148867 -149.974297)
			(xy 12.09343 -149.980397) (xy 12.037696 -149.97836) (xy 11.982853 -149.96823) (xy 11.930069 -149.950223)
			(xy 11.880469 -149.924722) (xy 11.835111 -149.892271) (xy 11.794962 -149.853562) (xy 11.760876 -149.809419)
			(xy 11.73358 -149.760784) (xy 11.713657 -149.708693) (xy 11.701531 -149.654256) (xy 11.69746 -149.598634)
			(xy 10.725686 -149.598634) (xy 10.747443 -149.645045) (xy 10.763511 -149.698452) (xy 10.771631 -149.753628)
			(xy 10.77214 -149.781514) (xy 10.771631 -149.8094) (xy 10.763511 -149.864576) (xy 10.747443 -149.917983)
			(xy 10.723771 -149.96848) (xy 10.692998 -150.014993) (xy 10.655781 -150.05653) (xy 10.612913 -150.092205)
			(xy 10.565307 -150.121259) (xy 10.513978 -150.143071) (xy 10.460021 -150.157177) (xy 10.404584 -150.163277)
			(xy 10.34885 -150.16124) (xy 10.294007 -150.15111) (xy 10.241223 -150.133103) (xy 10.191623 -150.107602)
			(xy 10.146265 -150.075151) (xy 10.106116 -150.036442) (xy 10.07203 -149.992299) (xy 10.044734 -149.943664)
			(xy 10.024811 -149.891573) (xy 10.012685 -149.837136) (xy 10.008614 -149.781514) (xy 1.64338 -149.781514)
			(xy 1.64338 -150.357548) (xy 3.049578 -150.357548) (xy 3.052851 -150.302413) (xy 3.064041 -150.248326)
			(xy 3.082914 -150.196418) (xy 3.109075 -150.147775) (xy 3.141977 -150.103412) (xy 3.180933 -150.064257)
			(xy 3.225128 -150.03113) (xy 3.273638 -150.004722) (xy 3.325449 -149.985586) (xy 3.379478 -149.974121)
			(xy 3.434596 -149.970568) (xy 3.489651 -149.975) (xy 3.54349 -149.987325) (xy 3.59499 -150.007285)
			(xy 3.643073 -150.034463) (xy 3.686733 -150.068291) (xy 3.72506 -150.108062) (xy 3.75725 -150.152944)
			(xy 3.770376 -150.177246) (xy 3.781425 -150.197507) (xy 3.809713 -150.233965) (xy 3.844116 -150.264718)
			(xy 3.883505 -150.288757) (xy 3.926587 -150.305291) (xy 3.971945 -150.313778) (xy 4.018089 -150.313939)
			(xy 4.063505 -150.305768) (xy 4.106701 -150.289534) (xy 4.126738 -150.278084) (xy 4.150668 -150.264291)
			(xy 4.201629 -150.242992) (xy 4.255128 -150.229265) (xy 4.310048 -150.223397) (xy 4.36524 -150.225509)
			(xy 4.41955 -150.235559) (xy 4.471844 -150.253336) (xy 4.521027 -150.278468) (xy 4.54626 -150.296372)
			(xy 6.75843 -150.296372) (xy 6.762501 -150.24075) (xy 6.774627 -150.186313) (xy 6.79455 -150.134222)
			(xy 6.821846 -150.085587) (xy 6.855932 -150.041444) (xy 6.896081 -150.002735) (xy 6.941439 -149.970284)
			(xy 6.991039 -149.944783) (xy 7.043823 -149.926776) (xy 7.098666 -149.916646) (xy 7.1544 -149.914609)
			(xy 7.209837 -149.920709) (xy 7.263794 -149.934815) (xy 7.315123 -149.956627) (xy 7.362729 -149.985681)
			(xy 7.405597 -150.021356) (xy 7.442814 -150.062893) (xy 7.473587 -150.109406) (xy 7.497259 -150.159903)
			(xy 7.513327 -150.21331) (xy 7.521447 -150.268486) (xy 7.521956 -150.296372) (xy 7.521447 -150.324258)
			(xy 7.513327 -150.379434) (xy 7.497259 -150.432841) (xy 7.473587 -150.483338) (xy 7.442814 -150.529851)
			(xy 7.405597 -150.571388) (xy 7.362729 -150.607063) (xy 7.315123 -150.636117) (xy 7.263794 -150.657929)
			(xy 7.209837 -150.672035) (xy 7.1544 -150.678135) (xy 7.098666 -150.676098) (xy 7.043823 -150.665968)
			(xy 6.991039 -150.647961) (xy 6.941439 -150.62246) (xy 6.896081 -150.590009) (xy 6.855932 -150.5513)
			(xy 6.821846 -150.507157) (xy 6.79455 -150.458522) (xy 6.774627 -150.406431) (xy 6.762501 -150.351994)
			(xy 6.75843 -150.296372) (xy 4.54626 -150.296372) (xy 4.566072 -150.310429) (xy 4.606038 -150.348553)
			(xy 4.640087 -150.392041) (xy 4.66751 -150.439985) (xy 4.687732 -150.491383) (xy 4.700331 -150.545159)
			(xy 4.705043 -150.60019) (xy 4.70177 -150.655326) (xy 4.69058 -150.709413) (xy 4.671708 -150.761321)
			(xy 4.645547 -150.809965) (xy 4.612645 -150.854328) (xy 4.573689 -150.893482) (xy 4.569225 -150.896828)
			(xy 10.92276 -150.896828) (xy 10.926831 -150.841206) (xy 10.938957 -150.786769) (xy 10.95888 -150.734678)
			(xy 10.986176 -150.686043) (xy 11.020262 -150.6419) (xy 11.060411 -150.603191) (xy 11.105769 -150.57074)
			(xy 11.155369 -150.545239) (xy 11.208153 -150.527232) (xy 11.262996 -150.517102) (xy 11.31873 -150.515065)
			(xy 11.374167 -150.521165) (xy 11.428124 -150.535271) (xy 11.479453 -150.557083) (xy 11.527059 -150.586137)
			(xy 11.569927 -150.621812) (xy 11.607144 -150.663349) (xy 11.637917 -150.709862) (xy 11.661589 -150.760359)
			(xy 11.677657 -150.813766) (xy 11.685777 -150.868942) (xy 11.686286 -150.896828) (xy 11.685777 -150.924714)
			(xy 11.677657 -150.97989) (xy 11.661589 -151.033297) (xy 11.637917 -151.083794) (xy 11.607144 -151.130307)
			(xy 11.569927 -151.171844) (xy 11.527059 -151.207519) (xy 11.479453 -151.236573) (xy 11.428124 -151.258385)
			(xy 11.374167 -151.272491) (xy 11.31873 -151.278591) (xy 11.262996 -151.276554) (xy 11.208153 -151.266424)
			(xy 11.155369 -151.248417) (xy 11.105769 -151.222916) (xy 11.060411 -151.190465) (xy 11.020262 -151.151756)
			(xy 10.986176 -151.107613) (xy 10.95888 -151.058978) (xy 10.938957 -151.006887) (xy 10.926831 -150.95245)
			(xy 10.92276 -150.896828) (xy 4.569225 -150.896828) (xy 4.529494 -150.92661) (xy 4.480984 -150.953018)
			(xy 4.429173 -150.972155) (xy 4.375143 -150.98362) (xy 4.320025 -150.987173) (xy 4.264971 -150.982741)
			(xy 4.211131 -150.970417) (xy 4.159631 -150.950457) (xy 4.111548 -150.923279) (xy 4.067887 -150.889451)
			(xy 4.029561 -150.84968) (xy 3.99737 -150.804798) (xy 3.984244 -150.780496) (xy 3.97316 -150.760255)
			(xy 3.944879 -150.723795) (xy 3.910482 -150.693038) (xy 3.871098 -150.668996) (xy 3.828021 -150.652459)
			(xy 3.782666 -150.643969) (xy 3.736524 -150.643806) (xy 3.691111 -150.651975) (xy 3.647918 -150.668208)
			(xy 3.627882 -150.679658) (xy 3.603951 -150.693449) (xy 3.55299 -150.714747) (xy 3.499491 -150.728474)
			(xy 3.444571 -150.734343) (xy 3.389379 -150.73223) (xy 3.335069 -150.72218) (xy 3.282775 -150.704403)
			(xy 3.233592 -150.679271) (xy 3.188547 -150.647309) (xy 3.148582 -150.609186) (xy 3.114533 -150.565697)
			(xy 3.08711 -150.517753) (xy 3.066889 -150.466356) (xy 3.05429 -150.412579) (xy 3.049578 -150.357548)
			(xy 1.64338 -150.357548) (xy 1.64338 -151.331168) (xy 5.175756 -151.331168) (xy 5.179827 -151.275546)
			(xy 5.191953 -151.221109) (xy 5.211876 -151.169018) (xy 5.239172 -151.120383) (xy 5.273258 -151.07624)
			(xy 5.313407 -151.037531) (xy 5.358765 -151.00508) (xy 5.408365 -150.979579) (xy 5.461149 -150.961572)
			(xy 5.515992 -150.951442) (xy 5.571726 -150.949405) (xy 5.627163 -150.955505) (xy 5.68112 -150.969611)
			(xy 5.732449 -150.991423) (xy 5.780055 -151.020477) (xy 5.822923 -151.056152) (xy 5.86014 -151.097689)
			(xy 5.890913 -151.144202) (xy 5.914585 -151.194699) (xy 5.930653 -151.248106) (xy 5.938773 -151.303282)
			(xy 5.939282 -151.331168) (xy 5.938773 -151.359054) (xy 5.930653 -151.41423) (xy 5.914585 -151.467637)
			(xy 5.890913 -151.518134) (xy 5.86014 -151.564647) (xy 5.822923 -151.606184) (xy 5.780055 -151.641859)
			(xy 5.732449 -151.670913) (xy 5.68112 -151.692725) (xy 5.627163 -151.706831) (xy 5.594819 -151.71039)
			(xy 8.365742 -151.71039) (xy 8.369813 -151.654768) (xy 8.381939 -151.600331) (xy 8.401862 -151.54824)
			(xy 8.429158 -151.499605) (xy 8.463244 -151.455462) (xy 8.503393 -151.416753) (xy 8.548751 -151.384302)
			(xy 8.598351 -151.358801) (xy 8.651135 -151.340794) (xy 8.705978 -151.330664) (xy 8.761712 -151.328627)
			(xy 8.817149 -151.334727) (xy 8.871106 -151.348833) (xy 8.922435 -151.370645) (xy 8.970041 -151.399699)
			(xy 9.012909 -151.435374) (xy 9.050126 -151.476911) (xy 9.080899 -151.523424) (xy 9.104571 -151.573921)
			(xy 9.120639 -151.627328) (xy 9.128759 -151.682504) (xy 9.129268 -151.71039) (xy 9.128759 -151.738276)
			(xy 9.120639 -151.793452) (xy 9.104571 -151.846859) (xy 9.080899 -151.897356) (xy 9.050126 -151.943869)
			(xy 9.012909 -151.985406) (xy 8.970041 -152.021081) (xy 8.922435 -152.050135) (xy 8.871106 -152.071947)
			(xy 8.817149 -152.086053) (xy 8.761712 -152.092153) (xy 8.705978 -152.090116) (xy 8.651135 -152.079986)
			(xy 8.598351 -152.061979) (xy 8.548751 -152.036478) (xy 8.503393 -152.004027) (xy 8.463244 -151.965318)
			(xy 8.429158 -151.921175) (xy 8.401862 -151.87254) (xy 8.381939 -151.820449) (xy 8.369813 -151.766012)
			(xy 8.365742 -151.71039) (xy 5.594819 -151.71039) (xy 5.571726 -151.712931) (xy 5.515992 -151.710894)
			(xy 5.461149 -151.700764) (xy 5.408365 -151.682757) (xy 5.358765 -151.657256) (xy 5.313407 -151.624805)
			(xy 5.273258 -151.586096) (xy 5.239172 -151.541953) (xy 5.211876 -151.493318) (xy 5.191953 -151.441227)
			(xy 5.179827 -151.38679) (xy 5.175756 -151.331168) (xy 1.64338 -151.331168) (xy 1.64338 -152.897078)
			(xy 3.300982 -152.897078) (xy 3.305053 -152.841456) (xy 3.317179 -152.787019) (xy 3.337102 -152.734928)
			(xy 3.364398 -152.686293) (xy 3.398484 -152.64215) (xy 3.438633 -152.603441) (xy 3.483991 -152.57099)
			(xy 3.533591 -152.545489) (xy 3.586375 -152.527482) (xy 3.641218 -152.517352) (xy 3.696952 -152.515315)
			(xy 3.752389 -152.521415) (xy 3.806346 -152.535521) (xy 3.857675 -152.557333) (xy 3.905281 -152.586387)
			(xy 3.948149 -152.622062) (xy 3.985366 -152.663599) (xy 4.016139 -152.710112) (xy 4.039811 -152.760609)
			(xy 4.055879 -152.814016) (xy 4.063999 -152.869192) (xy 4.064508 -152.897078) (xy 4.063999 -152.924964)
			(xy 4.059244 -152.957276) (xy 6.798562 -152.957276) (xy 6.802633 -152.901654) (xy 6.814759 -152.847217)
			(xy 6.834682 -152.795126) (xy 6.861978 -152.746491) (xy 6.896064 -152.702348) (xy 6.936213 -152.663639)
			(xy 6.981571 -152.631188) (xy 7.031171 -152.605687) (xy 7.083955 -152.58768) (xy 7.138798 -152.57755)
			(xy 7.194532 -152.575513) (xy 7.249969 -152.581613) (xy 7.303926 -152.595719) (xy 7.355255 -152.617531)
			(xy 7.402861 -152.646585) (xy 7.445729 -152.68226) (xy 7.482946 -152.723797) (xy 7.513719 -152.77031)
			(xy 7.537391 -152.820807) (xy 7.553459 -152.874214) (xy 7.561579 -152.92939) (xy 7.562088 -152.957276)
			(xy 7.561912 -152.966928) (xy 8.035542 -152.966928) (xy 8.039613 -152.911306) (xy 8.051739 -152.856869)
			(xy 8.071662 -152.804778) (xy 8.098958 -152.756143) (xy 8.133044 -152.712) (xy 8.173193 -152.673291)
			(xy 8.218551 -152.64084) (xy 8.268151 -152.615339) (xy 8.320935 -152.597332) (xy 8.375778 -152.587202)
			(xy 8.431512 -152.585165) (xy 8.486949 -152.591265) (xy 8.540906 -152.605371) (xy 8.592235 -152.627183)
			(xy 8.639841 -152.656237) (xy 8.682709 -152.691912) (xy 8.719926 -152.733449) (xy 8.750699 -152.779962)
			(xy 8.774371 -152.830459) (xy 8.790439 -152.883866) (xy 8.798559 -152.939042) (xy 8.799068 -152.966928)
			(xy 8.798559 -152.994814) (xy 8.790439 -153.04999) (xy 8.774371 -153.103397) (xy 8.750699 -153.153894)
			(xy 8.719926 -153.200407) (xy 8.682709 -153.241944) (xy 8.639841 -153.277619) (xy 8.592235 -153.306673)
			(xy 8.540906 -153.328485) (xy 8.486949 -153.342591) (xy 8.431512 -153.348691) (xy 8.375778 -153.346654)
			(xy 8.320935 -153.336524) (xy 8.268151 -153.318517) (xy 8.218551 -153.293016) (xy 8.173193 -153.260565)
			(xy 8.133044 -153.221856) (xy 8.098958 -153.177713) (xy 8.071662 -153.129078) (xy 8.051739 -153.076987)
			(xy 8.039613 -153.02255) (xy 8.035542 -152.966928) (xy 7.561912 -152.966928) (xy 7.561579 -152.985162)
			(xy 7.553459 -153.040338) (xy 7.537391 -153.093745) (xy 7.513719 -153.144242) (xy 7.482946 -153.190755)
			(xy 7.445729 -153.232292) (xy 7.402861 -153.267967) (xy 7.355255 -153.297021) (xy 7.303926 -153.318833)
			(xy 7.249969 -153.332939) (xy 7.194532 -153.339039) (xy 7.138798 -153.337002) (xy 7.083955 -153.326872)
			(xy 7.031171 -153.308865) (xy 6.981571 -153.283364) (xy 6.936213 -153.250913) (xy 6.896064 -153.212204)
			(xy 6.861978 -153.168061) (xy 6.834682 -153.119426) (xy 6.814759 -153.067335) (xy 6.802633 -153.012898)
			(xy 6.798562 -152.957276) (xy 4.059244 -152.957276) (xy 4.055879 -152.98014) (xy 4.039811 -153.033547)
			(xy 4.016139 -153.084044) (xy 3.985366 -153.130557) (xy 3.948149 -153.172094) (xy 3.905281 -153.207769)
			(xy 3.857675 -153.236823) (xy 3.806346 -153.258635) (xy 3.752389 -153.272741) (xy 3.696952 -153.278841)
			(xy 3.641218 -153.276804) (xy 3.586375 -153.266674) (xy 3.533591 -153.248667) (xy 3.483991 -153.223166)
			(xy 3.438633 -153.190715) (xy 3.398484 -153.152006) (xy 3.364398 -153.107863) (xy 3.337102 -153.059228)
			(xy 3.317179 -153.007137) (xy 3.305053 -152.9527) (xy 3.300982 -152.897078) (xy 1.64338 -152.897078)
			(xy 1.64338 -153.55833) (xy 9.615329 -153.55833) (xy 9.620508 -153.503394) (xy 9.633545 -153.449777)
			(xy 9.654167 -153.398596) (xy 9.681945 -153.350918) (xy 9.7163 -153.307738) (xy 9.736074 -153.288492)
			(xy 9.752498 -153.27242) (xy 9.779783 -153.235449) (xy 9.799972 -153.194173) (xy 9.812406 -153.149938)
			(xy 9.81668 -153.104187) (xy 9.812653 -153.058415) (xy 9.800459 -153.014113) (xy 9.780493 -152.972728)
			(xy 9.753408 -152.93561) (xy 9.73709 -152.91943) (xy 9.717424 -152.900074) (xy 9.683321 -152.856696)
			(xy 9.655821 -152.808858) (xy 9.635496 -152.757559) (xy 9.62277 -152.703868) (xy 9.61791 -152.648903)
			(xy 9.621015 -152.593812) (xy 9.632022 -152.539742) (xy 9.650701 -152.487821) (xy 9.676662 -152.439131)
			(xy 9.709365 -152.394688) (xy 9.748127 -152.355417) (xy 9.79214 -152.322137) (xy 9.840487 -152.295543)
			(xy 9.89216 -152.276188) (xy 9.946082 -152.264477) (xy 10.001128 -152.260653) (xy 10.056151 -152.264796)
			(xy 10.110004 -152.27682) (xy 10.161564 -152.296473) (xy 10.209756 -152.323348) (xy 10.253575 -152.356882)
			(xy 10.282014 -152.38603) (xy 17.050002 -152.38603) (xy 17.054073 -152.330408) (xy 17.066199 -152.275971)
			(xy 17.086122 -152.22388) (xy 17.113418 -152.175245) (xy 17.147504 -152.131102) (xy 17.187653 -152.092393)
			(xy 17.233011 -152.059942) (xy 17.282611 -152.034441) (xy 17.335395 -152.016434) (xy 17.390238 -152.006304)
			(xy 17.445972 -152.004267) (xy 17.501409 -152.010367) (xy 17.555366 -152.024473) (xy 17.606695 -152.046285)
			(xy 17.654301 -152.075339) (xy 17.697169 -152.111014) (xy 17.734386 -152.152551) (xy 17.765159 -152.199064)
			(xy 17.788831 -152.249561) (xy 17.804899 -152.302968) (xy 17.813019 -152.358144) (xy 17.813528 -152.38603)
			(xy 17.813019 -152.413916) (xy 17.804899 -152.469092) (xy 17.788831 -152.522499) (xy 17.765159 -152.572996)
			(xy 17.734386 -152.619509) (xy 17.697169 -152.661046) (xy 17.654301 -152.696721) (xy 17.606695 -152.725775)
			(xy 17.555366 -152.747587) (xy 17.501409 -152.761693) (xy 17.445972 -152.767793) (xy 17.390238 -152.765756)
			(xy 17.335395 -152.755626) (xy 17.282611 -152.737619) (xy 17.233011 -152.712118) (xy 17.187653 -152.679667)
			(xy 17.147504 -152.640958) (xy 17.113418 -152.596815) (xy 17.086122 -152.54818) (xy 17.066199 -152.496089)
			(xy 17.054073 -152.441652) (xy 17.050002 -152.38603) (xy 10.282014 -152.38603) (xy 10.292109 -152.396377)
			(xy 10.324553 -152.441009) (xy 10.350232 -152.489849) (xy 10.368609 -152.541877) (xy 10.379302 -152.59601)
			(xy 10.382088 -152.651119) (xy 10.376909 -152.706054) (xy 10.363873 -152.75967) (xy 10.343251 -152.810851)
			(xy 10.315474 -152.858528) (xy 10.28112 -152.901708) (xy 10.261346 -152.920954) (xy 10.244935 -152.937039)
			(xy 10.217649 -152.974007) (xy 10.197458 -153.015281) (xy 10.185023 -153.059514) (xy 10.180747 -153.105263)
			(xy 10.181202 -153.110438) (xy 10.755882 -153.110438) (xy 10.759953 -153.054816) (xy 10.772079 -153.000379)
			(xy 10.792002 -152.948288) (xy 10.819298 -152.899653) (xy 10.853384 -152.85551) (xy 10.893533 -152.816801)
			(xy 10.938891 -152.78435) (xy 10.988491 -152.758849) (xy 11.041275 -152.740842) (xy 11.096118 -152.730712)
			(xy 11.151852 -152.728675) (xy 11.207289 -152.734775) (xy 11.261246 -152.748881) (xy 11.312575 -152.770693)
			(xy 11.329175 -152.780824) (xy 18.193859 -152.780824) (xy 18.201666 -152.725437) (xy 18.217477 -152.671784)
			(xy 18.240954 -152.621015) (xy 18.271593 -152.574219) (xy 18.308738 -152.532399) (xy 18.351592 -152.496451)
			(xy 18.399236 -152.467148) (xy 18.450649 -152.445116) (xy 18.504728 -152.430828) (xy 18.560313 -152.424591)
			(xy 18.616214 -152.426539) (xy 18.67123 -152.436628) (xy 18.724184 -152.454645) (xy 18.773939 -152.480201)
			(xy 18.819428 -152.512749) (xy 18.859677 -152.551591) (xy 18.893821 -152.595895) (xy 18.92113 -152.64471)
			(xy 18.941017 -152.696989) (xy 18.953056 -152.751612) (xy 18.955512 -152.779476) (xy 18.95762 -152.80166)
			(xy 18.968481 -152.844873) (xy 18.986704 -152.885532) (xy 19.011732 -152.922395) (xy 19.042798 -152.954334)
			(xy 19.078954 -152.980373) (xy 19.119093 -152.999715) (xy 19.161988 -153.011768) (xy 19.184112 -153.014426)
			(xy 19.21191 -153.017572) (xy 19.266183 -153.031146) (xy 19.317893 -153.0525) (xy 19.365929 -153.081177)
			(xy 19.409262 -153.116562) (xy 19.446963 -153.157896) (xy 19.478224 -153.204293) (xy 19.502373 -153.254757)
			(xy 19.518894 -153.308208) (xy 19.527432 -153.363498) (xy 19.527803 -153.419442) (xy 19.520001 -153.47484)
			(xy 19.504191 -153.528505) (xy 19.480714 -153.579286) (xy 19.450073 -153.626093) (xy 19.412924 -153.667924)
			(xy 19.370065 -153.703882) (xy 19.322413 -153.733194) (xy 19.270992 -153.755234) (xy 19.216904 -153.769527)
			(xy 19.161308 -153.775768) (xy 19.105397 -153.773823) (xy 19.050369 -153.763733) (xy 18.997404 -153.745716)
			(xy 18.947639 -153.720156) (xy 18.90214 -153.687603) (xy 18.861883 -153.648754) (xy 18.827731 -153.604442)
			(xy 18.800417 -153.555618) (xy 18.780526 -153.503329) (xy 18.768484 -153.448695) (xy 18.766028 -153.420826)
			(xy 18.763971 -153.398635) (xy 18.753107 -153.355418) (xy 18.734879 -153.314754) (xy 18.709845 -153.277889)
			(xy 18.67877 -153.245949) (xy 18.642606 -153.219912) (xy 18.602458 -153.200575) (xy 18.559555 -153.188529)
			(xy 18.537428 -153.185876) (xy 18.509643 -153.182659) (xy 18.455382 -153.169079) (xy 18.403685 -153.147721)
			(xy 18.355662 -153.119043) (xy 18.312342 -153.083659) (xy 18.274654 -153.042328) (xy 18.243405 -152.995937)
			(xy 18.219266 -152.945479) (xy 18.202755 -152.892037) (xy 18.194225 -152.836757) (xy 18.193859 -152.780824)
			(xy 11.329175 -152.780824) (xy 11.360181 -152.799747) (xy 11.403049 -152.835422) (xy 11.440266 -152.876959)
			(xy 11.471039 -152.923472) (xy 11.494711 -152.973969) (xy 11.510779 -153.027376) (xy 11.518899 -153.082552)
			(xy 11.519408 -153.110438) (xy 11.518899 -153.138324) (xy 11.510779 -153.1935) (xy 11.494711 -153.246907)
			(xy 11.471039 -153.297404) (xy 11.440266 -153.343917) (xy 11.403049 -153.385454) (xy 11.360181 -153.421129)
			(xy 11.312575 -153.450183) (xy 11.261246 -153.471995) (xy 11.207289 -153.486101) (xy 11.151852 -153.492201)
			(xy 11.096118 -153.490164) (xy 11.041275 -153.480034) (xy 10.988491 -153.462027) (xy 10.938891 -153.436526)
			(xy 10.893533 -153.404075) (xy 10.853384 -153.365366) (xy 10.819298 -153.321223) (xy 10.792002 -153.272588)
			(xy 10.772079 -153.220497) (xy 10.759953 -153.16606) (xy 10.755882 -153.110438) (xy 10.181202 -153.110438)
			(xy 10.184772 -153.151034) (xy 10.196965 -153.195335) (xy 10.216929 -153.236719) (xy 10.244012 -153.273836)
			(xy 10.26033 -153.290016) (xy 10.279996 -153.309372) (xy 10.3141 -153.352751) (xy 10.341601 -153.400588)
			(xy 10.361926 -153.451888) (xy 10.374652 -153.50558) (xy 10.379513 -153.560545) (xy 10.376408 -153.615637)
			(xy 10.365401 -153.669707) (xy 10.346722 -153.721629) (xy 10.320761 -153.770319) (xy 10.288058 -153.814764)
			(xy 10.249296 -153.854035) (xy 10.205282 -153.887315) (xy 10.156935 -153.91391) (xy 10.105261 -153.933264)
			(xy 10.051339 -153.944976) (xy 9.996292 -153.9488) (xy 9.941269 -153.944657) (xy 9.887415 -153.932633)
			(xy 9.835855 -153.912979) (xy 9.787662 -153.886105) (xy 9.743842 -153.85257) (xy 9.705308 -153.813074)
			(xy 9.672864 -153.768441) (xy 9.647185 -153.719601) (xy 9.628808 -153.667572) (xy 9.618115 -153.613439)
			(xy 9.615329 -153.55833) (xy 1.64338 -153.55833) (xy 1.64338 -155.973832) (xy 3.516963 -155.973832)
			(xy 3.523686 -155.918458) (xy 3.5384 -155.864654) (xy 3.560791 -155.813565) (xy 3.590382 -155.76628)
			(xy 3.626542 -155.723808) (xy 3.647186 -155.705048) (xy 3.663471 -155.69016) (xy 3.691139 -155.655792)
			(xy 3.712453 -155.617161) (xy 3.726773 -155.575429) (xy 3.733668 -155.531851) (xy 3.732931 -155.487736)
			(xy 3.724583 -155.444413) (xy 3.708876 -155.403183) (xy 3.697986 -155.383992) (xy 3.684166 -155.359761)
			(xy 3.662932 -155.308181) (xy 3.649434 -155.254058) (xy 3.643961 -155.198546) (xy 3.646628 -155.14283)
			(xy 3.657379 -155.088095) (xy 3.675985 -155.035509) (xy 3.702049 -154.986193) (xy 3.735016 -154.941196)
			(xy 3.774183 -154.901479) (xy 3.818715 -154.867888) (xy 3.867663 -154.841139) (xy 3.919984 -154.821802)
			(xy 3.974563 -154.810288) (xy 4.030237 -154.806844) (xy 4.08582 -154.811542) (xy 4.140126 -154.824283)
			(xy 4.191998 -154.844796) (xy 4.24033 -154.872642) (xy 4.284094 -154.907228) (xy 4.322355 -154.947818)
			(xy 4.354299 -154.993546) (xy 4.379244 -155.043438) (xy 4.39666 -155.09643) (xy 4.406174 -155.151393)
			(xy 4.407585 -155.207156) (xy 4.400861 -155.262529) (xy 4.386147 -155.316334) (xy 4.363756 -155.367423)
			(xy 4.334165 -155.414708) (xy 4.298004 -155.45718) (xy 4.283509 -155.470352) (xy 6.776972 -155.470352)
			(xy 6.781043 -155.41473) (xy 6.793169 -155.360293) (xy 6.813092 -155.308202) (xy 6.840388 -155.259567)
			(xy 6.874474 -155.215424) (xy 6.914623 -155.176715) (xy 6.959981 -155.144264) (xy 7.009581 -155.118763)
			(xy 7.062365 -155.100756) (xy 7.117208 -155.090626) (xy 7.172942 -155.088589) (xy 7.228379 -155.094689)
			(xy 7.282336 -155.108795) (xy 7.333665 -155.130607) (xy 7.381271 -155.159661) (xy 7.424139 -155.195336)
			(xy 7.441604 -155.214828) (xy 8.998202 -155.214828) (xy 9.002273 -155.159206) (xy 9.014399 -155.104769)
			(xy 9.034322 -155.052678) (xy 9.061618 -155.004043) (xy 9.095704 -154.9599) (xy 9.135853 -154.921191)
			(xy 9.181211 -154.88874) (xy 9.230811 -154.863239) (xy 9.283595 -154.845232) (xy 9.338438 -154.835102)
			(xy 9.394172 -154.833065) (xy 9.449609 -154.839165) (xy 9.503566 -154.853271) (xy 9.554895 -154.875083)
			(xy 9.602501 -154.904137) (xy 9.645369 -154.939812) (xy 9.682586 -154.981349) (xy 9.713359 -155.027862)
			(xy 9.737031 -155.078359) (xy 9.753099 -155.131766) (xy 9.761219 -155.186942) (xy 9.761728 -155.214828)
			(xy 9.761219 -155.242714) (xy 9.753099 -155.29789) (xy 9.737031 -155.351297) (xy 9.713359 -155.401794)
			(xy 9.682586 -155.448307) (xy 9.645369 -155.489844) (xy 9.602501 -155.525519) (xy 9.554895 -155.554573)
			(xy 9.514596 -155.571698) (xy 10.527282 -155.571698) (xy 10.531353 -155.516076) (xy 10.543479 -155.461639)
			(xy 10.563402 -155.409548) (xy 10.590698 -155.360913) (xy 10.624784 -155.31677) (xy 10.664933 -155.278061)
			(xy 10.710291 -155.24561) (xy 10.759891 -155.220109) (xy 10.812675 -155.202102) (xy 10.867518 -155.191972)
			(xy 10.923252 -155.189935) (xy 10.978689 -155.196035) (xy 11.032646 -155.210141) (xy 11.040033 -155.21328)
			(xy 18.206529 -155.21328) (xy 18.214527 -155.158335) (xy 18.230406 -155.10513) (xy 18.253828 -155.054788)
			(xy 18.2843 -155.008373) (xy 18.321177 -154.966864) (xy 18.363682 -154.931139) (xy 18.410916 -154.901953)
			(xy 18.461882 -154.87992) (xy 18.515503 -154.865508) (xy 18.543016 -154.861768) (xy 18.564547 -154.858793)
			(xy 18.606225 -154.846471) (xy 18.645198 -154.827235) (xy 18.68033 -154.801648) (xy 18.710594 -154.770456)
			(xy 18.73511 -154.734568) (xy 18.753161 -154.695033) (xy 18.76422 -154.653002) (xy 18.766536 -154.63139)
			(xy 18.769467 -154.603778) (xy 18.782209 -154.549736) (xy 18.80265 -154.498112) (xy 18.830358 -154.449996)
			(xy 18.864748 -154.406405) (xy 18.905093 -154.368258) (xy 18.950541 -154.336363) (xy 19.000133 -154.311392)
			(xy 19.05282 -154.293873) (xy 19.107491 -154.284176) (xy 19.162989 -154.282506) (xy 19.218144 -154.288898)
			(xy 19.271789 -154.303218) (xy 19.322792 -154.325162) (xy 19.370076 -154.354267) (xy 19.412642 -154.389918)
			(xy 19.44959 -154.431363) (xy 19.480141 -154.477726) (xy 19.503649 -154.528028) (xy 19.519618 -154.581206)
			(xy 19.527709 -154.636136) (xy 19.527753 -154.69166) (xy 19.519749 -154.746604) (xy 19.503864 -154.799807)
			(xy 19.480436 -154.850146) (xy 19.449959 -154.896557) (xy 19.413076 -154.93806) (xy 19.370567 -154.973779)
			(xy 19.323329 -155.002959) (xy 19.272361 -155.024984) (xy 19.218738 -155.039388) (xy 19.191224 -155.043124)
			(xy 19.169699 -155.046137) (xy 19.128022 -155.058453) (xy 19.089049 -155.077682) (xy 19.053917 -155.103263)
			(xy 19.023651 -155.13445) (xy 18.999134 -155.170333) (xy 18.981082 -155.209865) (xy 18.970021 -155.251892)
			(xy 18.967704 -155.273502) (xy 18.964848 -155.301121) (xy 18.952107 -155.355163) (xy 18.931667 -155.406788)
			(xy 18.924025 -155.42006) (xy 27.466542 -155.42006) (xy 27.470613 -155.364438) (xy 27.482739 -155.310001)
			(xy 27.502662 -155.25791) (xy 27.529958 -155.209275) (xy 27.564044 -155.165132) (xy 27.604193 -155.126423)
			(xy 27.649551 -155.093972) (xy 27.699151 -155.068471) (xy 27.751935 -155.050464) (xy 27.806778 -155.040334)
			(xy 27.862512 -155.038297) (xy 27.917949 -155.044397) (xy 27.971906 -155.058503) (xy 28.023235 -155.080315)
			(xy 28.070841 -155.109369) (xy 28.113709 -155.145044) (xy 28.150926 -155.186581) (xy 28.181699 -155.233094)
			(xy 28.205371 -155.283591) (xy 28.221439 -155.336998) (xy 28.229559 -155.392174) (xy 28.230068 -155.42006)
			(xy 28.229559 -155.447946) (xy 28.221439 -155.503122) (xy 28.205371 -155.556529) (xy 28.181699 -155.607026)
			(xy 28.150926 -155.653539) (xy 28.113709 -155.695076) (xy 28.070841 -155.730751) (xy 28.023235 -155.759805)
			(xy 27.971906 -155.781617) (xy 27.917949 -155.795723) (xy 27.862512 -155.801823) (xy 27.806778 -155.799786)
			(xy 27.751935 -155.789656) (xy 27.699151 -155.771649) (xy 27.649551 -155.746148) (xy 27.604193 -155.713697)
			(xy 27.564044 -155.674988) (xy 27.529958 -155.630845) (xy 27.502662 -155.58221) (xy 27.482739 -155.530119)
			(xy 27.470613 -155.475682) (xy 27.466542 -155.42006) (xy 18.924025 -155.42006) (xy 18.90396 -155.454905)
			(xy 18.869571 -155.498497) (xy 18.829227 -155.536645) (xy 18.783779 -155.568543) (xy 18.734188 -155.593516)
			(xy 18.681501 -155.611037) (xy 18.626831 -155.620737) (xy 18.571332 -155.62241) (xy 18.516177 -155.616021)
			(xy 18.46253 -155.601705) (xy 18.411525 -155.579764) (xy 18.364239 -155.550662) (xy 18.32167 -155.515014)
			(xy 18.284718 -155.473572) (xy 18.254162 -155.427211) (xy 18.23065 -155.376911) (xy 18.214676 -155.323735)
			(xy 18.206579 -155.268804) (xy 18.206529 -155.21328) (xy 11.040033 -155.21328) (xy 11.083975 -155.231953)
			(xy 11.131581 -155.261007) (xy 11.174449 -155.296682) (xy 11.211666 -155.338219) (xy 11.242439 -155.384732)
			(xy 11.266111 -155.435229) (xy 11.282179 -155.488636) (xy 11.290299 -155.543812) (xy 11.290808 -155.571698)
			(xy 11.290299 -155.599584) (xy 11.282179 -155.65476) (xy 11.266111 -155.708167) (xy 11.242439 -155.758664)
			(xy 11.211666 -155.805177) (xy 11.174449 -155.846714) (xy 11.131581 -155.882389) (xy 11.083975 -155.911443)
			(xy 11.032646 -155.933255) (xy 10.978689 -155.947361) (xy 10.923252 -155.953461) (xy 10.867518 -155.951424)
			(xy 10.812675 -155.941294) (xy 10.759891 -155.923287) (xy 10.710291 -155.897786) (xy 10.664933 -155.865335)
			(xy 10.624784 -155.826626) (xy 10.590698 -155.782483) (xy 10.563402 -155.733848) (xy 10.543479 -155.681757)
			(xy 10.531353 -155.62732) (xy 10.527282 -155.571698) (xy 9.514596 -155.571698) (xy 9.503566 -155.576385)
			(xy 9.449609 -155.590491) (xy 9.394172 -155.596591) (xy 9.338438 -155.594554) (xy 9.283595 -155.584424)
			(xy 9.230811 -155.566417) (xy 9.181211 -155.540916) (xy 9.135853 -155.508465) (xy 9.095704 -155.469756)
			(xy 9.061618 -155.425613) (xy 9.034322 -155.376978) (xy 9.014399 -155.324887) (xy 9.002273 -155.27045)
			(xy 8.998202 -155.214828) (xy 7.441604 -155.214828) (xy 7.461356 -155.236873) (xy 7.492129 -155.283386)
			(xy 7.515801 -155.333883) (xy 7.531869 -155.38729) (xy 7.539989 -155.442466) (xy 7.540498 -155.470352)
			(xy 7.539989 -155.498238) (xy 7.531869 -155.553414) (xy 7.515801 -155.606821) (xy 7.492129 -155.657318)
			(xy 7.461356 -155.703831) (xy 7.424139 -155.745368) (xy 7.381271 -155.781043) (xy 7.333665 -155.810097)
			(xy 7.282336 -155.831909) (xy 7.228379 -155.846015) (xy 7.172942 -155.852115) (xy 7.117208 -155.850078)
			(xy 7.062365 -155.839948) (xy 7.009581 -155.821941) (xy 6.959981 -155.79644) (xy 6.914623 -155.763989)
			(xy 6.874474 -155.72528) (xy 6.840388 -155.681137) (xy 6.813092 -155.632502) (xy 6.793169 -155.580411)
			(xy 6.781043 -155.525974) (xy 6.776972 -155.470352) (xy 4.283509 -155.470352) (xy 4.27736 -155.47594)
			(xy 4.261076 -155.49083) (xy 4.233409 -155.525197) (xy 4.212095 -155.563828) (xy 4.197775 -155.605559)
			(xy 4.19088 -155.649138) (xy 4.191617 -155.693252) (xy 4.199964 -155.736575) (xy 4.21567 -155.777805)
			(xy 4.22656 -155.796996) (xy 4.240381 -155.821226) (xy 4.261615 -155.872807) (xy 4.275112 -155.926929)
			(xy 4.280585 -155.98244) (xy 4.277918 -156.038157) (xy 4.267167 -156.092891) (xy 4.248561 -156.145477)
			(xy 4.226944 -156.186378) (xy 12.884402 -156.186378) (xy 12.888473 -156.130756) (xy 12.900599 -156.076319)
			(xy 12.920522 -156.024228) (xy 12.947818 -155.975593) (xy 12.981904 -155.93145) (xy 13.022053 -155.892741)
			(xy 13.067411 -155.86029) (xy 13.117011 -155.834789) (xy 13.169795 -155.816782) (xy 13.224638 -155.806652)
			(xy 13.280372 -155.804615) (xy 13.335809 -155.810715) (xy 13.389766 -155.824821) (xy 13.441095 -155.846633)
			(xy 13.488701 -155.875687) (xy 13.531569 -155.911362) (xy 13.551992 -155.934156) (xy 15.764762 -155.934156)
			(xy 15.768833 -155.878534) (xy 15.780959 -155.824097) (xy 15.800882 -155.772006) (xy 15.828178 -155.723371)
			(xy 15.862264 -155.679228) (xy 15.902413 -155.640519) (xy 15.947771 -155.608068) (xy 15.997371 -155.582567)
			(xy 16.050155 -155.56456) (xy 16.104998 -155.55443) (xy 16.160732 -155.552393) (xy 16.216169 -155.558493)
			(xy 16.270126 -155.572599) (xy 16.321455 -155.594411) (xy 16.369061 -155.623465) (xy 16.411929 -155.65914)
			(xy 16.449146 -155.700677) (xy 16.479919 -155.74719) (xy 16.503591 -155.797687) (xy 16.519659 -155.851094)
			(xy 16.527779 -155.90627) (xy 16.528131 -155.925549) (xy 23.511867 -155.925549) (xy 23.51451 -155.869541)
			(xy 23.52532 -155.814523) (xy 23.544067 -155.76168) (xy 23.570346 -155.71215) (xy 23.603592 -155.666999)
			(xy 23.643087 -155.6272) (xy 23.687983 -155.593611) (xy 23.737311 -155.566954) (xy 23.790009 -155.547803)
			(xy 23.844943 -155.536572) (xy 23.900929 -155.533502) (xy 23.956761 -155.538659) (xy 24.011237 -155.551932)
			(xy 24.063184 -155.573035) (xy 24.111483 -155.601514) (xy 24.155094 -155.636755) (xy 24.17445 -155.657042)
			(xy 24.190917 -155.674064) (xy 24.22888 -155.702366) (xy 24.271427 -155.723149) (xy 24.317088 -155.735692)
			(xy 24.364281 -155.739561) (xy 24.411375 -155.734624) (xy 24.45674 -155.721051) (xy 24.498807 -155.699311)
			(xy 24.536119 -155.670157) (xy 24.552148 -155.652724) (xy 24.570803 -155.632317) (xy 24.612895 -155.596474)
			(xy 24.659722 -155.567083) (xy 24.710301 -155.544762) (xy 24.763574 -155.529977) (xy 24.818423 -155.523039)
			(xy 24.873699 -155.524093) (xy 24.928243 -155.533116) (xy 24.980913 -155.549921) (xy 25.030605 -155.574154)
			(xy 25.076277 -155.605308) (xy 25.116973 -155.64273) (xy 25.151839 -155.685635) (xy 25.180145 -155.733125)
			(xy 25.201298 -155.784205) (xy 25.214854 -155.837803) (xy 25.220529 -155.892797) (xy 25.218204 -155.948034)
			(xy 25.207929 -156.002357) (xy 25.189918 -156.054626) (xy 25.164548 -156.103748) (xy 25.132352 -156.148692)
			(xy 25.094005 -156.188516) (xy 25.050309 -156.222387) (xy 25.00218 -156.249593) (xy 24.976582 -156.260038)
			(xy 24.955115 -156.268948) (xy 24.915559 -156.293339) (xy 24.881092 -156.324509) (xy 24.85286 -156.361421)
			(xy 24.831802 -156.402848) (xy 24.818619 -156.447411) (xy 24.81375 -156.493626) (xy 24.815038 -156.516832)
			(xy 24.816543 -156.54115) (xy 24.814129 -156.589813) (xy 24.810212 -156.61386) (xy 24.806662 -156.636637)
			(xy 24.806701 -156.647896) (xy 27.430982 -156.647896) (xy 27.435053 -156.592274) (xy 27.447179 -156.537837)
			(xy 27.467102 -156.485746) (xy 27.494398 -156.437111) (xy 27.528484 -156.392968) (xy 27.568633 -156.354259)
			(xy 27.613991 -156.321808) (xy 27.663591 -156.296307) (xy 27.716375 -156.2783) (xy 27.771218 -156.26817)
			(xy 27.826952 -156.266133) (xy 27.882389 -156.272233) (xy 27.936346 -156.286339) (xy 27.987675 -156.308151)
			(xy 28.035281 -156.337205) (xy 28.078149 -156.37288) (xy 28.115366 -156.414417) (xy 28.146139 -156.46093)
			(xy 28.169811 -156.511427) (xy 28.185879 -156.564834) (xy 28.193999 -156.62001) (xy 28.194508 -156.647896)
			(xy 28.193999 -156.675782) (xy 28.185879 -156.730958) (xy 28.169811 -156.784365) (xy 28.146139 -156.834862)
			(xy 28.115366 -156.881375) (xy 28.078149 -156.922912) (xy 28.035281 -156.958587) (xy 27.987675 -156.987641)
			(xy 27.936346 -157.009453) (xy 27.882389 -157.023559) (xy 27.826952 -157.029659) (xy 27.771218 -157.027622)
			(xy 27.716375 -157.017492) (xy 27.663591 -156.999485) (xy 27.613991 -156.973984) (xy 27.568633 -156.941533)
			(xy 27.528484 -156.902824) (xy 27.494398 -156.858681) (xy 27.467102 -156.810046) (xy 27.447179 -156.757955)
			(xy 27.435053 -156.703518) (xy 27.430982 -156.647896) (xy 24.806701 -156.647896) (xy 24.806822 -156.682729)
			(xy 24.815294 -156.728036) (xy 24.831797 -156.771072) (xy 24.855792 -156.810426) (xy 24.886492 -156.844806)
			(xy 24.922889 -156.873086) (xy 24.96379 -156.894337) (xy 25.007852 -156.907863) (xy 25.030684 -156.91104)
			(xy 25.058261 -156.914774) (xy 25.112004 -156.929218) (xy 25.163078 -156.951313) (xy 25.210403 -156.980592)
			(xy 25.252974 -157.016432) (xy 25.289889 -157.058075) (xy 25.320365 -157.104638) (xy 25.343756 -157.155132)
			(xy 25.359566 -157.208489) (xy 25.36746 -157.263575) (xy 25.36727 -157.319224) (xy 25.359001 -157.374256)
			(xy 25.342827 -157.427503) (xy 25.319092 -157.477837) (xy 25.2883 -157.52419) (xy 25.251102 -157.565581)
			(xy 25.208287 -157.60113) (xy 25.160764 -157.630085) (xy 25.10954 -157.651832) (xy 25.0557 -157.665909)
			(xy 25.000387 -157.672018) (xy 24.944774 -157.670029) (xy 24.890038 -157.659986) (xy 24.837342 -157.642099)
			(xy 24.787801 -157.61675) (xy 24.742467 -157.584475) (xy 24.702301 -157.545959) (xy 24.668154 -157.502018)
			(xy 24.64075 -157.453583) (xy 24.620671 -157.401683) (xy 24.608341 -157.347417) (xy 24.604023 -157.291935)
			(xy 24.607808 -157.236415) (xy 24.619616 -157.182032) (xy 24.639196 -157.129941) (xy 24.652224 -157.10535)
			(xy 24.659578 -157.090966) (xy 24.667567 -157.059676) (xy 24.667447 -157.027383) (xy 24.659225 -156.996154)
			(xy 24.643429 -156.967987) (xy 24.621069 -156.944687) (xy 24.593577 -156.927744) (xy 24.562712 -156.918245)
			(xy 24.530451 -156.916795) (xy 24.514556 -156.919676) (xy 24.490426 -156.923994) (xy 24.466961 -156.928003)
			(xy 24.421991 -156.943598) (xy 24.380712 -156.967295) (xy 24.344567 -156.998263) (xy 24.31482 -157.03542)
			(xy 24.292512 -157.077466) (xy 24.278423 -157.12293) (xy 24.273047 -157.170223) (xy 24.274272 -157.193996)
			(xy 24.275839 -157.221634) (xy 24.271947 -157.276852) (xy 24.260116 -157.330928) (xy 24.240594 -157.382727)
			(xy 24.213792 -157.431161) (xy 24.180271 -157.475213) (xy 24.140737 -157.513958) (xy 24.096018 -157.546584)
			(xy 24.047054 -157.572404) (xy 23.994872 -157.590878) (xy 23.940568 -157.601617) (xy 23.885283 -157.604395)
			(xy 23.830176 -157.599155) (xy 23.776405 -157.586006) (xy 23.725099 -157.565225) (xy 23.677335 -157.537248)
			(xy 23.634114 -157.502661) (xy 23.596346 -157.462192) (xy 23.564823 -157.416689) (xy 23.540206 -157.367109)
			(xy 23.523013 -157.314491) (xy 23.513604 -157.259942) (xy 23.512177 -157.204605) (xy 23.518762 -157.149643)
			(xy 23.53322 -157.096209) (xy 23.555248 -157.045426) (xy 23.584385 -156.998359) (xy 23.620017 -156.955997)
			(xy 23.661397 -156.919228) (xy 23.707656 -156.888826) (xy 23.757823 -156.865428) (xy 23.810844 -156.849525)
			(xy 23.838154 -156.845) (xy 23.861617 -156.840982) (xy 23.906588 -156.82539) (xy 23.947868 -156.801695)
			(xy 23.984014 -156.770729) (xy 24.013762 -156.733573) (xy 24.03607 -156.691527) (xy 24.050158 -156.646063)
			(xy 24.055534 -156.598771) (xy 24.054308 -156.574998) (xy 24.053292 -156.545026) (xy 24.052832 -156.522382)
			(xy 24.045003 -156.47778) (xy 24.029391 -156.435272) (xy 24.006491 -156.396205) (xy 23.977028 -156.361816)
			(xy 23.941936 -156.333195) (xy 23.902326 -156.311247) (xy 23.859453 -156.296669) (xy 23.837138 -156.292804)
			(xy 23.809488 -156.288146) (xy 23.755856 -156.271793) (xy 23.705194 -156.247767) (xy 23.658595 -156.216585)
			(xy 23.617061 -156.178918) (xy 23.581487 -156.135578) (xy 23.55264 -156.087498) (xy 23.53114 -156.035714)
			(xy 23.517451 -155.98134) (xy 23.511867 -155.925549) (xy 16.528131 -155.925549) (xy 16.528288 -155.934156)
			(xy 16.527779 -155.962042) (xy 16.519659 -156.017218) (xy 16.503591 -156.070625) (xy 16.479919 -156.121122)
			(xy 16.449146 -156.167635) (xy 16.411929 -156.209172) (xy 16.369061 -156.244847) (xy 16.321455 -156.273901)
			(xy 16.270126 -156.295713) (xy 16.216169 -156.309819) (xy 16.160732 -156.315919) (xy 16.104998 -156.313882)
			(xy 16.050155 -156.303752) (xy 15.997371 -156.285745) (xy 15.947771 -156.260244) (xy 15.902413 -156.227793)
			(xy 15.862264 -156.189084) (xy 15.828178 -156.144941) (xy 15.800882 -156.096306) (xy 15.780959 -156.044215)
			(xy 15.768833 -155.989778) (xy 15.764762 -155.934156) (xy 13.551992 -155.934156) (xy 13.568786 -155.952899)
			(xy 13.599559 -155.999412) (xy 13.623231 -156.049909) (xy 13.639299 -156.103316) (xy 13.647419 -156.158492)
			(xy 13.647928 -156.186378) (xy 13.647419 -156.214264) (xy 13.639299 -156.26944) (xy 13.623231 -156.322847)
			(xy 13.599559 -156.373344) (xy 13.568786 -156.419857) (xy 13.531569 -156.461394) (xy 13.488701 -156.497069)
			(xy 13.441095 -156.526123) (xy 13.389766 -156.547935) (xy 13.335809 -156.562041) (xy 13.280372 -156.568141)
			(xy 13.224638 -156.566104) (xy 13.169795 -156.555974) (xy 13.117011 -156.537967) (xy 13.067411 -156.512466)
			(xy 13.022053 -156.480015) (xy 12.981904 -156.441306) (xy 12.947818 -156.397163) (xy 12.920522 -156.348528)
			(xy 12.900599 -156.296437) (xy 12.888473 -156.242) (xy 12.884402 -156.186378) (xy 4.226944 -156.186378)
			(xy 4.222497 -156.194793) (xy 4.18953 -156.239789) (xy 4.150364 -156.279506) (xy 4.105832 -156.313097)
			(xy 4.056884 -156.339846) (xy 4.004563 -156.359184) (xy 3.949984 -156.370697) (xy 3.89431 -156.374141)
			(xy 3.838728 -156.369443) (xy 3.784422 -156.356702) (xy 3.73255 -156.33619) (xy 3.684218 -156.308344)
			(xy 3.640454 -156.273758) (xy 3.602193 -156.233168) (xy 3.570249 -156.18744) (xy 3.545304 -156.137549)
			(xy 3.527888 -156.084557) (xy 3.518374 -156.029594) (xy 3.516963 -155.973832) (xy 1.64338 -155.973832)
			(xy 1.64338 -156.960824) (xy 2.660902 -156.960824) (xy 2.664973 -156.905202) (xy 2.677099 -156.850765)
			(xy 2.697022 -156.798674) (xy 2.724318 -156.750039) (xy 2.758404 -156.705896) (xy 2.798553 -156.667187)
			(xy 2.843911 -156.634736) (xy 2.893511 -156.609235) (xy 2.946295 -156.591228) (xy 3.001138 -156.581098)
			(xy 3.056872 -156.579061) (xy 3.112309 -156.585161) (xy 3.166266 -156.599267) (xy 3.217595 -156.621079)
			(xy 3.265201 -156.650133) (xy 3.308069 -156.685808) (xy 3.345286 -156.727345) (xy 3.376059 -156.773858)
			(xy 3.399731 -156.824355) (xy 3.415799 -156.877762) (xy 3.423919 -156.932938) (xy 3.424159 -156.946092)
			(xy 7.426958 -156.946092) (xy 7.431029 -156.89047) (xy 7.443155 -156.836033) (xy 7.463078 -156.783942)
			(xy 7.490374 -156.735307) (xy 7.52446 -156.691164) (xy 7.564609 -156.652455) (xy 7.609967 -156.620004)
			(xy 7.659567 -156.594503) (xy 7.712351 -156.576496) (xy 7.767194 -156.566366) (xy 7.822928 -156.564329)
			(xy 7.878365 -156.570429) (xy 7.932322 -156.584535) (xy 7.983651 -156.606347) (xy 8.031257 -156.635401)
			(xy 8.074125 -156.671076) (xy 8.111342 -156.712613) (xy 8.123644 -156.731208) (xy 8.72693 -156.731208)
			(xy 8.731001 -156.675586) (xy 8.743127 -156.621149) (xy 8.76305 -156.569058) (xy 8.790346 -156.520423)
			(xy 8.824432 -156.47628) (xy 8.864581 -156.437571) (xy 8.909939 -156.40512) (xy 8.959539 -156.379619)
			(xy 9.012323 -156.361612) (xy 9.067166 -156.351482) (xy 9.1229 -156.349445) (xy 9.178337 -156.355545)
			(xy 9.232294 -156.369651) (xy 9.283623 -156.391463) (xy 9.331229 -156.420517) (xy 9.374097 -156.456192)
			(xy 9.411314 -156.497729) (xy 9.442087 -156.544242) (xy 9.465759 -156.594739) (xy 9.481827 -156.648146)
			(xy 9.486425 -156.679392) (xy 11.677902 -156.679392) (xy 11.681973 -156.62377) (xy 11.694099 -156.569333)
			(xy 11.714022 -156.517242) (xy 11.741318 -156.468607) (xy 11.775404 -156.424464) (xy 11.815553 -156.385755)
			(xy 11.860911 -156.353304) (xy 11.910511 -156.327803) (xy 11.963295 -156.309796) (xy 12.018138 -156.299666)
			(xy 12.073872 -156.297629) (xy 12.129309 -156.303729) (xy 12.183266 -156.317835) (xy 12.234595 -156.339647)
			(xy 12.282201 -156.368701) (xy 12.325069 -156.404376) (xy 12.362286 -156.445913) (xy 12.393059 -156.492426)
			(xy 12.416731 -156.542923) (xy 12.432799 -156.59633) (xy 12.440919 -156.651506) (xy 12.441428 -156.679392)
			(xy 12.440919 -156.707278) (xy 12.432799 -156.762454) (xy 12.416731 -156.815861) (xy 12.393059 -156.866358)
			(xy 12.362286 -156.912871) (xy 12.325069 -156.954408) (xy 12.282201 -156.990083) (xy 12.234595 -157.019137)
			(xy 12.183266 -157.040949) (xy 12.129309 -157.055055) (xy 12.073872 -157.061155) (xy 12.018138 -157.059118)
			(xy 11.963295 -157.048988) (xy 11.910511 -157.030981) (xy 11.860911 -157.00548) (xy 11.815553 -156.973029)
			(xy 11.775404 -156.93432) (xy 11.741318 -156.890177) (xy 11.714022 -156.841542) (xy 11.694099 -156.789451)
			(xy 11.681973 -156.735014) (xy 11.677902 -156.679392) (xy 9.486425 -156.679392) (xy 9.489947 -156.703322)
			(xy 9.490456 -156.731208) (xy 9.489947 -156.759094) (xy 9.481827 -156.81427) (xy 9.465759 -156.867677)
			(xy 9.442087 -156.918174) (xy 9.411314 -156.964687) (xy 9.374097 -157.006224) (xy 9.331229 -157.041899)
			(xy 9.283623 -157.070953) (xy 9.232294 -157.092765) (xy 9.178337 -157.106871) (xy 9.1229 -157.112971)
			(xy 9.067166 -157.110934) (xy 9.012323 -157.100804) (xy 8.959539 -157.082797) (xy 8.909939 -157.057296)
			(xy 8.864581 -157.024845) (xy 8.824432 -156.986136) (xy 8.790346 -156.941993) (xy 8.76305 -156.893358)
			(xy 8.743127 -156.841267) (xy 8.731001 -156.78683) (xy 8.72693 -156.731208) (xy 8.123644 -156.731208)
			(xy 8.142115 -156.759126) (xy 8.165787 -156.809623) (xy 8.181855 -156.86303) (xy 8.189975 -156.918206)
			(xy 8.190484 -156.946092) (xy 8.189975 -156.973978) (xy 8.181855 -157.029154) (xy 8.165787 -157.082561)
			(xy 8.142115 -157.133058) (xy 8.111342 -157.179571) (xy 8.074125 -157.221108) (xy 8.031257 -157.256783)
			(xy 7.983651 -157.285837) (xy 7.932322 -157.307649) (xy 7.878365 -157.321755) (xy 7.822928 -157.327855)
			(xy 7.767194 -157.325818) (xy 7.712351 -157.315688) (xy 7.659567 -157.297681) (xy 7.609967 -157.27218)
			(xy 7.564609 -157.239729) (xy 7.52446 -157.20102) (xy 7.490374 -157.156877) (xy 7.463078 -157.108242)
			(xy 7.443155 -157.056151) (xy 7.431029 -157.001714) (xy 7.426958 -156.946092) (xy 3.424159 -156.946092)
			(xy 3.424428 -156.960824) (xy 3.423919 -156.98871) (xy 3.415799 -157.043886) (xy 3.399731 -157.097293)
			(xy 3.376059 -157.14779) (xy 3.345286 -157.194303) (xy 3.308069 -157.23584) (xy 3.265201 -157.271515)
			(xy 3.217595 -157.300569) (xy 3.166266 -157.322381) (xy 3.112309 -157.336487) (xy 3.056872 -157.342587)
			(xy 3.001138 -157.34055) (xy 2.946295 -157.33042) (xy 2.893511 -157.312413) (xy 2.843911 -157.286912)
			(xy 2.798553 -157.254461) (xy 2.758404 -157.215752) (xy 2.724318 -157.171609) (xy 2.697022 -157.122974)
			(xy 2.677099 -157.070883) (xy 2.664973 -157.016446) (xy 2.660902 -156.960824) (xy 1.64338 -156.960824)
			(xy 1.64338 -157.802518) (xy 11.825404 -157.802518) (xy 11.82797 -157.74682) (xy 11.838615 -157.692088)
			(xy 11.857114 -157.639489) (xy 11.883072 -157.590142) (xy 11.915937 -157.5451) (xy 11.955008 -157.505321)
			(xy 11.999453 -157.471653) (xy 12.048325 -157.444813) (xy 12.100584 -157.425372) (xy 12.155116 -157.413746)
			(xy 12.210759 -157.410181) (xy 12.266329 -157.414753) (xy 12.2936 -157.420564) (xy 12.315036 -157.424985)
			(xy 12.35873 -157.427422) (xy 12.402195 -157.422336) (xy 12.444146 -157.409877) (xy 12.483341 -157.390414)
			(xy 12.518621 -157.364522) (xy 12.548943 -157.332968) (xy 12.57341 -157.296685) (xy 12.591297 -157.256746)
			(xy 12.59713 -157.235652) (xy 12.60448 -157.208643) (xy 12.62601 -157.156976) (xy 12.654859 -157.109009)
			(xy 12.690407 -157.065772) (xy 12.731891 -157.028194) (xy 12.77842 -156.99708) (xy 12.828997 -156.973099)
			(xy 12.882535 -156.956766) (xy 12.937884 -156.94843) (xy 12.993858 -156.948272) (xy 13.049254 -156.956294)
			(xy 13.102883 -156.972324) (xy 13.153594 -156.996018) (xy 13.2003 -157.026867) (xy 13.241996 -157.06421)
			(xy 13.277788 -157.107245) (xy 13.306908 -157.155047) (xy 13.328731 -157.206592) (xy 13.342788 -157.260772)
			(xy 13.348778 -157.316424) (xy 13.346571 -157.372354) (xy 13.336216 -157.427362) (xy 13.317935 -157.480266)
			(xy 13.292119 -157.529931) (xy 13.259324 -157.575291) (xy 13.220253 -157.615373) (xy 13.175745 -157.649315)
			(xy 13.126754 -157.676389) (xy 13.074334 -157.696015) (xy 13.019609 -157.70777) (xy 12.963753 -157.711404)
			(xy 12.907966 -157.706836) (xy 12.880594 -157.70098) (xy 12.859164 -157.69652) (xy 12.815466 -157.694083)
			(xy 12.771997 -157.699171) (xy 12.730043 -157.711633) (xy 12.690845 -157.731101) (xy 12.655563 -157.756998)
			(xy 12.625241 -157.788559) (xy 12.600777 -157.824849) (xy 12.582894 -157.864795) (xy 12.577064 -157.885892)
			(xy 12.569156 -157.914884) (xy 12.545473 -157.970111) (xy 12.513407 -158.020931) (xy 12.494006 -158.04388)
			(xy 12.48006 -158.060343) (xy 12.457458 -158.097095) (xy 12.441396 -158.137139) (xy 12.432339 -158.179323)
			(xy 12.430547 -158.222431) (xy 12.436071 -158.265222) (xy 12.448752 -158.306461) (xy 12.468225 -158.344962)
			(xy 12.493928 -158.379616) (xy 12.525123 -158.409422) (xy 12.542774 -158.421832) (xy 12.565362 -158.437699)
			(xy 12.585151 -158.455729) (xy 15.164285 -158.455729) (xy 15.169485 -158.399798) (xy 15.182831 -158.345233)
			(xy 15.204035 -158.293216) (xy 15.232637 -158.244871) (xy 15.26802 -158.201243) (xy 15.309419 -158.163275)
			(xy 15.355938 -158.131789) (xy 15.406571 -158.107466) (xy 15.460224 -158.090831) (xy 15.487904 -158.086044)
			(xy 15.510696 -158.081984) (xy 15.554412 -158.066767) (xy 15.594646 -158.043877) (xy 15.630064 -158.014074)
			(xy 15.659494 -157.978344) (xy 15.681959 -157.937872) (xy 15.696716 -157.893998) (xy 15.700502 -157.87116)
			(xy 15.705206 -157.84257) (xy 15.722089 -157.787146) (xy 15.747149 -157.734909) (xy 15.779812 -157.687055)
			(xy 15.819328 -157.644684) (xy 15.841726 -157.626304) (xy 15.854612 -157.615454) (xy 15.874691 -157.588424)
			(xy 15.887003 -157.557084) (xy 15.890689 -157.523614) (xy 15.885493 -157.490345) (xy 15.871777 -157.459593)
			(xy 15.861538 -157.446218) (xy 15.844604 -157.424735) (xy 15.816409 -157.377859) (xy 15.795199 -157.327438)
			(xy 15.781406 -157.274504) (xy 15.775315 -157.220142) (xy 15.77705 -157.165469) (xy 15.786575 -157.111603)
			(xy 15.803695 -157.05965) (xy 15.82806 -157.010674) (xy 15.859169 -156.96568) (xy 15.896385 -156.92559)
			(xy 15.938946 -156.891226) (xy 15.985977 -156.863293) (xy 16.036516 -156.842363) (xy 16.089526 -156.828865)
			(xy 16.14392 -156.823076) (xy 16.198584 -156.825115) (xy 16.252396 -156.834939) (xy 16.304253 -156.852348)
			(xy 16.353092 -156.876985) (xy 16.397912 -156.908344) (xy 16.437795 -156.945782) (xy 16.471921 -156.988533)
			(xy 16.499593 -157.035719) (xy 16.520242 -157.086373) (xy 16.533445 -157.139458) (xy 16.538931 -157.193883)
			(xy 16.536589 -157.248534) (xy 16.526465 -157.302291) (xy 16.508768 -157.354051) (xy 16.48386 -157.402752)
			(xy 16.452253 -157.447397) (xy 16.414593 -157.487071) (xy 16.393414 -157.504384) (xy 16.38054 -157.515248)
			(xy 16.360455 -157.542272) (xy 16.348138 -157.57361) (xy 16.344449 -157.607079) (xy 16.349645 -157.640346)
			(xy 16.363362 -157.671097) (xy 16.373602 -157.68447) (xy 16.390234 -157.70542) (xy 16.417949 -157.751174)
			(xy 16.439 -157.800352) (xy 16.450257 -157.84195) (xy 27.408122 -157.84195) (xy 27.412193 -157.786328)
			(xy 27.424319 -157.731891) (xy 27.444242 -157.6798) (xy 27.471538 -157.631165) (xy 27.505624 -157.587022)
			(xy 27.545773 -157.548313) (xy 27.591131 -157.515862) (xy 27.640731 -157.490361) (xy 27.693515 -157.472354)
			(xy 27.748358 -157.462224) (xy 27.804092 -157.460187) (xy 27.859529 -157.466287) (xy 27.913486 -157.480393)
			(xy 27.964815 -157.502205) (xy 28.012421 -157.531259) (xy 28.055289 -157.566934) (xy 28.092506 -157.608471)
			(xy 28.123279 -157.654984) (xy 28.146951 -157.705481) (xy 28.163019 -157.758888) (xy 28.171139 -157.814064)
			(xy 28.171648 -157.84195) (xy 28.171139 -157.869836) (xy 28.163019 -157.925012) (xy 28.146951 -157.978419)
			(xy 28.123279 -158.028916) (xy 28.092506 -158.075429) (xy 28.055289 -158.116966) (xy 28.012421 -158.152641)
			(xy 27.964815 -158.181695) (xy 27.913486 -158.203507) (xy 27.859529 -158.217613) (xy 27.804092 -158.223713)
			(xy 27.748358 -158.221676) (xy 27.693515 -158.211546) (xy 27.640731 -158.193539) (xy 27.591131 -158.168038)
			(xy 27.545773 -158.135587) (xy 27.505624 -158.096878) (xy 27.471538 -158.052735) (xy 27.444242 -158.0041)
			(xy 27.424319 -157.952009) (xy 27.412193 -157.897572) (xy 27.408122 -157.84195) (xy 16.450257 -157.84195)
			(xy 16.452973 -157.851988) (xy 16.459596 -157.90507) (xy 16.458738 -157.958557) (xy 16.450415 -158.011399)
			(xy 16.434792 -158.06256) (xy 16.412174 -158.111037) (xy 16.383005 -158.155879) (xy 16.347858 -158.196205)
			(xy 16.307422 -158.231226) (xy 16.262489 -158.260254) (xy 16.213941 -158.282719) (xy 16.162731 -158.298182)
			(xy 16.136366 -158.302706) (xy 16.113578 -158.306785) (xy 16.069865 -158.322003) (xy 16.029634 -158.344891)
			(xy 15.994218 -158.374692) (xy 15.964788 -158.410417) (xy 15.94232 -158.450885) (xy 15.927558 -158.494754)
			(xy 15.923768 -158.51759) (xy 15.919257 -158.545316) (xy 15.903157 -158.599132) (xy 15.879339 -158.650005)
			(xy 15.848317 -158.696835) (xy 15.810764 -158.73861) (xy 15.76749 -158.774425) (xy 15.719432 -158.803508)
			(xy 15.667629 -158.825228) (xy 15.6132 -158.839117) (xy 15.557323 -158.844873) (xy 15.501206 -158.842373)
			(xy 15.446062 -158.831671) (xy 15.393084 -158.812997) (xy 15.343417 -158.786756) (xy 15.298136 -158.753516)
			(xy 15.258219 -158.713994) (xy 15.224529 -158.669045) (xy 15.197795 -158.619642) (xy 15.178595 -158.566853)
			(xy 15.167344 -158.511818) (xy 15.164285 -158.455729) (xy 12.585151 -158.455729) (xy 12.606164 -158.474875)
			(xy 12.641187 -158.517539) (xy 12.669699 -158.564804) (xy 12.691107 -158.615682) (xy 12.704963 -158.669113)
			(xy 12.710979 -158.723983) (xy 12.70903 -158.779147) (xy 12.704572 -158.806388) (xy 12.700905 -158.829189)
			(xy 12.701011 -158.875369) (xy 12.709453 -158.92077) (xy 12.725954 -158.9639) (xy 12.749972 -159.003342)
			(xy 12.780718 -159.037799) (xy 12.817179 -159.066137) (xy 12.858159 -159.087426) (xy 12.880086 -159.094678)
			(xy 12.906161 -159.10314) (xy 12.955748 -159.126512) (xy 13.001479 -159.156741) (xy 13.042414 -159.193203)
			(xy 13.077708 -159.235149) (xy 13.106635 -159.281715) (xy 13.128599 -159.331941) (xy 13.143149 -159.384794)
			(xy 13.149984 -159.439186) (xy 13.148964 -159.493995) (xy 13.140109 -159.548095) (xy 13.123603 -159.60037)
			(xy 13.099785 -159.649744) (xy 13.069145 -159.695201) (xy 13.032315 -159.735805) (xy 12.990052 -159.770719)
			(xy 12.943228 -159.799225) (xy 12.892805 -159.820735) (xy 12.839823 -159.834807) (xy 12.785372 -159.841152)
			(xy 12.730574 -159.839637) (xy 12.676557 -159.830295) (xy 12.624433 -159.813318) (xy 12.575275 -159.789056)
			(xy 12.530097 -159.758007) (xy 12.489827 -159.720812) (xy 12.455295 -159.678236) (xy 12.427213 -159.631156)
			(xy 12.406158 -159.580541) (xy 12.392564 -159.527435) (xy 12.386712 -159.472929) (xy 12.38872 -159.418146)
			(xy 12.393168 -159.391096) (xy 12.396719 -159.368279) (xy 12.396627 -159.322111) (xy 12.3882 -159.276718)
			(xy 12.371715 -159.233593) (xy 12.347713 -159.194154) (xy 12.316984 -159.159698) (xy 12.280538 -159.131356)
			(xy 12.239574 -159.110062) (xy 12.217654 -159.102806) (xy 12.191794 -159.094396) (xy 12.142568 -159.071296)
			(xy 12.097121 -159.041439) (xy 12.056375 -159.005431) (xy 12.021157 -158.964) (xy 11.99218 -158.917987)
			(xy 11.970031 -158.868326) (xy 11.95516 -158.816022) (xy 11.947869 -158.762136) (xy 11.948305 -158.707761)
			(xy 11.956458 -158.653999) (xy 11.972165 -158.60194) (xy 11.995107 -158.552639) (xy 12.024817 -158.507097)
			(xy 12.042394 -158.486348) (xy 12.056309 -158.46986) (xy 12.078913 -158.433113) (xy 12.094976 -158.393073)
			(xy 12.104035 -158.350893) (xy 12.105831 -158.307788) (xy 12.100311 -158.265001) (xy 12.087633 -158.223764)
			(xy 12.068165 -158.185264) (xy 12.042465 -158.150612) (xy 12.011275 -158.120806) (xy 11.993626 -158.108396)
			(xy 11.970867 -158.092284) (xy 11.929705 -158.054672) (xy 11.894456 -158.01147) (xy 11.865871 -157.963598)
			(xy 11.844559 -157.912074) (xy 11.830974 -157.857997) (xy 11.825404 -157.802518) (xy 1.64338 -157.802518)
			(xy 1.64338 -159.587438) (xy 3.313682 -159.587438) (xy 3.317753 -159.531816) (xy 3.329879 -159.477379)
			(xy 3.349802 -159.425288) (xy 3.377098 -159.376653) (xy 3.411184 -159.33251) (xy 3.451333 -159.293801)
			(xy 3.496691 -159.26135) (xy 3.546291 -159.235849) (xy 3.599075 -159.217842) (xy 3.653918 -159.207712)
			(xy 3.709652 -159.205675) (xy 3.765089 -159.211775) (xy 3.819046 -159.225881) (xy 3.870375 -159.247693)
			(xy 3.917981 -159.276747) (xy 3.960849 -159.312422) (xy 3.998066 -159.353959) (xy 4.028839 -159.400472)
			(xy 4.052511 -159.450969) (xy 4.068579 -159.504376) (xy 4.076699 -159.559552) (xy 4.077208 -159.587438)
			(xy 4.076699 -159.615324) (xy 4.068579 -159.6705) (xy 4.052511 -159.723907) (xy 4.028839 -159.774404)
			(xy 3.998066 -159.820917) (xy 3.960849 -159.862454) (xy 3.917981 -159.898129) (xy 3.870375 -159.927183)
			(xy 3.819046 -159.948995) (xy 3.765089 -159.963101) (xy 3.709652 -159.969201) (xy 3.653918 -159.967164)
			(xy 3.599075 -159.957034) (xy 3.546291 -159.939027) (xy 3.496691 -159.913526) (xy 3.451333 -159.881075)
			(xy 3.411184 -159.842366) (xy 3.377098 -159.798223) (xy 3.349802 -159.749588) (xy 3.329879 -159.697497)
			(xy 3.317753 -159.64306) (xy 3.313682 -159.587438) (xy 1.64338 -159.587438) (xy 1.64338 -160.393888)
			(xy 1.980182 -160.393888) (xy 1.984253 -160.338266) (xy 1.996379 -160.283829) (xy 2.016302 -160.231738)
			(xy 2.043598 -160.183103) (xy 2.077684 -160.13896) (xy 2.117833 -160.100251) (xy 2.163191 -160.0678)
			(xy 2.212791 -160.042299) (xy 2.265575 -160.024292) (xy 2.320418 -160.014162) (xy 2.376152 -160.012125)
			(xy 2.431589 -160.018225) (xy 2.484142 -160.031964) (xy 13.903107 -160.031964) (xy 13.908373 -159.976853)
			(xy 13.92155 -159.923082) (xy 13.942363 -159.871781) (xy 13.970373 -159.824028) (xy 14.004993 -159.780826)
			(xy 14.045494 -159.743083) (xy 14.091027 -159.711591) (xy 14.140634 -159.687013) (xy 14.193273 -159.669864)
			(xy 14.247839 -159.660506) (xy 14.303183 -159.659134) (xy 14.358145 -159.665778) (xy 14.411569 -159.680297)
			(xy 14.462333 -159.702388) (xy 14.50937 -159.731585) (xy 14.551692 -159.767276) (xy 14.588409 -159.80871)
			(xy 14.618751 -159.855017) (xy 14.64208 -159.905223) (xy 14.650466 -159.931608) (xy 14.65769 -159.9537)
			(xy 14.678849 -159.995075) (xy 14.707172 -160.031917) (xy 14.741718 -160.063) (xy 14.781337 -160.087288)
			(xy 14.824709 -160.103975) (xy 14.870391 -160.112503) (xy 14.916862 -160.11259) (xy 14.962575 -160.104232)
			(xy 14.984476 -160.096454) (xy 15.000986 -160.090612) (xy 15.022498 -160.082986) (xy 15.062586 -160.061177)
			(xy 15.09813 -160.032553) (xy 15.127986 -159.998037) (xy 15.151192 -159.958741) (xy 15.167 -159.915929)
			(xy 15.174902 -159.870982) (xy 15.174644 -159.825346) (xy 15.170912 -159.80283) (xy 15.166335 -159.775464)
			(xy 15.164174 -159.720023) (xy 15.170066 -159.664854) (xy 15.183886 -159.611121) (xy 15.205343 -159.559955)
			(xy 15.233986 -159.512437) (xy 15.269208 -159.469569) (xy 15.310269 -159.432255) (xy 15.356301 -159.401281)
			(xy 15.406334 -159.377302) (xy 15.459313 -159.360822) (xy 15.51412 -159.352189) (xy 15.569599 -159.351587)
			(xy 15.624581 -159.359026) (xy 15.677905 -159.37435) (xy 15.728448 -159.397237) (xy 15.775142 -159.427203)
			(xy 15.817004 -159.463616) (xy 15.85315 -159.505709) (xy 15.882818 -159.552593) (xy 15.905382 -159.60328)
			(xy 15.913354 -159.629856) (xy 15.919949 -159.651534) (xy 15.939706 -159.692305) (xy 15.966381 -159.728926)
			(xy 15.999127 -159.760236) (xy 16.036907 -159.785243) (xy 16.078523 -159.803152) (xy 16.122656 -159.813397)
			(xy 16.145256 -159.815022) (xy 16.173129 -159.81679) (xy 16.227917 -159.82764) (xy 16.280538 -159.846362)
			(xy 16.329867 -159.872555) (xy 16.37485 -159.905661) (xy 16.414526 -159.944971) (xy 16.448047 -159.989645)
			(xy 16.474696 -160.038729) (xy 16.493905 -160.091174) (xy 16.505262 -160.14586) (xy 16.508525 -160.201616)
			(xy 16.503624 -160.257253) (xy 16.490664 -160.311581) (xy 16.469922 -160.363438) (xy 16.441842 -160.411718)
			(xy 16.407022 -160.455388) (xy 16.366208 -160.493514) (xy 16.320271 -160.525283) (xy 16.270193 -160.550015)
			(xy 16.217045 -160.567182) (xy 16.161961 -160.576417) (xy 16.10612 -160.577522) (xy 16.050714 -160.570474)
			(xy 15.996928 -160.555424) (xy 15.945911 -160.532693) (xy 15.898753 -160.502767) (xy 15.856462 -160.466285)
			(xy 15.819942 -160.424027) (xy 15.789972 -160.376897) (xy 15.767195 -160.325901) (xy 15.759176 -160.299146)
			(xy 15.751545 -160.274292) (xy 15.727628 -160.228136) (xy 15.694846 -160.187791) (xy 15.675102 -160.170876)
			(xy 15.66182 -160.160784) (xy 15.631374 -160.147184) (xy 15.598444 -160.141937) (xy 15.56528 -160.1454)
			(xy 15.534144 -160.157336) (xy 15.507164 -160.176931) (xy 15.486181 -160.202847) (xy 15.472629 -160.233314)
			(xy 15.467432 -160.266251) (xy 15.470946 -160.299411) (xy 15.476474 -160.315148) (xy 15.486078 -160.341411)
			(xy 15.498484 -160.395934) (xy 15.502798 -160.451684) (xy 15.498927 -160.507466) (xy 15.486954 -160.562086)
			(xy 15.467135 -160.614372) (xy 15.439896 -160.663206) (xy 15.40582 -160.707539) (xy 15.365637 -160.746423)
			(xy 15.320207 -160.779024) (xy 15.270505 -160.804644) (xy 15.217596 -160.822734) (xy 15.162612 -160.832906)
			(xy 15.106733 -160.834942) (xy 15.051154 -160.828799) (xy 14.997069 -160.814607) (xy 14.945634 -160.792673)
			(xy 14.897952 -160.763464) (xy 14.855046 -160.727608) (xy 14.817833 -160.685871) (xy 14.787113 -160.63915)
			(xy 14.763541 -160.588444) (xy 14.755114 -160.561782) (xy 14.74792 -160.539679) (xy 14.726757 -160.498303)
			(xy 14.698429 -160.461461) (xy 14.663879 -160.430378) (xy 14.624257 -160.40609) (xy 14.580881 -160.389405)
			(xy 14.535196 -160.380879) (xy 14.488722 -160.380795) (xy 14.443006 -160.389156) (xy 14.421104 -160.396936)
			(xy 14.395073 -160.406362) (xy 14.341044 -160.41844) (xy 14.285837 -160.42258) (xy 14.230612 -160.418696)
			(xy 14.176528 -160.406869) (xy 14.124722 -160.387348) (xy 14.076282 -160.360542) (xy 14.032227 -160.327015)
			(xy 13.993481 -160.287471) (xy 13.96086 -160.242741) (xy 13.935047 -160.193765) (xy 13.916586 -160.141571)
			(xy 13.905864 -160.087257) (xy 13.903107 -160.031964) (xy 2.484142 -160.031964) (xy 2.485546 -160.032331)
			(xy 2.536875 -160.054143) (xy 2.584481 -160.083197) (xy 2.627349 -160.118872) (xy 2.664566 -160.160409)
			(xy 2.695339 -160.206922) (xy 2.719011 -160.257419) (xy 2.735079 -160.310826) (xy 2.743199 -160.366002)
			(xy 2.743708 -160.393888) (xy 2.743199 -160.421774) (xy 2.735079 -160.47695) (xy 2.719011 -160.530357)
			(xy 2.695339 -160.580854) (xy 2.664566 -160.627367) (xy 2.627349 -160.668904) (xy 2.584481 -160.704579)
			(xy 2.536875 -160.733633) (xy 2.485546 -160.755445) (xy 2.431589 -160.769551) (xy 2.376152 -160.775651)
			(xy 2.320418 -160.773614) (xy 2.265575 -160.763484) (xy 2.212791 -160.745477) (xy 2.163191 -160.719976)
			(xy 2.117833 -160.687525) (xy 2.077684 -160.648816) (xy 2.043598 -160.604673) (xy 2.016302 -160.556038)
			(xy 1.996379 -160.503947) (xy 1.984253 -160.44951) (xy 1.980182 -160.393888) (xy 1.64338 -160.393888)
			(xy 1.64338 -161.245804) (xy 3.12496 -161.245804) (xy 3.129031 -161.190182) (xy 3.141157 -161.135745)
			(xy 3.16108 -161.083654) (xy 3.188376 -161.035019) (xy 3.222462 -160.990876) (xy 3.262611 -160.952167)
			(xy 3.307969 -160.919716) (xy 3.357569 -160.894215) (xy 3.410353 -160.876208) (xy 3.465196 -160.866078)
			(xy 3.52093 -160.864041) (xy 3.576367 -160.870141) (xy 3.630324 -160.884247) (xy 3.681653 -160.906059)
			(xy 3.713108 -160.925256) (xy 11.528042 -160.925256) (xy 11.532113 -160.869634) (xy 11.544239 -160.815197)
			(xy 11.564162 -160.763106) (xy 11.591458 -160.714471) (xy 11.625544 -160.670328) (xy 11.665693 -160.631619)
			(xy 11.711051 -160.599168) (xy 11.760651 -160.573667) (xy 11.813435 -160.55566) (xy 11.868278 -160.54553)
			(xy 11.924012 -160.543493) (xy 11.979449 -160.549593) (xy 12.033406 -160.563699) (xy 12.084735 -160.585511)
			(xy 12.132341 -160.614565) (xy 12.175209 -160.65024) (xy 12.212426 -160.691777) (xy 12.243199 -160.73829)
			(xy 12.266871 -160.788787) (xy 12.282939 -160.842194) (xy 12.291059 -160.89737) (xy 12.291568 -160.925256)
			(xy 12.291059 -160.953142) (xy 12.282939 -161.008318) (xy 12.266871 -161.061725) (xy 12.243199 -161.112222)
			(xy 12.212426 -161.158735) (xy 12.175209 -161.200272) (xy 12.132341 -161.235947) (xy 12.084735 -161.265001)
			(xy 12.033406 -161.286813) (xy 11.979449 -161.300919) (xy 11.924012 -161.307019) (xy 11.868278 -161.304982)
			(xy 11.813435 -161.294852) (xy 11.760651 -161.276845) (xy 11.711051 -161.251344) (xy 11.665693 -161.218893)
			(xy 11.625544 -161.180184) (xy 11.591458 -161.136041) (xy 11.564162 -161.087406) (xy 11.544239 -161.035315)
			(xy 11.532113 -160.980878) (xy 11.528042 -160.925256) (xy 3.713108 -160.925256) (xy 3.729259 -160.935113)
			(xy 3.772127 -160.970788) (xy 3.809344 -161.012325) (xy 3.840117 -161.058838) (xy 3.863789 -161.109335)
			(xy 3.879857 -161.162742) (xy 3.887977 -161.217918) (xy 3.888486 -161.245804) (xy 3.887977 -161.27369)
			(xy 3.879857 -161.328866) (xy 3.863789 -161.382273) (xy 3.840117 -161.43277) (xy 3.809344 -161.479283)
			(xy 3.772127 -161.52082) (xy 3.729259 -161.556495) (xy 3.681653 -161.585549) (xy 3.630324 -161.607361)
			(xy 3.576367 -161.621467) (xy 3.52093 -161.627567) (xy 3.465196 -161.62553) (xy 3.410353 -161.6154)
			(xy 3.357569 -161.597393) (xy 3.307969 -161.571892) (xy 3.262611 -161.539441) (xy 3.222462 -161.500732)
			(xy 3.188376 -161.456589) (xy 3.16108 -161.407954) (xy 3.141157 -161.355863) (xy 3.129031 -161.301426)
			(xy 3.12496 -161.245804) (xy 1.64338 -161.245804) (xy 1.64338 -161.77133) (xy 12.361162 -161.77133)
			(xy 12.365233 -161.715708) (xy 12.377359 -161.661271) (xy 12.397282 -161.60918) (xy 12.424578 -161.560545)
			(xy 12.458664 -161.516402) (xy 12.498813 -161.477693) (xy 12.544171 -161.445242) (xy 12.593771 -161.419741)
			(xy 12.646555 -161.401734) (xy 12.701398 -161.391604) (xy 12.757132 -161.389567) (xy 12.812569 -161.395667)
			(xy 12.866526 -161.409773) (xy 12.917855 -161.431585) (xy 12.965461 -161.460639) (xy 13.008329 -161.496314)
			(xy 13.045546 -161.537851) (xy 13.076319 -161.584364) (xy 13.099991 -161.634861) (xy 13.116059 -161.688268)
			(xy 13.124179 -161.743444) (xy 13.124688 -161.77133) (xy 13.124179 -161.799216) (xy 13.116059 -161.854392)
			(xy 13.099991 -161.907799) (xy 13.076319 -161.958296) (xy 13.045546 -162.004809) (xy 13.008329 -162.046346)
			(xy 12.965461 -162.082021) (xy 12.917855 -162.111075) (xy 12.866526 -162.132887) (xy 12.812569 -162.146993)
			(xy 12.757132 -162.153093) (xy 12.701398 -162.151056) (xy 12.646555 -162.140926) (xy 12.593771 -162.122919)
			(xy 12.544171 -162.097418) (xy 12.498813 -162.064967) (xy 12.458664 -162.026258) (xy 12.424578 -161.982115)
			(xy 12.397282 -161.93348) (xy 12.377359 -161.881389) (xy 12.365233 -161.826952) (xy 12.361162 -161.77133)
			(xy 1.64338 -161.77133) (xy 1.64338 -162.229546) (xy 1.964942 -162.229546) (xy 1.969013 -162.173924)
			(xy 1.981139 -162.119487) (xy 2.001062 -162.067396) (xy 2.028358 -162.018761) (xy 2.062444 -161.974618)
			(xy 2.102593 -161.935909) (xy 2.147951 -161.903458) (xy 2.197551 -161.877957) (xy 2.250335 -161.85995)
			(xy 2.305178 -161.84982) (xy 2.360912 -161.847783) (xy 2.416349 -161.853883) (xy 2.470306 -161.867989)
			(xy 2.521635 -161.889801) (xy 2.569241 -161.918855) (xy 2.612109 -161.95453) (xy 2.649326 -161.996067)
			(xy 2.680099 -162.04258) (xy 2.703771 -162.093077) (xy 2.719839 -162.146484) (xy 2.727959 -162.20166)
			(xy 2.728468 -162.229546) (xy 2.727959 -162.257432) (xy 2.719839 -162.312608) (xy 2.703771 -162.366015)
			(xy 2.680099 -162.416512) (xy 2.649326 -162.463025) (xy 2.612109 -162.504562) (xy 2.569241 -162.540237)
			(xy 2.521635 -162.569291) (xy 2.470306 -162.591103) (xy 2.416349 -162.605209) (xy 2.360912 -162.611309)
			(xy 2.305178 -162.609272) (xy 2.250335 -162.599142) (xy 2.197551 -162.581135) (xy 2.147951 -162.555634)
			(xy 2.102593 -162.523183) (xy 2.062444 -162.484474) (xy 2.028358 -162.440331) (xy 2.001062 -162.391696)
			(xy 1.981139 -162.339605) (xy 1.969013 -162.285168) (xy 1.964942 -162.229546) (xy 1.64338 -162.229546)
			(xy 1.64338 -163.557712) (xy 12.581634 -163.557712) (xy 12.585705 -163.50209) (xy 12.597831 -163.447653)
			(xy 12.617754 -163.395562) (xy 12.64505 -163.346927) (xy 12.679136 -163.302784) (xy 12.719285 -163.264075)
			(xy 12.764643 -163.231624) (xy 12.814243 -163.206123) (xy 12.867027 -163.188116) (xy 12.92187 -163.177986)
			(xy 12.977604 -163.175949) (xy 13.033041 -163.182049) (xy 13.086998 -163.196155) (xy 13.138327 -163.217967)
			(xy 13.185933 -163.247021) (xy 13.228801 -163.282696) (xy 13.251148 -163.307637) (xy 14.703189 -163.307637)
			(xy 14.705729 -163.253107) (xy 14.716016 -163.199495) (xy 14.73384 -163.147897) (xy 14.758837 -163.099367)
			(xy 14.790496 -163.054895) (xy 14.828171 -163.01539) (xy 14.871093 -162.981659) (xy 14.918384 -162.954391)
			(xy 14.96908 -162.934142) (xy 15.022144 -162.921327) (xy 15.076493 -162.916206) (xy 15.131017 -162.918884)
			(xy 15.184603 -162.929308) (xy 15.236155 -162.947263) (xy 15.284622 -162.972383) (xy 15.329013 -163.004155)
			(xy 15.368422 -163.04193) (xy 15.402043 -163.084938) (xy 15.416022 -163.108386) (xy 15.428153 -163.128474)
			(xy 15.45856 -163.164209) (xy 15.495006 -163.19376) (xy 15.536255 -163.216123) (xy 15.580906 -163.23054)
			(xy 15.627444 -163.236521) (xy 15.67429 -163.233863) (xy 15.6972 -163.228782) (xy 15.724254 -163.222632)
			(xy 15.779471 -163.217267) (xy 15.834884 -163.219958) (xy 15.889322 -163.230648) (xy 15.941637 -163.249112)
			(xy 15.990726 -163.27496) (xy 16.035552 -163.307646) (xy 16.07517 -163.346481) (xy 16.108745 -163.390647)
			(xy 16.135567 -163.43921) (xy 16.15507 -163.491146) (xy 16.166845 -163.54536) (xy 16.170641 -163.600708)
			(xy 16.166379 -163.656022) (xy 16.16075 -163.683188) (xy 16.156276 -163.705051) (xy 16.154169 -163.749622)
			(xy 16.159882 -163.793877) (xy 16.173238 -163.836453) (xy 16.193827 -163.876041) (xy 16.221014 -163.911423)
			(xy 16.253965 -163.941512) (xy 16.291666 -163.965382) (xy 16.312134 -163.974272) (xy 16.337832 -163.985344)
			(xy 16.385923 -164.01395) (xy 16.42932 -164.049274) (xy 16.467091 -164.090559) (xy 16.498427 -164.136918)
			(xy 16.522654 -164.187357) (xy 16.539253 -164.240794) (xy 16.547868 -164.296083) (xy 16.548315 -164.352037)
			(xy 16.540583 -164.407456) (xy 16.524838 -164.461152) (xy 16.51587 -164.480613) (xy 23.82729 -164.480613)
			(xy 23.828425 -164.424404) (xy 23.837796 -164.368971) (xy 23.855202 -164.315512) (xy 23.880263 -164.265187)
			(xy 23.912439 -164.219084) (xy 23.931372 -164.1983) (xy 23.947309 -164.180753) (xy 23.972925 -164.14087)
			(xy 23.990705 -164.096932) (xy 24.000034 -164.050459) (xy 24.000587 -164.003062) (xy 23.992347 -163.956384)
			(xy 23.975597 -163.912042) (xy 23.95092 -163.871572) (xy 23.935436 -163.853622) (xy 23.917329 -163.832794)
			(xy 23.886687 -163.786892) (xy 23.862979 -163.737054) (xy 23.8467 -163.684321) (xy 23.838189 -163.629792)
			(xy 23.837624 -163.574605) (xy 23.845018 -163.519913) (xy 23.860214 -163.466857) (xy 23.882898 -163.416545)
			(xy 23.912594 -163.370026) (xy 23.948683 -163.328272) (xy 23.990412 -163.292153) (xy 24.03691 -163.262425)
			(xy 24.087207 -163.239707) (xy 24.140252 -163.224473) (xy 24.194938 -163.217041) (xy 24.250125 -163.217567)
			(xy 24.30466 -163.22604) (xy 24.357405 -163.242282) (xy 24.40726 -163.265955) (xy 24.453182 -163.296565)
			(xy 24.494215 -163.333472) (xy 24.529502 -163.375907) (xy 24.558306 -163.422983) (xy 24.580026 -163.473719)
			(xy 24.594209 -163.527055) (xy 24.597868 -163.55441) (xy 24.600858 -163.576018) (xy 24.613188 -163.617856)
			(xy 24.632485 -163.656972) (xy 24.658181 -163.692216) (xy 24.689521 -163.722552) (xy 24.725583 -163.747087)
			(xy 24.733105 -163.750498) (xy 27.370022 -163.750498) (xy 27.374093 -163.694876) (xy 27.386219 -163.640439)
			(xy 27.406142 -163.588348) (xy 27.433438 -163.539713) (xy 27.467524 -163.49557) (xy 27.507673 -163.456861)
			(xy 27.553031 -163.42441) (xy 27.602631 -163.398909) (xy 27.655415 -163.380902) (xy 27.710258 -163.370772)
			(xy 27.765992 -163.368735) (xy 27.821429 -163.374835) (xy 27.875386 -163.388941) (xy 27.926715 -163.410753)
			(xy 27.974321 -163.439807) (xy 28.017189 -163.475482) (xy 28.054406 -163.517019) (xy 28.085179 -163.563532)
			(xy 28.108851 -163.614029) (xy 28.124919 -163.667436) (xy 28.133039 -163.722612) (xy 28.133548 -163.750498)
			(xy 28.133039 -163.778384) (xy 28.124919 -163.83356) (xy 28.108851 -163.886967) (xy 28.085179 -163.937464)
			(xy 28.054406 -163.983977) (xy 28.017189 -164.025514) (xy 27.974321 -164.061189) (xy 27.926715 -164.090243)
			(xy 27.875386 -164.112055) (xy 27.821429 -164.126161) (xy 27.765992 -164.132261) (xy 27.710258 -164.130224)
			(xy 27.655415 -164.120094) (xy 27.602631 -164.102087) (xy 27.553031 -164.076586) (xy 27.507673 -164.044135)
			(xy 27.467524 -164.005426) (xy 27.433438 -163.961283) (xy 27.406142 -163.912648) (xy 27.386219 -163.860557)
			(xy 27.374093 -163.80612) (xy 27.370022 -163.750498) (xy 24.733105 -163.750498) (xy 24.765306 -163.7651)
			(xy 24.807524 -163.776061) (xy 24.850993 -163.779649) (xy 24.894436 -163.775756) (xy 24.915622 -163.770564)
			(xy 24.942226 -163.763949) (xy 24.99667 -163.757538) (xy 25.051472 -163.758987) (xy 25.105501 -163.768266)
			(xy 25.157645 -163.785185) (xy 25.206831 -163.809394) (xy 25.252044 -163.840394) (xy 25.292354 -163.877548)
			(xy 25.326929 -163.92009) (xy 25.355059 -163.967143) (xy 25.376162 -164.017739) (xy 25.389806 -164.070835)
			(xy 25.395707 -164.125336) (xy 25.393746 -164.180122) (xy 25.383962 -164.234062) (xy 25.366558 -164.286046)
			(xy 25.34189 -164.335003) (xy 25.310468 -164.379925) (xy 25.29205 -164.40023) (xy 25.281898 -164.411805)
			(xy 25.266904 -164.438683) (xy 25.258776 -164.468369) (xy 25.257987 -164.499136) (xy 25.264584 -164.529199)
			(xy 25.278182 -164.55681) (xy 25.287732 -164.568886) (xy 25.305064 -164.590076) (xy 25.334027 -164.63653)
			(xy 25.356053 -164.686648) (xy 25.37069 -164.739399) (xy 25.377636 -164.7937) (xy 25.376835 -164.843206)
			(xy 27.370022 -164.843206) (xy 27.374093 -164.787584) (xy 27.386219 -164.733147) (xy 27.406142 -164.681056)
			(xy 27.433438 -164.632421) (xy 27.467524 -164.588278) (xy 27.507673 -164.549569) (xy 27.553031 -164.517118)
			(xy 27.602631 -164.491617) (xy 27.655415 -164.47361) (xy 27.710258 -164.46348) (xy 27.765992 -164.461443)
			(xy 27.821429 -164.467543) (xy 27.875386 -164.481649) (xy 27.926715 -164.503461) (xy 27.974321 -164.532515)
			(xy 28.017189 -164.56819) (xy 28.054406 -164.609727) (xy 28.085179 -164.65624) (xy 28.108851 -164.706737)
			(xy 28.124919 -164.760144) (xy 28.133039 -164.81532) (xy 28.133548 -164.843206) (xy 28.133039 -164.871092)
			(xy 28.124919 -164.926268) (xy 28.108851 -164.979675) (xy 28.085179 -165.030172) (xy 28.054406 -165.076685)
			(xy 28.017189 -165.118222) (xy 27.974321 -165.153897) (xy 27.926715 -165.182951) (xy 27.875386 -165.204763)
			(xy 27.821429 -165.218869) (xy 27.765992 -165.224969) (xy 27.710258 -165.222932) (xy 27.655415 -165.212802)
			(xy 27.602631 -165.194795) (xy 27.553031 -165.169294) (xy 27.507673 -165.136843) (xy 27.467524 -165.098134)
			(xy 27.433438 -165.053991) (xy 27.406142 -165.005356) (xy 27.386219 -164.953265) (xy 27.374093 -164.898828)
			(xy 27.370022 -164.843206) (xy 25.376835 -164.843206) (xy 25.37675 -164.848437) (xy 25.368049 -164.902485)
			(xy 25.351713 -164.954735) (xy 25.328076 -165.004113) (xy 25.297624 -165.049605) (xy 25.260982 -165.090278)
			(xy 25.218904 -165.125297) (xy 25.172252 -165.153941) (xy 25.121985 -165.175623) (xy 25.069134 -165.189898)
			(xy 25.014787 -165.196472) (xy 24.960057 -165.195211) (xy 24.90607 -165.18614) (xy 24.853934 -165.169446)
			(xy 24.804719 -165.145472) (xy 24.759436 -165.114709) (xy 24.719015 -165.07779) (xy 24.684285 -165.035472)
			(xy 24.655961 -164.988625) (xy 24.644858 -164.963602) (xy 24.635089 -164.941966) (xy 24.608773 -164.902463)
			(xy 24.575584 -164.86853) (xy 24.536674 -164.841345) (xy 24.493396 -164.821852) (xy 24.447252 -164.810728)
			(xy 24.399846 -164.808361) (xy 24.352823 -164.814831) (xy 24.330152 -164.82187) (xy 24.303354 -164.83037)
			(xy 24.248006 -164.840239) (xy 24.19181 -164.841878) (xy 24.135981 -164.835252) (xy 24.081729 -164.820505)
			(xy 24.030229 -164.797956) (xy 23.982596 -164.768093) (xy 23.93986 -164.731563) (xy 23.902949 -164.689157)
			(xy 23.87266 -164.641793) (xy 23.84965 -164.590498) (xy 23.834417 -164.53638) (xy 23.82729 -164.480613)
			(xy 16.51587 -164.480613) (xy 16.501419 -164.511971) (xy 16.470827 -164.558824) (xy 16.43372 -164.600706)
			(xy 16.390892 -164.636718) (xy 16.343264 -164.666088) (xy 16.291856 -164.688185) (xy 16.237771 -164.702536)
			(xy 16.182171 -164.708832) (xy 16.126247 -164.706939) (xy 16.071199 -164.696897) (xy 16.018209 -164.678921)
			(xy 15.968413 -164.653398) (xy 15.92288 -164.620874) (xy 15.882586 -164.582048) (xy 15.848396 -164.537752)
			(xy 15.821043 -164.488937) (xy 15.801115 -164.43665) (xy 15.789038 -164.382013) (xy 15.785072 -164.326198)
			(xy 15.789301 -164.270402) (xy 15.79499 -164.243004) (xy 15.799449 -164.221139) (xy 15.801553 -164.176569)
			(xy 15.79584 -164.132317) (xy 15.782485 -164.089744) (xy 15.761899 -164.050157) (xy 15.734715 -164.014775)
			(xy 15.701768 -163.984685) (xy 15.664072 -163.960813) (xy 15.643606 -163.95192) (xy 15.620452 -163.941975)
			(xy 15.576765 -163.916858) (xy 15.536769 -163.886204) (xy 15.50116 -163.850548) (xy 15.470559 -163.81051)
			(xy 15.457678 -163.788852) (xy 15.445534 -163.768772) (xy 15.415132 -163.733034) (xy 15.378689 -163.703481)
			(xy 15.337442 -163.681115) (xy 15.292792 -163.666697) (xy 15.246254 -163.660716) (xy 15.19941 -163.663375)
			(xy 15.1765 -163.668456) (xy 15.14989 -163.674549) (xy 15.095567 -163.679946) (xy 15.041031 -163.677544)
			(xy 14.987393 -163.667394) (xy 14.93575 -163.649701) (xy 14.887156 -163.624827) (xy 14.842604 -163.593281)
			(xy 14.803004 -163.555706) (xy 14.769164 -163.51287) (xy 14.741776 -163.465648) (xy 14.721398 -163.415004)
			(xy 14.708448 -163.361973) (xy 14.703189 -163.307637) (xy 13.251148 -163.307637) (xy 13.266018 -163.324233)
			(xy 13.296791 -163.370746) (xy 13.320463 -163.421243) (xy 13.336531 -163.47465) (xy 13.344651 -163.529826)
			(xy 13.34516 -163.557712) (xy 13.344651 -163.585598) (xy 13.336531 -163.640774) (xy 13.320463 -163.694181)
			(xy 13.296791 -163.744678) (xy 13.266018 -163.791191) (xy 13.228801 -163.832728) (xy 13.185933 -163.868403)
			(xy 13.138327 -163.897457) (xy 13.086998 -163.919269) (xy 13.033041 -163.933375) (xy 12.977604 -163.939475)
			(xy 12.92187 -163.937438) (xy 12.867027 -163.927308) (xy 12.814243 -163.909301) (xy 12.764643 -163.8838)
			(xy 12.719285 -163.851349) (xy 12.679136 -163.81264) (xy 12.64505 -163.768497) (xy 12.617754 -163.719862)
			(xy 12.597831 -163.667771) (xy 12.585705 -163.613334) (xy 12.581634 -163.557712) (xy 1.64338 -163.557712)
			(xy 1.64338 -165.564312) (xy 9.249662 -165.564312) (xy 9.253733 -165.50869) (xy 9.265859 -165.454253)
			(xy 9.285782 -165.402162) (xy 9.313078 -165.353527) (xy 9.347164 -165.309384) (xy 9.387313 -165.270675)
			(xy 9.432671 -165.238224) (xy 9.482271 -165.212723) (xy 9.535055 -165.194716) (xy 9.589898 -165.184586)
			(xy 9.645632 -165.182549) (xy 9.701069 -165.188649) (xy 9.755026 -165.202755) (xy 9.806355 -165.224567)
			(xy 9.853961 -165.253621) (xy 9.896829 -165.289296) (xy 9.934046 -165.330833) (xy 9.954247 -165.361366)
			(xy 10.956542 -165.361366) (xy 10.960613 -165.305744) (xy 10.972739 -165.251307) (xy 10.992662 -165.199216)
			(xy 11.019958 -165.150581) (xy 11.054044 -165.106438) (xy 11.094193 -165.067729) (xy 11.139551 -165.035278)
			(xy 11.189151 -165.009777) (xy 11.241935 -164.99177) (xy 11.296778 -164.98164) (xy 11.352512 -164.979603)
			(xy 11.407949 -164.985703) (xy 11.461906 -164.999809) (xy 11.513235 -165.021621) (xy 11.560841 -165.050675)
			(xy 11.603709 -165.08635) (xy 11.640926 -165.127887) (xy 11.671699 -165.1744) (xy 11.695371 -165.224897)
			(xy 11.711439 -165.278304) (xy 11.719559 -165.33348) (xy 11.720068 -165.361366) (xy 11.719559 -165.389252)
			(xy 11.711439 -165.444428) (xy 11.695371 -165.497835) (xy 11.671699 -165.548332) (xy 11.640926 -165.594845)
			(xy 11.622539 -165.615366) (xy 13.270736 -165.615366) (xy 13.274807 -165.559744) (xy 13.286933 -165.505307)
			(xy 13.306856 -165.453216) (xy 13.334152 -165.404581) (xy 13.368238 -165.360438) (xy 13.408387 -165.321729)
			(xy 13.453745 -165.289278) (xy 13.503345 -165.263777) (xy 13.556129 -165.24577) (xy 13.610972 -165.23564)
			(xy 13.666706 -165.233603) (xy 13.722143 -165.239703) (xy 13.7761 -165.253809) (xy 13.827429 -165.275621)
			(xy 13.875035 -165.304675) (xy 13.917903 -165.34035) (xy 13.95512 -165.381887) (xy 13.985893 -165.4284)
			(xy 14.009565 -165.478897) (xy 14.025633 -165.532304) (xy 14.033753 -165.58748) (xy 14.034262 -165.615366)
			(xy 14.033753 -165.643252) (xy 14.025633 -165.698428) (xy 14.009565 -165.751835) (xy 13.985893 -165.802332)
			(xy 13.95512 -165.848845) (xy 13.917903 -165.890382) (xy 13.875035 -165.926057) (xy 13.827429 -165.955111)
			(xy 13.7761 -165.976923) (xy 13.722143 -165.991029) (xy 13.666706 -165.997129) (xy 13.610972 -165.995092)
			(xy 13.556129 -165.984962) (xy 13.503345 -165.966955) (xy 13.453745 -165.941454) (xy 13.408387 -165.909003)
			(xy 13.368238 -165.870294) (xy 13.334152 -165.826151) (xy 13.306856 -165.777516) (xy 13.286933 -165.725425)
			(xy 13.274807 -165.670988) (xy 13.270736 -165.615366) (xy 11.622539 -165.615366) (xy 11.603709 -165.636382)
			(xy 11.560841 -165.672057) (xy 11.513235 -165.701111) (xy 11.461906 -165.722923) (xy 11.407949 -165.737029)
			(xy 11.352512 -165.743129) (xy 11.296778 -165.741092) (xy 11.241935 -165.730962) (xy 11.189151 -165.712955)
			(xy 11.139551 -165.687454) (xy 11.094193 -165.655003) (xy 11.054044 -165.616294) (xy 11.019958 -165.572151)
			(xy 10.992662 -165.523516) (xy 10.972739 -165.471425) (xy 10.960613 -165.416988) (xy 10.956542 -165.361366)
			(xy 9.954247 -165.361366) (xy 9.964819 -165.377346) (xy 9.988491 -165.427843) (xy 10.004559 -165.48125)
			(xy 10.012679 -165.536426) (xy 10.013188 -165.564312) (xy 10.012679 -165.592198) (xy 10.004559 -165.647374)
			(xy 9.988491 -165.700781) (xy 9.964819 -165.751278) (xy 9.934046 -165.797791) (xy 9.896829 -165.839328)
			(xy 9.853961 -165.875003) (xy 9.806355 -165.904057) (xy 9.755026 -165.925869) (xy 9.701069 -165.939975)
			(xy 9.645632 -165.946075) (xy 9.589898 -165.944038) (xy 9.535055 -165.933908) (xy 9.482271 -165.915901)
			(xy 9.432671 -165.8904) (xy 9.387313 -165.857949) (xy 9.347164 -165.81924) (xy 9.313078 -165.775097)
			(xy 9.285782 -165.726462) (xy 9.265859 -165.674371) (xy 9.253733 -165.619934) (xy 9.249662 -165.564312)
			(xy 1.64338 -165.564312) (xy 1.64338 -166.017194) (xy 15.264382 -166.017194) (xy 15.268453 -165.961572)
			(xy 15.280579 -165.907135) (xy 15.300502 -165.855044) (xy 15.327798 -165.806409) (xy 15.361884 -165.762266)
			(xy 15.402033 -165.723557) (xy 15.447391 -165.691106) (xy 15.496991 -165.665605) (xy 15.549775 -165.647598)
			(xy 15.604618 -165.637468) (xy 15.660352 -165.635431) (xy 15.715789 -165.641531) (xy 15.769746 -165.655637)
			(xy 15.821075 -165.677449) (xy 15.868681 -165.706503) (xy 15.911549 -165.742178) (xy 15.948766 -165.783715)
			(xy 15.979539 -165.830228) (xy 16.003211 -165.880725) (xy 16.019279 -165.934132) (xy 16.027399 -165.989308)
			(xy 16.027908 -166.017194) (xy 16.027399 -166.04508) (xy 16.019279 -166.100256) (xy 16.003211 -166.153663)
			(xy 15.979539 -166.20416) (xy 15.948766 -166.250673) (xy 15.911549 -166.29221) (xy 15.868681 -166.327885)
			(xy 15.821075 -166.356939) (xy 15.769746 -166.378751) (xy 15.715789 -166.392857) (xy 15.660352 -166.398957)
			(xy 15.604618 -166.39692) (xy 15.549775 -166.38679) (xy 15.496991 -166.368783) (xy 15.447391 -166.343282)
			(xy 15.402033 -166.310831) (xy 15.361884 -166.272122) (xy 15.327798 -166.227979) (xy 15.300502 -166.179344)
			(xy 15.280579 -166.127253) (xy 15.268453 -166.072816) (xy 15.264382 -166.017194) (xy 1.64338 -166.017194)
			(xy 1.64338 -166.5605) (xy 5.756654 -166.5605) (xy 5.760725 -166.504878) (xy 5.772851 -166.450441)
			(xy 5.792774 -166.39835) (xy 5.82007 -166.349715) (xy 5.854156 -166.305572) (xy 5.894305 -166.266863)
			(xy 5.939663 -166.234412) (xy 5.989263 -166.208911) (xy 6.042047 -166.190904) (xy 6.09689 -166.180774)
			(xy 6.152624 -166.178737) (xy 6.208061 -166.184837) (xy 6.262018 -166.198943) (xy 6.313347 -166.220755)
			(xy 6.360953 -166.249809) (xy 6.403821 -166.285484) (xy 6.441038 -166.327021) (xy 6.471811 -166.373534)
			(xy 6.495483 -166.424031) (xy 6.511551 -166.477438) (xy 6.519671 -166.532614) (xy 6.52018 -166.5605)
			(xy 6.519671 -166.588386) (xy 6.511551 -166.643562) (xy 6.495483 -166.696969) (xy 6.482538 -166.724584)
			(xy 10.026902 -166.724584) (xy 10.030973 -166.668962) (xy 10.043099 -166.614525) (xy 10.063022 -166.562434)
			(xy 10.090318 -166.513799) (xy 10.124404 -166.469656) (xy 10.164553 -166.430947) (xy 10.209911 -166.398496)
			(xy 10.259511 -166.372995) (xy 10.312295 -166.354988) (xy 10.367138 -166.344858) (xy 10.422872 -166.342821)
			(xy 10.478309 -166.348921) (xy 10.532266 -166.363027) (xy 10.583595 -166.384839) (xy 10.631201 -166.413893)
			(xy 10.674069 -166.449568) (xy 10.711286 -166.491105) (xy 10.742059 -166.537618) (xy 10.765731 -166.588115)
			(xy 10.781799 -166.641522) (xy 10.789919 -166.696698) (xy 10.790428 -166.724584) (xy 10.789919 -166.75247)
			(xy 10.781799 -166.807646) (xy 10.765731 -166.861053) (xy 10.742059 -166.91155) (xy 10.711286 -166.958063)
			(xy 10.674069 -166.9996) (xy 10.631201 -167.035275) (xy 10.583595 -167.064329) (xy 10.532266 -167.086141)
			(xy 10.478309 -167.100247) (xy 10.422872 -167.106347) (xy 10.367138 -167.10431) (xy 10.312295 -167.09418)
			(xy 10.259511 -167.076173) (xy 10.209911 -167.050672) (xy 10.164553 -167.018221) (xy 10.124404 -166.979512)
			(xy 10.090318 -166.935369) (xy 10.063022 -166.886734) (xy 10.043099 -166.834643) (xy 10.030973 -166.780206)
			(xy 10.026902 -166.724584) (xy 6.482538 -166.724584) (xy 6.471811 -166.747466) (xy 6.441038 -166.793979)
			(xy 6.403821 -166.835516) (xy 6.360953 -166.871191) (xy 6.313347 -166.900245) (xy 6.262018 -166.922057)
			(xy 6.208061 -166.936163) (xy 6.152624 -166.942263) (xy 6.09689 -166.940226) (xy 6.042047 -166.930096)
			(xy 5.989263 -166.912089) (xy 5.939663 -166.886588) (xy 5.894305 -166.854137) (xy 5.854156 -166.815428)
			(xy 5.82007 -166.771285) (xy 5.792774 -166.72265) (xy 5.772851 -166.670559) (xy 5.760725 -166.616122)
			(xy 5.756654 -166.5605) (xy 1.64338 -166.5605) (xy 1.64338 -167.373554) (xy 3.954016 -167.373554)
			(xy 3.958087 -167.317932) (xy 3.970213 -167.263495) (xy 3.990136 -167.211404) (xy 4.017432 -167.162769)
			(xy 4.051518 -167.118626) (xy 4.091667 -167.079917) (xy 4.137025 -167.047466) (xy 4.186625 -167.021965)
			(xy 4.239409 -167.003958) (xy 4.294252 -166.993828) (xy 4.349986 -166.991791) (xy 4.405423 -166.997891)
			(xy 4.45938 -167.011997) (xy 4.510709 -167.033809) (xy 4.558315 -167.062863) (xy 4.601183 -167.098538)
			(xy 4.6384 -167.140075) (xy 4.669173 -167.186588) (xy 4.692845 -167.237085) (xy 4.708913 -167.290492)
			(xy 4.717033 -167.345668) (xy 4.717542 -167.373554) (xy 7.228838 -167.373554) (xy 7.232909 -167.317932)
			(xy 7.245035 -167.263495) (xy 7.264958 -167.211404) (xy 7.292254 -167.162769) (xy 7.32634 -167.118626)
			(xy 7.366489 -167.079917) (xy 7.411847 -167.047466) (xy 7.461447 -167.021965) (xy 7.514231 -167.003958)
			(xy 7.569074 -166.993828) (xy 7.624808 -166.991791) (xy 7.680245 -166.997891) (xy 7.734202 -167.011997)
			(xy 7.785531 -167.033809) (xy 7.833137 -167.062863) (xy 7.876005 -167.098538) (xy 7.913222 -167.140075)
			(xy 7.943995 -167.186588) (xy 7.967667 -167.237085) (xy 7.983735 -167.290492) (xy 7.991855 -167.345668)
			(xy 7.992364 -167.373554) (xy 7.991855 -167.40144) (xy 7.983735 -167.456616) (xy 7.967667 -167.510023)
			(xy 7.943995 -167.56052) (xy 7.913222 -167.607033) (xy 7.876005 -167.64857) (xy 7.852119 -167.668448)
			(xy 37.245542 -167.668448) (xy 37.249613 -167.612826) (xy 37.261739 -167.558389) (xy 37.281662 -167.506298)
			(xy 37.308958 -167.457663) (xy 37.343044 -167.41352) (xy 37.383193 -167.374811) (xy 37.428551 -167.34236)
			(xy 37.478151 -167.316859) (xy 37.530935 -167.298852) (xy 37.585778 -167.288722) (xy 37.641512 -167.286685)
			(xy 37.696949 -167.292785) (xy 37.750906 -167.306891) (xy 37.802235 -167.328703) (xy 37.849841 -167.357757)
			(xy 37.892709 -167.393432) (xy 37.929926 -167.434969) (xy 37.960699 -167.481482) (xy 37.984371 -167.531979)
			(xy 38.000439 -167.585386) (xy 38.008559 -167.640562) (xy 38.009068 -167.668448) (xy 38.008559 -167.696334)
			(xy 38.000439 -167.75151) (xy 37.984371 -167.804917) (xy 37.960699 -167.855414) (xy 37.929926 -167.901927)
			(xy 37.892709 -167.943464) (xy 37.849841 -167.979139) (xy 37.802235 -168.008193) (xy 37.750906 -168.030005)
			(xy 37.696949 -168.044111) (xy 37.641512 -168.050211) (xy 37.585778 -168.048174) (xy 37.530935 -168.038044)
			(xy 37.478151 -168.020037) (xy 37.428551 -167.994536) (xy 37.383193 -167.962085) (xy 37.343044 -167.923376)
			(xy 37.308958 -167.879233) (xy 37.281662 -167.830598) (xy 37.261739 -167.778507) (xy 37.249613 -167.72407)
			(xy 37.245542 -167.668448) (xy 7.852119 -167.668448) (xy 7.833137 -167.684245) (xy 7.785531 -167.713299)
			(xy 7.734202 -167.735111) (xy 7.680245 -167.749217) (xy 7.624808 -167.755317) (xy 7.569074 -167.75328)
			(xy 7.514231 -167.74315) (xy 7.461447 -167.725143) (xy 7.411847 -167.699642) (xy 7.366489 -167.667191)
			(xy 7.32634 -167.628482) (xy 7.292254 -167.584339) (xy 7.264958 -167.535704) (xy 7.245035 -167.483613)
			(xy 7.232909 -167.429176) (xy 7.228838 -167.373554) (xy 4.717542 -167.373554) (xy 4.717033 -167.40144)
			(xy 4.708913 -167.456616) (xy 4.692845 -167.510023) (xy 4.669173 -167.56052) (xy 4.6384 -167.607033)
			(xy 4.601183 -167.64857) (xy 4.558315 -167.684245) (xy 4.510709 -167.713299) (xy 4.45938 -167.735111)
			(xy 4.405423 -167.749217) (xy 4.349986 -167.755317) (xy 4.294252 -167.75328) (xy 4.239409 -167.74315)
			(xy 4.186625 -167.725143) (xy 4.137025 -167.699642) (xy 4.091667 -167.667191) (xy 4.051518 -167.628482)
			(xy 4.017432 -167.584339) (xy 3.990136 -167.535704) (xy 3.970213 -167.483613) (xy 3.958087 -167.429176)
			(xy 3.954016 -167.373554) (xy 1.64338 -167.373554) (xy 1.64338 -167.671496) (xy 2.276348 -168.304464)
			(xy 33.194242 -168.304464) (xy 33.198313 -168.248842) (xy 33.210439 -168.194405) (xy 33.230362 -168.142314)
			(xy 33.257658 -168.093679) (xy 33.291744 -168.049536) (xy 33.331893 -168.010827) (xy 33.377251 -167.978376)
			(xy 33.426851 -167.952875) (xy 33.479635 -167.934868) (xy 33.534478 -167.924738) (xy 33.590212 -167.922701)
			(xy 33.645649 -167.928801) (xy 33.699606 -167.942907) (xy 33.750935 -167.964719) (xy 33.798541 -167.993773)
			(xy 33.841409 -168.029448) (xy 33.878626 -168.070985) (xy 33.909399 -168.117498) (xy 33.933071 -168.167995)
			(xy 33.949139 -168.221402) (xy 33.957259 -168.276578) (xy 33.957768 -168.304464) (xy 33.957259 -168.33235)
			(xy 33.949139 -168.387526) (xy 33.933071 -168.440933) (xy 33.909399 -168.49143) (xy 33.878626 -168.537943)
			(xy 33.841409 -168.57948) (xy 33.798541 -168.615155) (xy 33.750935 -168.644209) (xy 33.699606 -168.666021)
			(xy 33.645649 -168.680127) (xy 33.590212 -168.686227) (xy 33.534478 -168.68419) (xy 33.479635 -168.67406)
			(xy 33.426851 -168.656053) (xy 33.377251 -168.630552) (xy 33.331893 -168.598101) (xy 33.291744 -168.559392)
			(xy 33.257658 -168.515249) (xy 33.230362 -168.466614) (xy 33.210439 -168.414523) (xy 33.198313 -168.360086)
			(xy 33.194242 -168.304464) (xy 2.276348 -168.304464) (xy 2.32664 -168.354756) (xy 10.573766 -168.354756)
			(xy 11.6967 -169.47769) (xy 29.536642 -169.47769) (xy 29.540713 -169.422068) (xy 29.552839 -169.367631)
			(xy 29.572762 -169.31554) (xy 29.600058 -169.266905) (xy 29.634144 -169.222762) (xy 29.674293 -169.184053)
			(xy 29.719651 -169.151602) (xy 29.769251 -169.126101) (xy 29.822035 -169.108094) (xy 29.876878 -169.097964)
			(xy 29.932612 -169.095927) (xy 29.988049 -169.102027) (xy 30.042006 -169.116133) (xy 30.093335 -169.137945)
			(xy 30.140941 -169.166999) (xy 30.183809 -169.202674) (xy 30.221026 -169.244211) (xy 30.251799 -169.290724)
			(xy 30.261811 -169.312082) (xy 32.190942 -169.312082) (xy 32.195013 -169.25646) (xy 32.207139 -169.202023)
			(xy 32.227062 -169.149932) (xy 32.254358 -169.101297) (xy 32.288444 -169.057154) (xy 32.328593 -169.018445)
			(xy 32.373951 -168.985994) (xy 32.423551 -168.960493) (xy 32.476335 -168.942486) (xy 32.531178 -168.932356)
			(xy 32.586912 -168.930319) (xy 32.642349 -168.936419) (xy 32.696306 -168.950525) (xy 32.747635 -168.972337)
			(xy 32.795241 -169.001391) (xy 32.838109 -169.037066) (xy 32.875326 -169.078603) (xy 32.906099 -169.125116)
			(xy 32.929771 -169.175613) (xy 32.945839 -169.22902) (xy 32.953959 -169.284196) (xy 32.954468 -169.312082)
			(xy 32.953959 -169.339968) (xy 32.945839 -169.395144) (xy 32.929771 -169.448551) (xy 32.906099 -169.499048)
			(xy 32.875326 -169.545561) (xy 32.838109 -169.587098) (xy 32.795241 -169.622773) (xy 32.747635 -169.651827)
			(xy 32.696306 -169.673639) (xy 32.642349 -169.687745) (xy 32.586912 -169.693845) (xy 32.531178 -169.691808)
			(xy 32.476335 -169.681678) (xy 32.423551 -169.663671) (xy 32.373951 -169.63817) (xy 32.328593 -169.605719)
			(xy 32.288444 -169.56701) (xy 32.254358 -169.522867) (xy 32.227062 -169.474232) (xy 32.207139 -169.422141)
			(xy 32.195013 -169.367704) (xy 32.190942 -169.312082) (xy 30.261811 -169.312082) (xy 30.275471 -169.341221)
			(xy 30.291539 -169.394628) (xy 30.299659 -169.449804) (xy 30.300168 -169.47769) (xy 30.299659 -169.505576)
			(xy 30.291539 -169.560752) (xy 30.275471 -169.614159) (xy 30.251799 -169.664656) (xy 30.221026 -169.711169)
			(xy 30.183809 -169.752706) (xy 30.140941 -169.788381) (xy 30.093335 -169.817435) (xy 30.042006 -169.839247)
			(xy 29.988049 -169.853353) (xy 29.932612 -169.859453) (xy 29.876878 -169.857416) (xy 29.822035 -169.847286)
			(xy 29.769251 -169.829279) (xy 29.719651 -169.803778) (xy 29.674293 -169.771327) (xy 29.634144 -169.732618)
			(xy 29.600058 -169.688475) (xy 29.572762 -169.63984) (xy 29.552839 -169.587749) (xy 29.540713 -169.533312)
			(xy 29.536642 -169.47769) (xy 11.6967 -169.47769) (xy 13.536019 -171.317009) (xy 30.328679 -171.317009)
			(xy 30.333277 -171.261249) (xy 30.345969 -171.206759) (xy 30.366484 -171.154707) (xy 30.394381 -171.106209)
			(xy 30.429061 -171.062306) (xy 30.469783 -171.023939) (xy 30.492446 -171.007532) (xy 30.511342 -170.993699)
			(xy 30.544206 -170.960346) (xy 30.570401 -170.921535) (xy 30.58904 -170.878581) (xy 30.599493 -170.832939)
			(xy 30.601406 -170.786155) (xy 30.594712 -170.739812) (xy 30.57964 -170.69548) (xy 30.5567 -170.654661)
			(xy 30.526668 -170.618737) (xy 30.508956 -170.603418) (xy 30.487739 -170.58518) (xy 30.45028 -170.543626)
			(xy 30.419291 -170.497046) (xy 30.395438 -170.44644) (xy 30.379232 -170.392892) (xy 30.37102 -170.337552)
			(xy 30.370979 -170.281606) (xy 30.37911 -170.226254) (xy 30.395238 -170.172683) (xy 30.419017 -170.122042)
			(xy 30.449937 -170.075417) (xy 30.487335 -170.033807) (xy 30.53041 -169.998107) (xy 30.578236 -169.96908)
			(xy 30.62979 -169.947349) (xy 30.683964 -169.933381) (xy 30.739598 -169.927476) (xy 30.795497 -169.929759)
			(xy 30.850464 -169.940181) (xy 30.903319 -169.95852) (xy 30.94082 -169.97807) (xy 37.260782 -169.97807)
			(xy 37.264853 -169.922448) (xy 37.276979 -169.868011) (xy 37.296902 -169.81592) (xy 37.324198 -169.767285)
			(xy 37.358284 -169.723142) (xy 37.398433 -169.684433) (xy 37.443791 -169.651982) (xy 37.493391 -169.626481)
			(xy 37.546175 -169.608474) (xy 37.601018 -169.598344) (xy 37.656752 -169.596307) (xy 37.712189 -169.602407)
			(xy 37.766146 -169.616513) (xy 37.817475 -169.638325) (xy 37.865081 -169.667379) (xy 37.907949 -169.703054)
			(xy 37.945166 -169.744591) (xy 37.975939 -169.791104) (xy 37.999611 -169.841601) (xy 38.015679 -169.895008)
			(xy 38.023799 -169.950184) (xy 38.024308 -169.97807) (xy 38.023799 -170.005956) (xy 38.015679 -170.061132)
			(xy 37.999611 -170.114539) (xy 37.975939 -170.165036) (xy 37.945166 -170.211549) (xy 37.907949 -170.253086)
			(xy 37.865081 -170.288761) (xy 37.817475 -170.317815) (xy 37.766146 -170.339627) (xy 37.712189 -170.353733)
			(xy 37.656752 -170.359833) (xy 37.601018 -170.357796) (xy 37.546175 -170.347666) (xy 37.493391 -170.329659)
			(xy 37.443791 -170.304158) (xy 37.398433 -170.271707) (xy 37.358284 -170.232998) (xy 37.324198 -170.188855)
			(xy 37.296902 -170.14022) (xy 37.276979 -170.088129) (xy 37.264853 -170.033692) (xy 37.260782 -169.97807)
			(xy 30.94082 -169.97807) (xy 30.952928 -169.984382) (xy 30.998229 -170.017213) (xy 31.038249 -170.056307)
			(xy 31.072129 -170.100828) (xy 31.099145 -170.149819) (xy 31.118715 -170.20223) (xy 31.13042 -170.256938)
			(xy 31.13401 -170.312769) (xy 31.129407 -170.368525) (xy 31.11671 -170.423011) (xy 31.096191 -170.475059)
			(xy 31.068291 -170.523552) (xy 31.033607 -170.567449) (xy 30.992884 -170.605811) (xy 30.97022 -170.622214)
			(xy 30.951281 -170.635991) (xy 30.945837 -170.641518) (xy 33.158682 -170.641518) (xy 33.162753 -170.585896)
			(xy 33.174879 -170.531459) (xy 33.194802 -170.479368) (xy 33.222098 -170.430733) (xy 33.256184 -170.38659)
			(xy 33.296333 -170.347881) (xy 33.341691 -170.31543) (xy 33.391291 -170.289929) (xy 33.444075 -170.271922)
			(xy 33.498918 -170.261792) (xy 33.554652 -170.259755) (xy 33.610089 -170.265855) (xy 33.664046 -170.279961)
			(xy 33.715375 -170.301773) (xy 33.762981 -170.330827) (xy 33.805849 -170.366502) (xy 33.843066 -170.408039)
			(xy 33.873839 -170.454552) (xy 33.897511 -170.505049) (xy 33.913579 -170.558456) (xy 33.921699 -170.613632)
			(xy 33.922208 -170.641518) (xy 33.921699 -170.669404) (xy 33.913579 -170.72458) (xy 33.897511 -170.777987)
			(xy 33.873839 -170.828484) (xy 33.843066 -170.874997) (xy 33.805849 -170.916534) (xy 33.762981 -170.952209)
			(xy 33.715375 -170.981263) (xy 33.664046 -171.003075) (xy 33.610089 -171.017181) (xy 33.554652 -171.023281)
			(xy 33.498918 -171.021244) (xy 33.444075 -171.011114) (xy 33.391291 -170.993107) (xy 33.341691 -170.967606)
			(xy 33.296333 -170.935155) (xy 33.256184 -170.896446) (xy 33.222098 -170.852303) (xy 33.194802 -170.803668)
			(xy 33.174879 -170.751577) (xy 33.162753 -170.69714) (xy 33.158682 -170.641518) (xy 30.945837 -170.641518)
			(xy 30.918421 -170.669354) (xy 30.892229 -170.708174) (xy 30.873594 -170.751135) (xy 30.863146 -170.796784)
			(xy 30.861239 -170.843574) (xy 30.867937 -170.889922) (xy 30.883014 -170.934257) (xy 30.905959 -170.97508)
			(xy 30.935996 -171.011007) (xy 30.95371 -171.026328) (xy 30.974963 -171.044524) (xy 31.012428 -171.086078)
			(xy 31.043421 -171.132657) (xy 31.06728 -171.183264) (xy 31.083491 -171.236813) (xy 31.091707 -171.292155)
			(xy 31.091753 -171.348104) (xy 31.083627 -171.403459) (xy 31.067503 -171.457034) (xy 31.043727 -171.50768)
			(xy 31.012809 -171.55431) (xy 30.975413 -171.595924) (xy 30.932339 -171.63163) (xy 30.884513 -171.660663)
			(xy 30.837752 -171.680378) (xy 35.205922 -171.680378) (xy 35.209993 -171.624756) (xy 35.222119 -171.570319)
			(xy 35.242042 -171.518228) (xy 35.269338 -171.469593) (xy 35.303424 -171.42545) (xy 35.343573 -171.386741)
			(xy 35.388931 -171.35429) (xy 35.438531 -171.328789) (xy 35.491315 -171.310782) (xy 35.546158 -171.300652)
			(xy 35.601892 -171.298615) (xy 35.657329 -171.304715) (xy 35.711286 -171.318821) (xy 35.762615 -171.340633)
			(xy 35.810221 -171.369687) (xy 35.853089 -171.405362) (xy 35.890306 -171.446899) (xy 35.921079 -171.493412)
			(xy 35.944751 -171.543909) (xy 35.960819 -171.597316) (xy 35.968939 -171.652492) (xy 35.969448 -171.680378)
			(xy 35.968939 -171.708264) (xy 35.968568 -171.710788) (xy 37.333735 -171.710788) (xy 37.338177 -171.656299)
			(xy 37.350352 -171.603001) (xy 37.370011 -171.551988) (xy 37.396751 -171.504303) (xy 37.430025 -171.460924)
			(xy 37.46915 -171.42274) (xy 37.513326 -171.390531) (xy 37.561647 -171.364959) (xy 37.613124 -171.346547)
			(xy 37.666701 -171.335673) (xy 37.721283 -171.332558) (xy 37.77575 -171.337267) (xy 37.828987 -171.349703)
			(xy 37.879904 -171.369612) (xy 37.903912 -171.38269) (xy 37.923608 -171.393333) (xy 37.965814 -171.408254)
			(xy 38.009981 -171.415548) (xy 38.054743 -171.414989) (xy 38.098715 -171.406596) (xy 38.140535 -171.390627)
			(xy 38.17891 -171.367577) (xy 38.212652 -171.338159) (xy 38.240718 -171.303284) (xy 38.251892 -171.283884)
			(xy 38.26535 -171.260242) (xy 38.29804 -171.216759) (xy 38.336576 -171.178359) (xy 38.380174 -171.145822)
			(xy 38.427952 -171.119807) (xy 38.47894 -171.100841) (xy 38.532105 -171.08931) (xy 38.586369 -171.085447)
			(xy 38.640631 -171.08933) (xy 38.693792 -171.10088) (xy 38.744774 -171.119864) (xy 38.792542 -171.145896)
			(xy 38.836129 -171.178449) (xy 38.87465 -171.216863) (xy 38.907325 -171.260358) (xy 38.933491 -171.308053)
			(xy 38.952617 -171.358981) (xy 38.964317 -171.41211) (xy 38.968352 -171.466361) (xy 38.96464 -171.520635)
			(xy 38.953258 -171.573833) (xy 38.934436 -171.624874) (xy 38.908554 -171.672724) (xy 38.892734 -171.694856)
			(xy 38.879322 -171.71381) (xy 38.858898 -171.755503) (xy 38.846383 -171.800212) (xy 38.842196 -171.84645)
			(xy 38.846474 -171.892679) (xy 38.859076 -171.937363) (xy 38.879583 -171.979016) (xy 38.907312 -172.016252)
			(xy 38.923976 -172.032422) (xy 38.943698 -172.05128) (xy 38.977998 -172.093719) (xy 39.005905 -172.14061)
			(xy 39.026848 -172.190998) (xy 39.040401 -172.243856) (xy 39.046288 -172.298105) (xy 39.044388 -172.352639)
			(xy 39.03474 -172.406346) (xy 39.017542 -172.458132) (xy 38.993142 -172.506941) (xy 38.96204 -172.551777)
			(xy 38.924869 -172.591725) (xy 38.882387 -172.625973) (xy 38.83546 -172.65382) (xy 38.785046 -172.6747)
			(xy 38.732172 -172.688187) (xy 38.677915 -172.694005) (xy 38.623384 -172.692037) (xy 38.569688 -172.682322)
			(xy 38.517924 -172.665058) (xy 38.469146 -172.640597) (xy 38.42435 -172.609438) (xy 38.384447 -172.572217)
			(xy 38.350254 -172.529692) (xy 38.322465 -172.482731) (xy 38.301648 -172.43229) (xy 38.288228 -172.379399)
			(xy 38.282478 -172.325135) (xy 38.284515 -172.270606) (xy 38.294298 -172.216923) (xy 38.311627 -172.16518)
			(xy 38.336149 -172.116433) (xy 38.367363 -172.071676) (xy 38.404635 -172.031821) (xy 38.425628 -172.014388)
			(xy 38.43757 -172.004238) (xy 38.456435 -171.979217) (xy 38.468632 -171.950353) (xy 38.473425 -171.919386)
			(xy 38.470526 -171.888185) (xy 38.46011 -171.858632) (xy 38.442804 -171.832509) (xy 38.419652 -171.811392)
			(xy 38.40607 -171.803568) (xy 38.398196 -171.798996) (xy 38.378493 -171.788368) (xy 38.336289 -171.773447)
			(xy 38.292124 -171.766153) (xy 38.247363 -171.76671) (xy 38.203393 -171.775102) (xy 38.161574 -171.791069)
			(xy 38.123199 -171.814116) (xy 38.089457 -171.843531) (xy 38.061391 -171.878404) (xy 38.050216 -171.897802)
			(xy 38.036693 -171.921562) (xy 38.003846 -171.965265) (xy 37.965097 -172.003831) (xy 37.921239 -172.03647)
			(xy 37.873171 -172.062514) (xy 37.821877 -172.08143) (xy 37.768408 -172.092829) (xy 37.713859 -172.096479)
			(xy 37.659349 -172.092304) (xy 37.605992 -172.08039) (xy 37.554883 -172.060981) (xy 37.507068 -172.034475)
			(xy 37.463527 -172.001414) (xy 37.425151 -171.962476) (xy 37.392727 -171.918459) (xy 37.366918 -171.870264)
			(xy 37.348254 -171.818878) (xy 37.337117 -171.765354) (xy 37.333735 -171.710788) (xy 35.968568 -171.710788)
			(xy 35.960819 -171.76344) (xy 35.944751 -171.816847) (xy 35.921079 -171.867344) (xy 35.890306 -171.913857)
			(xy 35.853089 -171.955394) (xy 35.810221 -171.991069) (xy 35.762615 -172.020123) (xy 35.711286 -172.041935)
			(xy 35.657329 -172.056041) (xy 35.601892 -172.062141) (xy 35.546158 -172.060104) (xy 35.491315 -172.049974)
			(xy 35.438531 -172.031967) (xy 35.388931 -172.006466) (xy 35.343573 -171.974015) (xy 35.303424 -171.935306)
			(xy 35.269338 -171.891163) (xy 35.242042 -171.842528) (xy 35.222119 -171.790437) (xy 35.209993 -171.736)
			(xy 35.205922 -171.680378) (xy 30.837752 -171.680378) (xy 30.832959 -171.682399) (xy 30.778783 -171.696372)
			(xy 30.723148 -171.702283) (xy 30.667245 -171.700005) (xy 30.612275 -171.689587) (xy 30.559416 -171.671252)
			(xy 30.509801 -171.645394) (xy 30.464496 -171.612566) (xy 30.42447 -171.573473) (xy 30.390584 -171.528954)
			(xy 30.363562 -171.479963) (xy 30.343986 -171.427551) (xy 30.332275 -171.372842) (xy 30.328679 -171.317009)
			(xy 13.536019 -171.317009) (xy 13.97508 -171.75607) (xy 13.97508 -172.857414) (xy 24.614122 -172.857414)
			(xy 24.618193 -172.801792) (xy 24.630319 -172.747355) (xy 24.650242 -172.695264) (xy 24.677538 -172.646629)
			(xy 24.711624 -172.602486) (xy 24.751773 -172.563777) (xy 24.797131 -172.531326) (xy 24.846731 -172.505825)
			(xy 24.899515 -172.487818) (xy 24.954358 -172.477688) (xy 25.010092 -172.475651) (xy 25.065529 -172.481751)
			(xy 25.119486 -172.495857) (xy 25.170815 -172.517669) (xy 25.218421 -172.546723) (xy 25.261289 -172.582398)
			(xy 25.298506 -172.623935) (xy 25.329279 -172.670448) (xy 25.33298 -172.678344) (xy 32.704022 -172.678344)
			(xy 32.708093 -172.622722) (xy 32.720219 -172.568285) (xy 32.740142 -172.516194) (xy 32.767438 -172.467559)
			(xy 32.801524 -172.423416) (xy 32.841673 -172.384707) (xy 32.887031 -172.352256) (xy 32.936631 -172.326755)
			(xy 32.989415 -172.308748) (xy 33.044258 -172.298618) (xy 33.099992 -172.296581) (xy 33.155429 -172.302681)
			(xy 33.209386 -172.316787) (xy 33.260715 -172.338599) (xy 33.308321 -172.367653) (xy 33.351189 -172.403328)
			(xy 33.388406 -172.444865) (xy 33.419179 -172.491378) (xy 33.442851 -172.541875) (xy 33.458919 -172.595282)
			(xy 33.467039 -172.650458) (xy 33.467548 -172.678344) (xy 33.467039 -172.70623) (xy 33.458919 -172.761406)
			(xy 33.442851 -172.814813) (xy 33.419179 -172.86531) (xy 33.388406 -172.911823) (xy 33.351189 -172.95336)
			(xy 33.308321 -172.989035) (xy 33.260715 -173.018089) (xy 33.209386 -173.039901) (xy 33.155429 -173.054007)
			(xy 33.099992 -173.060107) (xy 33.044258 -173.05807) (xy 32.989415 -173.04794) (xy 32.936631 -173.029933)
			(xy 32.887031 -173.004432) (xy 32.841673 -172.971981) (xy 32.801524 -172.933272) (xy 32.767438 -172.889129)
			(xy 32.740142 -172.840494) (xy 32.720219 -172.788403) (xy 32.708093 -172.733966) (xy 32.704022 -172.678344)
			(xy 25.33298 -172.678344) (xy 25.352951 -172.720945) (xy 25.369019 -172.774352) (xy 25.377139 -172.829528)
			(xy 25.377648 -172.857414) (xy 25.377139 -172.8853) (xy 25.369019 -172.940476) (xy 25.352951 -172.993883)
			(xy 25.329279 -173.04438) (xy 25.298506 -173.090893) (xy 25.261289 -173.13243) (xy 25.218421 -173.168105)
			(xy 25.170815 -173.197159) (xy 25.119486 -173.218971) (xy 25.065529 -173.233077) (xy 25.010092 -173.239177)
			(xy 24.954358 -173.23714) (xy 24.899515 -173.22701) (xy 24.846731 -173.209003) (xy 24.797131 -173.183502)
			(xy 24.751773 -173.151051) (xy 24.711624 -173.112342) (xy 24.677538 -173.068199) (xy 24.650242 -173.019564)
			(xy 24.630319 -172.967473) (xy 24.618193 -172.913036) (xy 24.614122 -172.857414) (xy 13.97508 -172.857414)
			(xy 13.97508 -175.179228) (xy 20.098002 -175.179228) (xy 20.102073 -175.123606) (xy 20.114199 -175.069169)
			(xy 20.134122 -175.017078) (xy 20.161418 -174.968443) (xy 20.195504 -174.9243) (xy 20.235653 -174.885591)
			(xy 20.281011 -174.85314) (xy 20.330611 -174.827639) (xy 20.383395 -174.809632) (xy 20.438238 -174.799502)
			(xy 20.493972 -174.797465) (xy 20.549409 -174.803565) (xy 20.603366 -174.817671) (xy 20.654695 -174.839483)
			(xy 20.702301 -174.868537) (xy 20.745169 -174.904212) (xy 20.782386 -174.945749) (xy 20.813159 -174.992262)
			(xy 20.836831 -175.042759) (xy 20.852899 -175.096166) (xy 20.861019 -175.151342) (xy 20.861528 -175.179228)
			(xy 20.861019 -175.207114) (xy 20.852899 -175.26229) (xy 20.836831 -175.315697) (xy 20.813159 -175.366194)
			(xy 20.782386 -175.412707) (xy 20.745169 -175.454244) (xy 20.702301 -175.489919) (xy 20.654695 -175.518973)
			(xy 20.603366 -175.540785) (xy 20.549409 -175.554891) (xy 20.493972 -175.560991) (xy 20.438238 -175.558954)
			(xy 20.383395 -175.548824) (xy 20.330611 -175.530817) (xy 20.281011 -175.505316) (xy 20.235653 -175.472865)
			(xy 20.195504 -175.434156) (xy 20.161418 -175.390013) (xy 20.134122 -175.341378) (xy 20.114199 -175.289287)
			(xy 20.102073 -175.23485) (xy 20.098002 -175.179228) (xy 13.97508 -175.179228) (xy 13.97508 -177.712961)
			(xy 20.992058 -177.712961) (xy 20.999867 -177.535341) (xy 21.015543 -177.358242) (xy 21.039055 -177.182012)
			(xy 21.070358 -177.006998) (xy 21.109389 -176.833543) (xy 21.156072 -176.66199) (xy 21.210314 -176.492675)
			(xy 21.27201 -176.325931) (xy 21.341038 -176.162086) (xy 21.417262 -176.001463) (xy 21.500532 -175.844378)
			(xy 21.590685 -175.691138) (xy 21.687543 -175.542046) (xy 21.790916 -175.397395) (xy 21.9006 -175.25747)
			(xy 22.01638 -175.122544) (xy 22.138029 -174.992885) (xy 22.265306 -174.868746) (xy 22.397961 -174.750372)
			(xy 22.535735 -174.637996) (xy 22.678355 -174.531839) (xy 22.825541 -174.432109) (xy 22.977004 -174.339003)
			(xy 23.132446 -174.252703) (xy 23.291561 -174.17338) (xy 23.454037 -174.101189) (xy 23.619553 -174.036272)
			(xy 23.787785 -173.978758) (xy 23.958401 -173.928758) (xy 24.131067 -173.886372) (xy 24.305441 -173.851683)
			(xy 24.481182 -173.824759) (xy 24.657945 -173.805653) (xy 24.83538 -173.794402) (xy 25.013139 -173.791029)
			(xy 25.190874 -173.795541) (xy 25.368233 -173.807927) (xy 25.544869 -173.828165) (xy 25.720435 -173.856215)
			(xy 25.894583 -173.89202) (xy 25.980898 -173.913292) (xy 26.068383 -173.935873) (xy 26.241428 -173.987915)
			(xy 26.411952 -174.047702) (xy 26.579609 -174.115111) (xy 26.744058 -174.190006) (xy 26.904966 -174.272235)
			(xy 27.062006 -174.36163) (xy 27.132404 -174.406019) (xy 32.538897 -174.406019) (xy 32.546616 -174.350477)
			(xy 32.562381 -174.296662) (xy 32.585852 -174.245735) (xy 32.616525 -174.198791) (xy 32.653738 -174.156841)
			(xy 32.69669 -174.120791) (xy 32.744455 -174.091415) (xy 32.796007 -174.069346) (xy 32.850232 -174.05506)
			(xy 32.905965 -174.048865) (xy 32.962005 -174.050893) (xy 33.017144 -174.061102) (xy 33.070195 -174.079271)
			(xy 33.120016 -174.105009) (xy 33.165533 -174.137762) (xy 33.205766 -174.176824) (xy 33.2232 -174.198788)
			(xy 33.237901 -174.217182) (xy 33.272924 -174.248649) (xy 33.313146 -174.273123) (xy 33.35719 -174.289766)
			(xy 33.403546 -174.298006) (xy 33.450627 -174.297563) (xy 33.49682 -174.28845) (xy 33.540543 -174.270981)
			(xy 33.580297 -174.245753) (xy 33.61472 -174.213631) (xy 33.629092 -174.194978) (xy 33.646688 -174.172039)
			(xy 33.687636 -174.131232) (xy 33.734269 -174.097063) (xy 33.759648 -174.083218) (xy 33.778968 -174.072598)
			(xy 33.813969 -174.0458) (xy 33.843815 -174.013358) (xy 33.867608 -173.976249) (xy 33.884633 -173.935588)
			(xy 33.894378 -173.892597) (xy 33.896551 -173.848568) (xy 33.891085 -173.804827) (xy 33.878146 -173.762687)
			(xy 33.858122 -173.723415) (xy 33.845246 -173.70552) (xy 33.828983 -173.683117) (xy 33.802499 -173.634503)
			(xy 33.783319 -173.582572) (xy 33.771844 -173.528415) (xy 33.768315 -173.473167) (xy 33.772807 -173.41799)
			(xy 33.785225 -173.364041) (xy 33.805308 -173.312452) (xy 33.832636 -173.264308) (xy 33.866633 -173.220617)
			(xy 33.906587 -173.182297) (xy 33.951659 -173.150154) (xy 33.976056 -173.137068) (xy 33.995769 -173.126456)
			(xy 34.031424 -173.099388) (xy 34.061784 -173.066491) (xy 34.085911 -173.028783) (xy 34.103058 -172.987432)
			(xy 34.112694 -172.943716) (xy 34.114522 -172.898987) (xy 34.108485 -172.85463) (xy 34.094769 -172.812018)
			(xy 34.073799 -172.772467) (xy 34.060384 -172.754544) (xy 34.043841 -172.732565) (xy 34.016577 -172.684787)
			(xy 33.996459 -172.633588) (xy 33.983903 -172.58003) (xy 33.97917 -172.525224) (xy 33.982359 -172.470307)
			(xy 33.993403 -172.416417) (xy 34.012073 -172.364673) (xy 34.037982 -172.316146) (xy 34.070593 -172.271845)
			(xy 34.109229 -172.232687) (xy 34.153088 -172.199485) (xy 34.201263 -172.172927) (xy 34.252752 -172.153564)
			(xy 34.306489 -172.141798) (xy 34.361358 -172.137873) (xy 34.416222 -172.141869) (xy 34.469944 -172.153705)
			(xy 34.521408 -172.173135) (xy 34.569548 -172.199755) (xy 34.613364 -172.233015) (xy 34.651949 -172.272223)
			(xy 34.684502 -172.316566) (xy 34.710348 -172.365126) (xy 34.728951 -172.416895) (xy 34.739925 -172.470799)
			(xy 34.743042 -172.52572) (xy 34.738239 -172.58052) (xy 34.725613 -172.634061) (xy 34.705428 -172.685234)
			(xy 34.678102 -172.732977) (xy 34.644201 -172.776299) (xy 34.60443 -172.814303) (xy 34.559612 -172.846199)
			(xy 34.535364 -172.859192) (xy 34.515683 -172.86986) (xy 34.480029 -172.89692) (xy 34.449668 -172.929809)
			(xy 34.425539 -172.967509) (xy 34.40839 -173.008853) (xy 34.39875 -173.052563) (xy 34.396918 -173.097286)
			(xy 34.40295 -173.141638) (xy 34.41666 -173.184246) (xy 34.437624 -173.223794) (xy 34.451036 -173.241716)
			(xy 34.467854 -173.263957) (xy 34.495418 -173.312429) (xy 34.515631 -173.364397) (xy 34.528062 -173.418754)
			(xy 34.531188 -173.458378) (xy 36.149024 -173.458378) (xy 36.153095 -173.402756) (xy 36.165221 -173.348319)
			(xy 36.185144 -173.296228) (xy 36.21244 -173.247593) (xy 36.246526 -173.20345) (xy 36.286675 -173.164741)
			(xy 36.332033 -173.13229) (xy 36.381633 -173.106789) (xy 36.434417 -173.088782) (xy 36.48926 -173.078652)
			(xy 36.544994 -173.076615) (xy 36.600431 -173.082715) (xy 36.654388 -173.096821) (xy 36.705717 -173.118633)
			(xy 36.753323 -173.147687) (xy 36.796191 -173.183362) (xy 36.833408 -173.224899) (xy 36.864181 -173.271412)
			(xy 36.887853 -173.321909) (xy 36.892918 -173.338744) (xy 37.931342 -173.338744) (xy 37.935413 -173.283122)
			(xy 37.947539 -173.228685) (xy 37.967462 -173.176594) (xy 37.994758 -173.127959) (xy 38.028844 -173.083816)
			(xy 38.068993 -173.045107) (xy 38.114351 -173.012656) (xy 38.163951 -172.987155) (xy 38.216735 -172.969148)
			(xy 38.271578 -172.959018) (xy 38.327312 -172.956981) (xy 38.382749 -172.963081) (xy 38.436706 -172.977187)
			(xy 38.488035 -172.998999) (xy 38.535641 -173.028053) (xy 38.578509 -173.063728) (xy 38.597038 -173.084408)
			(xy 39.15352 -173.084408) (xy 39.16059 -173.028906) (xy 39.175691 -172.975032) (xy 39.198499 -172.923941)
			(xy 39.228526 -172.876729) (xy 39.265126 -172.83441) (xy 39.307515 -172.797891) (xy 39.354784 -172.767955)
			(xy 39.405918 -172.745244) (xy 39.432738 -172.737272) (xy 39.453385 -172.731052) (xy 39.492378 -172.71265)
			(xy 39.527707 -172.687933) (xy 39.55836 -172.65761) (xy 39.583457 -172.62255) (xy 39.602279 -172.583758)
			(xy 39.614285 -172.542346) (xy 39.619133 -172.499502) (xy 39.616682 -172.456455) (xy 39.607003 -172.414438)
			(xy 39.599108 -172.394372) (xy 39.589534 -172.370341) (xy 39.576176 -172.320367) (xy 39.569697 -172.269046)
			(xy 39.570215 -172.217321) (xy 39.577722 -172.16614) (xy 39.592079 -172.116444) (xy 39.602156 -172.09262)
			(xy 39.610814 -172.071814) (xy 39.621522 -172.028046) (xy 39.624342 -171.983075) (xy 39.619185 -171.938312)
			(xy 39.606212 -171.89516) (xy 39.585831 -171.854974) (xy 39.55868 -171.819014) (xy 39.525611 -171.788406)
			(xy 39.487662 -171.764113) (xy 39.467028 -171.755054) (xy 39.441896 -171.744121) (xy 39.394769 -171.716143)
			(xy 39.35213 -171.681711) (xy 39.314855 -171.641534) (xy 39.283711 -171.596437) (xy 39.259338 -171.547348)
			(xy 39.242239 -171.495278) (xy 39.232765 -171.441298) (xy 39.23111 -171.386517) (xy 39.237309 -171.332063)
			(xy 39.251234 -171.279056) (xy 39.272599 -171.228586) (xy 39.300965 -171.181692) (xy 39.335747 -171.139337)
			(xy 39.37623 -171.102395) (xy 39.421582 -171.071623) (xy 39.47087 -171.047656) (xy 39.523079 -171.030987)
			(xy 39.577136 -171.021957) (xy 39.631928 -171.020754) (xy 39.686329 -171.027401) (xy 39.73922 -171.041763)
			(xy 39.789512 -171.063543) (xy 39.836171 -171.092294) (xy 39.878237 -171.127424) (xy 39.914845 -171.16821)
			(xy 39.945242 -171.213814) (xy 39.968802 -171.263297) (xy 39.985041 -171.315642) (xy 39.993625 -171.369771)
			(xy 39.994376 -171.424572) (xy 39.990395 -171.455064) (xy 40.286579 -171.455064) (xy 40.289509 -171.399563)
			(xy 40.300462 -171.345075) (xy 40.319205 -171.292754) (xy 40.345342 -171.243706) (xy 40.37832 -171.198969)
			(xy 40.41744 -171.159491) (xy 40.461875 -171.126108) (xy 40.510683 -171.099526) (xy 40.562833 -171.080308)
			(xy 40.617218 -171.06886) (xy 40.67269 -171.065425) (xy 40.728073 -171.070076) (xy 40.782194 -171.082714)
			(xy 40.833909 -171.103072) (xy 40.882123 -171.130718) (xy 40.925815 -171.165068) (xy 40.964059 -171.205394)
			(xy 40.996048 -171.250843) (xy 41.021103 -171.300453) (xy 41.038694 -171.353173) (xy 41.048449 -171.407888)
			(xy 41.050161 -171.463439) (xy 41.043794 -171.518651) (xy 41.029483 -171.572354) (xy 41.018968 -171.598082)
			(xy 41.010272 -171.619376) (xy 41.000024 -171.664217) (xy 40.99801 -171.710169) (xy 41.004294 -171.755733)
			(xy 41.018672 -171.799425) (xy 41.040674 -171.839817) (xy 41.069583 -171.875593) (xy 41.104455 -171.905586)
			(xy 41.144154 -171.928817) (xy 41.187383 -171.944528) (xy 41.209976 -171.948856) (xy 41.22547 -171.951904)
			(xy 41.248272 -171.956129) (xy 41.294619 -171.957365) (xy 41.340421 -171.950169) (xy 41.384156 -171.93478)
			(xy 41.424372 -171.911709) (xy 41.459733 -171.881722) (xy 41.489064 -171.845815) (xy 41.511391 -171.805181)
			(xy 41.525973 -171.76117) (xy 41.532325 -171.715244) (xy 41.531794 -171.692062) (xy 41.531044 -171.664182)
			(xy 41.536686 -171.608696) (xy 41.550343 -171.554621) (xy 41.571724 -171.50311) (xy 41.600374 -171.455259)
			(xy 41.635682 -171.412087) (xy 41.676898 -171.374513) (xy 41.723143 -171.343338) (xy 41.773432 -171.319224)
			(xy 41.826696 -171.302686) (xy 41.881799 -171.294075) (xy 41.937569 -171.293575) (xy 41.992818 -171.301197)
			(xy 42.046369 -171.316778) (xy 42.097083 -171.339987) (xy 42.143879 -171.370329) (xy 42.185762 -171.407158)
			(xy 42.221838 -171.44969) (xy 42.251341 -171.49702) (xy 42.273642 -171.54814) (xy 42.288265 -171.60196)
			(xy 42.294901 -171.657336) (xy 42.293406 -171.713089) (xy 42.283814 -171.76803) (xy 42.266329 -171.82099)
			(xy 42.241322 -171.870841) (xy 42.209327 -171.916523) (xy 42.171024 -171.957062) (xy 42.127229 -171.991595)
			(xy 42.078875 -172.019387) (xy 42.026991 -172.039846) (xy 41.972682 -172.052536) (xy 41.917104 -172.057188)
			(xy 41.861441 -172.053702) (xy 41.834054 -172.048424) (xy 41.811272 -172.044086) (xy 41.764914 -172.042862)
			(xy 41.719104 -172.05007) (xy 41.675363 -172.065472) (xy 41.635144 -172.088556) (xy 41.599781 -172.118556)
			(xy 41.57045 -172.154475) (xy 41.548124 -172.19512) (xy 41.533545 -172.239143) (xy 41.527197 -172.28508)
			(xy 41.52773 -172.308266) (xy 41.528383 -172.335679) (xy 41.522921 -172.390238) (xy 41.509705 -172.443453)
			(xy 41.489007 -172.494227) (xy 41.461253 -172.541516) (xy 41.427016 -172.584344) (xy 41.387001 -172.62183)
			(xy 41.342031 -172.653202) (xy 41.293033 -172.677813) (xy 41.241017 -172.695156) (xy 41.187054 -172.704874)
			(xy 41.132255 -172.706767) (xy 41.07775 -172.700795) (xy 41.024661 -172.687083) (xy 40.974082 -172.665912)
			(xy 40.927054 -172.637718) (xy 40.884547 -172.603082) (xy 40.847437 -172.562718) (xy 40.816486 -172.517457)
			(xy 40.792334 -172.468232) (xy 40.775478 -172.416056) (xy 40.766264 -172.362004) (xy 40.764883 -172.30719)
			(xy 40.771363 -172.252743) (xy 40.785571 -172.199785) (xy 40.795956 -172.174408) (xy 40.804647 -172.153112)
			(xy 40.814891 -172.108273) (xy 40.816903 -172.062322) (xy 40.810618 -172.016759) (xy 40.796241 -171.973069)
			(xy 40.77424 -171.932678) (xy 40.745333 -171.896903) (xy 40.710463 -171.86691) (xy 40.670767 -171.843678)
			(xy 40.627539 -171.827964) (xy 40.604948 -171.823634) (xy 40.577644 -171.818436) (xy 40.524766 -171.801325)
			(xy 40.47493 -171.776722) (xy 40.429192 -171.745148) (xy 40.38852 -171.707272) (xy 40.353774 -171.663894)
			(xy 40.32569 -171.615934) (xy 40.304863 -171.564406) (xy 40.291733 -171.510402) (xy 40.286579 -171.455064)
			(xy 39.990395 -171.455064) (xy 39.987281 -171.478916) (xy 39.972484 -171.531687) (xy 39.96182 -171.556934)
			(xy 39.953059 -171.577701) (xy 39.942352 -171.621482) (xy 39.939538 -171.666464) (xy 39.944704 -171.711238)
			(xy 39.957689 -171.754398) (xy 39.978085 -171.79459) (xy 40.005252 -171.830553) (xy 40.038338 -171.861158)
			(xy 40.076306 -171.885446) (xy 40.096948 -171.8945) (xy 40.122448 -171.90561) (xy 40.170191 -171.934145)
			(xy 40.213285 -171.96931) (xy 40.250818 -172.010358) (xy 40.281994 -172.05642) (xy 40.306153 -172.10652)
			(xy 40.322782 -172.159596) (xy 40.33153 -172.214525) (xy 40.332212 -172.270141) (xy 40.324811 -172.325268)
			(xy 40.309487 -172.378736) (xy 40.286562 -172.429412) (xy 40.256523 -172.476224) (xy 40.220007 -172.518179)
			(xy 40.177787 -172.554388) (xy 40.130757 -172.584084) (xy 40.079914 -172.606639) (xy 40.05326 -172.61459)
			(xy 40.032587 -172.620731) (xy 39.993588 -172.63914) (xy 39.958255 -172.663865) (xy 39.9276 -172.694197)
			(xy 39.902503 -172.729268) (xy 39.883683 -172.76807) (xy 39.871681 -172.809491) (xy 39.86684 -172.852344)
			(xy 39.8693 -172.895399) (xy 39.878989 -172.937422) (xy 39.88689 -172.95749) (xy 39.897249 -172.983481)
			(xy 39.911085 -173.037694) (xy 39.916853 -173.093347) (xy 39.91443 -173.149246) (xy 39.903869 -173.204191)
			(xy 39.885395 -173.257004) (xy 39.859406 -173.306552) (xy 39.826457 -173.351773) (xy 39.787257 -173.391696)
			(xy 39.742646 -173.425465) (xy 39.693581 -173.452356) (xy 39.641114 -173.471791) (xy 39.586372 -173.483355)
			(xy 39.530527 -173.486798) (xy 39.474778 -173.482048) (xy 39.420321 -173.469206) (xy 39.368324 -173.448547)
			(xy 39.319902 -173.420514) (xy 39.276094 -173.38571) (xy 39.237839 -173.34488) (xy 39.205959 -173.2989)
			(xy 39.181137 -173.248757) (xy 39.163905 -173.195525) (xy 39.154633 -173.140348) (xy 39.15352 -173.084408)
			(xy 38.597038 -173.084408) (xy 38.615726 -173.105265) (xy 38.646499 -173.151778) (xy 38.670171 -173.202275)
			(xy 38.686239 -173.255682) (xy 38.694359 -173.310858) (xy 38.694868 -173.338744) (xy 38.694359 -173.36663)
			(xy 38.686239 -173.421806) (xy 38.670171 -173.475213) (xy 38.64945 -173.519414) (xy 40.154686 -173.519414)
			(xy 40.155109 -173.463983) (xy 40.163548 -173.409198) (xy 40.179827 -173.35621) (xy 40.203604 -173.306136)
			(xy 40.234376 -173.26003) (xy 40.271497 -173.218863) (xy 40.314185 -173.183502) (xy 40.361541 -173.15469)
			(xy 40.412568 -173.133036) (xy 40.466192 -173.118993) (xy 40.521284 -173.112859) (xy 40.576683 -173.114763)
			(xy 40.631223 -173.124664) (xy 40.683757 -173.142353) (xy 40.733177 -173.167459) (xy 40.778444 -173.199453)
			(xy 40.818605 -173.237661) (xy 40.852813 -173.281279) (xy 40.880348 -173.329388) (xy 40.890952 -173.355)
			(xy 40.899991 -173.376501) (xy 40.924667 -173.416073) (xy 40.956155 -173.450473) (xy 40.993394 -173.478545)
			(xy 41.035135 -173.499344) (xy 41.079971 -173.51217) (xy 41.126396 -173.516593) (xy 41.172848 -173.512464)
			(xy 41.217764 -173.499921) (xy 41.238932 -173.490128) (xy 41.268505 -173.47641) (xy 41.331083 -173.458155)
			(xy 41.363392 -173.453806) (xy 41.384706 -173.450898) (xy 41.426004 -173.438868) (xy 41.464687 -173.420058)
			(xy 41.499652 -173.395005) (xy 41.5299 -173.364424) (xy 41.554569 -173.329187) (xy 41.572955 -173.290301)
			(xy 41.584533 -173.248874) (xy 41.588972 -173.20609) (xy 41.586145 -173.163169) (xy 41.581578 -173.142148)
			(xy 41.575492 -173.11486) (xy 41.570499 -173.059174) (xy 41.573689 -173.003356) (xy 41.584994 -172.948601)
			(xy 41.604171 -172.896083) (xy 41.630809 -172.846928) (xy 41.664338 -172.802187) (xy 41.704039 -172.762821)
			(xy 41.749062 -172.729673) (xy 41.798442 -172.703452) (xy 41.85112 -172.684721) (xy 41.905969 -172.673882)
			(xy 41.961812 -172.671165) (xy 42.017454 -172.67663) (xy 42.071702 -172.690159) (xy 42.123393 -172.711462)
			(xy 42.171421 -172.740084) (xy 42.214756 -172.775411) (xy 42.25247 -172.816685) (xy 42.283754 -172.863022)
			(xy 42.307938 -172.913431) (xy 42.324504 -172.96683) (xy 42.333097 -173.022075) (xy 42.333533 -173.077983)
			(xy 42.325803 -173.133355) (xy 42.310072 -173.187006) (xy 42.286677 -173.237785) (xy 42.25612 -173.284605)
			(xy 42.219055 -173.326463) (xy 42.176276 -173.362461) (xy 42.128701 -173.391828) (xy 42.077348 -173.413936)
			(xy 42.023317 -173.42831) (xy 41.995598 -173.431962) (xy 41.974269 -173.434781) (xy 41.932964 -173.446817)
			(xy 41.894275 -173.465635) (xy 41.859306 -173.490698) (xy 41.829055 -173.521289) (xy 41.804387 -173.556537)
			(xy 41.786004 -173.595435) (xy 41.774432 -173.636872) (xy 41.770002 -173.679666) (xy 41.772839 -173.722596)
			(xy 41.777412 -173.74362) (xy 41.783009 -173.768675) (xy 41.788193 -173.81975) (xy 41.786482 -173.87106)
			(xy 41.777906 -173.921676) (xy 41.762621 -173.970686) (xy 41.749248 -173.999329) (xy 42.116716 -173.999329)
			(xy 42.11728 -173.944093) (xy 42.125804 -173.889515) (xy 42.14211 -173.836738) (xy 42.165857 -173.786864)
			(xy 42.196549 -173.740936) (xy 42.233543 -173.699914) (xy 42.276067 -173.664656) (xy 42.323231 -173.6359)
			(xy 42.374049 -173.614246) (xy 42.427459 -173.600148) (xy 42.482343 -173.5939) (xy 42.537555 -173.595632)
			(xy 42.59194 -173.605309) (xy 42.644361 -173.622728) (xy 42.693722 -173.647525) (xy 42.73899 -173.679181)
			(xy 42.749436 -173.68901) (xy 43.097702 -173.68901) (xy 43.101773 -173.633388) (xy 43.113899 -173.578951)
			(xy 43.133822 -173.52686) (xy 43.161118 -173.478225) (xy 43.195204 -173.434082) (xy 43.235353 -173.395373)
			(xy 43.280711 -173.362922) (xy 43.330311 -173.337421) (xy 43.383095 -173.319414) (xy 43.437938 -173.309284)
			(xy 43.493672 -173.307247) (xy 43.549109 -173.313347) (xy 43.603066 -173.327453) (xy 43.654395 -173.349265)
			(xy 43.702001 -173.378319) (xy 43.744869 -173.413994) (xy 43.782086 -173.455531) (xy 43.812859 -173.502044)
			(xy 43.836531 -173.552541) (xy 43.852599 -173.605948) (xy 43.860719 -173.661124) (xy 43.861228 -173.68901)
			(xy 43.860719 -173.716896) (xy 43.852599 -173.772072) (xy 43.836531 -173.825479) (xy 43.812859 -173.875976)
			(xy 43.812201 -173.87697) (xy 45.887384 -173.87697) (xy 45.891455 -173.821348) (xy 45.903581 -173.766911)
			(xy 45.923504 -173.71482) (xy 45.9508 -173.666185) (xy 45.984886 -173.622042) (xy 46.025035 -173.583333)
			(xy 46.070393 -173.550882) (xy 46.119993 -173.525381) (xy 46.172777 -173.507374) (xy 46.22762 -173.497244)
			(xy 46.283354 -173.495207) (xy 46.338791 -173.501307) (xy 46.392748 -173.515413) (xy 46.444077 -173.537225)
			(xy 46.491683 -173.566279) (xy 46.534551 -173.601954) (xy 46.571768 -173.643491) (xy 46.602541 -173.690004)
			(xy 46.626213 -173.740501) (xy 46.642281 -173.793908) (xy 46.650401 -173.849084) (xy 46.65091 -173.87697)
			(xy 46.650401 -173.904856) (xy 46.642281 -173.960032) (xy 46.626213 -174.013439) (xy 46.602541 -174.063936)
			(xy 46.571768 -174.110449) (xy 46.534551 -174.151986) (xy 46.491683 -174.187661) (xy 46.444077 -174.216715)
			(xy 46.392748 -174.238527) (xy 46.338791 -174.252633) (xy 46.283354 -174.258733) (xy 46.22762 -174.256696)
			(xy 46.172777 -174.246566) (xy 46.119993 -174.228559) (xy 46.070393 -174.203058) (xy 46.025035 -174.170607)
			(xy 45.984886 -174.131898) (xy 45.9508 -174.087755) (xy 45.923504 -174.03912) (xy 45.903581 -173.987029)
			(xy 45.891455 -173.932592) (xy 45.887384 -173.87697) (xy 43.812201 -173.87697) (xy 43.782086 -173.922489)
			(xy 43.744869 -173.964026) (xy 43.702001 -173.999701) (xy 43.654395 -174.028755) (xy 43.603066 -174.050567)
			(xy 43.549109 -174.064673) (xy 43.493672 -174.070773) (xy 43.437938 -174.068736) (xy 43.383095 -174.058606)
			(xy 43.330311 -174.040599) (xy 43.280711 -174.015098) (xy 43.235353 -173.982647) (xy 43.195204 -173.943938)
			(xy 43.161118 -173.899795) (xy 43.133822 -173.85116) (xy 43.113899 -173.799069) (xy 43.101773 -173.744632)
			(xy 43.097702 -173.68901) (xy 42.749436 -173.68901) (xy 42.77922 -173.717035) (xy 42.81357 -173.760295)
			(xy 42.841322 -173.808057) (xy 42.861895 -173.859322) (xy 42.87486 -173.913018) (xy 42.879946 -173.968023)
			(xy 42.877046 -174.023186) (xy 42.866221 -174.077354) (xy 42.85742 -174.103538) (xy 42.849985 -174.126018)
			(xy 42.842642 -174.172787) (xy 42.84409 -174.220106) (xy 42.854278 -174.266339) (xy 42.872854 -174.309884)
			(xy 42.899175 -174.349235) (xy 42.932331 -174.383028) (xy 42.971172 -174.410095) (xy 42.992548 -174.420276)
			(xy 43.017542 -174.432052) (xy 43.064124 -174.461763) (xy 43.105933 -174.497882) (xy 43.142096 -174.539654)
			(xy 43.171857 -174.586204) (xy 43.194592 -174.63656) (xy 43.209828 -174.689668) (xy 43.217245 -174.744418)
			(xy 43.216688 -174.799666) (xy 43.208169 -174.854256) (xy 43.191865 -174.907046) (xy 43.189376 -174.912274)
			(xy 45.07941 -174.912274) (xy 45.083481 -174.856652) (xy 45.095607 -174.802215) (xy 45.11553 -174.750124)
			(xy 45.142826 -174.701489) (xy 45.176912 -174.657346) (xy 45.217061 -174.618637) (xy 45.262419 -174.586186)
			(xy 45.312019 -174.560685) (xy 45.364803 -174.542678) (xy 45.419646 -174.532548) (xy 45.47538 -174.530511)
			(xy 45.530817 -174.536611) (xy 45.584774 -174.550717) (xy 45.636103 -174.572529) (xy 45.683709 -174.601583)
			(xy 45.726577 -174.637258) (xy 45.763794 -174.678795) (xy 45.794567 -174.725308) (xy 45.818239 -174.775805)
			(xy 45.834307 -174.829212) (xy 45.842427 -174.884388) (xy 45.842936 -174.912274) (xy 45.842427 -174.94016)
			(xy 45.834307 -174.995336) (xy 45.818239 -175.048743) (xy 45.794567 -175.09924) (xy 45.763794 -175.145753)
			(xy 45.726577 -175.18729) (xy 45.683709 -175.222965) (xy 45.636103 -175.252019) (xy 45.584774 -175.273831)
			(xy 45.530817 -175.287937) (xy 45.47538 -175.294037) (xy 45.419646 -175.292) (xy 45.364803 -175.28187)
			(xy 45.312019 -175.263863) (xy 45.262419 -175.238362) (xy 45.217061 -175.205911) (xy 45.176912 -175.167202)
			(xy 45.142826 -175.123059) (xy 45.11553 -175.074424) (xy 45.095607 -175.022333) (xy 45.083481 -174.967896)
			(xy 45.07941 -174.912274) (xy 43.189376 -174.912274) (xy 43.168119 -174.956933) (xy 43.137426 -175.002874)
			(xy 43.100428 -175.043907) (xy 43.057899 -175.079176) (xy 43.010728 -175.107942) (xy 42.959901 -175.129605)
			(xy 42.906481 -175.14371) (xy 42.851586 -175.149964) (xy 42.796363 -175.148235) (xy 42.741966 -175.138559)
			(xy 42.689533 -175.12114) (xy 42.640161 -175.09634) (xy 42.594882 -175.064679) (xy 42.554643 -175.026819)
			(xy 42.520284 -174.983551) (xy 42.492525 -174.93578) (xy 42.471946 -174.884506) (xy 42.458977 -174.830799)
			(xy 42.45389 -174.775783) (xy 42.45679 -174.720609) (xy 42.467617 -174.66643) (xy 42.47642 -174.64024)
			(xy 42.483857 -174.617762) (xy 42.491196 -174.570993) (xy 42.489745 -174.523674) (xy 42.479555 -174.477443)
			(xy 42.460978 -174.433899) (xy 42.434658 -174.394549) (xy 42.401505 -174.360754) (xy 42.362667 -174.333685)
			(xy 42.341292 -174.323502) (xy 42.316333 -174.311662) (xy 42.269766 -174.281949) (xy 42.227971 -174.24583)
			(xy 42.191822 -174.204062) (xy 42.162074 -174.157517) (xy 42.13935 -174.107169) (xy 42.124125 -174.054069)
			(xy 42.116716 -173.999329) (xy 41.749248 -173.999329) (xy 41.740903 -174.017204) (xy 41.727374 -174.039022)
			(xy 41.715992 -174.057655) (xy 41.699031 -174.097882) (xy 41.689193 -174.140416) (xy 41.686768 -174.184006)
			(xy 41.691826 -174.227369) (xy 41.70422 -174.269229) (xy 41.723585 -174.308357) (xy 41.749351 -174.343599)
			(xy 41.78076 -174.373921) (xy 41.816888 -174.39843) (xy 41.836594 -174.40783) (xy 41.862709 -174.420271)
			(xy 41.911205 -174.4518) (xy 41.954389 -174.490285) (xy 41.991271 -174.534845) (xy 42.021007 -174.584461)
			(xy 42.042917 -174.637995) (xy 42.056498 -174.694222) (xy 42.061439 -174.751854) (xy 42.057628 -174.809572)
			(xy 42.045152 -174.866055) (xy 42.035222 -174.893224) (xy 42.02744 -174.91469) (xy 42.018789 -174.959516)
			(xy 42.018292 -175.005167) (xy 42.025965 -175.050171) (xy 42.041561 -175.093078) (xy 42.064578 -175.132505)
			(xy 42.094273 -175.167181) (xy 42.12969 -175.195989) (xy 42.169687 -175.218) (xy 42.191178 -175.22571)
			(xy 42.21708 -175.235002) (xy 42.266172 -175.259857) (xy 42.311185 -175.291507) (xy 42.351184 -175.329295)
			(xy 42.38534 -175.372436) (xy 42.412944 -175.420037) (xy 42.433424 -175.47111) (xy 42.446355 -175.524595)
			(xy 42.451468 -175.579382) (xy 42.448658 -175.634336) (xy 42.437983 -175.688317) (xy 42.419665 -175.740204)
			(xy 42.394082 -175.788921) (xy 42.361767 -175.833458) (xy 42.323388 -175.872891) (xy 42.279744 -175.906401)
			(xy 42.231738 -175.933295) (xy 42.180366 -175.953013) (xy 42.126695 -175.965147) (xy 42.071837 -175.969445)
			(xy 42.016931 -175.965819) (xy 41.963116 -175.954342) (xy 41.911507 -175.935254) (xy 41.863175 -175.90895)
			(xy 41.819124 -175.875976) (xy 41.780266 -175.837015) (xy 41.747408 -175.792877) (xy 41.721231 -175.744477)
			(xy 41.702279 -175.692818) (xy 41.690944 -175.638972) (xy 41.687462 -175.584057) (xy 41.691905 -175.52921)
			(xy 41.70418 -175.475571) (xy 41.713658 -175.449738) (xy 41.721496 -175.428291) (xy 41.730144 -175.383458)
			(xy 41.730636 -175.337802) (xy 41.722956 -175.292793) (xy 41.707353 -175.249883) (xy 41.684329 -175.210454)
			(xy 41.654626 -175.175777) (xy 41.619201 -175.14697) (xy 41.579196 -175.124961) (xy 41.557702 -175.117252)
			(xy 41.530208 -175.107377) (xy 41.478344 -175.080496) (xy 41.431172 -175.046039) (xy 41.389789 -175.00481)
			(xy 41.372028 -174.981616) (xy 41.357633 -174.963071) (xy 41.323364 -174.931) (xy 41.283786 -174.90577)
			(xy 41.240248 -174.88824) (xy 41.19423 -174.879006) (xy 41.147298 -174.878383) (xy 41.101051 -174.886392)
			(xy 41.057062 -174.902759) (xy 41.016829 -174.92693) (xy 40.98172 -174.958079) (xy 40.966898 -174.976282)
			(xy 40.949388 -174.998019) (xy 40.909074 -175.036621) (xy 40.863566 -175.068938) (xy 40.813834 -175.094279)
			(xy 40.760941 -175.112104) (xy 40.706016 -175.122032) (xy 40.65023 -175.123852) (xy 40.594774 -175.117524)
			(xy 40.540832 -175.103184) (xy 40.489555 -175.081138) (xy 40.442037 -175.051856) (xy 40.399293 -175.015963)
			(xy 40.362234 -174.974225) (xy 40.331652 -174.927533) (xy 40.308199 -174.876884) (xy 40.292376 -174.823358)
			(xy 40.284521 -174.768098) (xy 40.2848 -174.712283) (xy 40.293209 -174.657105) (xy 40.309568 -174.60374)
			(xy 40.333527 -174.553328) (xy 40.364575 -174.506946) (xy 40.40205 -174.465581) (xy 40.445152 -174.430119)
			(xy 40.492961 -174.401314) (xy 40.544457 -174.379783) (xy 40.59854 -174.365984) (xy 40.654056 -174.360213)
			(xy 40.709821 -174.362591) (xy 40.764644 -174.373069) (xy 40.817356 -174.391423) (xy 40.866831 -174.417262)
			(xy 40.912013 -174.450033) (xy 40.951939 -174.489037) (xy 40.985755 -174.533442) (xy 41.012741 -174.5823)
			(xy 41.032321 -174.634569) (xy 41.044076 -174.689133) (xy 41.0464 -174.716948) (xy 41.04789 -174.732671)
			(xy 41.057696 -174.762683) (xy 41.07458 -174.789364) (xy 41.097505 -174.811075) (xy 41.125064 -174.826484)
			(xy 41.155566 -174.834645) (xy 41.187137 -174.835056) (xy 41.217841 -174.827694) (xy 41.245793 -174.813008)
			(xy 41.269276 -174.791902) (xy 41.28685 -174.765671) (xy 41.297435 -174.735924) (xy 41.299384 -174.72025)
			(xy 41.30281 -174.68998) (xy 41.318087 -174.631011) (xy 41.342553 -174.575224) (xy 41.358566 -174.549308)
			(xy 41.369937 -174.530668) (xy 41.386906 -174.490443) (xy 41.396751 -174.447909) (xy 41.399181 -174.404319)
			(xy 41.394125 -174.360954) (xy 41.381732 -174.319092) (xy 41.362367 -174.279964) (xy 41.336599 -174.244722)
			(xy 41.305186 -174.214402) (xy 41.269054 -174.189897) (xy 41.249346 -174.1805) (xy 41.222747 -174.16785)
			(xy 41.173453 -174.135614) (xy 41.129694 -174.096192) (xy 41.092507 -174.050518) (xy 41.062774 -173.999677)
			(xy 41.05148 -173.972474) (xy 41.042413 -173.950986) (xy 41.017738 -173.911418) (xy 40.986253 -173.877021)
			(xy 40.949017 -173.848951) (xy 40.907282 -173.828153) (xy 40.86245 -173.815324) (xy 40.81603 -173.810897)
			(xy 40.769582 -173.815021) (xy 40.724667 -173.827557) (xy 40.7035 -173.837346) (xy 40.678375 -173.849058)
			(xy 40.625578 -173.865945) (xy 40.570893 -173.875014) (xy 40.515471 -173.876074) (xy 40.46048 -173.869101)
			(xy 40.407076 -173.854244) (xy 40.356384 -173.831815) (xy 40.309473 -173.802285) (xy 40.267328 -173.766278)
			(xy 40.230839 -173.72455) (xy 40.200772 -173.677981) (xy 40.177761 -173.627551) (xy 40.162291 -173.574321)
			(xy 40.154686 -173.519414) (xy 38.64945 -173.519414) (xy 38.646499 -173.52571) (xy 38.615726 -173.572223)
			(xy 38.578509 -173.61376) (xy 38.535641 -173.649435) (xy 38.488035 -173.678489) (xy 38.436706 -173.700301)
			(xy 38.382749 -173.714407) (xy 38.327312 -173.720507) (xy 38.271578 -173.71847) (xy 38.216735 -173.70834)
			(xy 38.163951 -173.690333) (xy 38.114351 -173.664832) (xy 38.068993 -173.632381) (xy 38.028844 -173.593672)
			(xy 37.994758 -173.549529) (xy 37.967462 -173.500894) (xy 37.947539 -173.448803) (xy 37.935413 -173.394366)
			(xy 37.931342 -173.338744) (xy 36.892918 -173.338744) (xy 36.903921 -173.375316) (xy 36.912041 -173.430492)
			(xy 36.91255 -173.458378) (xy 36.912041 -173.486264) (xy 36.903921 -173.54144) (xy 36.887853 -173.594847)
			(xy 36.864181 -173.645344) (xy 36.833408 -173.691857) (xy 36.796191 -173.733394) (xy 36.753323 -173.769069)
			(xy 36.705717 -173.798123) (xy 36.654388 -173.819935) (xy 36.600431 -173.834041) (xy 36.544994 -173.840141)
			(xy 36.48926 -173.838104) (xy 36.434417 -173.827974) (xy 36.381633 -173.809967) (xy 36.332033 -173.784466)
			(xy 36.286675 -173.752015) (xy 36.246526 -173.713306) (xy 36.21244 -173.669163) (xy 36.185144 -173.620528)
			(xy 36.165221 -173.568437) (xy 36.153095 -173.514) (xy 36.149024 -173.458378) (xy 34.531188 -173.458378)
			(xy 34.532447 -173.474342) (xy 34.528691 -173.529977) (xy 34.516874 -173.584471) (xy 34.49725 -173.636664)
			(xy 34.470235 -173.685444) (xy 34.436405 -173.729771) (xy 34.396483 -173.768699) (xy 34.351317 -173.8014)
			(xy 34.32683 -173.81474) (xy 34.307465 -173.825283) (xy 34.272463 -173.852092) (xy 34.242617 -173.884544)
			(xy 34.218826 -173.921664) (xy 34.201805 -173.962335) (xy 34.192064 -174.005335) (xy 34.189898 -174.049371)
			(xy 34.195371 -174.09312) (xy 34.208319 -174.135266) (xy 34.228352 -174.174541) (xy 34.241232 -174.192438)
			(xy 34.257204 -174.214434) (xy 34.283356 -174.262088) (xy 34.30248 -174.312971) (xy 34.314189 -174.366053)
			(xy 34.318247 -174.42026) (xy 34.317712 -174.42815) (xy 34.964114 -174.42815) (xy 34.968185 -174.372528)
			(xy 34.980311 -174.318091) (xy 35.000234 -174.266) (xy 35.02753 -174.217365) (xy 35.061616 -174.173222)
			(xy 35.101765 -174.134513) (xy 35.147123 -174.102062) (xy 35.196723 -174.076561) (xy 35.249507 -174.058554)
			(xy 35.30435 -174.048424) (xy 35.360084 -174.046387) (xy 35.415521 -174.052487) (xy 35.469478 -174.066593)
			(xy 35.520807 -174.088405) (xy 35.568413 -174.117459) (xy 35.611281 -174.153134) (xy 35.648498 -174.194671)
			(xy 35.679271 -174.241184) (xy 35.702943 -174.291681) (xy 35.719011 -174.345088) (xy 35.727131 -174.400264)
			(xy 35.72764 -174.42815) (xy 35.727131 -174.456036) (xy 35.719011 -174.511212) (xy 35.702943 -174.564619)
			(xy 35.679271 -174.615116) (xy 35.650575 -174.658489) (xy 37.147143 -174.658489) (xy 37.147702 -174.603729)
			(xy 37.156084 -174.549611) (xy 37.172117 -174.497248) (xy 37.19547 -174.447714) (xy 37.225665 -174.402028)
			(xy 37.262081 -174.361128) (xy 37.30397 -174.325854) (xy 37.350472 -174.296931) (xy 37.400631 -174.274952)
			(xy 37.453417 -174.26037) (xy 37.507745 -174.253485) (xy 37.562499 -174.254436) (xy 37.616556 -174.263206)
			(xy 37.668803 -174.279613) (xy 37.718168 -174.303321) (xy 37.763636 -174.333843) (xy 37.804274 -174.370551)
			(xy 37.822124 -174.39132) (xy 37.836541 -174.408006) (xy 37.870134 -174.436567) (xy 37.908154 -174.458898)
			(xy 37.94946 -174.474329) (xy 37.992809 -174.482396) (xy 38.0369 -174.482856) (xy 38.080409 -174.475696)
			(xy 38.122027 -174.46113) (xy 38.160505 -174.439598) (xy 38.194688 -174.411744) (xy 38.209474 -174.395384)
			(xy 38.227729 -174.374974) (xy 38.269107 -174.33911) (xy 38.315188 -174.30953) (xy 38.365023 -174.286841)
			(xy 38.417591 -174.27151) (xy 38.47181 -174.263851) (xy 38.526567 -174.264022) (xy 38.580738 -174.272019)
			(xy 38.633209 -174.287678) (xy 38.682902 -174.310677) (xy 38.728797 -174.340544) (xy 38.769951 -174.376666)
			(xy 38.805518 -174.418299) (xy 38.834768 -174.46459) (xy 38.8571 -174.514587) (xy 38.872055 -174.567262)
			(xy 38.879327 -174.621535) (xy 38.878764 -174.67629) (xy 38.87038 -174.730402) (xy 38.854347 -174.782759)
			(xy 38.830993 -174.832287) (xy 38.800798 -174.877967) (xy 38.764384 -174.918862) (xy 38.722497 -174.954131)
			(xy 38.675998 -174.983049) (xy 38.625843 -175.005023) (xy 38.573062 -175.019601) (xy 38.518739 -175.026485)
			(xy 38.46399 -175.025531) (xy 38.409939 -175.01676) (xy 38.357697 -175.000353) (xy 38.308338 -174.976646)
			(xy 38.262875 -174.946126) (xy 38.222241 -174.90942) (xy 38.204394 -174.888652) (xy 38.189957 -174.871985)
			(xy 38.156366 -174.843427) (xy 38.118348 -174.821098) (xy 38.077046 -174.805668) (xy 38.0337 -174.797601)
			(xy 37.989613 -174.797138) (xy 37.946107 -174.804295) (xy 37.904491 -174.818856) (xy 37.866014 -174.840384)
			(xy 37.831831 -174.868231) (xy 37.817044 -174.884588) (xy 37.798817 -174.905025) (xy 37.757438 -174.940896)
			(xy 37.711355 -174.970483) (xy 37.661516 -174.993178) (xy 37.608945 -175.008515) (xy 37.554721 -175.016179)
			(xy 37.499959 -175.016012) (xy 37.445782 -175.008018) (xy 37.393306 -174.992362) (xy 37.343606 -174.969364)
			(xy 37.297704 -174.939497) (xy 37.256544 -174.903375) (xy 37.220971 -174.861739) (xy 37.191715 -174.815446)
			(xy 37.169378 -174.765446) (xy 37.154418 -174.712766) (xy 37.147143 -174.658489) (xy 35.650575 -174.658489)
			(xy 35.648498 -174.661629) (xy 35.611281 -174.703166) (xy 35.568413 -174.738841) (xy 35.520807 -174.767895)
			(xy 35.469478 -174.789707) (xy 35.415521 -174.803813) (xy 35.360084 -174.809913) (xy 35.30435 -174.807876)
			(xy 35.249507 -174.797746) (xy 35.196723 -174.779739) (xy 35.147123 -174.754238) (xy 35.101765 -174.721787)
			(xy 35.061616 -174.683078) (xy 35.02753 -174.638935) (xy 35.000234 -174.5903) (xy 34.980311 -174.538209)
			(xy 34.968185 -174.483772) (xy 34.964114 -174.42815) (xy 34.317712 -174.42815) (xy 34.31457 -174.474494)
			(xy 34.303233 -174.527657) (xy 34.284466 -174.578673) (xy 34.258649 -174.626509) (xy 34.226305 -174.670198)
			(xy 34.188087 -174.708853) (xy 34.14477 -174.741694) (xy 34.097231 -174.768054) (xy 34.046432 -174.787401)
			(xy 33.993401 -174.799343) (xy 33.939213 -174.803637) (xy 33.884963 -174.800198) (xy 33.831751 -174.789094)
			(xy 33.780653 -174.770551) (xy 33.732704 -174.744943) (xy 33.688875 -174.71279) (xy 33.650053 -174.674742)
			(xy 33.633156 -174.653448) (xy 33.618391 -174.635107) (xy 33.58338 -174.603636) (xy 33.543168 -174.579157)
			(xy 33.499133 -174.562509) (xy 33.452784 -174.554263) (xy 33.40571 -174.5547) (xy 33.359522 -174.563807)
			(xy 33.315804 -174.58127) (xy 33.276054 -174.606492) (xy 33.241634 -174.638608) (xy 33.227264 -174.657258)
			(xy 33.210193 -174.679507) (xy 33.170654 -174.719271) (xy 33.125721 -174.752821) (xy 33.076362 -174.779432)
			(xy 33.023639 -174.798533) (xy 32.968688 -174.809711) (xy 32.912693 -174.812727) (xy 32.85686 -174.807514)
			(xy 32.802391 -174.794186) (xy 32.750459 -174.773028) (xy 32.702183 -174.744498) (xy 32.658603 -174.70921)
			(xy 32.620657 -174.667922) (xy 32.589162 -174.621526) (xy 32.564797 -174.57102) (xy 32.548087 -174.517491)
			(xy 32.539391 -174.462093) (xy 32.538897 -174.406019) (xy 27.132404 -174.406019) (xy 27.214858 -174.45801)
			(xy 27.363212 -174.56118) (xy 27.506766 -174.67093) (xy 27.64523 -174.787036) (xy 27.778322 -174.909264)
			(xy 27.905771 -175.037364) (xy 28.027319 -175.171076) (xy 28.142718 -175.31013) (xy 28.251735 -175.454242)
			(xy 28.354148 -175.603119) (xy 28.449748 -175.75646) (xy 28.538342 -175.913953) (xy 28.61975 -176.075278)
			(xy 28.634043 -176.10709) (xy 42.701208 -176.10709) (xy 42.705279 -176.051468) (xy 42.717405 -175.997031)
			(xy 42.737328 -175.94494) (xy 42.764624 -175.896305) (xy 42.79871 -175.852162) (xy 42.838859 -175.813453)
			(xy 42.884217 -175.781002) (xy 42.933817 -175.755501) (xy 42.986601 -175.737494) (xy 43.041444 -175.727364)
			(xy 43.097178 -175.725327) (xy 43.152615 -175.731427) (xy 43.206572 -175.745533) (xy 43.257901 -175.767345)
			(xy 43.305507 -175.796399) (xy 43.348375 -175.832074) (xy 43.385592 -175.873611) (xy 43.416365 -175.920124)
			(xy 43.440037 -175.970621) (xy 43.456105 -176.024028) (xy 43.464225 -176.079204) (xy 43.464734 -176.10709)
			(xy 43.464225 -176.134976) (xy 43.456105 -176.190152) (xy 43.440037 -176.243559) (xy 43.416365 -176.294056)
			(xy 43.385592 -176.340569) (xy 43.348375 -176.382106) (xy 43.305507 -176.417781) (xy 43.257901 -176.446835)
			(xy 43.206572 -176.468647) (xy 43.152615 -176.482753) (xy 43.097178 -176.488853) (xy 43.041444 -176.486816)
			(xy 42.986601 -176.476686) (xy 42.933817 -176.458679) (xy 42.884217 -176.433178) (xy 42.838859 -176.400727)
			(xy 42.79871 -176.362018) (xy 42.764624 -176.317875) (xy 42.737328 -176.26924) (xy 42.717405 -176.217149)
			(xy 42.705279 -176.162712) (xy 42.701208 -176.10709) (xy 28.634043 -176.10709) (xy 28.693806 -176.240107)
			(xy 28.76036 -176.408105) (xy 28.819277 -176.578932) (xy 28.840073 -176.64938) (xy 33.524442 -176.64938)
			(xy 33.528513 -176.593758) (xy 33.540639 -176.539321) (xy 33.560562 -176.48723) (xy 33.587858 -176.438595)
			(xy 33.621944 -176.394452) (xy 33.662093 -176.355743) (xy 33.707451 -176.323292) (xy 33.757051 -176.297791)
			(xy 33.809835 -176.279784) (xy 33.864678 -176.269654) (xy 33.920412 -176.267617) (xy 33.975849 -176.273717)
			(xy 34.029806 -176.287823) (xy 34.081135 -176.309635) (xy 34.128741 -176.338689) (xy 34.171609 -176.374364)
			(xy 34.208826 -176.415901) (xy 34.239599 -176.462414) (xy 34.263271 -176.512911) (xy 34.279339 -176.566318)
			(xy 34.287459 -176.621494) (xy 34.287968 -176.64938) (xy 34.287459 -176.677266) (xy 34.279339 -176.732442)
			(xy 34.263271 -176.785849) (xy 34.239599 -176.836346) (xy 34.208826 -176.882859) (xy 34.171609 -176.924396)
			(xy 34.128741 -176.960071) (xy 34.122995 -176.963578) (xy 34.854386 -176.963578) (xy 34.858457 -176.907956)
			(xy 34.870583 -176.853519) (xy 34.890506 -176.801428) (xy 34.917802 -176.752793) (xy 34.951888 -176.70865)
			(xy 34.992037 -176.669941) (xy 35.037395 -176.63749) (xy 35.086995 -176.611989) (xy 35.139779 -176.593982)
			(xy 35.194622 -176.583852) (xy 35.250356 -176.581815) (xy 35.305793 -176.587915) (xy 35.35975 -176.602021)
			(xy 35.411079 -176.623833) (xy 35.458685 -176.652887) (xy 35.501553 -176.688562) (xy 35.53877 -176.730099)
			(xy 35.569543 -176.776612) (xy 35.593215 -176.827109) (xy 35.609283 -176.880516) (xy 35.617403 -176.935692)
			(xy 35.617912 -176.963578) (xy 35.617403 -176.991464) (xy 35.609283 -177.04664) (xy 35.593215 -177.100047)
			(xy 35.569543 -177.150544) (xy 35.56451 -177.158152) (xy 42.612482 -177.158152) (xy 42.613735 -177.103184)
			(xy 42.622865 -177.048966) (xy 42.639683 -176.996619) (xy 42.663841 -176.947229) (xy 42.694838 -176.901817)
			(xy 42.732034 -176.861326) (xy 42.774656 -176.826593) (xy 42.821822 -176.798338) (xy 42.872556 -176.777146)
			(xy 42.925806 -176.763456) (xy 42.98047 -176.757551) (xy 43.035416 -176.759554) (xy 43.089505 -176.769424)
			(xy 43.141617 -176.786955) (xy 43.190673 -176.811785) (xy 43.235657 -176.8434) (xy 43.275636 -176.881145)
			(xy 43.309784 -176.924237) (xy 43.337392 -176.971785) (xy 43.35789 -177.022803) (xy 43.370852 -177.076236)
			(xy 43.376009 -177.130975) (xy 43.373256 -177.185888) (xy 43.362648 -177.239838) (xy 43.344407 -177.291706)
			(xy 43.318909 -177.340418) (xy 43.286683 -177.384966) (xy 43.267884 -177.40503) (xy 43.252411 -177.421701)
			(xy 43.227079 -177.459471) (xy 43.208873 -177.501147) (xy 43.198374 -177.545398) (xy 43.195917 -177.59081)
			(xy 43.201581 -177.635935) (xy 43.215184 -177.679332) (xy 43.236293 -177.719615) (xy 43.264234 -177.755499)
			(xy 43.280838 -177.771044) (xy 43.301019 -177.789716) (xy 43.336328 -177.831859) (xy 43.365222 -177.878634)
			(xy 43.387103 -177.929072) (xy 43.401518 -177.982128) (xy 43.408167 -178.036704) (xy 43.406914 -178.091669)
			(xy 43.397784 -178.145886) (xy 43.380966 -178.19823) (xy 43.356808 -178.247618) (xy 43.325812 -178.293027)
			(xy 43.288618 -178.333517) (xy 43.245998 -178.368248) (xy 43.198834 -178.396502) (xy 43.148102 -178.417693)
			(xy 43.094854 -178.431383) (xy 43.040193 -178.437288) (xy 42.98525 -178.435285) (xy 42.931163 -178.425417)
			(xy 42.879053 -178.407887) (xy 42.829999 -178.383059) (xy 42.785016 -178.351446) (xy 42.745038 -178.313704)
			(xy 42.71089 -178.270614) (xy 42.683282 -178.223069) (xy 42.662784 -178.172054) (xy 42.649821 -178.118624)
			(xy 42.644662 -178.063887) (xy 42.647414 -178.008976) (xy 42.658018 -177.955029) (xy 42.676257 -177.903163)
			(xy 42.701752 -177.854452) (xy 42.733975 -177.809904) (xy 42.752772 -177.78984) (xy 42.76828 -177.773199)
			(xy 42.793615 -177.735424) (xy 42.811823 -177.693743) (xy 42.822321 -177.649486) (xy 42.824775 -177.604068)
			(xy 42.819106 -177.558938) (xy 42.805495 -177.515538) (xy 42.784378 -177.475253) (xy 42.756427 -177.43937)
			(xy 42.739818 -177.423826) (xy 42.71964 -177.405149) (xy 42.684328 -177.363005) (xy 42.655432 -177.316229)
			(xy 42.633549 -177.265789) (xy 42.619133 -177.212731) (xy 42.612482 -177.158152) (xy 35.56451 -177.158152)
			(xy 35.53877 -177.197057) (xy 35.501553 -177.238594) (xy 35.458685 -177.274269) (xy 35.411079 -177.303323)
			(xy 35.35975 -177.325135) (xy 35.305793 -177.339241) (xy 35.250356 -177.345341) (xy 35.194622 -177.343304)
			(xy 35.139779 -177.333174) (xy 35.086995 -177.315167) (xy 35.037395 -177.289666) (xy 34.992037 -177.257215)
			(xy 34.951888 -177.218506) (xy 34.917802 -177.174363) (xy 34.890506 -177.125728) (xy 34.870583 -177.073637)
			(xy 34.858457 -177.0192) (xy 34.854386 -176.963578) (xy 34.122995 -176.963578) (xy 34.081135 -176.989125)
			(xy 34.029806 -177.010937) (xy 33.975849 -177.025043) (xy 33.920412 -177.031143) (xy 33.864678 -177.029106)
			(xy 33.809835 -177.018976) (xy 33.757051 -177.000969) (xy 33.707451 -176.975468) (xy 33.662093 -176.943017)
			(xy 33.621944 -176.904308) (xy 33.587858 -176.860165) (xy 33.560562 -176.81153) (xy 33.540639 -176.759439)
			(xy 33.528513 -176.705002) (xy 33.524442 -176.64938) (xy 28.840073 -176.64938) (xy 28.870437 -176.75224)
			(xy 28.913736 -176.927677) (xy 28.949086 -177.104886) (xy 28.976416 -177.283509) (xy 28.995669 -177.463182)
			(xy 29.006807 -177.643539) (xy 29.009808 -177.824215) (xy 29.004664 -178.004843) (xy 28.991387 -178.185056)
			(xy 28.970003 -178.364488) (xy 28.940556 -178.542773) (xy 28.903106 -178.719551) (xy 28.857728 -178.894462)
			(xy 28.804516 -179.067151) (xy 28.743576 -179.237266) (xy 28.675034 -179.404463) (xy 28.599027 -179.568402)
			(xy 28.515711 -179.728749) (xy 28.425254 -179.88518) (xy 28.327841 -180.037376) (xy 28.223669 -180.185028)
			(xy 28.11295 -180.327836) (xy 27.995909 -180.465511) (xy 27.872784 -180.597772) (xy 27.743824 -180.724351)
			(xy 27.609291 -180.844991) (xy 27.539696 -180.90261) (xy 27.515946 -180.922625) (xy 27.473217 -180.967703)
			(xy 27.436503 -181.017803) (xy 27.406389 -181.072126) (xy 27.383354 -181.129808) (xy 27.367764 -181.189931)
			(xy 27.359868 -181.251539) (xy 27.359356 -181.282594) (xy 27.359356 -181.93385) (xy 29.017974 -181.93385)
			(xy 29.022045 -181.878228) (xy 29.034171 -181.823791) (xy 29.054094 -181.7717) (xy 29.08139 -181.723065)
			(xy 29.115476 -181.678922) (xy 29.155625 -181.640213) (xy 29.200983 -181.607762) (xy 29.250583 -181.582261)
			(xy 29.303367 -181.564254) (xy 29.35821 -181.554124) (xy 29.413944 -181.552087) (xy 29.469381 -181.558187)
			(xy 29.523338 -181.572293) (xy 29.574667 -181.594105) (xy 29.622273 -181.623159) (xy 29.665141 -181.658834)
			(xy 29.702358 -181.700371) (xy 29.733131 -181.746884) (xy 29.756803 -181.797381) (xy 29.772871 -181.850788)
			(xy 29.780991 -181.905964) (xy 29.7815 -181.93385) (xy 29.780991 -181.961736) (xy 29.772871 -182.016912)
			(xy 29.756803 -182.070319) (xy 29.733131 -182.120816) (xy 29.702358 -182.167329) (xy 29.665141 -182.208866)
			(xy 29.651022 -182.220616) (xy 32.79902 -182.220616) (xy 32.79902 -179.550822) (xy 32.799601 -179.51789)
			(xy 32.808126 -179.452579) (xy 32.825011 -179.388916) (xy 32.849971 -179.327964) (xy 32.882591 -179.270744)
			(xy 32.922325 -179.218214) (xy 32.968506 -179.171253) (xy 33.020364 -179.130645) (xy 33.077029 -179.097071)
			(xy 33.137554 -179.071093) (xy 33.169098 -179.061618) (xy 33.183292 -179.057117) (xy 33.209279 -179.042605)
			(xy 33.23119 -179.022458) (xy 33.247827 -178.997777) (xy 33.258283 -178.969908) (xy 33.260538 -178.955192)
			(xy 33.264259 -178.929082) (xy 33.277922 -178.878142) (xy 33.298466 -178.829569) (xy 33.325501 -178.784285)
			(xy 33.358512 -178.743154) (xy 33.39687 -178.706958) (xy 33.439846 -178.676387) (xy 33.48662 -178.652022)
			(xy 33.536303 -178.634327) (xy 33.562036 -178.628548) (xy 33.576306 -178.625224) (xy 33.602881 -178.612896)
			(xy 33.625931 -178.594817) (xy 33.644237 -178.571945) (xy 33.656826 -178.545493) (xy 33.660334 -178.531266)
			(xy 33.667447 -178.500756) (xy 33.688271 -178.441667) (xy 33.716199 -178.385586) (xy 33.750808 -178.333363)
			(xy 33.791574 -178.285789) (xy 33.837878 -178.243586) (xy 33.889017 -178.207394) (xy 33.944217 -178.177762)
			(xy 34.00264 -178.155139) (xy 34.063401 -178.139868) (xy 34.125579 -178.13218) (xy 34.156904 -178.131724)
			(xy 40.14724 -178.131724) (xy 41.081452 -179.06619) (xy 41.081452 -179.147216) (xy 42.612054 -179.147216)
			(xy 42.616125 -179.091594) (xy 42.628251 -179.037157) (xy 42.648174 -178.985066) (xy 42.67547 -178.936431)
			(xy 42.709556 -178.892288) (xy 42.749705 -178.853579) (xy 42.795063 -178.821128) (xy 42.844663 -178.795627)
			(xy 42.897447 -178.77762) (xy 42.95229 -178.76749) (xy 43.008024 -178.765453) (xy 43.063461 -178.771553)
			(xy 43.117418 -178.785659) (xy 43.168747 -178.807471) (xy 43.216353 -178.836525) (xy 43.259221 -178.8722)
			(xy 43.296438 -178.913737) (xy 43.327211 -178.96025) (xy 43.350883 -179.010747) (xy 43.366951 -179.064154)
			(xy 43.375071 -179.11933) (xy 43.37558 -179.147216) (xy 43.375071 -179.175102) (xy 43.366951 -179.230278)
			(xy 43.350883 -179.283685) (xy 43.334843 -179.317902) (xy 44.900615 -179.317902) (xy 44.90449 -179.26363)
			(xy 44.916037 -179.210459) (xy 44.935021 -179.159468) (xy 44.961057 -179.111691) (xy 44.993617 -179.068098)
			(xy 45.03204 -179.029573) (xy 45.053504 -179.01285) (xy 45.071995 -178.998287) (xy 45.10375 -178.963552)
			(xy 45.128567 -178.923565) (xy 45.145599 -178.879692) (xy 45.154264 -178.833434) (xy 45.154264 -178.786371)
			(xy 45.145601 -178.740113) (xy 45.12857 -178.69624) (xy 45.103753 -178.656252) (xy 45.071999 -178.621516)
			(xy 45.053504 -178.606958) (xy 45.032044 -178.59023) (xy 44.99362 -178.551706) (xy 44.961059 -178.508113)
			(xy 44.935023 -178.460337) (xy 44.916038 -178.409346) (xy 44.904491 -178.356175) (xy 44.900615 -178.301902)
			(xy 44.90449 -178.24763) (xy 44.916037 -178.194459) (xy 44.935021 -178.143468) (xy 44.961057 -178.095691)
			(xy 44.993617 -178.052098) (xy 45.03204 -178.013573) (xy 45.053504 -177.99685) (xy 45.071995 -177.982287)
			(xy 45.10375 -177.947552) (xy 45.128567 -177.907565) (xy 45.145599 -177.863692) (xy 45.154264 -177.817434)
			(xy 45.154264 -177.770371) (xy 45.145601 -177.724113) (xy 45.12857 -177.68024) (xy 45.103753 -177.640252)
			(xy 45.071999 -177.605516) (xy 45.053504 -177.590958) (xy 45.031383 -177.573725) (xy 44.991958 -177.53385)
			(xy 44.958794 -177.488633) (xy 44.932607 -177.439049) (xy 44.91396 -177.386166) (xy 44.903254 -177.331123)
			(xy 44.900722 -177.275106) (xy 44.906416 -177.219321) (xy 44.920214 -177.164971) (xy 44.94182 -177.113226)
			(xy 44.970767 -177.065201) (xy 45.006433 -177.02193) (xy 45.048048 -176.984347) (xy 45.094717 -176.95326)
			(xy 45.145433 -176.929339) (xy 45.199104 -176.913099) (xy 45.254575 -176.904891) (xy 45.310649 -176.904891)
			(xy 45.36612 -176.913099) (xy 45.419791 -176.929339) (xy 45.470507 -176.95326) (xy 45.517176 -176.984347)
			(xy 45.558791 -177.02193) (xy 45.594457 -177.065201) (xy 45.623404 -177.113226) (xy 45.64501 -177.164971)
			(xy 45.658808 -177.219321) (xy 45.664502 -177.275106) (xy 45.66197 -177.331123) (xy 45.651264 -177.386166)
			(xy 45.632617 -177.439049) (xy 45.60643 -177.488633) (xy 45.573266 -177.53385) (xy 45.533841 -177.573725)
			(xy 45.51172 -177.590958) (xy 45.493219 -177.60551) (xy 45.461462 -177.640246) (xy 45.436642 -177.680235)
			(xy 45.419609 -177.724109) (xy 45.410944 -177.77037) (xy 45.410945 -177.817435) (xy 45.41961 -177.863695)
			(xy 45.436644 -177.90757) (xy 45.461465 -177.947558) (xy 45.493223 -177.982293) (xy 45.51172 -177.99685)
			(xy 45.533187 -178.013569) (xy 45.571609 -178.052095) (xy 45.604168 -178.095689) (xy 45.630202 -178.143467)
			(xy 45.649185 -178.194459) (xy 45.660731 -178.24763) (xy 45.664606 -178.301902) (xy 45.660731 -178.356175)
			(xy 45.649184 -178.409346) (xy 45.6302 -178.460338) (xy 45.604165 -178.508115) (xy 45.571606 -178.551708)
			(xy 45.533183 -178.590234) (xy 45.51172 -178.606958) (xy 45.493219 -178.62151) (xy 45.461462 -178.656246)
			(xy 45.436642 -178.696235) (xy 45.419609 -178.740109) (xy 45.410944 -178.78637) (xy 45.410945 -178.833435)
			(xy 45.41961 -178.879695) (xy 45.436644 -178.92357) (xy 45.461465 -178.963558) (xy 45.493223 -178.998293)
			(xy 45.51172 -179.01285) (xy 45.533187 -179.029569) (xy 45.571609 -179.068095) (xy 45.604168 -179.111689)
			(xy 45.630202 -179.159467) (xy 45.649185 -179.210459) (xy 45.660731 -179.26363) (xy 45.664606 -179.317902)
			(xy 45.660731 -179.372175) (xy 45.649184 -179.425346) (xy 45.6302 -179.476338) (xy 45.604165 -179.524115)
			(xy 45.571606 -179.567708) (xy 45.533183 -179.606234) (xy 45.51172 -179.622958) (xy 45.493219 -179.63751)
			(xy 45.461462 -179.672246) (xy 45.436642 -179.712235) (xy 45.419609 -179.756109) (xy 45.410944 -179.80237)
			(xy 45.410945 -179.849435) (xy 45.41961 -179.895695) (xy 45.436644 -179.93957) (xy 45.436844 -179.939893)
			(xy 47.305259 -179.939893) (xy 47.306702 -179.884975) (xy 47.316005 -179.830832) (xy 47.332978 -179.778582)
			(xy 47.357268 -179.729307) (xy 47.388374 -179.684025) (xy 47.425653 -179.643672) (xy 47.446692 -179.626006)
			(xy 47.463705 -179.611635) (xy 47.492912 -179.578021) (xy 47.515811 -179.539829) (xy 47.5317 -179.498229)
			(xy 47.540092 -179.454497) (xy 47.54073 -179.409971) (xy 47.533596 -179.366016) (xy 47.518906 -179.323978)
			(xy 47.497112 -179.285145) (xy 47.46888 -179.250707) (xy 47.45228 -179.235862) (xy 47.43171 -179.217652)
			(xy 47.395575 -179.17627) (xy 47.365748 -179.130133) (xy 47.342847 -179.080196) (xy 47.327343 -179.027491)
			(xy 47.319559 -178.973107) (xy 47.319654 -178.918169) (xy 47.327628 -178.863813) (xy 47.343314 -178.811161)
			(xy 47.366389 -178.761304) (xy 47.396376 -178.715272) (xy 47.432654 -178.674016) (xy 47.474475 -178.638389)
			(xy 47.520972 -178.609128) (xy 47.571185 -178.586838) (xy 47.624076 -178.571979) (xy 47.678551 -178.56486)
			(xy 47.733483 -178.565626) (xy 47.787739 -178.574263) (xy 47.840194 -178.590591) (xy 47.889766 -178.614274)
			(xy 47.935428 -178.644821) (xy 47.976238 -178.681601) (xy 48.011352 -178.723853) (xy 48.040042 -178.770704)
			(xy 48.061717 -178.821186) (xy 48.075929 -178.874254) (xy 48.082382 -178.928812) (xy 48.080945 -178.983731)
			(xy 48.071646 -179.037877) (xy 48.054678 -179.090129) (xy 48.030392 -179.139407) (xy 47.999289 -179.184694)
			(xy 47.962014 -179.225051) (xy 47.940976 -179.24272) (xy 47.923939 -179.257063) (xy 47.894735 -179.290683)
			(xy 47.87184 -179.32888) (xy 47.855955 -179.370483) (xy 47.847566 -179.414218) (xy 47.84693 -179.458747)
			(xy 47.854067 -179.502704) (xy 47.868759 -179.544743) (xy 47.890555 -179.583578) (xy 47.918787 -179.618017)
			(xy 47.935388 -179.632864) (xy 47.955925 -179.651112) (xy 47.992057 -179.692495) (xy 48.02188 -179.738631)
			(xy 48.044779 -179.788569) (xy 48.060279 -179.841273) (xy 48.06806 -179.895656) (xy 48.067961 -179.950593)
			(xy 48.059985 -180.004948) (xy 48.044295 -180.057597) (xy 48.021217 -180.107451) (xy 47.991228 -180.153481)
			(xy 47.954948 -180.194733) (xy 47.913126 -180.230356) (xy 47.866628 -180.259613) (xy 47.816414 -180.281899)
			(xy 47.763524 -180.296754) (xy 47.70905 -180.303869) (xy 47.654118 -180.303098) (xy 47.599865 -180.294457)
			(xy 47.547412 -180.278125) (xy 47.497844 -180.25444) (xy 47.452185 -180.22389) (xy 47.411379 -180.187107)
			(xy 47.37627 -180.144853) (xy 47.347584 -180.098) (xy 47.325914 -180.047518) (xy 47.311708 -179.99445)
			(xy 47.305259 -179.939893) (xy 45.436844 -179.939893) (xy 45.461465 -179.979558) (xy 45.493223 -180.014293)
			(xy 45.51172 -180.02885) (xy 45.533841 -180.046083) (xy 45.573266 -180.085958) (xy 45.60643 -180.131175)
			(xy 45.632617 -180.180759) (xy 45.651264 -180.233642) (xy 45.66197 -180.288685) (xy 45.664502 -180.344702)
			(xy 45.658808 -180.400487) (xy 45.64501 -180.454837) (xy 45.623404 -180.506582) (xy 45.594457 -180.554607)
			(xy 45.558791 -180.597878) (xy 45.517176 -180.635461) (xy 45.470507 -180.666548) (xy 45.419791 -180.690469)
			(xy 45.36612 -180.706709) (xy 45.310649 -180.714917) (xy 45.254575 -180.714917) (xy 45.199104 -180.706709)
			(xy 45.145433 -180.690469) (xy 45.094717 -180.666548) (xy 45.048048 -180.635461) (xy 45.006433 -180.597878)
			(xy 44.970767 -180.554607) (xy 44.94182 -180.506582) (xy 44.920214 -180.454837) (xy 44.906416 -180.400487)
			(xy 44.900722 -180.344702) (xy 44.903254 -180.288685) (xy 44.91396 -180.233642) (xy 44.932607 -180.180759)
			(xy 44.958794 -180.131175) (xy 44.991958 -180.085958) (xy 45.031383 -180.046083) (xy 45.053504 -180.02885)
			(xy 45.071995 -180.014287) (xy 45.10375 -179.979552) (xy 45.128567 -179.939565) (xy 45.145599 -179.895692)
			(xy 45.154264 -179.849434) (xy 45.154264 -179.802371) (xy 45.145601 -179.756113) (xy 45.12857 -179.71224)
			(xy 45.103753 -179.672252) (xy 45.071999 -179.637516) (xy 45.053504 -179.622958) (xy 45.032044 -179.60623)
			(xy 44.99362 -179.567706) (xy 44.961059 -179.524113) (xy 44.935023 -179.476337) (xy 44.916038 -179.425346)
			(xy 44.904491 -179.372175) (xy 44.900615 -179.317902) (xy 43.334843 -179.317902) (xy 43.327211 -179.334182)
			(xy 43.296438 -179.380695) (xy 43.259221 -179.422232) (xy 43.216353 -179.457907) (xy 43.168747 -179.486961)
			(xy 43.117418 -179.508773) (xy 43.063461 -179.522879) (xy 43.008024 -179.528979) (xy 42.95229 -179.526942)
			(xy 42.897447 -179.516812) (xy 42.844663 -179.498805) (xy 42.795063 -179.473304) (xy 42.749705 -179.440853)
			(xy 42.709556 -179.402144) (xy 42.67547 -179.358001) (xy 42.648174 -179.309366) (xy 42.628251 -179.257275)
			(xy 42.616125 -179.202838) (xy 42.612054 -179.147216) (xy 41.081452 -179.147216) (xy 41.081452 -180.477668)
			(xy 42.678856 -180.477668) (xy 42.682927 -180.422046) (xy 42.695053 -180.367609) (xy 42.714976 -180.315518)
			(xy 42.742272 -180.266883) (xy 42.776358 -180.22274) (xy 42.816507 -180.184031) (xy 42.861865 -180.15158)
			(xy 42.911465 -180.126079) (xy 42.964249 -180.108072) (xy 43.019092 -180.097942) (xy 43.074826 -180.095905)
			(xy 43.130263 -180.102005) (xy 43.18422 -180.116111) (xy 43.235549 -180.137923) (xy 43.283155 -180.166977)
			(xy 43.326023 -180.202652) (xy 43.36324 -180.244189) (xy 43.394013 -180.290702) (xy 43.417685 -180.341199)
			(xy 43.433753 -180.394606) (xy 43.441873 -180.449782) (xy 43.442382 -180.477668) (xy 43.441873 -180.505554)
			(xy 43.433753 -180.56073) (xy 43.417685 -180.614137) (xy 43.394013 -180.664634) (xy 43.36324 -180.711147)
			(xy 43.326023 -180.752684) (xy 43.283155 -180.788359) (xy 43.235549 -180.817413) (xy 43.18422 -180.839225)
			(xy 43.130263 -180.853331) (xy 43.074826 -180.859431) (xy 43.019092 -180.857394) (xy 42.964249 -180.847264)
			(xy 42.911465 -180.829257) (xy 42.861865 -180.803756) (xy 42.816507 -180.771305) (xy 42.776358 -180.732596)
			(xy 42.742272 -180.688453) (xy 42.714976 -180.639818) (xy 42.695053 -180.587727) (xy 42.682927 -180.53329)
			(xy 42.678856 -180.477668) (xy 41.081452 -180.477668) (xy 41.081452 -180.974746) (xy 46.719742 -180.974746)
			(xy 46.723813 -180.919124) (xy 46.735939 -180.864687) (xy 46.755862 -180.812596) (xy 46.783158 -180.763961)
			(xy 46.817244 -180.719818) (xy 46.857393 -180.681109) (xy 46.902751 -180.648658) (xy 46.952351 -180.623157)
			(xy 47.005135 -180.60515) (xy 47.059978 -180.59502) (xy 47.115712 -180.592983) (xy 47.171149 -180.599083)
			(xy 47.225106 -180.613189) (xy 47.276435 -180.635001) (xy 47.324041 -180.664055) (xy 47.366909 -180.69973)
			(xy 47.404126 -180.741267) (xy 47.434899 -180.78778) (xy 47.458571 -180.838277) (xy 47.474639 -180.891684)
			(xy 47.482759 -180.94686) (xy 47.483268 -180.974746) (xy 47.482759 -181.002632) (xy 47.48219 -181.006496)
			(xy 48.368202 -181.006496) (xy 48.372273 -180.950874) (xy 48.384399 -180.896437) (xy 48.404322 -180.844346)
			(xy 48.431618 -180.795711) (xy 48.465704 -180.751568) (xy 48.505853 -180.712859) (xy 48.551211 -180.680408)
			(xy 48.600811 -180.654907) (xy 48.653595 -180.6369) (xy 48.708438 -180.62677) (xy 48.764172 -180.624733)
			(xy 48.819609 -180.630833) (xy 48.873566 -180.644939) (xy 48.924895 -180.666751) (xy 48.972501 -180.695805)
			(xy 49.015369 -180.73148) (xy 49.052586 -180.773017) (xy 49.083359 -180.81953) (xy 49.107031 -180.870027)
			(xy 49.123099 -180.923434) (xy 49.131219 -180.97861) (xy 49.131728 -181.006496) (xy 49.131219 -181.034382)
			(xy 49.123099 -181.089558) (xy 49.107031 -181.142965) (xy 49.083359 -181.193462) (xy 49.052586 -181.239975)
			(xy 49.015369 -181.281512) (xy 48.972501 -181.317187) (xy 48.924895 -181.346241) (xy 48.873566 -181.368053)
			(xy 48.819609 -181.382159) (xy 48.764172 -181.388259) (xy 48.708438 -181.386222) (xy 48.653595 -181.376092)
			(xy 48.600811 -181.358085) (xy 48.551211 -181.332584) (xy 48.505853 -181.300133) (xy 48.465704 -181.261424)
			(xy 48.431618 -181.217281) (xy 48.404322 -181.168646) (xy 48.384399 -181.116555) (xy 48.372273 -181.062118)
			(xy 48.368202 -181.006496) (xy 47.48219 -181.006496) (xy 47.474639 -181.057808) (xy 47.458571 -181.111215)
			(xy 47.434899 -181.161712) (xy 47.404126 -181.208225) (xy 47.366909 -181.249762) (xy 47.324041 -181.285437)
			(xy 47.276435 -181.314491) (xy 47.225106 -181.336303) (xy 47.171149 -181.350409) (xy 47.115712 -181.356509)
			(xy 47.059978 -181.354472) (xy 47.005135 -181.344342) (xy 46.952351 -181.326335) (xy 46.902751 -181.300834)
			(xy 46.857393 -181.268383) (xy 46.817244 -181.229674) (xy 46.783158 -181.185531) (xy 46.755862 -181.136896)
			(xy 46.735939 -181.084805) (xy 46.723813 -181.030368) (xy 46.719742 -180.974746) (xy 41.081452 -180.974746)
			(xy 41.081452 -181.780942) (xy 43.091098 -181.780942) (xy 43.095169 -181.72532) (xy 43.107295 -181.670883)
			(xy 43.127218 -181.618792) (xy 43.154514 -181.570157) (xy 43.1886 -181.526014) (xy 43.228749 -181.487305)
			(xy 43.274107 -181.454854) (xy 43.323707 -181.429353) (xy 43.376491 -181.411346) (xy 43.431334 -181.401216)
			(xy 43.487068 -181.399179) (xy 43.542505 -181.405279) (xy 43.596462 -181.419385) (xy 43.647791 -181.441197)
			(xy 43.695397 -181.470251) (xy 43.738265 -181.505926) (xy 43.775482 -181.547463) (xy 43.806255 -181.593976)
			(xy 43.829927 -181.644473) (xy 43.845995 -181.69788) (xy 43.854115 -181.753056) (xy 43.854624 -181.780942)
			(xy 43.854115 -181.808828) (xy 43.845995 -181.864004) (xy 43.829927 -181.917411) (xy 43.806255 -181.967908)
			(xy 43.775482 -182.014421) (xy 43.738265 -182.055958) (xy 43.695397 -182.091633) (xy 43.647791 -182.120687)
			(xy 43.596462 -182.142499) (xy 43.542505 -182.156605) (xy 43.487068 -182.162705) (xy 43.431334 -182.160668)
			(xy 43.376491 -182.150538) (xy 43.323707 -182.132531) (xy 43.274107 -182.10703) (xy 43.228749 -182.074579)
			(xy 43.1886 -182.03587) (xy 43.154514 -181.991727) (xy 43.127218 -181.943092) (xy 43.107295 -181.891001)
			(xy 43.095169 -181.836564) (xy 43.091098 -181.780942) (xy 41.081452 -181.780942) (xy 41.081452 -182.220362)
			(xy 40.951658 -182.350156) (xy 45.546262 -182.350156) (xy 45.550333 -182.294534) (xy 45.562459 -182.240097)
			(xy 45.582382 -182.188006) (xy 45.609678 -182.139371) (xy 45.643764 -182.095228) (xy 45.683913 -182.056519)
			(xy 45.729271 -182.024068) (xy 45.778871 -181.998567) (xy 45.831655 -181.98056) (xy 45.886498 -181.97043)
			(xy 45.942232 -181.968393) (xy 45.997669 -181.974493) (xy 46.051626 -181.988599) (xy 46.102955 -182.010411)
			(xy 46.150561 -182.039465) (xy 46.193429 -182.07514) (xy 46.230646 -182.116677) (xy 46.261419 -182.16319)
			(xy 46.285091 -182.213687) (xy 46.301159 -182.267094) (xy 46.309279 -182.32227) (xy 46.309788 -182.350156)
			(xy 46.309279 -182.378042) (xy 46.301159 -182.433218) (xy 46.285091 -182.486625) (xy 46.261419 -182.537122)
			(xy 46.230646 -182.583635) (xy 46.193429 -182.625172) (xy 46.150561 -182.660847) (xy 46.102955 -182.689901)
			(xy 46.051626 -182.711713) (xy 45.997669 -182.725819) (xy 45.942232 -182.731919) (xy 45.886498 -182.729882)
			(xy 45.831655 -182.719752) (xy 45.778871 -182.701745) (xy 45.729271 -182.676244) (xy 45.683913 -182.643793)
			(xy 45.643764 -182.605084) (xy 45.609678 -182.560941) (xy 45.582382 -182.512306) (xy 45.562459 -182.460215)
			(xy 45.550333 -182.405778) (xy 45.546262 -182.350156) (xy 40.951658 -182.350156) (xy 40.875966 -182.425848)
			(xy 33.004506 -182.425848) (xy 32.79902 -182.220616) (xy 29.651022 -182.220616) (xy 29.622273 -182.244541)
			(xy 29.574667 -182.273595) (xy 29.523338 -182.295407) (xy 29.469381 -182.309513) (xy 29.413944 -182.315613)
			(xy 29.35821 -182.313576) (xy 29.303367 -182.303446) (xy 29.250583 -182.285439) (xy 29.200983 -182.259938)
			(xy 29.155625 -182.227487) (xy 29.115476 -182.188778) (xy 29.08139 -182.144635) (xy 29.054094 -182.096)
			(xy 29.034171 -182.043909) (xy 29.022045 -181.989472) (xy 29.017974 -181.93385) (xy 27.359356 -181.93385)
			(xy 27.359356 -182.800244) (xy 27.358857 -182.868859) (xy 27.350878 -183.005857) (xy 27.337414 -183.121046)
			(xy 31.677862 -183.121046) (xy 31.681933 -183.065424) (xy 31.694059 -183.010987) (xy 31.713982 -182.958896)
			(xy 31.741278 -182.910261) (xy 31.775364 -182.866118) (xy 31.815513 -182.827409) (xy 31.860871 -182.794958)
			(xy 31.910471 -182.769457) (xy 31.963255 -182.75145) (xy 32.018098 -182.74132) (xy 32.073832 -182.739283)
			(xy 32.129269 -182.745383) (xy 32.183226 -182.759489) (xy 32.234555 -182.781301) (xy 32.282161 -182.810355)
			(xy 32.325029 -182.84603) (xy 32.362246 -182.887567) (xy 32.393019 -182.93408) (xy 32.39684 -182.94223)
			(xy 44.185584 -182.94223) (xy 44.189655 -182.886608) (xy 44.201781 -182.832171) (xy 44.221704 -182.78008)
			(xy 44.249 -182.731445) (xy 44.283086 -182.687302) (xy 44.323235 -182.648593) (xy 44.368593 -182.616142)
			(xy 44.418193 -182.590641) (xy 44.470977 -182.572634) (xy 44.52582 -182.562504) (xy 44.581554 -182.560467)
			(xy 44.636991 -182.566567) (xy 44.690948 -182.580673) (xy 44.742277 -182.602485) (xy 44.789883 -182.631539)
			(xy 44.832751 -182.667214) (xy 44.869968 -182.708751) (xy 44.900741 -182.755264) (xy 44.924413 -182.805761)
			(xy 44.940481 -182.859168) (xy 44.948601 -182.914344) (xy 44.94911 -182.94223) (xy 44.948601 -182.970116)
			(xy 44.940481 -183.025292) (xy 44.924413 -183.078699) (xy 44.900741 -183.129196) (xy 44.869968 -183.175709)
			(xy 44.832751 -183.217246) (xy 44.789883 -183.252921) (xy 44.742277 -183.281975) (xy 44.690948 -183.303787)
			(xy 44.636991 -183.317893) (xy 44.581554 -183.323993) (xy 44.52582 -183.321956) (xy 44.470977 -183.311826)
			(xy 44.418193 -183.293819) (xy 44.368593 -183.268318) (xy 44.323235 -183.235867) (xy 44.283086 -183.197158)
			(xy 44.249 -183.153015) (xy 44.221704 -183.10438) (xy 44.201781 -183.052289) (xy 44.189655 -182.997852)
			(xy 44.185584 -182.94223) (xy 32.39684 -182.94223) (xy 32.416691 -182.984577) (xy 32.432759 -183.037984)
			(xy 32.440879 -183.09316) (xy 32.441388 -183.121046) (xy 32.440879 -183.148932) (xy 32.432759 -183.204108)
			(xy 32.416691 -183.257515) (xy 32.393019 -183.308012) (xy 32.362246 -183.354525) (xy 32.325029 -183.396062)
			(xy 32.282161 -183.431737) (xy 32.234555 -183.460791) (xy 32.183226 -183.482603) (xy 32.129269 -183.496709)
			(xy 32.073832 -183.502809) (xy 32.018098 -183.500772) (xy 31.963255 -183.490642) (xy 31.910471 -183.472635)
			(xy 31.860871 -183.447134) (xy 31.815513 -183.414683) (xy 31.775364 -183.375974) (xy 31.741278 -183.331831)
			(xy 31.713982 -183.283196) (xy 31.694059 -183.231105) (xy 31.681933 -183.176668) (xy 31.677862 -183.121046)
			(xy 27.337414 -183.121046) (xy 27.334946 -183.142159) (xy 27.311117 -183.277304) (xy 27.279469 -183.410835)
			(xy 27.240111 -183.5423) (xy 27.193176 -183.671254) (xy 27.138822 -183.797261) (xy 27.077233 -183.919894)
			(xy 27.008618 -184.038739) (xy 26.933209 -184.153393) (xy 26.851261 -184.263468) (xy 26.763051 -184.368593)
			(xy 26.695746 -184.439932) (xy 33.845223 -184.439932) (xy 33.850056 -184.384021) (xy 33.863027 -184.329422)
			(xy 33.883855 -184.277311) (xy 33.912092 -184.228813) (xy 33.947127 -184.184973) (xy 33.988206 -184.146738)
			(xy 34.034441 -184.114933) (xy 34.084837 -184.090242) (xy 34.138306 -184.073199) (xy 34.193694 -184.064172)
			(xy 34.249808 -184.063355) (xy 34.305435 -184.070766) (xy 34.359378 -184.086244) (xy 34.410471 -184.109457)
			(xy 34.457614 -184.139903) (xy 34.499788 -184.176925) (xy 34.536085 -184.219726) (xy 34.565722 -184.267381)
			(xy 34.588059 -184.318863) (xy 34.595816 -184.345834) (xy 34.602289 -184.367945) (xy 34.622071 -184.409548)
			(xy 34.649023 -184.446908) (xy 34.682262 -184.478804) (xy 34.720701 -184.504192) (xy 34.763085 -184.522242)
			(xy 34.808026 -184.532364) (xy 34.83102 -184.533794) (xy 34.859044 -184.535379) (xy 34.914197 -184.545809)
			(xy 34.963768 -184.563004) (xy 37.682422 -184.563004) (xy 37.686493 -184.507382) (xy 37.698619 -184.452945)
			(xy 37.718542 -184.400854) (xy 37.745838 -184.352219) (xy 37.779924 -184.308076) (xy 37.820073 -184.269367)
			(xy 37.865431 -184.236916) (xy 37.915031 -184.211415) (xy 37.967815 -184.193408) (xy 38.022658 -184.183278)
			(xy 38.078392 -184.181241) (xy 38.133829 -184.187341) (xy 38.187786 -184.201447) (xy 38.239115 -184.223259)
			(xy 38.286721 -184.252313) (xy 38.329589 -184.287988) (xy 38.366806 -184.329525) (xy 38.397579 -184.376038)
			(xy 38.421251 -184.426535) (xy 38.437319 -184.479942) (xy 38.445439 -184.535118) (xy 38.445948 -184.563004)
			(xy 38.445439 -184.59089) (xy 38.437319 -184.646066) (xy 38.421251 -184.699473) (xy 38.397579 -184.74997)
			(xy 38.366806 -184.796483) (xy 38.329589 -184.83802) (xy 38.286721 -184.873695) (xy 38.239115 -184.902749)
			(xy 38.187786 -184.924561) (xy 38.133829 -184.938667) (xy 38.078392 -184.944767) (xy 38.022658 -184.94273)
			(xy 37.967815 -184.9326) (xy 37.915031 -184.914593) (xy 37.865431 -184.889092) (xy 37.820073 -184.856641)
			(xy 37.779924 -184.817932) (xy 37.745838 -184.773789) (xy 37.718542 -184.725154) (xy 37.698619 -184.673063)
			(xy 37.686493 -184.618626) (xy 37.682422 -184.563004) (xy 34.963768 -184.563004) (xy 34.967227 -184.564204)
			(xy 35.01699 -184.590169) (xy 35.062414 -184.623142) (xy 35.102519 -184.662413) (xy 35.136438 -184.707135)
			(xy 35.163441 -184.756343) (xy 35.182945 -184.808976) (xy 35.19453 -184.863897) (xy 35.197945 -184.919923)
			(xy 35.193117 -184.975845) (xy 35.18015 -185.030457) (xy 35.159323 -185.08258) (xy 35.135592 -185.123351)
			(xy 43.227629 -185.123351) (xy 43.234713 -185.069128) (xy 43.249467 -185.016471) (xy 43.271587 -184.966461)
			(xy 43.300621 -184.920121) (xy 43.335974 -184.878401) (xy 43.376922 -184.842156) (xy 43.422625 -184.812129)
			(xy 43.472147 -184.788935) (xy 43.524473 -184.77305) (xy 43.578531 -184.764798) (xy 43.633213 -184.764349)
			(xy 43.6874 -184.771712) (xy 43.73998 -184.786737) (xy 43.789876 -184.809114) (xy 43.813222 -184.823354)
			(xy 43.832844 -184.835239) (xy 43.875347 -184.85249) (xy 43.920258 -184.861822) (xy 43.966115 -184.862929)
			(xy 44.011425 -184.855777) (xy 44.054711 -184.840599) (xy 44.094565 -184.817888) (xy 44.129688 -184.788383)
			(xy 44.144692 -184.77103) (xy 44.162557 -184.750327) (xy 44.203128 -184.713666) (xy 44.248518 -184.683174)
			(xy 44.297796 -184.659474) (xy 44.349954 -184.643053) (xy 44.403921 -184.634246) (xy 44.458593 -184.633236)
			(xy 44.512849 -184.640041) (xy 44.565577 -184.654523) (xy 44.615698 -184.676385) (xy 44.662183 -184.705179)
			(xy 44.704082 -184.740315) (xy 44.740534 -184.781074) (xy 44.770794 -184.826619) (xy 44.794241 -184.876018)
			(xy 44.810395 -184.928258) (xy 44.818925 -184.98227) (xy 44.819656 -185.036946) (xy 44.812572 -185.091167)
			(xy 44.79782 -185.14382) (xy 44.775702 -185.193828) (xy 44.74667 -185.240166) (xy 44.71132 -185.281884)
			(xy 44.670375 -185.318127) (xy 44.624675 -185.348153) (xy 44.575157 -185.371347) (xy 44.522834 -185.387233)
			(xy 44.46878 -185.395486) (xy 44.4141 -185.395937) (xy 44.359917 -185.388576) (xy 44.30734 -185.373554)
			(xy 44.257446 -185.35118) (xy 44.2341 -185.336942) (xy 44.214464 -185.325081) (xy 44.171965 -185.307828)
			(xy 44.127057 -185.298495) (xy 44.081202 -185.297384) (xy 44.035895 -185.304532) (xy 43.99261 -185.319707)
			(xy 43.952757 -185.342415) (xy 43.917635 -185.371915) (xy 43.90263 -185.389266) (xy 43.884765 -185.409971)
			(xy 43.844193 -185.446636) (xy 43.798802 -185.477132) (xy 43.749522 -185.500835) (xy 43.697362 -185.517259)
			(xy 43.643392 -185.526068) (xy 43.588717 -185.52708) (xy 43.534457 -185.520276) (xy 43.481726 -185.505794)
			(xy 43.431602 -185.483932) (xy 43.385113 -185.455137) (xy 43.343211 -185.419999) (xy 43.306756 -185.379239)
			(xy 43.276494 -185.333691) (xy 43.253045 -185.284289) (xy 43.23689 -185.232046) (xy 43.22836 -185.178031)
			(xy 43.227629 -185.123351) (xy 35.135592 -185.123351) (xy 35.131087 -185.131091) (xy 35.09605 -185.174943)
			(xy 35.054967 -185.213189) (xy 35.008725 -185.245006) (xy 34.958322 -185.269706) (xy 34.904845 -185.286757)
			(xy 34.849447 -185.295791) (xy 34.793323 -185.296614) (xy 34.737683 -185.289207) (xy 34.683729 -185.27373)
			(xy 34.632624 -185.250517) (xy 34.58547 -185.220069) (xy 34.543284 -185.183043) (xy 34.506977 -185.140236)
			(xy 34.477331 -185.092574) (xy 34.454987 -185.041083) (xy 34.447226 -185.014108) (xy 34.440776 -184.991989)
			(xy 34.420995 -184.950381) (xy 34.394041 -184.913018) (xy 34.360799 -184.881121) (xy 34.322354 -184.855734)
			(xy 34.279965 -184.837688) (xy 34.235019 -184.827573) (xy 34.212022 -184.826148) (xy 34.184008 -184.824448)
			(xy 34.128868 -184.814013) (xy 34.07585 -184.795613) (xy 34.0261 -184.769647) (xy 33.980689 -184.736673)
			(xy 33.940598 -184.697404) (xy 33.906691 -184.652687) (xy 33.8797 -184.603485) (xy 33.860206 -184.55086)
			(xy 33.84863 -184.495948) (xy 33.845223 -184.439932) (xy 26.695746 -184.439932) (xy 26.668878 -184.46841)
			(xy 26.569061 -184.562583) (xy 26.463936 -184.650793) (xy 26.353861 -184.732741) (xy 26.239207 -184.80815)
			(xy 26.120362 -184.876765) (xy 25.997729 -184.938354) (xy 25.871722 -184.992708) (xy 25.742768 -185.039643)
			(xy 25.611303 -185.079001) (xy 25.477772 -185.110649) (xy 25.342627 -185.134478) (xy 25.206325 -185.15041)
			(xy 25.069327 -185.158389) (xy 24.932097 -185.158389) (xy 24.795099 -185.15041) (xy 24.658797 -185.134478)
			(xy 24.523652 -185.110649) (xy 24.390121 -185.079001) (xy 24.258656 -185.039643) (xy 24.129702 -184.992708)
			(xy 24.003695 -184.938354) (xy 23.881062 -184.876765) (xy 23.762217 -184.80815) (xy 23.647563 -184.732741)
			(xy 23.537488 -184.650793) (xy 23.432363 -184.562583) (xy 23.332546 -184.46841) (xy 23.238373 -184.368593)
			(xy 23.150163 -184.263468) (xy 23.068215 -184.153393) (xy 22.992806 -184.038739) (xy 22.924191 -183.919894)
			(xy 22.862602 -183.797261) (xy 22.808248 -183.671254) (xy 22.761313 -183.5423) (xy 22.721955 -183.410835)
			(xy 22.690307 -183.277304) (xy 22.666478 -183.142159) (xy 22.650546 -183.005857) (xy 22.642567 -182.868859)
			(xy 22.642068 -182.800244) (xy 22.642068 -181.282594) (xy 22.641619 -181.252219) (xy 22.63408 -181.191938)
			(xy 22.619168 -181.133045) (xy 22.59711 -181.076441) (xy 22.568242 -181.022987) (xy 22.533006 -180.973499)
			(xy 22.491937 -180.928732) (xy 22.469094 -180.908706) (xy 22.400484 -180.852178) (xy 22.26773 -180.733914)
			(xy 22.140351 -180.609881) (xy 22.018596 -180.480322) (xy 21.902704 -180.345492) (xy 21.792904 -180.205657)
			(xy 21.689411 -180.061092) (xy 21.59243 -179.91208) (xy 21.502151 -179.758915) (xy 21.41875 -179.601899)
			(xy 21.342394 -179.441339) (xy 21.27323 -179.277551) (xy 21.211397 -179.110859) (xy 21.157014 -178.941588)
			(xy 21.110189 -178.770074) (xy 21.071015 -178.596652) (xy 21.039568 -178.421663) (xy 21.01591 -178.245453)
			(xy 21.000087 -178.068366) (xy 20.992131 -177.890753) (xy 20.992058 -177.712961) (xy 13.97508 -177.712961)
			(xy 13.97508 -181.881272) (xy 20.66112 -181.881272) (xy 20.665191 -181.82565) (xy 20.677317 -181.771213)
			(xy 20.69724 -181.719122) (xy 20.724536 -181.670487) (xy 20.758622 -181.626344) (xy 20.798771 -181.587635)
			(xy 20.844129 -181.555184) (xy 20.893729 -181.529683) (xy 20.946513 -181.511676) (xy 21.001356 -181.501546)
			(xy 21.05709 -181.499509) (xy 21.112527 -181.505609) (xy 21.166484 -181.519715) (xy 21.217813 -181.541527)
			(xy 21.265419 -181.570581) (xy 21.308287 -181.606256) (xy 21.345504 -181.647793) (xy 21.376277 -181.694306)
			(xy 21.399949 -181.744803) (xy 21.416017 -181.79821) (xy 21.424137 -181.853386) (xy 21.424646 -181.881272)
			(xy 21.424137 -181.909158) (xy 21.416017 -181.964334) (xy 21.399949 -182.017741) (xy 21.376277 -182.068238)
			(xy 21.345504 -182.114751) (xy 21.308287 -182.156288) (xy 21.265419 -182.191963) (xy 21.217813 -182.221017)
			(xy 21.166484 -182.242829) (xy 21.112527 -182.256935) (xy 21.05709 -182.263035) (xy 21.001356 -182.260998)
			(xy 20.946513 -182.250868) (xy 20.893729 -182.232861) (xy 20.844129 -182.20736) (xy 20.798771 -182.174909)
			(xy 20.758622 -182.1362) (xy 20.724536 -182.092057) (xy 20.69724 -182.043422) (xy 20.677317 -181.991331)
			(xy 20.665191 -181.936894) (xy 20.66112 -181.881272) (xy 13.97508 -181.881272) (xy 13.97508 -185.552334)
			(xy 46.017178 -185.552334) (xy 46.021249 -185.496712) (xy 46.033375 -185.442275) (xy 46.053298 -185.390184)
			(xy 46.080594 -185.341549) (xy 46.11468 -185.297406) (xy 46.154829 -185.258697) (xy 46.200187 -185.226246)
			(xy 46.249787 -185.200745) (xy 46.302571 -185.182738) (xy 46.357414 -185.172608) (xy 46.413148 -185.170571)
			(xy 46.468585 -185.176671) (xy 46.522542 -185.190777) (xy 46.573871 -185.212589) (xy 46.621477 -185.241643)
			(xy 46.664345 -185.277318) (xy 46.701562 -185.318855) (xy 46.732335 -185.365368) (xy 46.756007 -185.415865)
			(xy 46.772075 -185.469272) (xy 46.780195 -185.524448) (xy 46.780704 -185.552334) (xy 46.780195 -185.58022)
			(xy 46.772075 -185.635396) (xy 46.756007 -185.688803) (xy 46.732335 -185.7393) (xy 46.701562 -185.785813)
			(xy 46.664345 -185.82735) (xy 46.621477 -185.863025) (xy 46.573871 -185.892079) (xy 46.522542 -185.913891)
			(xy 46.468585 -185.927997) (xy 46.413148 -185.934097) (xy 46.357414 -185.93206) (xy 46.302571 -185.92193)
			(xy 46.249787 -185.903923) (xy 46.200187 -185.878422) (xy 46.154829 -185.845971) (xy 46.11468 -185.807262)
			(xy 46.080594 -185.763119) (xy 46.053298 -185.714484) (xy 46.033375 -185.662393) (xy 46.021249 -185.607956)
			(xy 46.017178 -185.552334) (xy 13.97508 -185.552334) (xy 13.97508 -186.234578) (xy 25.074624 -186.234578)
			(xy 25.078695 -186.178956) (xy 25.090821 -186.124519) (xy 25.110744 -186.072428) (xy 25.13804 -186.023793)
			(xy 25.172126 -185.97965) (xy 25.212275 -185.940941) (xy 25.257633 -185.90849) (xy 25.307233 -185.882989)
			(xy 25.360017 -185.864982) (xy 25.41486 -185.854852) (xy 25.470594 -185.852815) (xy 25.526031 -185.858915)
			(xy 25.579988 -185.873021) (xy 25.631317 -185.894833) (xy 25.678923 -185.923887) (xy 25.721791 -185.959562)
			(xy 25.759008 -186.001099) (xy 25.789781 -186.047612) (xy 25.813453 -186.098109) (xy 25.829521 -186.151516)
			(xy 25.830601 -186.158855) (xy 33.231067 -186.158855) (xy 33.237595 -186.1047) (xy 33.251766 -186.052026)
			(xy 33.273292 -186.001906) (xy 33.301733 -185.955361) (xy 33.336511 -185.913338) (xy 33.376917 -185.876695)
			(xy 33.422128 -185.846177) (xy 33.471223 -185.822407) (xy 33.523202 -185.805867) (xy 33.577007 -185.796896)
			(xy 33.63154 -185.795676) (xy 33.685692 -185.802232) (xy 33.738358 -185.81643) (xy 33.788468 -185.837981)
			(xy 33.834998 -185.866447) (xy 33.877003 -185.901246) (xy 33.913625 -185.941671) (xy 33.94412 -185.986897)
			(xy 33.967865 -186.036005) (xy 33.976564 -186.061858) (xy 33.984151 -186.083948) (xy 34.006187 -186.125122)
			(xy 34.035374 -186.161579) (xy 34.070728 -186.192091) (xy 34.111061 -186.215633) (xy 34.155015 -186.231412)
			(xy 34.201112 -186.238897) (xy 34.224468 -186.238896) (xy 34.252772 -186.238815) (xy 34.308926 -186.245878)
			(xy 34.36342 -186.261158) (xy 34.41506 -186.284321) (xy 34.462711 -186.314857) (xy 34.505329 -186.352098)
			(xy 34.541978 -186.395225) (xy 34.571855 -186.443293) (xy 34.594303 -186.495248) (xy 34.60883 -186.549948)
			(xy 34.615117 -186.606194) (xy 34.613027 -186.662751) (xy 34.602605 -186.71838) (xy 34.58408 -186.771858)
			(xy 34.557858 -186.822014) (xy 34.527994 -186.862974) (xy 46.719742 -186.862974) (xy 46.723813 -186.807352)
			(xy 46.735939 -186.752915) (xy 46.755862 -186.700824) (xy 46.783158 -186.652189) (xy 46.817244 -186.608046)
			(xy 46.857393 -186.569337) (xy 46.902751 -186.536886) (xy 46.952351 -186.511385) (xy 47.005135 -186.493378)
			(xy 47.059978 -186.483248) (xy 47.115712 -186.481211) (xy 47.171149 -186.487311) (xy 47.225106 -186.501417)
			(xy 47.276435 -186.523229) (xy 47.324041 -186.552283) (xy 47.366909 -186.587958) (xy 47.404126 -186.629495)
			(xy 47.434899 -186.676008) (xy 47.458571 -186.726505) (xy 47.474639 -186.779912) (xy 47.482759 -186.835088)
			(xy 47.483268 -186.862974) (xy 47.862742 -186.862974) (xy 47.866813 -186.807352) (xy 47.878939 -186.752915)
			(xy 47.898862 -186.700824) (xy 47.926158 -186.652189) (xy 47.960244 -186.608046) (xy 48.000393 -186.569337)
			(xy 48.045751 -186.536886) (xy 48.095351 -186.511385) (xy 48.148135 -186.493378) (xy 48.202978 -186.483248)
			(xy 48.258712 -186.481211) (xy 48.314149 -186.487311) (xy 48.368106 -186.501417) (xy 48.419435 -186.523229)
			(xy 48.467041 -186.552283) (xy 48.509909 -186.587958) (xy 48.547126 -186.629495) (xy 48.577899 -186.676008)
			(xy 48.601571 -186.726505) (xy 48.617639 -186.779912) (xy 48.625759 -186.835088) (xy 48.625999 -186.848242)
			(xy 49.005742 -186.848242) (xy 49.009813 -186.79262) (xy 49.021939 -186.738183) (xy 49.041862 -186.686092)
			(xy 49.069158 -186.637457) (xy 49.103244 -186.593314) (xy 49.143393 -186.554605) (xy 49.188751 -186.522154)
			(xy 49.238351 -186.496653) (xy 49.291135 -186.478646) (xy 49.345978 -186.468516) (xy 49.401712 -186.466479)
			(xy 49.457149 -186.472579) (xy 49.511106 -186.486685) (xy 49.562435 -186.508497) (xy 49.610041 -186.537551)
			(xy 49.652909 -186.573226) (xy 49.690126 -186.614763) (xy 49.720899 -186.661276) (xy 49.744571 -186.711773)
			(xy 49.760639 -186.76518) (xy 49.768759 -186.820356) (xy 49.769268 -186.848242) (xy 49.768759 -186.876128)
			(xy 49.760639 -186.931304) (xy 49.744571 -186.984711) (xy 49.720899 -187.035208) (xy 49.690126 -187.081721)
			(xy 49.652909 -187.123258) (xy 49.610041 -187.158933) (xy 49.562435 -187.187987) (xy 49.511106 -187.209799)
			(xy 49.457149 -187.223905) (xy 49.401712 -187.230005) (xy 49.345978 -187.227968) (xy 49.291135 -187.217838)
			(xy 49.238351 -187.199831) (xy 49.188751 -187.17433) (xy 49.143393 -187.141879) (xy 49.103244 -187.10317)
			(xy 49.069158 -187.059027) (xy 49.041862 -187.010392) (xy 49.021939 -186.958301) (xy 49.009813 -186.903864)
			(xy 49.005742 -186.848242) (xy 48.625999 -186.848242) (xy 48.626268 -186.862974) (xy 48.625759 -186.89086)
			(xy 48.617639 -186.946036) (xy 48.601571 -186.999443) (xy 48.577899 -187.04994) (xy 48.547126 -187.096453)
			(xy 48.509909 -187.13799) (xy 48.467041 -187.173665) (xy 48.419435 -187.202719) (xy 48.368106 -187.224531)
			(xy 48.314149 -187.238637) (xy 48.258712 -187.244737) (xy 48.202978 -187.2427) (xy 48.148135 -187.23257)
			(xy 48.095351 -187.214563) (xy 48.045751 -187.189062) (xy 48.000393 -187.156611) (xy 47.960244 -187.117902)
			(xy 47.926158 -187.073759) (xy 47.898862 -187.025124) (xy 47.878939 -186.973033) (xy 47.866813 -186.918596)
			(xy 47.862742 -186.862974) (xy 47.483268 -186.862974) (xy 47.482759 -186.89086) (xy 47.474639 -186.946036)
			(xy 47.458571 -186.999443) (xy 47.434899 -187.04994) (xy 47.404126 -187.096453) (xy 47.366909 -187.13799)
			(xy 47.324041 -187.173665) (xy 47.276435 -187.202719) (xy 47.225106 -187.224531) (xy 47.171149 -187.238637)
			(xy 47.115712 -187.244737) (xy 47.059978 -187.2427) (xy 47.005135 -187.23257) (xy 46.952351 -187.214563)
			(xy 46.902751 -187.189062) (xy 46.857393 -187.156611) (xy 46.817244 -187.117902) (xy 46.783158 -187.073759)
			(xy 46.755862 -187.025124) (xy 46.735939 -186.973033) (xy 46.723813 -186.918596) (xy 46.719742 -186.862974)
			(xy 34.527994 -186.862974) (xy 34.524515 -186.867746) (xy 34.484782 -186.90805) (xy 34.462466 -186.925458)
			(xy 34.443963 -186.940008) (xy 34.412199 -186.974742) (xy 34.387375 -187.01473) (xy 34.370338 -187.058606)
			(xy 34.361672 -187.104869) (xy 34.361672 -187.151936) (xy 34.37034 -187.198198) (xy 34.387377 -187.242074)
			(xy 34.412202 -187.282062) (xy 34.443966 -187.316795) (xy 34.462466 -187.33135) (xy 34.484603 -187.348519)
			(xy 34.523978 -187.38837) (xy 34.557104 -187.433551) (xy 34.583268 -187.483089) (xy 34.601907 -187.53592)
			(xy 34.612622 -187.590908) (xy 34.615181 -187.646873) (xy 34.60953 -187.70261) (xy 34.59579 -187.756922)
			(xy 34.585054 -187.782708) (xy 44.809662 -187.782708) (xy 44.813733 -187.727086) (xy 44.825859 -187.672649)
			(xy 44.845782 -187.620558) (xy 44.873078 -187.571923) (xy 44.907164 -187.52778) (xy 44.947313 -187.489071)
			(xy 44.992671 -187.45662) (xy 45.042271 -187.431119) (xy 45.095055 -187.413112) (xy 45.149898 -187.402982)
			(xy 45.205632 -187.400945) (xy 45.261069 -187.407045) (xy 45.315026 -187.421151) (xy 45.366355 -187.442963)
			(xy 45.413961 -187.472017) (xy 45.456829 -187.507692) (xy 45.494046 -187.549229) (xy 45.524819 -187.595742)
			(xy 45.548491 -187.646239) (xy 45.564559 -187.699646) (xy 45.572679 -187.754822) (xy 45.573188 -187.782708)
			(xy 45.572679 -187.810594) (xy 45.564559 -187.86577) (xy 45.548491 -187.919177) (xy 45.524819 -187.969674)
			(xy 45.494046 -188.016187) (xy 45.456829 -188.057724) (xy 45.413961 -188.093399) (xy 45.366355 -188.122453)
			(xy 45.315026 -188.144265) (xy 45.261069 -188.158371) (xy 45.205632 -188.164471) (xy 45.149898 -188.162434)
			(xy 45.095055 -188.152304) (xy 45.042271 -188.134297) (xy 44.992671 -188.108796) (xy 44.947313 -188.076345)
			(xy 44.907164 -188.037636) (xy 44.873078 -187.993493) (xy 44.845782 -187.944858) (xy 44.825859 -187.892767)
			(xy 44.813733 -187.83833) (xy 44.809662 -187.782708) (xy 34.585054 -187.782708) (xy 34.574257 -187.808641)
			(xy 34.545393 -187.856656) (xy 34.509819 -187.899935) (xy 34.48939 -187.919106) (xy 34.472561 -187.935015)
			(xy 34.444431 -187.971799) (xy 34.423426 -188.013067) (xy 34.41024 -188.057457) (xy 34.405307 -188.1035)
			(xy 34.408791 -188.149675) (xy 34.420578 -188.194457) (xy 34.440276 -188.236365) (xy 34.467237 -188.274014)
			(xy 34.483548 -188.290454) (xy 34.503106 -188.309987) (xy 34.536946 -188.35369) (xy 34.564123 -188.401821)
			(xy 34.584067 -188.453371) (xy 34.596362 -188.50726) (xy 34.600748 -188.562359) (xy 34.597136 -188.617514)
			(xy 34.585599 -188.67157) (xy 34.56638 -188.723395) (xy 34.539882 -188.771903) (xy 34.506659 -188.816077)
			(xy 34.467407 -188.854993) (xy 34.422949 -188.887836) (xy 34.374216 -188.913917) (xy 34.322228 -188.93269)
			(xy 34.268075 -188.943762) (xy 34.21289 -188.946901) (xy 34.157831 -188.942042) (xy 34.10405 -188.929285)
			(xy 34.052673 -188.908899) (xy 34.004777 -188.88131) (xy 33.961366 -188.847096) (xy 33.923348 -188.806974)
			(xy 33.891519 -188.761784) (xy 33.866548 -188.712473) (xy 33.848955 -188.660074) (xy 33.839111 -188.605684)
			(xy 33.837221 -188.550443) (xy 33.843325 -188.495507) (xy 33.857295 -188.442028) (xy 33.878839 -188.391126)
			(xy 33.907505 -188.343867) (xy 33.942692 -188.301241) (xy 33.962848 -188.282326) (xy 33.979648 -188.266386)
			(xy 34.007785 -188.22961) (xy 34.028796 -188.188348) (xy 34.041989 -188.143962) (xy 34.046927 -188.097921)
			(xy 34.043446 -188.051748) (xy 34.031661 -188.006968) (xy 34.011963 -187.965062) (xy 33.985002 -187.927416)
			(xy 33.96869 -187.910978) (xy 33.949205 -187.891542) (xy 33.915462 -187.848065) (xy 33.88832 -187.80019)
			(xy 33.868343 -187.748909) (xy 33.855944 -187.69529) (xy 33.851382 -187.640445) (xy 33.854752 -187.585514)
			(xy 33.865984 -187.531638) (xy 33.884844 -187.479936) (xy 33.91094 -187.431482) (xy 33.943731 -187.387283)
			(xy 33.982534 -187.348257) (xy 34.00425 -187.33135) (xy 34.022745 -187.31679) (xy 34.054506 -187.282057)
			(xy 34.079329 -187.24207) (xy 34.096365 -187.198196) (xy 34.105031 -187.151935) (xy 34.105031 -187.10487)
			(xy 34.096366 -187.058609) (xy 34.079331 -187.014735) (xy 34.054509 -186.974747) (xy 34.022748 -186.940014)
			(xy 34.00425 -186.925458) (xy 33.980964 -186.907276) (xy 33.939747 -186.864955) (xy 33.905531 -186.816797)
			(xy 33.879131 -186.763948) (xy 33.86963 -186.735974) (xy 33.862088 -186.713868) (xy 33.840041 -186.672695)
			(xy 33.810845 -186.636241) (xy 33.775483 -186.605732) (xy 33.735144 -186.582193) (xy 33.691185 -186.566417)
			(xy 33.645084 -186.558934) (xy 33.621726 -186.558936) (xy 33.59445 -186.559143) (xy 33.540292 -186.552642)
			(xy 33.48761 -186.538498) (xy 33.437479 -186.516998) (xy 33.390919 -186.48858) (xy 33.348879 -186.453824)
			(xy 33.312216 -186.413436) (xy 33.281675 -186.368241) (xy 33.257879 -186.319158) (xy 33.241313 -186.267187)
			(xy 33.232315 -186.213388) (xy 33.231067 -186.158855) (xy 25.830601 -186.158855) (xy 25.837641 -186.206692)
			(xy 25.83815 -186.234578) (xy 25.837641 -186.262464) (xy 25.829521 -186.31764) (xy 25.813453 -186.371047)
			(xy 25.789781 -186.421544) (xy 25.759008 -186.468057) (xy 25.721791 -186.509594) (xy 25.678923 -186.545269)
			(xy 25.631317 -186.574323) (xy 25.579988 -186.596135) (xy 25.526031 -186.610241) (xy 25.470594 -186.616341)
			(xy 25.41486 -186.614304) (xy 25.360017 -186.604174) (xy 25.307233 -186.586167) (xy 25.257633 -186.560666)
			(xy 25.212275 -186.528215) (xy 25.172126 -186.489506) (xy 25.13804 -186.445363) (xy 25.110744 -186.396728)
			(xy 25.090821 -186.344637) (xy 25.078695 -186.2902) (xy 25.074624 -186.234578) (xy 13.97508 -186.234578)
			(xy 13.97508 -188.541035) (xy 30.180587 -188.541035) (xy 30.180896 -188.48571) (xy 30.189194 -188.431009)
			(xy 30.205308 -188.378081) (xy 30.228899 -188.328036) (xy 30.259472 -188.281925) (xy 30.277562 -188.26099)
			(xy 30.292474 -188.243651) (xy 30.316383 -188.20467) (xy 30.332932 -188.16204) (xy 30.341587 -188.117137)
			(xy 30.34207 -188.071411) (xy 30.334363 -188.026335) (xy 30.318717 -187.983366) (xy 30.295636 -187.943889)
			(xy 30.281118 -187.926218) (xy 30.263304 -187.904709) (xy 30.233505 -187.857476) (xy 30.210912 -187.806402)
			(xy 30.196009 -187.75258) (xy 30.189112 -187.69716) (xy 30.190371 -187.641326) (xy 30.199758 -187.586273)
			(xy 30.217073 -187.533177) (xy 30.241945 -187.483174) (xy 30.273842 -187.437331) (xy 30.312083 -187.396631)
			(xy 30.355851 -187.361941) (xy 30.404209 -187.334004) (xy 30.456124 -187.313418) (xy 30.510486 -187.300621)
			(xy 30.566132 -187.295889) (xy 30.621874 -187.299321) (xy 30.67652 -187.310846) (xy 30.728901 -187.330215)
			(xy 30.777898 -187.357015) (xy 30.822463 -187.390674) (xy 30.861644 -187.430471) (xy 30.894603 -187.475557)
			(xy 30.920635 -187.524966) (xy 30.939184 -187.577643) (xy 30.949853 -187.632462) (xy 30.952415 -187.688251)
			(xy 30.946814 -187.743817) (xy 30.93317 -187.797973) (xy 30.911776 -187.84956) (xy 30.883087 -187.897476)
			(xy 30.847719 -187.940696) (xy 30.806425 -187.978297) (xy 30.78353 -187.99429) (xy 30.770964 -188.003201)
			(xy 30.750292 -188.026036) (xy 30.735697 -188.05316) (xy 30.728028 -188.082991) (xy 30.727734 -188.113792)
			(xy 30.734832 -188.143764) (xy 30.748907 -188.171162) (xy 30.769139 -188.194387) (xy 30.781498 -188.203586)
			(xy 30.79115 -188.210444) (xy 30.809063 -188.223284) (xy 30.848312 -188.243319) (xy 30.89043 -188.25628)
			(xy 30.934153 -188.261777) (xy 30.978168 -188.259644) (xy 31.021155 -188.249948) (xy 31.061823 -188.232977)
			(xy 31.098952 -188.209242) (xy 31.115508 -188.194696) (xy 31.136442 -188.176276) (xy 31.182571 -188.144956)
			(xy 31.232768 -188.120686) (xy 31.285964 -188.103982) (xy 31.341025 -188.095199) (xy 31.396777 -188.094526)
			(xy 31.452034 -188.101977) (xy 31.505617 -188.117392) (xy 31.556386 -188.140443) (xy 31.603258 -188.17064)
			(xy 31.645234 -188.207338) (xy 31.681421 -188.249756) (xy 31.711048 -188.29699) (xy 31.733482 -188.348034)
			(xy 31.748247 -188.401801) (xy 31.755028 -188.457144) (xy 31.753679 -188.512884) (xy 31.744231 -188.567834)
			(xy 31.726883 -188.620823) (xy 31.702006 -188.670723) (xy 31.670131 -188.716469) (xy 31.631935 -188.757088)
			(xy 31.588232 -188.791714) (xy 31.539955 -188.819608) (xy 31.488131 -188.840178) (xy 31.433865 -188.852984)
			(xy 31.378313 -188.857753) (xy 31.322658 -188.854385) (xy 31.268087 -188.84295) (xy 31.215761 -188.823693)
			(xy 31.166796 -188.797024) (xy 31.14421 -188.780674) (xy 31.126325 -188.767792) (xy 31.08707 -188.747758)
			(xy 31.044946 -188.734801) (xy 31.001218 -188.729309) (xy 30.957198 -188.731446) (xy 30.914207 -188.74115)
			(xy 30.873537 -188.758128) (xy 30.836408 -188.781871) (xy 30.819852 -188.796422) (xy 30.799105 -188.814729)
			(xy 30.753387 -188.845887) (xy 30.703646 -188.870113) (xy 30.650928 -188.886899) (xy 30.596337 -188.895894)
			(xy 30.54102 -188.896907) (xy 30.486137 -188.889919) (xy 30.432839 -188.875075) (xy 30.382245 -188.852687)
			(xy 30.335415 -188.823224) (xy 30.293334 -188.787306) (xy 30.256882 -188.745685) (xy 30.226826 -188.699235)
			(xy 30.203795 -188.64893) (xy 30.188274 -188.595825) (xy 30.180587 -188.541035) (xy 13.97508 -188.541035)
			(xy 13.97508 -191.507373) (xy 30.072583 -191.507373) (xy 30.078686 -191.451899) (xy 30.092802 -191.397906)
			(xy 30.114629 -191.346543) (xy 30.143702 -191.298905) (xy 30.179401 -191.256009) (xy 30.220965 -191.218767)
			(xy 30.267509 -191.187973) (xy 30.31804 -191.164285) (xy 30.371482 -191.148207) (xy 30.426696 -191.140081)
			(xy 30.4546 -191.139572) (xy 30.482504 -191.140081) (xy 30.537718 -191.148207) (xy 30.59116 -191.164285)
			(xy 30.641691 -191.187973) (xy 30.688235 -191.218767) (xy 30.729799 -191.256009) (xy 30.765498 -191.298905)
			(xy 30.794571 -191.346543) (xy 30.816398 -191.397906) (xy 30.830514 -191.451899) (xy 30.836617 -191.507373)
			(xy 30.834579 -191.563144) (xy 30.824442 -191.618023) (xy 30.806423 -191.670843) (xy 30.780905 -191.720475)
			(xy 30.748433 -191.765863) (xy 30.709698 -191.80604) (xy 30.665526 -191.840148) (xy 30.616858 -191.867462)
			(xy 30.564732 -191.887398) (xy 30.510259 -191.899533) (xy 30.4546 -191.903607) (xy 30.398941 -191.899533)
			(xy 30.344468 -191.887398) (xy 30.292342 -191.867462) (xy 30.243674 -191.840148) (xy 30.199502 -191.80604)
			(xy 30.160767 -191.765863) (xy 30.128295 -191.720475) (xy 30.102777 -191.670843) (xy 30.084758 -191.618023)
			(xy 30.074621 -191.563144) (xy 30.072583 -191.507373) (xy 13.97508 -191.507373) (xy 13.97508 -192.786)
			(xy 31.520128 -192.786) (xy 31.524201 -192.730341) (xy 31.536336 -192.675868) (xy 31.556272 -192.623742)
			(xy 31.583586 -192.575074) (xy 31.617694 -192.530902) (xy 31.657871 -192.492167) (xy 31.703259 -192.459695)
			(xy 31.752891 -192.434177) (xy 31.805711 -192.416158) (xy 31.86059 -192.406021) (xy 31.916361 -192.403983)
			(xy 31.971835 -192.410086) (xy 32.025828 -192.424202) (xy 32.077191 -192.446029) (xy 32.124829 -192.475102)
			(xy 32.167725 -192.510801) (xy 32.204967 -192.552365) (xy 32.235761 -192.598909) (xy 32.259449 -192.64944)
			(xy 32.275527 -192.702882) (xy 32.283653 -192.758096) (xy 32.284162 -192.786) (xy 32.283653 -192.813904)
			(xy 32.275527 -192.869118) (xy 32.259449 -192.92256) (xy 32.235761 -192.973091) (xy 32.204967 -193.019635)
			(xy 32.167725 -193.061199) (xy 32.124829 -193.096898) (xy 32.077191 -193.125971) (xy 32.025828 -193.147798)
			(xy 31.971835 -193.161914) (xy 31.916361 -193.168017) (xy 31.86059 -193.165979) (xy 31.805711 -193.155842)
			(xy 31.752891 -193.137823) (xy 31.703259 -193.112305) (xy 31.657871 -193.079833) (xy 31.617694 -193.041098)
			(xy 31.583586 -192.996926) (xy 31.556272 -192.948258) (xy 31.536336 -192.896132) (xy 31.524201 -192.841659)
			(xy 31.520128 -192.786) (xy 13.97508 -192.786) (xy 13.97508 -193.45275) (xy 16.605502 -193.45275)
			(xy 16.609573 -193.397128) (xy 16.621699 -193.342691) (xy 16.641622 -193.2906) (xy 16.668918 -193.241965)
			(xy 16.703004 -193.197822) (xy 16.743153 -193.159113) (xy 16.788511 -193.126662) (xy 16.838111 -193.101161)
			(xy 16.890895 -193.083154) (xy 16.945738 -193.073024) (xy 17.001472 -193.070987) (xy 17.056909 -193.077087)
			(xy 17.110866 -193.091193) (xy 17.162195 -193.113005) (xy 17.209801 -193.142059) (xy 17.252669 -193.177734)
			(xy 17.289886 -193.219271) (xy 17.320659 -193.265784) (xy 17.344331 -193.316281) (xy 17.360399 -193.369688)
			(xy 17.368519 -193.424864) (xy 17.369028 -193.45275) (xy 17.368519 -193.480636) (xy 17.360399 -193.535812)
			(xy 17.344331 -193.589219) (xy 17.320659 -193.639716) (xy 17.289886 -193.686229) (xy 17.252669 -193.727766)
			(xy 17.209801 -193.763441) (xy 17.162195 -193.792495) (xy 17.110866 -193.814307) (xy 17.056909 -193.828413)
			(xy 17.001472 -193.834513) (xy 16.945738 -193.832476) (xy 16.890895 -193.822346) (xy 16.838111 -193.804339)
			(xy 16.788511 -193.778838) (xy 16.743153 -193.746387) (xy 16.703004 -193.707678) (xy 16.668918 -193.663535)
			(xy 16.641622 -193.6149) (xy 16.621699 -193.562809) (xy 16.609573 -193.508372) (xy 16.605502 -193.45275)
			(xy 13.97508 -193.45275) (xy 13.97508 -194.525918) (xy 22.429977 -194.525918) (xy 22.436077 -194.470481)
			(xy 22.450183 -194.416524) (xy 22.471995 -194.365195) (xy 22.501049 -194.317589) (xy 22.536724 -194.274721)
			(xy 22.578261 -194.237504) (xy 22.624774 -194.206731) (xy 22.675271 -194.183059) (xy 22.728678 -194.166991)
			(xy 22.783854 -194.158871) (xy 22.81174 -194.158362) (xy 22.839626 -194.158871) (xy 22.894802 -194.166991)
			(xy 22.948209 -194.183059) (xy 22.998706 -194.206731) (xy 23.045219 -194.237504) (xy 23.086756 -194.274721)
			(xy 23.122431 -194.317589) (xy 23.151485 -194.365195) (xy 23.173297 -194.416524) (xy 23.187403 -194.470481)
			(xy 23.193503 -194.525918) (xy 23.191466 -194.581652) (xy 23.181336 -194.636495) (xy 23.173137 -194.660529)
			(xy 24.355043 -194.660529) (xy 24.361146 -194.605055) (xy 24.375262 -194.551062) (xy 24.397089 -194.499699)
			(xy 24.426162 -194.452061) (xy 24.461861 -194.409165) (xy 24.503425 -194.371923) (xy 24.549969 -194.341129)
			(xy 24.6005 -194.317441) (xy 24.653942 -194.301363) (xy 24.709156 -194.293237) (xy 24.73706 -194.292728)
			(xy 24.764964 -194.293237) (xy 24.820178 -194.301363) (xy 24.87362 -194.317441) (xy 24.924151 -194.341129)
			(xy 24.970695 -194.371923) (xy 25.012259 -194.409165) (xy 25.047958 -194.452061) (xy 25.077031 -194.499699)
			(xy 25.098858 -194.551062) (xy 25.112974 -194.605055) (xy 25.119077 -194.660529) (xy 25.117039 -194.7163)
			(xy 25.106902 -194.771179) (xy 25.088883 -194.823999) (xy 25.063365 -194.873631) (xy 25.030893 -194.919019)
			(xy 24.992158 -194.959196) (xy 24.947986 -194.993304) (xy 24.899318 -195.020618) (xy 24.847192 -195.040554)
			(xy 24.792719 -195.052689) (xy 24.73706 -195.056763) (xy 24.681401 -195.052689) (xy 24.626928 -195.040554)
			(xy 24.574802 -195.020618) (xy 24.526134 -194.993304) (xy 24.481962 -194.959196) (xy 24.443227 -194.919019)
			(xy 24.410755 -194.873631) (xy 24.385237 -194.823999) (xy 24.367218 -194.771179) (xy 24.357081 -194.7163)
			(xy 24.355043 -194.660529) (xy 23.173137 -194.660529) (xy 23.163329 -194.689279) (xy 23.137828 -194.738879)
			(xy 23.105377 -194.784237) (xy 23.066668 -194.824386) (xy 23.022525 -194.858472) (xy 22.97389 -194.885768)
			(xy 22.921799 -194.905691) (xy 22.867362 -194.917817) (xy 22.81174 -194.921888) (xy 22.756118 -194.917817)
			(xy 22.701681 -194.905691) (xy 22.64959 -194.885768) (xy 22.600955 -194.858472) (xy 22.556812 -194.824386)
			(xy 22.518103 -194.784237) (xy 22.485652 -194.738879) (xy 22.460151 -194.689279) (xy 22.442144 -194.636495)
			(xy 22.432014 -194.581652) (xy 22.429977 -194.525918) (xy 13.97508 -194.525918) (xy 13.97508 -195.83908)
			(xy 48.627028 -195.83908) (xy 48.631099 -195.783458) (xy 48.643225 -195.729021) (xy 48.663148 -195.67693)
			(xy 48.690444 -195.628295) (xy 48.72453 -195.584152) (xy 48.764679 -195.545443) (xy 48.810037 -195.512992)
			(xy 48.859637 -195.487491) (xy 48.912421 -195.469484) (xy 48.967264 -195.459354) (xy 49.022998 -195.457317)
			(xy 49.078435 -195.463417) (xy 49.132392 -195.477523) (xy 49.183721 -195.499335) (xy 49.231327 -195.528389)
			(xy 49.274195 -195.564064) (xy 49.311412 -195.605601) (xy 49.342185 -195.652114) (xy 49.365857 -195.702611)
			(xy 49.381925 -195.756018) (xy 49.390045 -195.811194) (xy 49.390554 -195.83908) (xy 49.390045 -195.866966)
			(xy 49.381925 -195.922142) (xy 49.365857 -195.975549) (xy 49.342185 -196.026046) (xy 49.311412 -196.072559)
			(xy 49.274195 -196.114096) (xy 49.231327 -196.149771) (xy 49.183721 -196.178825) (xy 49.132392 -196.200637)
			(xy 49.078435 -196.214743) (xy 49.022998 -196.220843) (xy 48.967264 -196.218806) (xy 48.912421 -196.208676)
			(xy 48.859637 -196.190669) (xy 48.810037 -196.165168) (xy 48.764679 -196.132717) (xy 48.72453 -196.094008)
			(xy 48.690444 -196.049865) (xy 48.663148 -196.00123) (xy 48.643225 -195.949139) (xy 48.631099 -195.894702)
			(xy 48.627028 -195.83908) (xy 13.97508 -195.83908) (xy 13.97508 -196.3674) (xy 26.109928 -196.3674)
			(xy 26.114001 -196.311741) (xy 26.126136 -196.257268) (xy 26.146072 -196.205142) (xy 26.173386 -196.156474)
			(xy 26.207494 -196.112302) (xy 26.247671 -196.073567) (xy 26.293059 -196.041095) (xy 26.342691 -196.015577)
			(xy 26.395511 -195.997558) (xy 26.45039 -195.987421) (xy 26.506161 -195.985383) (xy 26.561635 -195.991486)
			(xy 26.615628 -196.005602) (xy 26.666991 -196.027429) (xy 26.714629 -196.056502) (xy 26.757525 -196.092201)
			(xy 26.794767 -196.133765) (xy 26.825561 -196.180309) (xy 26.849249 -196.23084) (xy 26.865327 -196.284282)
			(xy 26.873453 -196.339496) (xy 26.873962 -196.3674) (xy 26.873453 -196.395304) (xy 26.865327 -196.450518)
			(xy 26.849249 -196.50396) (xy 26.825561 -196.554491) (xy 26.794767 -196.601035) (xy 26.757525 -196.642599)
			(xy 26.714629 -196.678298) (xy 26.666991 -196.707371) (xy 26.615628 -196.729198) (xy 26.561635 -196.743314)
			(xy 26.506161 -196.749417) (xy 26.45039 -196.747379) (xy 26.395511 -196.737242) (xy 26.342691 -196.719223)
			(xy 26.293059 -196.693705) (xy 26.247671 -196.661233) (xy 26.207494 -196.622498) (xy 26.173386 -196.578326)
			(xy 26.146072 -196.529658) (xy 26.126136 -196.477532) (xy 26.114001 -196.423059) (xy 26.109928 -196.3674)
			(xy 13.97508 -196.3674) (xy 13.97508 -197.480016) (xy 40.380718 -197.480016) (xy 40.388313 -197.426016)
			(xy 40.403519 -197.373648) (xy 40.426026 -197.323977) (xy 40.455374 -197.278017) (xy 40.490966 -197.236702)
			(xy 40.532077 -197.200876) (xy 40.57787 -197.171267) (xy 40.627411 -197.148479) (xy 40.679692 -197.132975)
			(xy 40.733648 -197.125072) (xy 40.788179 -197.124931) (xy 40.842175 -197.132554) (xy 40.894536 -197.147787)
			(xy 40.944195 -197.170319) (xy 40.99014 -197.19969) (xy 41.031436 -197.235304) (xy 41.067242 -197.276433)
			(xy 41.096827 -197.322241) (xy 41.10863 -197.346824) (xy 41.116076 -197.361753) (xy 41.137367 -197.387422)
			(xy 41.164586 -197.40669) (xy 41.195871 -197.41824) (xy 41.229081 -197.42128) (xy 41.261944 -197.415604)
			(xy 41.277286 -197.409054) (xy 41.302271 -197.398028) (xy 41.354616 -197.382457) (xy 41.408647 -197.374507)
			(xy 41.463258 -197.374343) (xy 41.517336 -197.381967) (xy 41.569773 -197.397223) (xy 41.6195 -197.419799)
			(xy 41.6655 -197.449235) (xy 41.706834 -197.484929) (xy 41.742655 -197.526151) (xy 41.772234 -197.57206)
			(xy 41.794964 -197.621716) (xy 41.797636 -197.630796) (xy 42.124882 -197.630796) (xy 42.128953 -197.575174)
			(xy 42.141079 -197.520737) (xy 42.161002 -197.468646) (xy 42.188298 -197.420011) (xy 42.222384 -197.375868)
			(xy 42.262533 -197.337159) (xy 42.307891 -197.304708) (xy 42.357491 -197.279207) (xy 42.410275 -197.2612)
			(xy 42.465118 -197.25107) (xy 42.520852 -197.249033) (xy 42.576289 -197.255133) (xy 42.630246 -197.269239)
			(xy 42.681575 -197.291051) (xy 42.729181 -197.320105) (xy 42.772049 -197.35578) (xy 42.809266 -197.397317)
			(xy 42.840039 -197.44383) (xy 42.863711 -197.494327) (xy 42.879779 -197.547734) (xy 42.880452 -197.55231)
			(xy 44.632878 -197.55231) (xy 44.636949 -197.496688) (xy 44.649075 -197.442251) (xy 44.668998 -197.39016)
			(xy 44.696294 -197.341525) (xy 44.73038 -197.297382) (xy 44.770529 -197.258673) (xy 44.815887 -197.226222)
			(xy 44.865487 -197.200721) (xy 44.918271 -197.182714) (xy 44.973114 -197.172584) (xy 45.028848 -197.170547)
			(xy 45.084285 -197.176647) (xy 45.138242 -197.190753) (xy 45.189571 -197.212565) (xy 45.237177 -197.241619)
			(xy 45.280045 -197.277294) (xy 45.317262 -197.318831) (xy 45.348035 -197.365344) (xy 45.371707 -197.415841)
			(xy 45.387775 -197.469248) (xy 45.395895 -197.524424) (xy 45.396404 -197.55231) (xy 45.395895 -197.580196)
			(xy 45.388149 -197.632828) (xy 47.819562 -197.632828) (xy 47.823633 -197.577206) (xy 47.835759 -197.522769)
			(xy 47.855682 -197.470678) (xy 47.882978 -197.422043) (xy 47.917064 -197.3779) (xy 47.957213 -197.339191)
			(xy 48.002571 -197.30674) (xy 48.052171 -197.281239) (xy 48.104955 -197.263232) (xy 48.159798 -197.253102)
			(xy 48.215532 -197.251065) (xy 48.270969 -197.257165) (xy 48.324926 -197.271271) (xy 48.376255 -197.293083)
			(xy 48.423861 -197.322137) (xy 48.466729 -197.357812) (xy 48.503946 -197.399349) (xy 48.534719 -197.445862)
			(xy 48.558391 -197.496359) (xy 48.574459 -197.549766) (xy 48.582579 -197.604942) (xy 48.583088 -197.632828)
			(xy 48.582579 -197.660714) (xy 48.574459 -197.71589) (xy 48.558391 -197.769297) (xy 48.534719 -197.819794)
			(xy 48.503946 -197.866307) (xy 48.466729 -197.907844) (xy 48.423861 -197.943519) (xy 48.376255 -197.972573)
			(xy 48.324926 -197.994385) (xy 48.270969 -198.008491) (xy 48.215532 -198.014591) (xy 48.159798 -198.012554)
			(xy 48.104955 -198.002424) (xy 48.052171 -197.984417) (xy 48.002571 -197.958916) (xy 47.957213 -197.926465)
			(xy 47.917064 -197.887756) (xy 47.882978 -197.843613) (xy 47.855682 -197.794978) (xy 47.835759 -197.742887)
			(xy 47.823633 -197.68845) (xy 47.819562 -197.632828) (xy 45.388149 -197.632828) (xy 45.387775 -197.635372)
			(xy 45.371707 -197.688779) (xy 45.348035 -197.739276) (xy 45.317262 -197.785789) (xy 45.280045 -197.827326)
			(xy 45.237177 -197.863001) (xy 45.189571 -197.892055) (xy 45.138242 -197.913867) (xy 45.084285 -197.927973)
			(xy 45.028848 -197.934073) (xy 44.973114 -197.932036) (xy 44.918271 -197.921906) (xy 44.865487 -197.903899)
			(xy 44.815887 -197.878398) (xy 44.770529 -197.845947) (xy 44.73038 -197.807238) (xy 44.696294 -197.763095)
			(xy 44.668998 -197.71446) (xy 44.649075 -197.662369) (xy 44.636949 -197.607932) (xy 44.632878 -197.55231)
			(xy 42.880452 -197.55231) (xy 42.887899 -197.60291) (xy 42.888408 -197.630796) (xy 42.887899 -197.658682)
			(xy 42.879779 -197.713858) (xy 42.863711 -197.767265) (xy 42.840039 -197.817762) (xy 42.809266 -197.864275)
			(xy 42.772049 -197.905812) (xy 42.729181 -197.941487) (xy 42.681575 -197.970541) (xy 42.630246 -197.992353)
			(xy 42.576289 -198.006459) (xy 42.520852 -198.012559) (xy 42.465118 -198.010522) (xy 42.410275 -198.000392)
			(xy 42.357491 -197.982385) (xy 42.307891 -197.956884) (xy 42.262533 -197.924433) (xy 42.222384 -197.885724)
			(xy 42.188298 -197.841581) (xy 42.161002 -197.792946) (xy 42.141079 -197.740855) (xy 42.128953 -197.686418)
			(xy 42.124882 -197.630796) (xy 41.797636 -197.630796) (xy 41.810383 -197.674107) (xy 41.818174 -197.72816)
			(xy 41.818179 -197.782772) (xy 41.81475 -197.809866) (xy 41.811908 -197.833473) (xy 41.814011 -197.880968)
			(xy 41.8249 -197.927245) (xy 41.844197 -197.970695) (xy 41.871229 -198.009803) (xy 41.905056 -198.043209)
			(xy 41.9445 -198.069749) (xy 41.966134 -198.079614) (xy 41.991146 -198.090826) (xy 42.037932 -198.119381)
			(xy 42.080151 -198.154337) (xy 42.116934 -198.194974) (xy 42.147523 -198.240456) (xy 42.17129 -198.289847)
			(xy 42.187746 -198.342131) (xy 42.196551 -198.396231) (xy 42.197524 -198.451034) (xy 42.190646 -198.505413)
			(xy 42.176058 -198.558248) (xy 42.154059 -198.608451) (xy 42.125104 -198.654991) (xy 42.089788 -198.696909)
			(xy 42.048837 -198.733341) (xy 42.003094 -198.76354) (xy 41.953501 -198.786883) (xy 41.901078 -198.802889)
			(xy 41.846905 -198.81123) (xy 41.792095 -198.811733) (xy 41.737777 -198.804389) (xy 41.68507 -198.789348)
			(xy 41.635056 -198.76692) (xy 41.588767 -198.737567) (xy 41.547153 -198.701892) (xy 41.511073 -198.66063)
			(xy 41.481268 -198.61463) (xy 41.458351 -198.564839) (xy 41.442795 -198.512281) (xy 41.434919 -198.458038)
			(xy 41.434886 -198.403226) (xy 41.438322 -198.376032) (xy 41.441183 -198.352427) (xy 41.439079 -198.30493)
			(xy 41.428188 -198.25865) (xy 41.408889 -198.215199) (xy 41.381853 -198.17609) (xy 41.348022 -198.142686)
			(xy 41.308574 -198.116148) (xy 41.286938 -198.106284) (xy 41.261307 -198.094783) (xy 41.21346 -198.065341)
			(xy 41.170448 -198.029202) (xy 41.133199 -197.987147) (xy 41.102519 -197.940086) (xy 41.090342 -197.914768)
			(xy 41.082929 -197.89982) (xy 41.061631 -197.874151) (xy 41.034405 -197.854884) (xy 41.003113 -197.843337)
			(xy 40.969896 -197.840302) (xy 40.93703 -197.845984) (xy 40.921686 -197.852538) (xy 40.896755 -197.863584)
			(xy 40.844489 -197.879141) (xy 40.790542 -197.887099) (xy 40.736011 -197.887296) (xy 40.682007 -197.879727)
			(xy 40.629631 -197.864548) (xy 40.579949 -197.842068) (xy 40.533974 -197.812743) (xy 40.492641 -197.777172)
			(xy 40.456794 -197.736079) (xy 40.427161 -197.690302) (xy 40.404347 -197.640772) (xy 40.388817 -197.588499)
			(xy 40.380887 -197.534547) (xy 40.380718 -197.480016) (xy 13.97508 -197.480016) (xy 13.97508 -197.999622)
			(xy 26.707337 -197.999622) (xy 26.713437 -197.944185) (xy 26.727543 -197.890228) (xy 26.749355 -197.838899)
			(xy 26.778409 -197.791293) (xy 26.814084 -197.748425) (xy 26.855621 -197.711208) (xy 26.902134 -197.680435)
			(xy 26.952631 -197.656763) (xy 27.006038 -197.640695) (xy 27.061214 -197.632575) (xy 27.0891 -197.632066)
			(xy 27.116986 -197.632575) (xy 27.172162 -197.640695) (xy 27.225569 -197.656763) (xy 27.276066 -197.680435)
			(xy 27.322579 -197.711208) (xy 27.364116 -197.748425) (xy 27.399791 -197.791293) (xy 27.428845 -197.838899)
			(xy 27.450657 -197.890228) (xy 27.464763 -197.944185) (xy 27.470863 -197.999622) (xy 27.468826 -198.055356)
			(xy 27.458696 -198.110199) (xy 27.440689 -198.162983) (xy 27.415188 -198.212583) (xy 27.382737 -198.257941)
			(xy 27.344028 -198.29809) (xy 27.299885 -198.332176) (xy 27.25125 -198.359472) (xy 27.199159 -198.379395)
			(xy 27.144722 -198.391521) (xy 27.0891 -198.395592) (xy 27.033478 -198.391521) (xy 26.979041 -198.379395)
			(xy 26.92695 -198.359472) (xy 26.878315 -198.332176) (xy 26.834172 -198.29809) (xy 26.795463 -198.257941)
			(xy 26.763012 -198.212583) (xy 26.737511 -198.162983) (xy 26.719504 -198.110199) (xy 26.709374 -198.055356)
			(xy 26.707337 -197.999622) (xy 13.97508 -197.999622) (xy 13.97508 -198.756218) (xy 24.659906 -198.756218)
			(xy 24.663465 -198.701407) (xy 24.674847 -198.647673) (xy 24.693818 -198.596127) (xy 24.719986 -198.547835)
			(xy 24.752808 -198.503794) (xy 24.791607 -198.464916) (xy 24.835581 -198.432004) (xy 24.88382 -198.405739)
			(xy 24.935328 -198.386663) (xy 24.989038 -198.375171) (xy 25.043841 -198.371501) (xy 25.098605 -198.375728)
			(xy 25.152196 -198.387765) (xy 25.203506 -198.407364) (xy 25.251476 -198.434118) (xy 25.295113 -198.467475)
			(xy 25.314656 -198.486776) (xy 25.330572 -198.502337) (xy 25.366753 -198.528256) (xy 25.406895 -198.547475)
			(xy 25.449773 -198.559406) (xy 25.494073 -198.563686) (xy 25.538441 -198.560182) (xy 25.581521 -198.549003)
			(xy 25.621994 -198.530489) (xy 25.658623 -198.505208) (xy 25.690288 -198.473932) (xy 25.70353 -198.456042)
			(xy 25.720177 -198.433563) (xy 25.758847 -198.393154) (xy 25.803002 -198.358824) (xy 25.851697 -198.331309)
			(xy 25.903887 -198.311197) (xy 25.958454 -198.298922) (xy 26.014229 -198.294744) (xy 26.070016 -198.298755)
			(xy 26.12462 -198.310868) (xy 26.17687 -198.330823) (xy 26.225647 -198.358193) (xy 26.269904 -198.392391)
			(xy 26.308695 -198.432684) (xy 26.341187 -198.478209) (xy 26.366684 -198.527991) (xy 26.38464 -198.580961)
			(xy 26.39467 -198.635985) (xy 26.396558 -198.691884) (xy 26.390265 -198.74746) (xy 26.375925 -198.801522)
			(xy 26.353846 -198.85291) (xy 26.3245 -198.900524) (xy 26.288518 -198.943344) (xy 26.267918 -198.962264)
			(xy 26.252141 -198.976872) (xy 26.225214 -199.010388) (xy 26.204315 -199.04796) (xy 26.190042 -199.088514)
			(xy 26.1828 -199.130892) (xy 26.182799 -199.173885) (xy 26.190036 -199.216264) (xy 26.204306 -199.25682)
			(xy 26.225201 -199.294393) (xy 26.252125 -199.327911) (xy 26.267918 -199.342502) (xy 26.27812 -199.351728)
			(xy 26.297317 -199.371431) (xy 26.306272 -199.381872) (xy 26.321548 -199.399119) (xy 26.35714 -199.428367)
			(xy 26.397422 -199.450717) (xy 26.441074 -199.465436) (xy 26.486665 -199.472042) (xy 26.5327 -199.470318)
			(xy 26.577669 -199.46032) (xy 26.620098 -199.442377) (xy 26.658596 -199.417077) (xy 26.691899 -199.385248)
			(xy 26.705814 -199.366886) (xy 26.72205 -199.345363) (xy 26.759485 -199.30657) (xy 26.802008 -199.273433)
			(xy 26.848772 -199.24661) (xy 26.898846 -199.226637) (xy 26.951232 -199.213911) (xy 27.004888 -199.208686)
			(xy 27.058746 -199.211065) (xy 27.111732 -199.221001) (xy 27.162792 -199.238296) (xy 27.21091 -199.262606)
			(xy 27.255127 -199.293447) (xy 27.294562 -199.330205) (xy 27.311858 -199.350884) (xy 27.326664 -199.368509)
			(xy 27.361564 -199.39852) (xy 27.401298 -199.421755) (xy 27.444567 -199.437455) (xy 27.489955 -199.445106)
			(xy 27.53598 -199.444458) (xy 27.581135 -199.435533) (xy 27.623945 -199.418621) (xy 27.663009 -199.394277)
			(xy 27.697051 -199.363296) (xy 27.7114 -199.345296) (xy 27.719323 -199.335082) (xy 27.736355 -199.315633)
			(xy 27.745436 -199.306434) (xy 27.760903 -199.290443) (xy 27.78649 -199.254052) (xy 27.805345 -199.213759)
			(xy 27.816893 -199.170798) (xy 27.820779 -199.126482) (xy 27.816886 -199.082167) (xy 27.805333 -199.039207)
			(xy 27.786472 -198.998918) (xy 27.76088 -198.96253) (xy 27.745436 -198.946516) (xy 27.726469 -198.926929)
			(xy 27.693755 -198.883309) (xy 27.667585 -198.835477) (xy 27.648492 -198.784405) (xy 27.636864 -198.731136)
			(xy 27.632939 -198.676754) (xy 27.636796 -198.622367) (xy 27.648357 -198.569083) (xy 27.667386 -198.517988)
			(xy 27.693496 -198.470122) (xy 27.726154 -198.426462) (xy 27.764696 -198.387896) (xy 27.808336 -198.355209)
			(xy 27.856186 -198.32907) (xy 27.907269 -198.310008) (xy 27.960545 -198.298414) (xy 28.01493 -198.294523)
			(xy 28.069315 -198.298414) (xy 28.122591 -198.310008) (xy 28.173674 -198.32907) (xy 28.221524 -198.355209)
			(xy 28.265164 -198.387896) (xy 28.303706 -198.426462) (xy 28.336364 -198.470122) (xy 28.362474 -198.517988)
			(xy 28.381503 -198.569083) (xy 28.393064 -198.622367) (xy 28.396921 -198.676754) (xy 28.392996 -198.731136)
			(xy 28.381368 -198.784405) (xy 28.362275 -198.835477) (xy 28.336105 -198.883309) (xy 28.303391 -198.926929)
			(xy 28.284424 -198.946516) (xy 28.26904 -198.96257) (xy 28.243515 -198.998971) (xy 28.224706 -199.039254)
			(xy 28.213185 -199.082194) (xy 28.209303 -199.126482) (xy 28.213179 -199.170771) (xy 28.224694 -199.213713)
			(xy 28.243498 -199.253999) (xy 28.269018 -199.290403) (xy 28.284424 -199.306434) (xy 28.303955 -199.326767)
			(xy 28.337572 -199.372022) (xy 28.364164 -199.421731) (xy 28.383151 -199.474811) (xy 28.394121 -199.530109)
			(xy 28.396834 -199.586418) (xy 28.391231 -199.642513) (xy 28.377435 -199.697174) (xy 28.355746 -199.749209)
			(xy 28.326635 -199.797486) (xy 28.290738 -199.840954) (xy 28.248835 -199.878667) (xy 28.201838 -199.909802)
			(xy 28.150771 -199.933683) (xy 28.096747 -199.94979) (xy 28.04094 -199.957771) (xy 27.984566 -199.957454)
			(xy 27.928853 -199.948844) (xy 27.875013 -199.93213) (xy 27.824219 -199.907675) (xy 27.777576 -199.876011)
			(xy 27.736101 -199.837829) (xy 27.718004 -199.816212) (xy 27.703127 -199.79865) (xy 27.668238 -199.76864)
			(xy 27.628516 -199.745403) (xy 27.585258 -199.7297) (xy 27.539879 -199.722044) (xy 27.493864 -199.722685)
			(xy 27.448716 -199.731601) (xy 27.405912 -199.748503) (xy 27.366851 -199.772836) (xy 27.332811 -199.803806)
			(xy 27.318462 -199.8218) (xy 27.300795 -199.844107) (xy 27.259986 -199.883759) (xy 27.213741 -199.916911)
			(xy 27.163084 -199.942826) (xy 27.10914 -199.96093) (xy 27.053106 -199.97082) (xy 26.996224 -199.972279)
			(xy 26.939756 -199.965272) (xy 26.884955 -199.949957) (xy 26.833037 -199.926672) (xy 26.785153 -199.895934)
			(xy 26.742366 -199.858425) (xy 26.723594 -199.83704) (xy 26.708356 -199.819757) (xy 26.672759 -199.790507)
			(xy 26.632471 -199.768157) (xy 26.588813 -199.753439) (xy 26.543216 -199.746836) (xy 26.497176 -199.748564)
			(xy 26.452202 -199.758567) (xy 26.40977 -199.776517) (xy 26.37127 -199.801824) (xy 26.337966 -199.83366)
			(xy 26.324052 -199.852026) (xy 26.307296 -199.874339) (xy 26.268344 -199.914293) (xy 26.223988 -199.948149)
			(xy 26.175176 -199.975185) (xy 26.122947 -199.994825) (xy 26.068414 -200.00665) (xy 26.012741 -200.010408)
			(xy 25.957114 -200.006018) (xy 25.90272 -199.993575) (xy 25.850717 -199.973344) (xy 25.802214 -199.945756)
			(xy 25.758246 -199.911398) (xy 25.71975 -199.871005) (xy 25.687546 -199.825436) (xy 25.662322 -199.775663)
			(xy 25.644614 -199.722748) (xy 25.6348 -199.667818) (xy 25.63309 -199.612044) (xy 25.63952 -199.556616)
			(xy 25.653952 -199.502715) (xy 25.67608 -199.451491) (xy 25.705432 -199.404034) (xy 25.741381 -199.361358)
			(xy 25.76195 -199.342502) (xy 25.77779 -199.327945) (xy 25.804771 -199.294442) (xy 25.825713 -199.256867)
			(xy 25.840017 -199.216298) (xy 25.847272 -199.173897) (xy 25.84727 -199.13088) (xy 25.840011 -199.08848)
			(xy 25.825704 -199.047912) (xy 25.804758 -199.010339) (xy 25.777774 -198.976838) (xy 25.76195 -198.962264)
			(xy 25.742138 -198.943214) (xy 25.726238 -198.927634) (xy 25.690057 -198.901706) (xy 25.649912 -198.882479)
			(xy 25.607031 -198.870543) (xy 25.562725 -198.866262) (xy 25.518351 -198.869767) (xy 25.475268 -198.880952)
			(xy 25.434792 -198.899473) (xy 25.398164 -198.924765) (xy 25.366503 -198.956052) (xy 25.353264 -198.973948)
			(xy 25.336996 -198.99608) (xy 25.299157 -199.035893) (xy 25.255999 -199.069868) (xy 25.208415 -199.097302)
			(xy 25.157388 -199.117628) (xy 25.103974 -199.130427) (xy 25.049277 -199.135433) (xy 24.994427 -199.132542)
			(xy 24.940558 -199.121816) (xy 24.888784 -199.103475) (xy 24.840176 -199.077899) (xy 24.795739 -199.045616)
			(xy 24.75639 -199.007294) (xy 24.722945 -198.963725) (xy 24.696093 -198.915809) (xy 24.67639 -198.864539)
			(xy 24.664244 -198.810972) (xy 24.659906 -198.756218) (xy 13.97508 -198.756218) (xy 13.97508 -199.951594)
			(xy 13.97555 -199.973856) (xy 13.983322 -200.017698) (xy 13.998612 -200.059515) (xy 14.020952 -200.09803)
			(xy 14.049659 -200.132064) (xy 14.083856 -200.160578) (xy 14.122497 -200.182699) (xy 14.164401 -200.19775)
			(xy 14.208286 -200.205273) (xy 14.25281 -200.205037) (xy 14.2748 -200.20153) (xy 14.302516 -200.196397)
			(xy 14.358802 -200.193388) (xy 14.414918 -200.198693) (xy 14.469643 -200.212195) (xy 14.521786 -200.233602)
			(xy 14.570212 -200.262447) (xy 14.613868 -200.298102) (xy 14.651803 -200.339792) (xy 14.683192 -200.386609)
			(xy 14.707352 -200.437535) (xy 14.723757 -200.491461) (xy 14.73205 -200.547213) (xy 14.732051 -200.603579)
			(xy 14.723759 -200.659332) (xy 14.707355 -200.713259) (xy 14.683196 -200.764185) (xy 14.651808 -200.811002)
			(xy 14.613873 -200.852693) (xy 14.570218 -200.888349) (xy 14.521792 -200.917195) (xy 14.46965 -200.938602)
			(xy 14.414925 -200.952106) (xy 14.358809 -200.957411) (xy 14.302523 -200.954404) (xy 14.2748 -200.949306)
			(xy 14.25281 -200.945745) (xy 14.208267 -200.945475) (xy 14.164359 -200.952976) (xy 14.122432 -200.968018)
			(xy 14.08377 -200.990141) (xy 14.049558 -201.018667) (xy 14.020844 -201.052721) (xy 13.998948 -201.090502)
			(xy 17.633033 -201.090502) (xy 17.636925 -201.036147) (xy 17.648513 -200.9829) (xy 17.667561 -200.931844)
			(xy 17.693682 -200.884018) (xy 17.709642 -200.86193) (xy 17.723208 -200.842898) (xy 17.743939 -200.801019)
			(xy 17.756666 -200.756056) (xy 17.76096 -200.709524) (xy 17.756675 -200.662991) (xy 17.743956 -200.618026)
			(xy 17.723233 -200.576143) (xy 17.709642 -200.55713) (xy 17.693682 -200.535042) (xy 17.667561 -200.487216)
			(xy 17.648513 -200.43616) (xy 17.636925 -200.382913) (xy 17.633033 -200.328558) (xy 17.636917 -200.274203)
			(xy 17.648497 -200.220954) (xy 17.667538 -200.169895) (xy 17.693652 -200.122065) (xy 17.726307 -200.078439)
			(xy 17.764838 -200.039905) (xy 17.808462 -200.007247) (xy 17.856289 -199.98113) (xy 17.907347 -199.962085)
			(xy 17.960595 -199.950501) (xy 18.01495 -199.946613) (xy 18.069305 -199.950501) (xy 18.122553 -199.962085)
			(xy 18.173611 -199.98113) (xy 18.221438 -200.007247) (xy 18.265062 -200.039905) (xy 18.303593 -200.078439)
			(xy 18.336248 -200.122065) (xy 18.362362 -200.169895) (xy 18.381403 -200.220954) (xy 18.392983 -200.274203)
			(xy 18.396867 -200.328558) (xy 18.392975 -200.382913) (xy 18.381387 -200.43616) (xy 18.362339 -200.487216)
			(xy 18.336218 -200.535042) (xy 18.320258 -200.55713) (xy 18.306637 -200.576124) (xy 18.28591 -200.618013)
			(xy 18.27319 -200.662985) (xy 18.268904 -200.709524) (xy 18.273198 -200.756063) (xy 18.285927 -200.801032)
			(xy 18.306662 -200.842917) (xy 18.320258 -200.86193) (xy 18.336218 -200.884018) (xy 18.362339 -200.931844)
			(xy 18.381387 -200.9829) (xy 18.392975 -201.036147) (xy 18.396867 -201.090502) (xy 20.633027 -201.090502)
			(xy 20.636919 -201.036147) (xy 20.648507 -200.9829) (xy 20.667555 -200.931844) (xy 20.693676 -200.884018)
			(xy 20.709636 -200.86193) (xy 20.723202 -200.842898) (xy 20.743934 -200.801019) (xy 20.756661 -200.756056)
			(xy 20.760955 -200.709524) (xy 20.75667 -200.662991) (xy 20.743951 -200.618026) (xy 20.723227 -200.576143)
			(xy 20.709636 -200.55713) (xy 20.693676 -200.535042) (xy 20.667555 -200.487216) (xy 20.648507 -200.43616)
			(xy 20.636919 -200.382913) (xy 20.633027 -200.328558) (xy 20.636911 -200.274203) (xy 20.648491 -200.220954)
			(xy 20.667532 -200.169895) (xy 20.693646 -200.122065) (xy 20.726301 -200.078439) (xy 20.764832 -200.039905)
			(xy 20.808456 -200.007247) (xy 20.856283 -199.98113) (xy 20.907341 -199.962085) (xy 20.960589 -199.950501)
			(xy 21.014944 -199.946613) (xy 21.069299 -199.950501) (xy 21.122547 -199.962085) (xy 21.173605 -199.98113)
			(xy 21.221432 -200.007247) (xy 21.265056 -200.039905) (xy 21.303587 -200.078439) (xy 21.336242 -200.122065)
			(xy 21.362356 -200.169895) (xy 21.381397 -200.220954) (xy 21.392977 -200.274203) (xy 21.396861 -200.328558)
			(xy 21.392969 -200.382913) (xy 21.381381 -200.43616) (xy 21.362333 -200.487216) (xy 21.336212 -200.535042)
			(xy 21.320252 -200.55713) (xy 21.306631 -200.576124) (xy 21.285905 -200.618013) (xy 21.273185 -200.662985)
			(xy 21.2689 -200.709524) (xy 21.273194 -200.756062) (xy 21.285922 -200.801032) (xy 21.306656 -200.842917)
			(xy 21.320252 -200.86193) (xy 21.336212 -200.884018) (xy 21.362333 -200.931844) (xy 21.381381 -200.9829)
			(xy 21.392969 -201.036147) (xy 21.396861 -201.090502) (xy 23.633021 -201.090502) (xy 23.636913 -201.036147)
			(xy 23.648501 -200.9829) (xy 23.667549 -200.931844) (xy 23.69367 -200.884018) (xy 23.70963 -200.86193)
			(xy 23.723196 -200.842898) (xy 23.743929 -200.801019) (xy 23.756656 -200.756056) (xy 23.76095 -200.709524)
			(xy 23.756665 -200.662991) (xy 23.743946 -200.618025) (xy 23.723221 -200.576143) (xy 23.70963 -200.55713)
			(xy 23.693785 -200.535147) (xy 23.667768 -200.487614) (xy 23.648741 -200.436877) (xy 23.637088 -200.383958)
			(xy 23.633042 -200.329921) (xy 23.636685 -200.275857) (xy 23.647945 -200.222852) (xy 23.666593 -200.171975)
			(xy 23.692256 -200.124249) (xy 23.724415 -200.080637) (xy 23.762424 -200.042016) (xy 23.805516 -200.009163)
			(xy 23.852825 -199.982741) (xy 23.903398 -199.963281) (xy 23.956216 -199.951175) (xy 24.010215 -199.946668)
			(xy 24.03729 -199.947784) (xy 24.058733 -199.948673) (xy 24.101388 -199.943938) (xy 24.14264 -199.932099)
			(xy 24.181315 -199.913494) (xy 24.216311 -199.888651) (xy 24.246632 -199.858278) (xy 24.271415 -199.823239)
			(xy 24.289954 -199.784533) (xy 24.301722 -199.743261) (xy 24.304498 -199.721978) (xy 24.308039 -199.694409)
			(xy 24.322093 -199.640632) (xy 24.343803 -199.589465) (xy 24.372709 -199.54199) (xy 24.4082 -199.499213)
			(xy 24.449523 -199.46204) (xy 24.495804 -199.431259) (xy 24.546062 -199.40752) (xy 24.599234 -199.391327)
			(xy 24.654193 -199.383022) (xy 24.709775 -199.382782) (xy 24.764803 -199.390611) (xy 24.818113 -199.406344)
			(xy 24.868574 -199.429648) (xy 24.915119 -199.460028) (xy 24.956762 -199.496842) (xy 24.992621 -199.539311)
			(xy 25.021937 -199.586534) (xy 25.044088 -199.637512) (xy 25.058606 -199.691165) (xy 25.065184 -199.746357)
			(xy 25.063681 -199.801919) (xy 25.05413 -199.856675) (xy 25.036734 -199.909465) (xy 25.01186 -199.959171)
			(xy 24.980034 -200.004741) (xy 24.941933 -200.045209) (xy 24.898361 -200.079719) (xy 24.850242 -200.10754)
			(xy 24.798594 -200.128082) (xy 24.744512 -200.140911) (xy 24.689141 -200.145754) (xy 24.661368 -200.144634)
			(xy 24.639923 -200.143875) (xy 24.597279 -200.148598) (xy 24.556036 -200.160424) (xy 24.517367 -200.179014)
			(xy 24.482375 -200.203841) (xy 24.452053 -200.234197) (xy 24.427267 -200.269218) (xy 24.408721 -200.307907)
			(xy 24.396942 -200.349164) (xy 24.39416 -200.37044) (xy 24.390919 -200.395643) (xy 24.378654 -200.444954)
			(xy 24.359953 -200.492201) (xy 24.335147 -200.536548) (xy 24.320246 -200.55713) (xy 24.30662 -200.576122)
			(xy 24.285887 -200.61801) (xy 24.273162 -200.662983) (xy 24.268875 -200.709524) (xy 24.27317 -200.756065)
			(xy 24.285904 -200.801035) (xy 24.306646 -200.842919) (xy 24.320246 -200.86193) (xy 24.336206 -200.884018)
			(xy 24.362327 -200.931844) (xy 24.381375 -200.9829) (xy 24.392963 -201.036147) (xy 24.396855 -201.090502)
			(xy 28.633011 -201.090502) (xy 28.636903 -201.036147) (xy 28.648491 -200.9829) (xy 28.667539 -200.931844)
			(xy 28.69366 -200.884018) (xy 28.70962 -200.86193) (xy 28.723187 -200.842899) (xy 28.74392 -200.80102)
			(xy 28.756648 -200.756056) (xy 28.760942 -200.709524) (xy 28.756657 -200.662991) (xy 28.743937 -200.618025)
			(xy 28.723212 -200.576142) (xy 28.70962 -200.55713) (xy 28.693108 -200.534185) (xy 28.666273 -200.484435)
			(xy 28.647075 -200.431268) (xy 28.635935 -200.37585) (xy 28.633097 -200.319395) (xy 28.638623 -200.263139)
			(xy 28.652392 -200.208315) (xy 28.674103 -200.156124) (xy 28.703279 -200.107709) (xy 28.739282 -200.064131)
			(xy 28.781323 -200.026345) (xy 28.82848 -199.995177) (xy 28.879722 -199.971312) (xy 28.933925 -199.955272)
			(xy 28.961842 -199.950832) (xy 28.983338 -199.947363) (xy 29.024785 -199.934023) (xy 29.06335 -199.913812)
			(xy 29.097904 -199.88732) (xy 29.127435 -199.855325) (xy 29.151077 -199.818763) (xy 29.16814 -199.778706)
			(xy 29.178122 -199.736325) (xy 29.180732 -199.692863) (xy 29.178758 -199.671178) (xy 29.176162 -199.643875)
			(xy 29.178008 -199.589061) (xy 29.18768 -199.535075) (xy 29.204979 -199.483029) (xy 29.229549 -199.433996)
			(xy 29.260884 -199.388983) (xy 29.298339 -199.348919) (xy 29.341143 -199.314627) (xy 29.388413 -199.286815)
			(xy 29.439178 -199.266055) (xy 29.492391 -199.252774) (xy 29.519626 -199.249538) (xy 29.535607 -199.247543)
			(xy 29.565821 -199.236407) (xy 29.592289 -199.218068) (xy 29.613329 -199.193691) (xy 29.627602 -199.164826)
			(xy 29.634203 -199.133309) (xy 29.633926 -199.117204) (xy 29.633147 -199.089856) (xy 29.63843 -199.035402)
			(xy 29.651442 -198.982262) (xy 29.671916 -198.931528) (xy 29.699432 -198.884241) (xy 29.733424 -198.841373)
			(xy 29.773195 -198.803804) (xy 29.817927 -198.772305) (xy 29.866702 -198.747523) (xy 29.918519 -198.729968)
			(xy 29.94533 -198.72452) (xy 29.966522 -198.720078) (xy 30.007138 -198.705093) (xy 30.044625 -198.683438)
			(xy 30.077897 -198.655739) (xy 30.10599 -198.622799) (xy 30.12809 -198.585573) (xy 30.143558 -198.545138)
			(xy 30.151945 -198.502665) (xy 30.153009 -198.459386) (xy 30.146718 -198.416553) (xy 30.140402 -198.395844)
			(xy 30.132101 -198.369071) (xy 30.12262 -198.313826) (xy 30.121324 -198.257788) (xy 30.128242 -198.202164)
			(xy 30.143224 -198.148151) (xy 30.165948 -198.096911) (xy 30.195924 -198.049547) (xy 30.232508 -198.007079)
			(xy 30.274912 -197.970421) (xy 30.322223 -197.940362) (xy 30.373424 -197.917549) (xy 30.427411 -197.902473)
			(xy 30.483023 -197.895458) (xy 30.539063 -197.896656) (xy 30.594325 -197.906041) (xy 30.647618 -197.92341)
			(xy 30.697797 -197.94839) (xy 30.743781 -197.980444) (xy 30.784579 -198.01888) (xy 30.819315 -198.062873)
			(xy 30.84724 -198.111474) (xy 30.867754 -198.163638) (xy 30.880414 -198.218243) (xy 30.884948 -198.274112)
			(xy 30.881259 -198.330043) (xy 30.869426 -198.384833) (xy 30.849704 -198.437301) (xy 30.822516 -198.486319)
			(xy 30.78845 -198.530832) (xy 30.748237 -198.569881) (xy 30.702743 -198.602625) (xy 30.652948 -198.628361)
			(xy 30.599923 -198.646534) (xy 30.572456 -198.65213) (xy 30.551247 -198.6565) (xy 30.510626 -198.671492)
			(xy 30.473135 -198.693155) (xy 30.439861 -198.720862) (xy 30.411768 -198.75381) (xy 30.389669 -198.791045)
			(xy 30.374204 -198.831489) (xy 30.365822 -198.873969) (xy 30.364765 -198.917256) (xy 30.371064 -198.960095)
			(xy 30.377384 -198.980806) (xy 30.38577 -199.007959) (xy 30.395261 -199.063989) (xy 30.396335 -199.120807)
			(xy 30.388969 -199.177155) (xy 30.373326 -199.231788) (xy 30.349751 -199.283495) (xy 30.318767 -199.331134)
			(xy 30.281058 -199.373648) (xy 30.238181 -199.409496) (xy 30.788871 -199.409496) (xy 30.791842 -199.354895)
			(xy 30.802576 -199.301276) (xy 30.820855 -199.24974) (xy 30.846303 -199.20134) (xy 30.878399 -199.157068)
			(xy 30.916487 -199.117832) (xy 30.959785 -199.084435) (xy 31.007407 -199.05756) (xy 31.058378 -199.037758)
			(xy 31.111654 -199.025435) (xy 31.166143 -199.020843) (xy 31.220729 -199.024077) (xy 31.274295 -199.035069)
			(xy 31.325743 -199.053596) (xy 31.37402 -199.079277) (xy 31.418136 -199.111586) (xy 31.457189 -199.149861)
			(xy 31.474156 -199.171306) (xy 31.488496 -199.189185) (xy 31.522395 -199.220021) (xy 31.561272 -199.244283)
			(xy 31.603867 -199.261183) (xy 31.648802 -199.270175) (xy 31.694621 -199.270968) (xy 31.739841 -199.263536)
			(xy 31.782995 -199.24812) (xy 31.803086 -199.237092) (xy 31.82018 -199.227513) (xy 31.855935 -199.211474)
			(xy 31.87446 -199.205088) (xy 31.896244 -199.197395) (xy 31.936779 -199.175242) (xy 31.972644 -199.14613)
			(xy 32.00266 -199.111017) (xy 32.025839 -199.071059) (xy 32.041417 -199.027571) (xy 32.048881 -198.981985)
			(xy 32.047987 -198.9358) (xy 32.038764 -198.890536) (xy 32.021515 -198.847684) (xy 32.009588 -198.827898)
			(xy 31.995112 -198.804046) (xy 31.972389 -198.753093) (xy 31.95733 -198.699373) (xy 31.950257 -198.644033)
			(xy 31.951319 -198.588252) (xy 31.960496 -198.533222) (xy 31.97759 -198.480115) (xy 32.002237 -198.430064)
			(xy 32.033912 -198.384137) (xy 32.071938 -198.343313) (xy 32.115506 -198.308464) (xy 32.163684 -198.280332)
			(xy 32.215447 -198.259518) (xy 32.269689 -198.246466) (xy 32.325254 -198.241453) (xy 32.380957 -198.244588)
			(xy 32.435608 -198.255803) (xy 32.488044 -198.274858) (xy 32.537144 -198.301348) (xy 32.581863 -198.334707)
			(xy 32.621245 -198.374225) (xy 32.638238 -198.396352) (xy 32.652142 -198.414159) (xy 32.685066 -198.445084)
			(xy 32.722938 -198.469703) (xy 32.764565 -198.48724) (xy 32.808636 -198.497145) (xy 32.853764 -198.499105)
			(xy 32.898528 -198.493057) (xy 32.941519 -198.479194) (xy 32.981382 -198.45795) (xy 32.999426 -198.444358)
			(xy 33.020924 -198.427876) (xy 33.067765 -198.400661) (xy 33.117984 -198.380345) (xy 33.170572 -198.367336)
			(xy 33.224471 -198.361895) (xy 33.278598 -198.364131) (xy 33.331864 -198.374001) (xy 33.3832 -198.391304)
			(xy 33.431572 -198.415694) (xy 33.476008 -198.44668) (xy 33.515615 -198.483639) (xy 33.549597 -198.525829)
			(xy 33.575564 -198.569528) (xy 34.027736 -198.569528) (xy 34.028981 -198.515054) (xy 34.037962 -198.46131)
			(xy 34.054495 -198.409391) (xy 34.078245 -198.360351) (xy 34.108729 -198.315188) (xy 34.145326 -198.274819)
			(xy 34.187293 -198.240067) (xy 34.233777 -198.211637) (xy 34.283832 -198.190108) (xy 34.336439 -198.175917)
			(xy 34.390531 -198.169353) (xy 34.445006 -198.170549) (xy 34.498757 -198.179482) (xy 34.550692 -198.195968)
			(xy 34.599753 -198.219675) (xy 34.644943 -198.250118) (xy 34.685344 -198.286679) (xy 34.720134 -198.328615)
			(xy 34.748606 -198.375073) (xy 34.77018 -198.425109) (xy 34.771451 -198.429804) (xy 35.076639 -198.429804)
			(xy 35.082783 -198.375389) (xy 35.096643 -198.322411) (xy 35.117933 -198.271958) (xy 35.146217 -198.225066)
			(xy 35.180913 -198.182699) (xy 35.221309 -198.145727) (xy 35.266575 -198.114909) (xy 35.315781 -198.090878)
			(xy 35.367918 -198.074127) (xy 35.421913 -198.065001) (xy 35.476658 -198.063687) (xy 35.531029 -198.070212)
			(xy 35.583909 -198.084443) (xy 35.634212 -198.106086) (xy 35.680904 -198.134697) (xy 35.723027 -198.169689)
			(xy 35.759716 -198.210342) (xy 35.787241 -198.251387) (xy 36.593268 -198.251387) (xy 36.59955 -198.196755)
			(xy 36.613609 -198.143591) (xy 36.635154 -198.092996) (xy 36.663739 -198.046017) (xy 36.698773 -198.003629)
			(xy 36.739528 -197.966709) (xy 36.785162 -197.936023) (xy 36.834728 -197.912205) (xy 36.8872 -197.895749)
			(xy 36.94149 -197.886996) (xy 36.996475 -197.886128) (xy 37.051015 -197.893162) (xy 37.103981 -197.907953)
			(xy 37.154274 -197.930194) (xy 37.200854 -197.959424) (xy 37.242755 -197.995039) (xy 37.261292 -198.015352)
			(xy 37.276583 -198.031979) (xy 37.311918 -198.060113) (xy 37.35167 -198.081556) (xy 37.394588 -198.095631)
			(xy 37.439318 -198.101896) (xy 37.484451 -198.100152) (xy 37.528565 -198.090454) (xy 37.570268 -198.073109)
			(xy 37.608248 -198.048663) (xy 37.641306 -198.017886) (xy 37.655246 -198.000112) (xy 37.672001 -197.97857)
			(xy 37.710627 -197.940018) (xy 37.754352 -197.907363) (xy 37.802284 -197.881272) (xy 37.853444 -197.862277)
			(xy 37.906789 -197.850764) (xy 37.96123 -197.846971) (xy 38.015656 -197.850972) (xy 38.068957 -197.862688)
			(xy 38.120044 -197.881879) (xy 38.167876 -197.908154) (xy 38.211476 -197.940975) (xy 38.249954 -197.979674)
			(xy 38.282526 -198.023461) (xy 38.308527 -198.071442) (xy 38.327425 -198.122639) (xy 38.338837 -198.176005)
			(xy 38.342527 -198.230453) (xy 38.338422 -198.284872) (xy 38.326606 -198.33815) (xy 38.307318 -198.389201)
			(xy 38.280953 -198.436983) (xy 38.248049 -198.480521) (xy 38.209277 -198.518926) (xy 38.18763 -198.535544)
			(xy 38.17468 -198.545736) (xy 38.15416 -198.571512) (xy 38.140917 -198.601681) (xy 38.135832 -198.634233)
			(xy 38.139245 -198.667003) (xy 38.150928 -198.697809) (xy 38.170103 -198.724602) (xy 38.195494 -198.745597)
			(xy 38.210236 -198.752968) (xy 38.23196 -198.763306) (xy 38.272852 -198.788651) (xy 38.29177 -198.803514)
			(xy 38.309267 -198.81703) (xy 38.347918 -198.838489) (xy 38.389701 -198.852932) (xy 38.433352 -198.859922)
			(xy 38.477556 -198.85925) (xy 38.520975 -198.850935) (xy 38.562298 -198.835228) (xy 38.600279 -198.812604)
			(xy 38.633769 -198.783746) (xy 38.648132 -198.766938) (xy 38.667811 -198.74385) (xy 38.713185 -198.703588)
			(xy 38.76436 -198.671017) (xy 38.820047 -198.646959) (xy 38.8493 -198.638922) (xy 38.872094 -198.632565)
			(xy 38.914991 -198.6126) (xy 38.953452 -198.585042) (xy 38.986148 -198.550841) (xy 39.01195 -198.511179)
			(xy 39.029966 -198.467428) (xy 39.039574 -198.421098) (xy 39.040441 -198.373791) (xy 39.037006 -198.350378)
			(xy 39.032837 -198.323063) (xy 39.031555 -198.267821) (xy 39.038254 -198.212972) (xy 39.052793 -198.159663)
			(xy 39.07487 -198.109009) (xy 39.104021 -198.062068) (xy 39.139639 -198.019823) (xy 39.180976 -197.983156)
			(xy 39.227171 -197.952835) (xy 39.277255 -197.929494) (xy 39.330182 -197.91362) (xy 39.384845 -197.905546)
			(xy 39.440101 -197.905441) (xy 39.494795 -197.913306) (xy 39.547782 -197.928978) (xy 39.597955 -197.952128)
			(xy 39.644265 -197.982273) (xy 39.685742 -198.018781) (xy 39.72152 -198.060891) (xy 39.75085 -198.10772)
			(xy 39.77312 -198.15829) (xy 39.787863 -198.211543) (xy 39.794771 -198.266366) (xy 39.7937 -198.321612)
			(xy 39.784672 -198.376125) (xy 39.767875 -198.428767) (xy 39.743662 -198.478436) (xy 39.712538 -198.524092)
			(xy 39.675154 -198.564783) (xy 39.632293 -198.599656) (xy 39.58485 -198.627983) (xy 39.533817 -198.649171)
			(xy 39.50716 -198.656448) (xy 39.484369 -198.662812) (xy 39.441475 -198.682779) (xy 39.403018 -198.710339)
			(xy 39.370323 -198.744539) (xy 39.344522 -198.784199) (xy 39.326505 -198.827947) (xy 39.316895 -198.874274)
			(xy 39.316023 -198.92158) (xy 39.319454 -198.944992) (xy 39.323557 -198.971839) (xy 39.324927 -199.026131)
			(xy 39.318585 -199.080069) (xy 39.304658 -199.132563) (xy 39.283428 -199.182552) (xy 39.255325 -199.229025)
			(xy 39.220915 -199.271043) (xy 39.180895 -199.307757) (xy 39.136073 -199.338426) (xy 39.087355 -199.362428)
			(xy 39.035726 -199.37928) (xy 38.982229 -199.388641) (xy 38.927945 -199.390321) (xy 38.873972 -199.384286)
			(xy 38.821399 -199.370659) (xy 38.771291 -199.349715) (xy 38.724658 -199.321877) (xy 38.70325 -199.305164)
			(xy 38.685745 -199.291656) (xy 38.647097 -199.270189) (xy 38.605316 -199.255739) (xy 38.561664 -199.248744)
			(xy 38.51746 -199.249414) (xy 38.474039 -199.257729) (xy 38.432715 -199.273437) (xy 38.394736 -199.296065)
			(xy 38.361249 -199.324929) (xy 38.346888 -199.34174) (xy 38.329276 -199.362575) (xy 38.289037 -199.399417)
			(xy 38.243961 -199.430151) (xy 38.194967 -199.454152) (xy 38.143054 -199.470931) (xy 38.08928 -199.480146)
			(xy 38.034743 -199.481607) (xy 37.980553 -199.475287) (xy 37.927816 -199.461313) (xy 37.877607 -199.439971)
			(xy 37.830949 -199.411695) (xy 37.788793 -199.377062) (xy 37.770054 -199.357234) (xy 37.754079 -199.340424)
			(xy 37.717146 -199.312387) (xy 37.675736 -199.291523) (xy 37.631225 -199.278526) (xy 37.585094 -199.273827)
			(xy 37.538877 -199.277583) (xy 37.494111 -199.28967) (xy 37.452284 -199.309685) (xy 37.414786 -199.336962)
			(xy 37.398452 -199.353424) (xy 37.378898 -199.373326) (xy 37.334982 -199.40774) (xy 37.286522 -199.435392)
			(xy 37.234552 -199.455691) (xy 37.18018 -199.468205) (xy 37.124565 -199.472667) (xy 37.068893 -199.468981)
			(xy 37.014351 -199.457227) (xy 36.962103 -199.437655) (xy 36.913262 -199.410682) (xy 36.868871 -199.376883)
			(xy 36.829875 -199.33698) (xy 36.797106 -199.291823) (xy 36.771263 -199.242375) (xy 36.752897 -199.189691)
			(xy 36.7424 -199.134893) (xy 36.739996 -199.079151) (xy 36.745735 -199.023653) (xy 36.759496 -198.969583)
			(xy 36.780984 -198.918093) (xy 36.794948 -198.893938) (xy 36.806222 -198.874105) (xy 36.822337 -198.831434)
			(xy 36.830577 -198.786571) (xy 36.830679 -198.740958) (xy 36.822638 -198.696059) (xy 36.806713 -198.653316)
			(xy 36.783416 -198.614101) (xy 36.753494 -198.579673) (xy 36.73602 -198.565008) (xy 36.714863 -198.547441)
			(xy 36.677385 -198.507198) (xy 36.646072 -198.461992) (xy 36.621573 -198.412759) (xy 36.604395 -198.360519)
			(xy 36.594895 -198.306354) (xy 36.593268 -198.251387) (xy 35.787241 -198.251387) (xy 35.790216 -198.255823)
			(xy 35.813902 -198.305196) (xy 35.830287 -198.357449) (xy 35.839035 -198.411507) (xy 35.839966 -198.46626)
			(xy 35.83306 -198.520584) (xy 35.81846 -198.573363) (xy 35.796466 -198.623513) (xy 35.767528 -198.670004)
			(xy 35.750246 -198.691246) (xy 35.73573 -198.709127) (xy 35.712848 -198.749095) (xy 35.697552 -198.792535)
			(xy 35.690344 -198.838022) (xy 35.691462 -198.884063) (xy 35.700867 -198.929146) (xy 35.718252 -198.971793)
			(xy 35.743046 -199.010604) (xy 35.758374 -199.027796) (xy 35.776667 -199.048175) (xy 35.807803 -199.093224)
			(xy 35.83218 -199.142262) (xy 35.849297 -199.194281) (xy 35.858802 -199.248212) (xy 35.8605 -199.302948)
			(xy 35.854357 -199.357365) (xy 35.840498 -199.410345) (xy 35.819208 -199.4608) (xy 35.790925 -199.507693)
			(xy 35.756229 -199.550062) (xy 35.715832 -199.587036) (xy 35.670566 -199.617855) (xy 35.621358 -199.641888)
			(xy 35.569221 -199.65864) (xy 35.515225 -199.667767) (xy 35.460478 -199.669082) (xy 35.406105 -199.662558)
			(xy 35.353224 -199.648328) (xy 35.30292 -199.626685) (xy 35.256226 -199.598074) (xy 35.214101 -199.563082)
			(xy 35.177411 -199.522428) (xy 35.146909 -199.476947) (xy 35.123221 -199.427572) (xy 35.106835 -199.375319)
			(xy 35.098086 -199.32126) (xy 35.097155 -199.266505) (xy 35.10406 -199.21218) (xy 35.11866 -199.159399)
			(xy 35.140654 -199.109248) (xy 35.169592 -199.062755) (xy 35.186874 -199.041512) (xy 35.201331 -199.023586)
			(xy 35.224215 -198.983628) (xy 35.239514 -198.940197) (xy 35.246728 -198.894719) (xy 35.245619 -198.848685)
			(xy 35.236223 -198.803607) (xy 35.218849 -198.760964) (xy 35.194067 -198.722155) (xy 35.178746 -198.704962)
			(xy 35.160465 -198.684573) (xy 35.12933 -198.639524) (xy 35.104955 -198.590487) (xy 35.08784 -198.538469)
			(xy 35.078336 -198.484539) (xy 35.076639 -198.429804) (xy 34.771451 -198.429804) (xy 34.784418 -198.477704)
			(xy 34.79103 -198.53179) (xy 34.789883 -198.586266) (xy 34.780998 -198.640025) (xy 34.764558 -198.691974)
			(xy 34.740896 -198.741056) (xy 34.710493 -198.786274) (xy 34.69259 -198.806816) (xy 34.681874 -198.819519)
			(xy 34.666745 -198.849095) (xy 34.659767 -198.881574) (xy 34.661412 -198.914753) (xy 34.67157 -198.946382)
			(xy 34.68955 -198.974316) (xy 34.70148 -198.985886) (xy 34.721315 -199.004565) (xy 34.756024 -199.046562)
			(xy 34.784406 -199.093068) (xy 34.805885 -199.143139) (xy 34.820024 -199.195755) (xy 34.826536 -199.249848)
			(xy 34.825287 -199.304317) (xy 34.816304 -199.358054) (xy 34.79977 -199.409968) (xy 34.776019 -199.459002)
			(xy 34.745536 -199.504159) (xy 34.70894 -199.544522) (xy 34.666975 -199.579269) (xy 34.620495 -199.607694)
			(xy 34.570444 -199.629219) (xy 34.517841 -199.643407) (xy 34.463754 -199.649968) (xy 34.409284 -199.64877)
			(xy 34.355538 -199.639837) (xy 34.30361 -199.62335) (xy 34.254554 -199.599645) (xy 34.209368 -199.569204)
			(xy 34.168972 -199.532645) (xy 34.134186 -199.490712) (xy 34.105718 -199.444258) (xy 34.084147 -199.394227)
			(xy 34.06991 -199.341637) (xy 34.063299 -199.287556) (xy 34.064447 -199.233085) (xy 34.073331 -199.179331)
			(xy 34.08977 -199.127387) (xy 34.113429 -199.07831) (xy 34.143829 -199.033096) (xy 34.16173 -199.012556)
			(xy 34.172485 -198.999882) (xy 34.187622 -198.970299) (xy 34.194601 -198.93781) (xy 34.192949 -198.904621)
			(xy 34.182779 -198.872986) (xy 34.16478 -198.845052) (xy 34.15284 -198.833486) (xy 34.132983 -198.814827)
			(xy 34.098268 -198.772828) (xy 34.06988 -198.726319) (xy 34.048395 -198.676246) (xy 34.034252 -198.623625)
			(xy 34.027736 -198.569528) (xy 33.575564 -198.569528) (xy 33.577271 -198.5724) (xy 33.598079 -198.622417)
			(xy 33.611605 -198.674875) (xy 33.617576 -198.728718) (xy 33.615871 -198.782864) (xy 33.606526 -198.836225)
			(xy 33.589728 -198.887728) (xy 33.565814 -198.936337) (xy 33.535266 -198.981076) (xy 33.517332 -199.00138)
			(xy 33.503017 -199.01762) (xy 33.479589 -199.054023) (xy 33.462678 -199.093872) (xy 33.452773 -199.136013)
			(xy 33.450161 -199.179224) (xy 33.454919 -199.222251) (xy 33.466907 -199.263848) (xy 33.48578 -199.302807)
			(xy 33.498028 -199.320658) (xy 33.513559 -199.343179) (xy 33.538703 -199.391764) (xy 33.556652 -199.443441)
			(xy 33.567038 -199.497152) (xy 33.569647 -199.551795) (xy 33.564426 -199.606251) (xy 33.551482 -199.659404)
			(xy 33.53108 -199.710163) (xy 33.518486 -199.731884) (xy 40.339262 -199.731884) (xy 40.343333 -199.676262)
			(xy 40.355459 -199.621825) (xy 40.375382 -199.569734) (xy 40.402678 -199.521099) (xy 40.436764 -199.476956)
			(xy 40.476913 -199.438247) (xy 40.522271 -199.405796) (xy 40.571871 -199.380295) (xy 40.624655 -199.362288)
			(xy 40.679498 -199.352158) (xy 40.735232 -199.350121) (xy 40.790669 -199.356221) (xy 40.844626 -199.370327)
			(xy 40.895955 -199.392139) (xy 40.943561 -199.421193) (xy 40.986429 -199.456868) (xy 41.023646 -199.498405)
			(xy 41.041417 -199.525266) (xy 42.633128 -199.525266) (xy 42.634851 -199.469851) (xy 42.644575 -199.415268)
			(xy 42.662095 -199.362667) (xy 42.687044 -199.313156) (xy 42.718894 -199.267776) (xy 42.756977 -199.227482)
			(xy 42.778426 -199.209914) (xy 42.796904 -199.194677) (xy 42.8283 -199.158517) (xy 42.852365 -199.117115)
			(xy 42.868248 -199.071938) (xy 42.875385 -199.024585) (xy 42.873525 -198.976733) (xy 42.862733 -198.930078)
			(xy 42.843392 -198.88627) (xy 42.830242 -198.866252) (xy 42.815162 -198.84343) (xy 42.790897 -198.794409)
			(xy 42.773883 -198.742424) (xy 42.764468 -198.688542) (xy 42.762845 -198.633868) (xy 42.769047 -198.579522)
			(xy 42.782948 -198.52662) (xy 42.804262 -198.476245) (xy 42.832553 -198.429431) (xy 42.867239 -198.387137)
			(xy 42.907611 -198.350231) (xy 42.952839 -198.31947) (xy 43.001998 -198.295484) (xy 43.054078 -198.278764)
			(xy 43.108013 -198.269655) (xy 43.162695 -198.268342) (xy 43.189906 -198.27113) (xy 43.213149 -198.273428)
			(xy 43.259754 -198.270434) (xy 43.305028 -198.258974) (xy 43.347446 -198.239436) (xy 43.385579 -198.212476)
			(xy 43.418146 -198.179003) (xy 43.444048 -198.140143) (xy 43.462414 -198.097204) (xy 43.468036 -198.074534)
			(xy 43.474507 -198.047802) (xy 43.494122 -197.996417) (xy 43.520913 -197.948382) (xy 43.554323 -197.904692)
			(xy 43.593661 -197.866252) (xy 43.638111 -197.833859) (xy 43.686752 -197.808185) (xy 43.738575 -197.789761)
			(xy 43.792507 -197.77897) (xy 43.847429 -197.776035) (xy 43.902204 -197.781018) (xy 43.955696 -197.793814)
			(xy 44.006796 -197.814158) (xy 44.054444 -197.84163) (xy 44.097655 -197.875659) (xy 44.135531 -197.91554)
			(xy 44.167287 -197.960447) (xy 44.192266 -198.009448) (xy 44.20995 -198.061529) (xy 44.219972 -198.115609)
			(xy 44.222125 -198.170568) (xy 44.216363 -198.225266) (xy 44.202806 -198.27857) (xy 44.185772 -198.319644)
			(xy 45.972982 -198.319644) (xy 45.977053 -198.264022) (xy 45.989179 -198.209585) (xy 46.009102 -198.157494)
			(xy 46.036398 -198.108859) (xy 46.070484 -198.064716) (xy 46.110633 -198.026007) (xy 46.155991 -197.993556)
			(xy 46.205591 -197.968055) (xy 46.258375 -197.950048) (xy 46.313218 -197.939918) (xy 46.368952 -197.937881)
			(xy 46.424389 -197.943981) (xy 46.478346 -197.958087) (xy 46.529675 -197.979899) (xy 46.577281 -198.008953)
			(xy 46.620149 -198.044628) (xy 46.657366 -198.086165) (xy 46.688139 -198.132678) (xy 46.711811 -198.183175)
			(xy 46.727879 -198.236582) (xy 46.735999 -198.291758) (xy 46.736508 -198.319644) (xy 46.735999 -198.34753)
			(xy 46.727879 -198.402706) (xy 46.711811 -198.456113) (xy 46.688139 -198.50661) (xy 46.657366 -198.553123)
			(xy 46.620149 -198.59466) (xy 46.577281 -198.630335) (xy 46.529675 -198.659389) (xy 46.478346 -198.681201)
			(xy 46.424389 -198.695307) (xy 46.368952 -198.701407) (xy 46.313218 -198.69937) (xy 46.258375 -198.68924)
			(xy 46.205591 -198.671233) (xy 46.155991 -198.645732) (xy 46.110633 -198.613281) (xy 46.070484 -198.574572)
			(xy 46.036398 -198.530429) (xy 46.009102 -198.481794) (xy 45.989179 -198.429703) (xy 45.977053 -198.375266)
			(xy 45.972982 -198.319644) (xy 44.185772 -198.319644) (xy 44.181736 -198.329375) (xy 44.153589 -198.376628)
			(xy 44.118948 -198.419349) (xy 44.078531 -198.456653) (xy 44.033177 -198.487767) (xy 43.983825 -198.512046)
			(xy 43.931498 -198.528986) (xy 43.87728 -198.538237) (xy 43.822296 -198.539607) (xy 43.794934 -198.536814)
			(xy 43.771686 -198.5346) (xy 43.725089 -198.537587) (xy 43.679821 -198.549037) (xy 43.637408 -198.568564)
			(xy 43.599276 -198.595512) (xy 43.566709 -198.628972) (xy 43.540803 -198.667819) (xy 43.522431 -198.710746)
			(xy 43.516804 -198.73341) (xy 43.510682 -198.758704) (xy 43.492466 -198.807454) (xy 43.467801 -198.85328)
			(xy 43.437143 -198.895333) (xy 43.401061 -198.932836) (xy 43.380914 -198.94931) (xy 43.362419 -198.964528)
			(xy 43.331019 -199.00069) (xy 43.306952 -199.042095) (xy 43.291069 -199.087276) (xy 43.283933 -199.134633)
			(xy 43.285797 -199.182488) (xy 43.296595 -199.229146) (xy 43.315944 -199.272955) (xy 43.329098 -199.292972)
			(xy 43.344469 -199.316045) (xy 43.368981 -199.365774) (xy 43.386039 -199.418527) (xy 43.395282 -199.473193)
			(xy 43.396518 -199.528622) (xy 43.389719 -199.583645) (xy 43.375029 -199.637106) (xy 43.352757 -199.687878)
			(xy 43.323372 -199.734892) (xy 43.287493 -199.777159) (xy 43.245874 -199.813789) (xy 43.199393 -199.84401)
			(xy 43.149028 -199.867187) (xy 43.095839 -199.882831) (xy 43.040946 -199.890613) (xy 42.985504 -199.890369)
			(xy 42.930681 -199.882105) (xy 42.877632 -199.865994) (xy 42.827472 -199.842375) (xy 42.781259 -199.811746)
			(xy 42.739964 -199.774752) (xy 42.704458 -199.732171) (xy 42.675487 -199.684901) (xy 42.653662 -199.633935)
			(xy 42.639443 -199.580347) (xy 42.633128 -199.525266) (xy 41.041417 -199.525266) (xy 41.054419 -199.544918)
			(xy 41.078091 -199.595415) (xy 41.094159 -199.648822) (xy 41.102279 -199.703998) (xy 41.102788 -199.731884)
			(xy 41.102279 -199.75977) (xy 41.094159 -199.814946) (xy 41.078091 -199.868353) (xy 41.054419 -199.91885)
			(xy 41.023646 -199.965363) (xy 40.986429 -200.0069) (xy 40.943561 -200.042575) (xy 40.895955 -200.071629)
			(xy 40.844626 -200.093441) (xy 40.790669 -200.107547) (xy 40.735232 -200.113647) (xy 40.679498 -200.11161)
			(xy 40.624655 -200.10148) (xy 40.571871 -200.083473) (xy 40.522271 -200.057972) (xy 40.476913 -200.025521)
			(xy 40.436764 -199.986812) (xy 40.402678 -199.942669) (xy 40.375382 -199.894034) (xy 40.355459 -199.841943)
			(xy 40.343333 -199.787506) (xy 40.339262 -199.731884) (xy 33.518486 -199.731884) (xy 33.50364 -199.757489)
			(xy 33.469722 -199.800411) (xy 33.430022 -199.838049) (xy 33.385355 -199.869633) (xy 33.336635 -199.894514)
			(xy 33.284861 -199.912184) (xy 33.231095 -199.922278) (xy 33.176438 -199.924592) (xy 33.122011 -199.919076)
			(xy 33.06893 -199.905845) (xy 33.018282 -199.885169) (xy 32.971105 -199.857473) (xy 32.928367 -199.823323)
			(xy 32.890944 -199.783421) (xy 32.859602 -199.738583) (xy 32.834985 -199.689729) (xy 32.817596 -199.637861)
			(xy 32.807792 -199.584041) (xy 32.805775 -199.529372) (xy 32.811584 -199.474976) (xy 32.825103 -199.421967)
			(xy 32.846052 -199.371431) (xy 32.874003 -199.324405) (xy 32.908383 -199.281853) (xy 32.948488 -199.244646)
			(xy 32.970724 -199.22871) (xy 32.98394 -199.218899) (xy 33.005359 -199.193927) (xy 33.019666 -199.164301)
			(xy 33.025906 -199.132) (xy 33.023662 -199.099177) (xy 33.013085 -199.068025) (xy 32.99488 -199.040621)
			(xy 32.982916 -199.02932) (xy 32.968216 -199.015964) (xy 32.941364 -198.986695) (xy 32.929322 -198.9709)
			(xy 32.915455 -198.953062) (xy 32.882527 -198.922132) (xy 32.84465 -198.897509) (xy 32.803017 -198.879971)
			(xy 32.758939 -198.870068) (xy 32.713805 -198.868113) (xy 32.669035 -198.874167) (xy 32.626042 -198.888041)
			(xy 32.586177 -198.909296) (xy 32.568134 -198.922894) (xy 32.541472 -198.943084) (xy 32.482582 -198.974768)
			(xy 32.45104 -198.985886) (xy 32.42927 -198.993614) (xy 32.388738 -199.015764) (xy 32.352874 -199.044872)
			(xy 32.322859 -199.079981) (xy 32.29968 -199.119934) (xy 32.284101 -199.163417) (xy 32.276634 -199.208999)
			(xy 32.277525 -199.25518) (xy 32.286744 -199.300441) (xy 32.303988 -199.343291) (xy 32.315912 -199.363076)
			(xy 32.330376 -199.386784) (xy 32.353033 -199.437486) (xy 32.3681 -199.490938) (xy 32.37526 -199.546009)
			(xy 32.37436 -199.601536) (xy 32.36542 -199.656346) (xy 32.34863 -199.709282) (xy 32.324342 -199.759224)
			(xy 32.293071 -199.805117) (xy 32.255478 -199.845993) (xy 32.212356 -199.880986) (xy 32.164616 -199.909359)
			(xy 32.113268 -199.930512) (xy 32.059396 -199.943997) (xy 32.004138 -199.94953) (xy 31.948661 -199.946994)
			(xy 31.894138 -199.936443) (xy 31.841721 -199.918099) (xy 31.792516 -199.89235) (xy 31.747565 -199.85974)
			(xy 31.707815 -199.820958) (xy 31.690564 -199.799194) (xy 31.6763 -199.781251) (xy 31.642387 -199.750415)
			(xy 31.603497 -199.726157) (xy 31.560889 -199.709262) (xy 31.515942 -199.700278) (xy 31.470113 -199.699496)
			(xy 31.424886 -199.706942) (xy 31.381726 -199.722373) (xy 31.361634 -199.733408) (xy 31.337709 -199.746651)
			(xy 31.286931 -199.766942) (xy 31.233777 -199.779777) (xy 31.179334 -199.784893) (xy 31.124719 -199.782185)
			(xy 31.07105 -199.771709) (xy 31.019426 -199.753678) (xy 30.970904 -199.728463) (xy 30.926479 -199.69658)
			(xy 30.88706 -199.658682) (xy 30.853454 -199.615545) (xy 30.82635 -199.568053) (xy 30.806304 -199.517178)
			(xy 30.793725 -199.463962) (xy 30.788871 -199.409496) (xy 30.238181 -199.409496) (xy 30.23746 -199.410099)
			(xy 30.188937 -199.439679) (xy 30.136563 -199.461734) (xy 30.081497 -199.475775) (xy 30.05328 -199.479154)
			(xy 30.037301 -199.481162) (xy 30.007088 -199.492295) (xy 29.98062 -199.510632) (xy 29.95958 -199.535007)
			(xy 29.945306 -199.563869) (xy 29.938704 -199.595384) (xy 29.93898 -199.611488) (xy 29.939808 -199.639664)
			(xy 29.93408 -199.695742) (xy 29.920162 -199.750366) (xy 29.898355 -199.802347) (xy 29.869136 -199.850552)
			(xy 29.83314 -199.893932) (xy 29.791151 -199.931541) (xy 29.744085 -199.962561) (xy 29.692965 -199.986317)
			(xy 29.638906 -200.002289) (xy 29.611066 -200.006712) (xy 29.589562 -200.01014) (xy 29.548111 -200.023482)
			(xy 29.509543 -200.043697) (xy 29.474986 -200.070193) (xy 29.445455 -200.102193) (xy 29.421813 -200.138761)
			(xy 29.404753 -200.178826) (xy 29.394775 -200.221212) (xy 29.392172 -200.264679) (xy 29.39415 -200.286366)
			(xy 29.396773 -200.315008) (xy 29.394456 -200.372475) (xy 29.383536 -200.428942) (xy 29.36426 -200.483129)
			(xy 29.337065 -200.533806) (xy 29.320236 -200.55713) (xy 29.306611 -200.576122) (xy 29.285878 -200.61801)
			(xy 29.273153 -200.662983) (xy 29.268867 -200.709524) (xy 29.273162 -200.756064) (xy 29.285895 -200.801035)
			(xy 29.306636 -200.842919) (xy 29.320236 -200.86193) (xy 29.336196 -200.884018) (xy 29.362317 -200.931844)
			(xy 29.381365 -200.9829) (xy 29.392953 -201.036147) (xy 29.396845 -201.090502) (xy 35.632997 -201.090502)
			(xy 35.636889 -201.036147) (xy 35.648477 -200.9829) (xy 35.667525 -200.931844) (xy 35.693646 -200.884018)
			(xy 35.709606 -200.86193) (xy 35.723173 -200.842899) (xy 35.743908 -200.80102) (xy 35.756637 -200.756057)
			(xy 35.760931 -200.709524) (xy 35.756645 -200.66299) (xy 35.743925 -200.618025) (xy 35.723199 -200.576142)
			(xy 35.709606 -200.55713) (xy 35.693646 -200.535042) (xy 35.667525 -200.487216) (xy 35.648477 -200.43616)
			(xy 35.636889 -200.382913) (xy 35.632997 -200.328558) (xy 35.636881 -200.274203) (xy 35.648461 -200.220954)
			(xy 35.667502 -200.169895) (xy 35.693616 -200.122065) (xy 35.726271 -200.078439) (xy 35.764802 -200.039905)
			(xy 35.808426 -200.007247) (xy 35.856253 -199.98113) (xy 35.907311 -199.962085) (xy 35.960559 -199.950501)
			(xy 36.014914 -199.946613) (xy 36.069269 -199.950501) (xy 36.122517 -199.962085) (xy 36.173575 -199.98113)
			(xy 36.221402 -200.007247) (xy 36.265026 -200.039905) (xy 36.303557 -200.078439) (xy 36.336212 -200.122065)
			(xy 36.362326 -200.169895) (xy 36.381367 -200.220954) (xy 36.392947 -200.274203) (xy 36.396831 -200.328558)
			(xy 36.392939 -200.382913) (xy 36.381351 -200.43616) (xy 36.362303 -200.487216) (xy 36.336182 -200.535042)
			(xy 36.320222 -200.55713) (xy 36.306597 -200.576123) (xy 36.285866 -200.618011) (xy 36.273142 -200.662983)
			(xy 36.268856 -200.709524) (xy 36.273151 -200.756064) (xy 36.285883 -200.801034) (xy 36.306623 -200.842918)
			(xy 36.320222 -200.86193) (xy 36.336182 -200.884018) (xy 36.362303 -200.931844) (xy 36.381351 -200.9829)
			(xy 36.392939 -201.036147) (xy 36.396831 -201.090502) (xy 43.632981 -201.090502) (xy 43.636873 -201.036147)
			(xy 43.648461 -200.9829) (xy 43.667509 -200.931844) (xy 43.69363 -200.884018) (xy 43.70959 -200.86193)
			(xy 43.723158 -200.842899) (xy 43.743894 -200.801021) (xy 43.756624 -200.756057) (xy 43.760918 -200.709524)
			(xy 43.756632 -200.66299) (xy 43.743911 -200.618024) (xy 43.723183 -200.576142) (xy 43.70959 -200.55713)
			(xy 43.69363 -200.535042) (xy 43.667509 -200.487216) (xy 43.648461 -200.43616) (xy 43.636873 -200.382913)
			(xy 43.632981 -200.328558) (xy 43.636865 -200.274203) (xy 43.648445 -200.220954) (xy 43.667486 -200.169895)
			(xy 43.6936 -200.122065) (xy 43.726255 -200.078439) (xy 43.764786 -200.039905) (xy 43.80841 -200.007247)
			(xy 43.856237 -199.98113) (xy 43.907295 -199.962085) (xy 43.960543 -199.950501) (xy 44.014898 -199.946613)
			(xy 44.069253 -199.950501) (xy 44.122501 -199.962085) (xy 44.173559 -199.98113) (xy 44.221386 -200.007247)
			(xy 44.26501 -200.039905) (xy 44.303541 -200.078439) (xy 44.336196 -200.122065) (xy 44.36231 -200.169895)
			(xy 44.381351 -200.220954) (xy 44.392931 -200.274203) (xy 44.396815 -200.328558) (xy 44.392923 -200.382913)
			(xy 44.381335 -200.43616) (xy 44.362287 -200.487216) (xy 44.336166 -200.535042) (xy 44.320206 -200.55713)
			(xy 44.306582 -200.576123) (xy 44.285852 -200.618011) (xy 44.273129 -200.662984) (xy 44.268843 -200.709524)
			(xy 44.273138 -200.756064) (xy 44.285869 -200.801034) (xy 44.306607 -200.842918) (xy 44.320206 -200.86193)
			(xy 44.336166 -200.884018) (xy 44.362287 -200.931844) (xy 44.381335 -200.9829) (xy 44.392923 -201.036147)
			(xy 44.396815 -201.090502) (xy 44.392931 -201.144857) (xy 44.381351 -201.198106) (xy 44.36231 -201.249165)
			(xy 44.336196 -201.296995) (xy 44.303541 -201.340621) (xy 44.26501 -201.379155) (xy 44.221386 -201.411813)
			(xy 44.173559 -201.43793) (xy 44.122501 -201.456975) (xy 44.069253 -201.468559) (xy 44.014898 -201.472447)
			(xy 43.960543 -201.468559) (xy 43.907295 -201.456975) (xy 43.856237 -201.43793) (xy 43.80841 -201.411813)
			(xy 43.764786 -201.379155) (xy 43.726255 -201.340621) (xy 43.6936 -201.296995) (xy 43.667486 -201.249165)
			(xy 43.648445 -201.198106) (xy 43.636865 -201.144857) (xy 43.632981 -201.090502) (xy 36.396831 -201.090502)
			(xy 36.392947 -201.144857) (xy 36.381367 -201.198106) (xy 36.362326 -201.249165) (xy 36.336212 -201.296995)
			(xy 36.303557 -201.340621) (xy 36.265026 -201.379155) (xy 36.221402 -201.411813) (xy 36.173575 -201.43793)
			(xy 36.122517 -201.456975) (xy 36.069269 -201.468559) (xy 36.014914 -201.472447) (xy 35.960559 -201.468559)
			(xy 35.907311 -201.456975) (xy 35.856253 -201.43793) (xy 35.808426 -201.411813) (xy 35.764802 -201.379155)
			(xy 35.726271 -201.340621) (xy 35.693616 -201.296995) (xy 35.667502 -201.249165) (xy 35.648461 -201.198106)
			(xy 35.636881 -201.144857) (xy 35.632997 -201.090502) (xy 29.396845 -201.090502) (xy 29.392961 -201.144857)
			(xy 29.381381 -201.198106) (xy 29.36234 -201.249165) (xy 29.336226 -201.296995) (xy 29.303571 -201.340621)
			(xy 29.26504 -201.379155) (xy 29.221416 -201.411813) (xy 29.173589 -201.43793) (xy 29.122531 -201.456975)
			(xy 29.069283 -201.468559) (xy 29.014928 -201.472447) (xy 28.960573 -201.468559) (xy 28.907325 -201.456975)
			(xy 28.856267 -201.43793) (xy 28.80844 -201.411813) (xy 28.764816 -201.379155) (xy 28.726285 -201.340621)
			(xy 28.69363 -201.296995) (xy 28.667516 -201.249165) (xy 28.648475 -201.198106) (xy 28.636895 -201.144857)
			(xy 28.633011 -201.090502) (xy 24.396855 -201.090502) (xy 24.392971 -201.144857) (xy 24.381391 -201.198106)
			(xy 24.36235 -201.249165) (xy 24.336236 -201.296995) (xy 24.303581 -201.340621) (xy 24.26505 -201.379155)
			(xy 24.221426 -201.411813) (xy 24.173599 -201.43793) (xy 24.122541 -201.456975) (xy 24.069293 -201.468559)
			(xy 24.014938 -201.472447) (xy 23.960583 -201.468559) (xy 23.907335 -201.456975) (xy 23.856277 -201.43793)
			(xy 23.80845 -201.411813) (xy 23.764826 -201.379155) (xy 23.726295 -201.340621) (xy 23.69364 -201.296995)
			(xy 23.667526 -201.249165) (xy 23.648485 -201.198106) (xy 23.636905 -201.144857) (xy 23.633021 -201.090502)
			(xy 21.396861 -201.090502) (xy 21.392977 -201.144857) (xy 21.381397 -201.198106) (xy 21.362356 -201.249165)
			(xy 21.336242 -201.296995) (xy 21.303587 -201.340621) (xy 21.265056 -201.379155) (xy 21.221432 -201.411813)
			(xy 21.173605 -201.43793) (xy 21.122547 -201.456975) (xy 21.069299 -201.468559) (xy 21.014944 -201.472447)
			(xy 20.960589 -201.468559) (xy 20.907341 -201.456975) (xy 20.856283 -201.43793) (xy 20.808456 -201.411813)
			(xy 20.764832 -201.379155) (xy 20.726301 -201.340621) (xy 20.693646 -201.296995) (xy 20.667532 -201.249165)
			(xy 20.648491 -201.198106) (xy 20.636911 -201.144857) (xy 20.633027 -201.090502) (xy 18.396867 -201.090502)
			(xy 18.392983 -201.144857) (xy 18.381403 -201.198106) (xy 18.362362 -201.249165) (xy 18.336248 -201.296995)
			(xy 18.303593 -201.340621) (xy 18.265062 -201.379155) (xy 18.221438 -201.411813) (xy 18.173611 -201.43793)
			(xy 18.122553 -201.456975) (xy 18.069305 -201.468559) (xy 18.01495 -201.472447) (xy 17.960595 -201.468559)
			(xy 17.907347 -201.456975) (xy 17.856289 -201.43793) (xy 17.808462 -201.411813) (xy 17.764838 -201.379155)
			(xy 17.726307 -201.340621) (xy 17.693652 -201.296995) (xy 17.667538 -201.249165) (xy 17.648497 -201.198106)
			(xy 17.636917 -201.144857) (xy 17.633033 -201.090502) (xy 13.998948 -201.090502) (xy 13.998509 -201.09126)
			(xy 13.983236 -201.133104) (xy 13.975493 -201.17697) (xy 13.97508 -201.199242) (xy 13.97508 -201.43597)
			(xy 14.792706 -202.253596) (xy 47.050706 -202.253596)
		)
		(stroke
			(width 0)
			(type solid)
		)
		(fill yes)
		(layer "In7.Cu")
		(net "P12V_PDB")
	)
	(gr_poly
		(pts
			(xy 180.471826 -157.314392) (xy 180.488336 -157.298898) (xy 180.509678 -157.279597) (xy 180.55708 -157.246978)
			(xy 180.608841 -157.221844) (xy 180.663789 -157.204765) (xy 180.720678 -157.196128) (xy 180.778218 -157.196128)
			(xy 180.835107 -157.204765) (xy 180.890055 -157.221844) (xy 180.941816 -157.246978) (xy 180.989218 -157.279597)
			(xy 181.01056 -157.298898) (xy 181.02707 -157.314392) (xy 181.116732 -157.352492) (xy 181.29123 -157.352492)
			(xy 181.309749 -157.351863) (xy 181.345226 -157.341222) (xy 181.376137 -157.320819) (xy 181.388512 -157.307026)
			(xy 181.406739 -157.28596) (xy 181.448258 -157.248822) (xy 181.494737 -157.218117) (xy 181.545187 -157.194499)
			(xy 181.598536 -157.178468) (xy 181.653648 -157.170367) (xy 181.709354 -157.170367) (xy 181.764466 -157.178468)
			(xy 181.817815 -157.194499) (xy 181.868265 -157.218117) (xy 181.914744 -157.248822) (xy 181.956263 -157.28596)
			(xy 181.97449 -157.307026) (xy 181.986872 -157.320806) (xy 182.017797 -157.341171) (xy 182.053259 -157.351833)
			(xy 182.071772 -157.352492) (xy 182.551324 -157.352492) (xy 182.633874 -157.320742) (xy 182.655174 -157.30181)
			(xy 182.702331 -157.269816) (xy 182.753713 -157.245173) (xy 182.808183 -157.228426) (xy 182.864534 -157.219946)
			(xy 182.92152 -157.21992) (xy 182.977878 -157.228349) (xy 183.032363 -157.245047) (xy 183.083767 -157.269643)
			(xy 183.130954 -157.301594) (xy 183.152288 -157.320488) (xy 183.235092 -157.352492) (xy 194.148964 -157.352492)
			(xy 196.95668 -154.544776) (xy 196.95668 -78.894178) (xy 192.1002 -74.037698) (xy 192.1002 -44.861734)
			(xy 194.945 -42.016934) (xy 194.945 -8.9408) (xy 194.2592 -8.255) (xy 191.080644 -8.255) (xy 191.044111 -8.281345)
			(xy 190.967093 -8.328058) (xy 190.886153 -8.36759) (xy 190.801961 -8.399614) (xy 190.71521 -8.423866)
			(xy 190.626616 -8.440146) (xy 190.536911 -8.44832) (xy 190.446833 -8.44832) (xy 190.357128 -8.440146)
			(xy 190.268534 -8.423866) (xy 190.181783 -8.399614) (xy 190.097591 -8.36759) (xy 190.016651 -8.328058)
			(xy 189.939633 -8.281345) (xy 189.9031 -8.255) (xy 188.540644 -8.255) (xy 188.504111 -8.281345) (xy 188.427093 -8.328058)
			(xy 188.346153 -8.36759) (xy 188.261961 -8.399614) (xy 188.17521 -8.423866) (xy 188.086616 -8.440146)
			(xy 187.996911 -8.44832) (xy 187.906833 -8.44832) (xy 187.817128 -8.440146) (xy 187.728534 -8.423866)
			(xy 187.641783 -8.399614) (xy 187.557591 -8.36759) (xy 187.476651 -8.328058) (xy 187.399633 -8.281345)
			(xy 187.3631 -8.255) (xy 180.833268 -8.255) (xy 180.81798 -8.255447) (xy 180.788281 -8.262718) (xy 180.76117 -8.276858)
			(xy 180.738211 -8.297052) (xy 180.729128 -8.309356) (xy 180.704226 -8.34411) (xy 180.648756 -8.409177)
			(xy 180.587298 -8.468621) (xy 180.520421 -8.521894) (xy 180.448741 -8.568506) (xy 180.372919 -8.608024)
			(xy 180.293655 -8.640086) (xy 180.211681 -8.664395) (xy 180.127753 -8.680726) (xy 180.042645 -8.68893)
			(xy 179.957143 -8.68893) (xy 179.872035 -8.680726) (xy 179.788107 -8.664395) (xy 179.706133 -8.640086)
			(xy 179.626869 -8.608024) (xy 179.551047 -8.568506) (xy 179.479367 -8.521894) (xy 179.41249 -8.468621)
			(xy 179.351032 -8.409177) (xy 179.295562 -8.34411) (xy 179.27066 -8.309356) (xy 179.261543 -8.297079)
			(xy 179.238589 -8.276888) (xy 179.211491 -8.262737) (xy 179.181805 -8.255437) (xy 179.16652 -8.255)
			(xy 172.936408 -8.255) (xy 172.922692 -8.258048) (xy 172.880861 -8.266993) (xy 172.796067 -8.278326)
			(xy 172.710602 -8.282114) (xy 172.625137 -8.278326) (xy 172.540343 -8.266993) (xy 172.498512 -8.258048)
			(xy 172.484796 -8.255) (xy 170.396408 -8.255) (xy 170.382692 -8.258048) (xy 170.340861 -8.266993)
			(xy 170.256067 -8.278326) (xy 170.170602 -8.282114) (xy 170.085137 -8.278326) (xy 170.000343 -8.266993)
			(xy 169.958512 -8.258048) (xy 169.944796 -8.255) (xy 167.856408 -8.255) (xy 167.842692 -8.258048)
			(xy 167.800861 -8.266993) (xy 167.716067 -8.278326) (xy 167.630602 -8.282114) (xy 167.545137 -8.278326)
			(xy 167.460343 -8.266993) (xy 167.418512 -8.258048) (xy 167.404796 -8.255) (xy 165.316408 -8.255)
			(xy 165.302692 -8.258048) (xy 165.260861 -8.266993) (xy 165.176067 -8.278326) (xy 165.090602 -8.282114)
			(xy 165.005137 -8.278326) (xy 164.920343 -8.266993) (xy 164.878512 -8.258048) (xy 164.864796 -8.255)
			(xy 162.776408 -8.255) (xy 162.762692 -8.258048) (xy 162.720861 -8.266993) (xy 162.636067 -8.278326)
			(xy 162.550602 -8.282114) (xy 162.465137 -8.278326) (xy 162.380343 -8.266993) (xy 162.338512 -8.258048)
			(xy 162.324796 -8.255) (xy 157.03804 -8.255) (xy 157.024324 -8.258048) (xy 156.982493 -8.266993)
			(xy 156.897699 -8.278326) (xy 156.812234 -8.282114) (xy 156.726769 -8.278326) (xy 156.641975 -8.266993)
			(xy 156.600144 -8.258048) (xy 156.586428 -8.255) (xy 154.49804 -8.255) (xy 154.484324 -8.258048)
			(xy 154.442493 -8.266993) (xy 154.357699 -8.278326) (xy 154.272234 -8.282114) (xy 154.186769 -8.278326)
			(xy 154.101975 -8.266993) (xy 154.060144 -8.258048) (xy 154.046428 -8.255) (xy 151.95804 -8.255)
			(xy 151.944324 -8.258048) (xy 151.902493 -8.266993) (xy 151.817699 -8.278326) (xy 151.732234 -8.282114)
			(xy 151.646769 -8.278326) (xy 151.561975 -8.266993) (xy 151.520144 -8.258048) (xy 151.506428 -8.255)
			(xy 149.41804 -8.255) (xy 149.404324 -8.258048) (xy 149.362493 -8.266993) (xy 149.277699 -8.278326)
			(xy 149.192234 -8.282114) (xy 149.106769 -8.278326) (xy 149.021975 -8.266993) (xy 148.980144 -8.258048)
			(xy 148.966428 -8.255) (xy 146.87804 -8.255) (xy 146.864324 -8.258048) (xy 146.822493 -8.266993)
			(xy 146.737699 -8.278326) (xy 146.652234 -8.282114) (xy 146.566769 -8.278326) (xy 146.481975 -8.266993)
			(xy 146.440144 -8.258048) (xy 146.426428 -8.255) (xy 141.139926 -8.255) (xy 141.12621 -8.258048)
			(xy 141.084379 -8.266993) (xy 140.999585 -8.278326) (xy 140.91412 -8.282114) (xy 140.828655 -8.278326)
			(xy 140.743861 -8.266993) (xy 140.70203 -8.258048) (xy 140.688314 -8.255) (xy 138.599926 -8.255)
			(xy 138.58621 -8.258048) (xy 138.544379 -8.266993) (xy 138.459585 -8.278326) (xy 138.37412 -8.282114)
			(xy 138.288655 -8.278326) (xy 138.203861 -8.266993) (xy 138.16203 -8.258048) (xy 138.148314 -8.255)
			(xy 136.059926 -8.255) (xy 136.04621 -8.258048) (xy 136.004379 -8.266993) (xy 135.919585 -8.278326)
			(xy 135.83412 -8.282114) (xy 135.748655 -8.278326) (xy 135.663861 -8.266993) (xy 135.62203 -8.258048)
			(xy 135.608314 -8.255) (xy 133.519926 -8.255) (xy 133.50621 -8.258048) (xy 133.464379 -8.266993)
			(xy 133.379585 -8.278326) (xy 133.29412 -8.282114) (xy 133.208655 -8.278326) (xy 133.123861 -8.266993)
			(xy 133.08203 -8.258048) (xy 133.068314 -8.255) (xy 130.979926 -8.255) (xy 130.96621 -8.258048) (xy 130.924379 -8.266993)
			(xy 130.839585 -8.278326) (xy 130.75412 -8.282114) (xy 130.668655 -8.278326) (xy 130.583861 -8.266993)
			(xy 130.54203 -8.258048) (xy 130.528314 -8.255) (xy 129.6924 -8.255) (xy 128.74244 -9.20496) (xy 128.74244 -9.855962)
			(xy 129.787911 -9.855962) (xy 129.791914 -9.7681) (xy 129.80389 -9.680966) (xy 129.823741 -9.595282)
			(xy 129.8513 -9.511758) (xy 129.886341 -9.431086) (xy 129.928572 -9.353935) (xy 129.977644 -9.280944)
			(xy 130.033151 -9.212718) (xy 130.094631 -9.149822) (xy 130.161576 -9.092777) (xy 130.233431 -9.042056)
			(xy 130.309601 -8.998079) (xy 130.389454 -8.961211) (xy 130.472329 -8.931758) (xy 130.557539 -8.909962)
			(xy 130.644378 -8.896006) (xy 130.732126 -8.890003) (xy 130.820056 -8.892005) (xy 130.907441 -8.901995)
			(xy 130.993554 -8.91989) (xy 131.077684 -8.945541) (xy 131.159132 -8.978736) (xy 131.237225 -9.0192)
			(xy 131.311314 -9.066598) (xy 131.380786 -9.120537) (xy 131.445065 -9.18057) (xy 131.503619 -9.246199)
			(xy 131.555963 -9.316881) (xy 131.601662 -9.39203) (xy 131.640338 -9.471023) (xy 131.67167 -9.553206)
			(xy 131.6954 -9.637898) (xy 131.71133 -9.724397) (xy 131.719328 -9.811985) (xy 131.719828 -9.855962)
			(xy 132.327911 -9.855962) (xy 132.331914 -9.7681) (xy 132.34389 -9.680966) (xy 132.363741 -9.595282)
			(xy 132.3913 -9.511758) (xy 132.426341 -9.431086) (xy 132.468572 -9.353935) (xy 132.517644 -9.280944)
			(xy 132.573151 -9.212718) (xy 132.634631 -9.149822) (xy 132.701576 -9.092777) (xy 132.773431 -9.042056)
			(xy 132.849601 -8.998079) (xy 132.929454 -8.961211) (xy 133.012329 -8.931758) (xy 133.097539 -8.909962)
			(xy 133.184378 -8.896006) (xy 133.272126 -8.890003) (xy 133.360056 -8.892005) (xy 133.447441 -8.901995)
			(xy 133.533554 -8.91989) (xy 133.617684 -8.945541) (xy 133.699132 -8.978736) (xy 133.777225 -9.0192)
			(xy 133.851314 -9.066598) (xy 133.920786 -9.120537) (xy 133.985065 -9.18057) (xy 134.043619 -9.246199)
			(xy 134.095963 -9.316881) (xy 134.141662 -9.39203) (xy 134.180338 -9.471023) (xy 134.21167 -9.553206)
			(xy 134.2354 -9.637898) (xy 134.25133 -9.724397) (xy 134.259328 -9.811985) (xy 134.259828 -9.855962)
			(xy 134.867911 -9.855962) (xy 134.871914 -9.7681) (xy 134.88389 -9.680966) (xy 134.903741 -9.595282)
			(xy 134.9313 -9.511758) (xy 134.966341 -9.431086) (xy 135.008572 -9.353935) (xy 135.057644 -9.280944)
			(xy 135.113151 -9.212718) (xy 135.174631 -9.149822) (xy 135.241576 -9.092777) (xy 135.313431 -9.042056)
			(xy 135.389601 -8.998079) (xy 135.469454 -8.961211) (xy 135.552329 -8.931758) (xy 135.637539 -8.909962)
			(xy 135.724378 -8.896006) (xy 135.812126 -8.890003) (xy 135.900056 -8.892005) (xy 135.987441 -8.901995)
			(xy 136.073554 -8.91989) (xy 136.157684 -8.945541) (xy 136.239132 -8.978736) (xy 136.317225 -9.0192)
			(xy 136.391314 -9.066598) (xy 136.460786 -9.120537) (xy 136.525065 -9.18057) (xy 136.583619 -9.246199)
			(xy 136.635963 -9.316881) (xy 136.681662 -9.39203) (xy 136.720338 -9.471023) (xy 136.75167 -9.553206)
			(xy 136.7754 -9.637898) (xy 136.79133 -9.724397) (xy 136.799328 -9.811985) (xy 136.799828 -9.855962)
			(xy 137.407911 -9.855962) (xy 137.411914 -9.7681) (xy 137.42389 -9.680966) (xy 137.443741 -9.595282)
			(xy 137.4713 -9.511758) (xy 137.506341 -9.431086) (xy 137.548572 -9.353935) (xy 137.597644 -9.280944)
			(xy 137.653151 -9.212718) (xy 137.714631 -9.149822) (xy 137.781576 -9.092777) (xy 137.853431 -9.042056)
			(xy 137.929601 -8.998079) (xy 138.009454 -8.961211) (xy 138.092329 -8.931758) (xy 138.177539 -8.909962)
			(xy 138.264378 -8.896006) (xy 138.352126 -8.890003) (xy 138.440056 -8.892005) (xy 138.527441 -8.901995)
			(xy 138.613554 -8.91989) (xy 138.697684 -8.945541) (xy 138.779132 -8.978736) (xy 138.857225 -9.0192)
			(xy 138.931314 -9.066598) (xy 139.000786 -9.120537) (xy 139.065065 -9.18057) (xy 139.123619 -9.246199)
			(xy 139.175963 -9.316881) (xy 139.221662 -9.39203) (xy 139.260338 -9.471023) (xy 139.29167 -9.553206)
			(xy 139.3154 -9.637898) (xy 139.33133 -9.724397) (xy 139.339328 -9.811985) (xy 139.339828 -9.855962)
			(xy 139.947911 -9.855962) (xy 139.951914 -9.7681) (xy 139.96389 -9.680966) (xy 139.983741 -9.595282)
			(xy 140.0113 -9.511758) (xy 140.046341 -9.431086) (xy 140.088572 -9.353935) (xy 140.137644 -9.280944)
			(xy 140.193151 -9.212718) (xy 140.254631 -9.149822) (xy 140.321576 -9.092777) (xy 140.393431 -9.042056)
			(xy 140.469601 -8.998079) (xy 140.549454 -8.961211) (xy 140.632329 -8.931758) (xy 140.717539 -8.909962)
			(xy 140.804378 -8.896006) (xy 140.892126 -8.890003) (xy 140.980056 -8.892005) (xy 141.067441 -8.901995)
			(xy 141.153554 -8.91989) (xy 141.237684 -8.945541) (xy 141.319132 -8.978736) (xy 141.397225 -9.0192)
			(xy 141.471314 -9.066598) (xy 141.540786 -9.120537) (xy 141.605065 -9.18057) (xy 141.663619 -9.246199)
			(xy 141.715963 -9.316881) (xy 141.761662 -9.39203) (xy 141.800338 -9.471023) (xy 141.83167 -9.553206)
			(xy 141.8554 -9.637898) (xy 141.87133 -9.724397) (xy 141.879328 -9.811985) (xy 141.879828 -9.855962)
			(xy 145.686025 -9.855962) (xy 145.690028 -9.7681) (xy 145.702004 -9.680966) (xy 145.721855 -9.595282)
			(xy 145.749414 -9.511758) (xy 145.784455 -9.431086) (xy 145.826686 -9.353935) (xy 145.875758 -9.280944)
			(xy 145.931265 -9.212718) (xy 145.992745 -9.149822) (xy 146.05969 -9.092777) (xy 146.131545 -9.042056)
			(xy 146.207715 -8.998079) (xy 146.287568 -8.961211) (xy 146.370443 -8.931758) (xy 146.455653 -8.909962)
			(xy 146.542492 -8.896006) (xy 146.63024 -8.890003) (xy 146.71817 -8.892005) (xy 146.805555 -8.901995)
			(xy 146.891668 -8.91989) (xy 146.975798 -8.945541) (xy 147.057246 -8.978736) (xy 147.135339 -9.0192)
			(xy 147.209428 -9.066598) (xy 147.2789 -9.120537) (xy 147.343179 -9.18057) (xy 147.401733 -9.246199)
			(xy 147.454077 -9.316881) (xy 147.499776 -9.39203) (xy 147.538452 -9.471023) (xy 147.569784 -9.553206)
			(xy 147.593514 -9.637898) (xy 147.609444 -9.724397) (xy 147.617442 -9.811985) (xy 147.617942 -9.855962)
			(xy 148.226025 -9.855962) (xy 148.230028 -9.7681) (xy 148.242004 -9.680966) (xy 148.261855 -9.595282)
			(xy 148.289414 -9.511758) (xy 148.324455 -9.431086) (xy 148.366686 -9.353935) (xy 148.415758 -9.280944)
			(xy 148.471265 -9.212718) (xy 148.532745 -9.149822) (xy 148.59969 -9.092777) (xy 148.671545 -9.042056)
			(xy 148.747715 -8.998079) (xy 148.827568 -8.961211) (xy 148.910443 -8.931758) (xy 148.995653 -8.909962)
			(xy 149.082492 -8.896006) (xy 149.17024 -8.890003) (xy 149.25817 -8.892005) (xy 149.345555 -8.901995)
			(xy 149.431668 -8.91989) (xy 149.515798 -8.945541) (xy 149.597246 -8.978736) (xy 149.675339 -9.0192)
			(xy 149.749428 -9.066598) (xy 149.8189 -9.120537) (xy 149.883179 -9.18057) (xy 149.941733 -9.246199)
			(xy 149.994077 -9.316881) (xy 150.039776 -9.39203) (xy 150.078452 -9.471023) (xy 150.109784 -9.553206)
			(xy 150.133514 -9.637898) (xy 150.149444 -9.724397) (xy 150.157442 -9.811985) (xy 150.157942 -9.855962)
			(xy 150.766025 -9.855962) (xy 150.770028 -9.7681) (xy 150.782004 -9.680966) (xy 150.801855 -9.595282)
			(xy 150.829414 -9.511758) (xy 150.864455 -9.431086) (xy 150.906686 -9.353935) (xy 150.955758 -9.280944)
			(xy 151.011265 -9.212718) (xy 151.072745 -9.149822) (xy 151.13969 -9.092777) (xy 151.211545 -9.042056)
			(xy 151.287715 -8.998079) (xy 151.367568 -8.961211) (xy 151.450443 -8.931758) (xy 151.535653 -8.909962)
			(xy 151.622492 -8.896006) (xy 151.71024 -8.890003) (xy 151.79817 -8.892005) (xy 151.885555 -8.901995)
			(xy 151.971668 -8.91989) (xy 152.055798 -8.945541) (xy 152.137246 -8.978736) (xy 152.215339 -9.0192)
			(xy 152.289428 -9.066598) (xy 152.3589 -9.120537) (xy 152.423179 -9.18057) (xy 152.481733 -9.246199)
			(xy 152.534077 -9.316881) (xy 152.579776 -9.39203) (xy 152.618452 -9.471023) (xy 152.649784 -9.553206)
			(xy 152.673514 -9.637898) (xy 152.689444 -9.724397) (xy 152.697442 -9.811985) (xy 152.697942 -9.855962)
			(xy 153.306025 -9.855962) (xy 153.310028 -9.7681) (xy 153.322004 -9.680966) (xy 153.341855 -9.595282)
			(xy 153.369414 -9.511758) (xy 153.404455 -9.431086) (xy 153.446686 -9.353935) (xy 153.495758 -9.280944)
			(xy 153.551265 -9.212718) (xy 153.612745 -9.149822) (xy 153.67969 -9.092777) (xy 153.751545 -9.042056)
			(xy 153.827715 -8.998079) (xy 153.907568 -8.961211) (xy 153.990443 -8.931758) (xy 154.075653 -8.909962)
			(xy 154.162492 -8.896006) (xy 154.25024 -8.890003) (xy 154.33817 -8.892005) (xy 154.425555 -8.901995)
			(xy 154.511668 -8.91989) (xy 154.595798 -8.945541) (xy 154.677246 -8.978736) (xy 154.755339 -9.0192)
			(xy 154.829428 -9.066598) (xy 154.8989 -9.120537) (xy 154.963179 -9.18057) (xy 155.021733 -9.246199)
			(xy 155.074077 -9.316881) (xy 155.119776 -9.39203) (xy 155.158452 -9.471023) (xy 155.189784 -9.553206)
			(xy 155.213514 -9.637898) (xy 155.229444 -9.724397) (xy 155.237442 -9.811985) (xy 155.237942 -9.855962)
			(xy 155.846025 -9.855962) (xy 155.850028 -9.7681) (xy 155.862004 -9.680966) (xy 155.881855 -9.595282)
			(xy 155.909414 -9.511758) (xy 155.944455 -9.431086) (xy 155.986686 -9.353935) (xy 156.035758 -9.280944)
			(xy 156.091265 -9.212718) (xy 156.152745 -9.149822) (xy 156.21969 -9.092777) (xy 156.291545 -9.042056)
			(xy 156.367715 -8.998079) (xy 156.447568 -8.961211) (xy 156.530443 -8.931758) (xy 156.615653 -8.909962)
			(xy 156.702492 -8.896006) (xy 156.79024 -8.890003) (xy 156.87817 -8.892005) (xy 156.965555 -8.901995)
			(xy 157.051668 -8.91989) (xy 157.135798 -8.945541) (xy 157.217246 -8.978736) (xy 157.295339 -9.0192)
			(xy 157.369428 -9.066598) (xy 157.4389 -9.120537) (xy 157.503179 -9.18057) (xy 157.561733 -9.246199)
			(xy 157.614077 -9.316881) (xy 157.659776 -9.39203) (xy 157.698452 -9.471023) (xy 157.729784 -9.553206)
			(xy 157.753514 -9.637898) (xy 157.769444 -9.724397) (xy 157.777442 -9.811985) (xy 157.777942 -9.855962)
			(xy 161.584393 -9.855962) (xy 161.588396 -9.7681) (xy 161.600372 -9.680966) (xy 161.620223 -9.595282)
			(xy 161.647782 -9.511758) (xy 161.682823 -9.431086) (xy 161.725054 -9.353935) (xy 161.774126 -9.280944)
			(xy 161.829633 -9.212718) (xy 161.891113 -9.149822) (xy 161.958058 -9.092777) (xy 162.029913 -9.042056)
			(xy 162.106083 -8.998079) (xy 162.185936 -8.961211) (xy 162.268811 -8.931758) (xy 162.354021 -8.909962)
			(xy 162.44086 -8.896006) (xy 162.528608 -8.890003) (xy 162.616538 -8.892005) (xy 162.703923 -8.901995)
			(xy 162.790036 -8.91989) (xy 162.874166 -8.945541) (xy 162.955614 -8.978736) (xy 163.033707 -9.0192)
			(xy 163.107796 -9.066598) (xy 163.177268 -9.120537) (xy 163.241547 -9.18057) (xy 163.300101 -9.246199)
			(xy 163.352445 -9.316881) (xy 163.398144 -9.39203) (xy 163.43682 -9.471023) (xy 163.468152 -9.553206)
			(xy 163.491882 -9.637898) (xy 163.507812 -9.724397) (xy 163.51581 -9.811985) (xy 163.51631 -9.855962)
			(xy 164.124393 -9.855962) (xy 164.128396 -9.7681) (xy 164.140372 -9.680966) (xy 164.160223 -9.595282)
			(xy 164.187782 -9.511758) (xy 164.222823 -9.431086) (xy 164.265054 -9.353935) (xy 164.314126 -9.280944)
			(xy 164.369633 -9.212718) (xy 164.431113 -9.149822) (xy 164.498058 -9.092777) (xy 164.569913 -9.042056)
			(xy 164.646083 -8.998079) (xy 164.725936 -8.961211) (xy 164.808811 -8.931758) (xy 164.894021 -8.909962)
			(xy 164.98086 -8.896006) (xy 165.068608 -8.890003) (xy 165.156538 -8.892005) (xy 165.243923 -8.901995)
			(xy 165.330036 -8.91989) (xy 165.414166 -8.945541) (xy 165.495614 -8.978736) (xy 165.573707 -9.0192)
			(xy 165.647796 -9.066598) (xy 165.717268 -9.120537) (xy 165.781547 -9.18057) (xy 165.840101 -9.246199)
			(xy 165.892445 -9.316881) (xy 165.938144 -9.39203) (xy 165.97682 -9.471023) (xy 166.008152 -9.553206)
			(xy 166.031882 -9.637898) (xy 166.047812 -9.724397) (xy 166.05581 -9.811985) (xy 166.05631 -9.855962)
			(xy 166.664393 -9.855962) (xy 166.668396 -9.7681) (xy 166.680372 -9.680966) (xy 166.700223 -9.595282)
			(xy 166.727782 -9.511758) (xy 166.762823 -9.431086) (xy 166.805054 -9.353935) (xy 166.854126 -9.280944)
			(xy 166.909633 -9.212718) (xy 166.971113 -9.149822) (xy 167.038058 -9.092777) (xy 167.109913 -9.042056)
			(xy 167.186083 -8.998079) (xy 167.265936 -8.961211) (xy 167.348811 -8.931758) (xy 167.434021 -8.909962)
			(xy 167.52086 -8.896006) (xy 167.608608 -8.890003) (xy 167.696538 -8.892005) (xy 167.783923 -8.901995)
			(xy 167.870036 -8.91989) (xy 167.954166 -8.945541) (xy 168.035614 -8.978736) (xy 168.113707 -9.0192)
			(xy 168.187796 -9.066598) (xy 168.257268 -9.120537) (xy 168.321547 -9.18057) (xy 168.380101 -9.246199)
			(xy 168.432445 -9.316881) (xy 168.478144 -9.39203) (xy 168.51682 -9.471023) (xy 168.548152 -9.553206)
			(xy 168.571882 -9.637898) (xy 168.587812 -9.724397) (xy 168.59581 -9.811985) (xy 168.59631 -9.855962)
			(xy 169.204393 -9.855962) (xy 169.208396 -9.7681) (xy 169.220372 -9.680966) (xy 169.240223 -9.595282)
			(xy 169.267782 -9.511758) (xy 169.302823 -9.431086) (xy 169.345054 -9.353935) (xy 169.394126 -9.280944)
			(xy 169.449633 -9.212718) (xy 169.511113 -9.149822) (xy 169.578058 -9.092777) (xy 169.649913 -9.042056)
			(xy 169.726083 -8.998079) (xy 169.805936 -8.961211) (xy 169.888811 -8.931758) (xy 169.974021 -8.909962)
			(xy 170.06086 -8.896006) (xy 170.148608 -8.890003) (xy 170.236538 -8.892005) (xy 170.323923 -8.901995)
			(xy 170.410036 -8.91989) (xy 170.494166 -8.945541) (xy 170.575614 -8.978736) (xy 170.653707 -9.0192)
			(xy 170.727796 -9.066598) (xy 170.797268 -9.120537) (xy 170.861547 -9.18057) (xy 170.920101 -9.246199)
			(xy 170.972445 -9.316881) (xy 171.018144 -9.39203) (xy 171.05682 -9.471023) (xy 171.088152 -9.553206)
			(xy 171.111882 -9.637898) (xy 171.127812 -9.724397) (xy 171.13581 -9.811985) (xy 171.13631 -9.855962)
			(xy 171.744393 -9.855962) (xy 171.748396 -9.7681) (xy 171.760372 -9.680966) (xy 171.780223 -9.595282)
			(xy 171.807782 -9.511758) (xy 171.842823 -9.431086) (xy 171.885054 -9.353935) (xy 171.934126 -9.280944)
			(xy 171.989633 -9.212718) (xy 172.051113 -9.149822) (xy 172.118058 -9.092777) (xy 172.189913 -9.042056)
			(xy 172.266083 -8.998079) (xy 172.345936 -8.961211) (xy 172.428811 -8.931758) (xy 172.514021 -8.909962)
			(xy 172.60086 -8.896006) (xy 172.688608 -8.890003) (xy 172.776538 -8.892005) (xy 172.863923 -8.901995)
			(xy 172.950036 -8.91989) (xy 173.034166 -8.945541) (xy 173.115614 -8.978736) (xy 173.193707 -9.0192)
			(xy 173.267796 -9.066598) (xy 173.337268 -9.120537) (xy 173.401547 -9.18057) (xy 173.460101 -9.246199)
			(xy 173.512445 -9.316881) (xy 173.558144 -9.39203) (xy 173.59682 -9.471023) (xy 173.628152 -9.553206)
			(xy 173.651882 -9.637898) (xy 173.667812 -9.724397) (xy 173.67581 -9.811985) (xy 173.67631 -9.855962)
			(xy 173.67581 -9.899939) (xy 173.667812 -9.987527) (xy 173.651882 -10.074026) (xy 173.628152 -10.158718)
			(xy 173.59682 -10.240901) (xy 173.558144 -10.319894) (xy 173.512445 -10.395043) (xy 173.460101 -10.465725)
			(xy 173.401547 -10.531354) (xy 173.337268 -10.591387) (xy 173.267796 -10.645326) (xy 173.193707 -10.692724)
			(xy 173.115614 -10.733188) (xy 173.034166 -10.766383) (xy 172.950036 -10.792034) (xy 172.863923 -10.809929)
			(xy 172.776538 -10.819919) (xy 172.688608 -10.821921) (xy 172.60086 -10.815918) (xy 172.514021 -10.801962)
			(xy 172.428811 -10.780166) (xy 172.345936 -10.750713) (xy 172.266083 -10.713845) (xy 172.189913 -10.669868)
			(xy 172.118058 -10.619147) (xy 172.051113 -10.562102) (xy 171.989633 -10.499206) (xy 171.934126 -10.43098)
			(xy 171.885054 -10.357989) (xy 171.842823 -10.280838) (xy 171.807782 -10.200166) (xy 171.780223 -10.116642)
			(xy 171.760372 -10.030958) (xy 171.748396 -9.943824) (xy 171.744393 -9.855962) (xy 171.13631 -9.855962)
			(xy 171.13581 -9.899939) (xy 171.127812 -9.987527) (xy 171.111882 -10.074026) (xy 171.088152 -10.158718)
			(xy 171.05682 -10.240901) (xy 171.018144 -10.319894) (xy 170.972445 -10.395043) (xy 170.920101 -10.465725)
			(xy 170.861547 -10.531354) (xy 170.797268 -10.591387) (xy 170.727796 -10.645326) (xy 170.653707 -10.692724)
			(xy 170.575614 -10.733188) (xy 170.494166 -10.766383) (xy 170.410036 -10.792034) (xy 170.323923 -10.809929)
			(xy 170.236538 -10.819919) (xy 170.148608 -10.821921) (xy 170.06086 -10.815918) (xy 169.974021 -10.801962)
			(xy 169.888811 -10.780166) (xy 169.805936 -10.750713) (xy 169.726083 -10.713845) (xy 169.649913 -10.669868)
			(xy 169.578058 -10.619147) (xy 169.511113 -10.562102) (xy 169.449633 -10.499206) (xy 169.394126 -10.43098)
			(xy 169.345054 -10.357989) (xy 169.302823 -10.280838) (xy 169.267782 -10.200166) (xy 169.240223 -10.116642)
			(xy 169.220372 -10.030958) (xy 169.208396 -9.943824) (xy 169.204393 -9.855962) (xy 168.59631 -9.855962)
			(xy 168.59581 -9.899939) (xy 168.587812 -9.987527) (xy 168.571882 -10.074026) (xy 168.548152 -10.158718)
			(xy 168.51682 -10.240901) (xy 168.478144 -10.319894) (xy 168.432445 -10.395043) (xy 168.380101 -10.465725)
			(xy 168.321547 -10.531354) (xy 168.257268 -10.591387) (xy 168.187796 -10.645326) (xy 168.113707 -10.692724)
			(xy 168.035614 -10.733188) (xy 167.954166 -10.766383) (xy 167.870036 -10.792034) (xy 167.783923 -10.809929)
			(xy 167.696538 -10.819919) (xy 167.608608 -10.821921) (xy 167.52086 -10.815918) (xy 167.434021 -10.801962)
			(xy 167.348811 -10.780166) (xy 167.265936 -10.750713) (xy 167.186083 -10.713845) (xy 167.109913 -10.669868)
			(xy 167.038058 -10.619147) (xy 166.971113 -10.562102) (xy 166.909633 -10.499206) (xy 166.854126 -10.43098)
			(xy 166.805054 -10.357989) (xy 166.762823 -10.280838) (xy 166.727782 -10.200166) (xy 166.700223 -10.116642)
			(xy 166.680372 -10.030958) (xy 166.668396 -9.943824) (xy 166.664393 -9.855962) (xy 166.05631 -9.855962)
			(xy 166.05581 -9.899939) (xy 166.047812 -9.987527) (xy 166.031882 -10.074026) (xy 166.008152 -10.158718)
			(xy 165.97682 -10.240901) (xy 165.938144 -10.319894) (xy 165.892445 -10.395043) (xy 165.840101 -10.465725)
			(xy 165.781547 -10.531354) (xy 165.717268 -10.591387) (xy 165.647796 -10.645326) (xy 165.573707 -10.692724)
			(xy 165.495614 -10.733188) (xy 165.414166 -10.766383) (xy 165.330036 -10.792034) (xy 165.243923 -10.809929)
			(xy 165.156538 -10.819919) (xy 165.068608 -10.821921) (xy 164.98086 -10.815918) (xy 164.894021 -10.801962)
			(xy 164.808811 -10.780166) (xy 164.725936 -10.750713) (xy 164.646083 -10.713845) (xy 164.569913 -10.669868)
			(xy 164.498058 -10.619147) (xy 164.431113 -10.562102) (xy 164.369633 -10.499206) (xy 164.314126 -10.43098)
			(xy 164.265054 -10.357989) (xy 164.222823 -10.280838) (xy 164.187782 -10.200166) (xy 164.160223 -10.116642)
			(xy 164.140372 -10.030958) (xy 164.128396 -9.943824) (xy 164.124393 -9.855962) (xy 163.51631 -9.855962)
			(xy 163.51581 -9.899939) (xy 163.507812 -9.987527) (xy 163.491882 -10.074026) (xy 163.468152 -10.158718)
			(xy 163.43682 -10.240901) (xy 163.398144 -10.319894) (xy 163.352445 -10.395043) (xy 163.300101 -10.465725)
			(xy 163.241547 -10.531354) (xy 163.177268 -10.591387) (xy 163.107796 -10.645326) (xy 163.033707 -10.692724)
			(xy 162.955614 -10.733188) (xy 162.874166 -10.766383) (xy 162.790036 -10.792034) (xy 162.703923 -10.809929)
			(xy 162.616538 -10.819919) (xy 162.528608 -10.821921) (xy 162.44086 -10.815918) (xy 162.354021 -10.801962)
			(xy 162.268811 -10.780166) (xy 162.185936 -10.750713) (xy 162.106083 -10.713845) (xy 162.029913 -10.669868)
			(xy 161.958058 -10.619147) (xy 161.891113 -10.562102) (xy 161.829633 -10.499206) (xy 161.774126 -10.43098)
			(xy 161.725054 -10.357989) (xy 161.682823 -10.280838) (xy 161.647782 -10.200166) (xy 161.620223 -10.116642)
			(xy 161.600372 -10.030958) (xy 161.588396 -9.943824) (xy 161.584393 -9.855962) (xy 157.777942 -9.855962)
			(xy 157.777442 -9.899939) (xy 157.769444 -9.987527) (xy 157.753514 -10.074026) (xy 157.729784 -10.158718)
			(xy 157.698452 -10.240901) (xy 157.659776 -10.319894) (xy 157.614077 -10.395043) (xy 157.561733 -10.465725)
			(xy 157.503179 -10.531354) (xy 157.4389 -10.591387) (xy 157.369428 -10.645326) (xy 157.295339 -10.692724)
			(xy 157.217246 -10.733188) (xy 157.135798 -10.766383) (xy 157.051668 -10.792034) (xy 156.965555 -10.809929)
			(xy 156.87817 -10.819919) (xy 156.79024 -10.821921) (xy 156.702492 -10.815918) (xy 156.615653 -10.801962)
			(xy 156.530443 -10.780166) (xy 156.447568 -10.750713) (xy 156.367715 -10.713845) (xy 156.291545 -10.669868)
			(xy 156.21969 -10.619147) (xy 156.152745 -10.562102) (xy 156.091265 -10.499206) (xy 156.035758 -10.43098)
			(xy 155.986686 -10.357989) (xy 155.944455 -10.280838) (xy 155.909414 -10.200166) (xy 155.881855 -10.116642)
			(xy 155.862004 -10.030958) (xy 155.850028 -9.943824) (xy 155.846025 -9.855962) (xy 155.237942 -9.855962)
			(xy 155.237442 -9.899939) (xy 155.229444 -9.987527) (xy 155.213514 -10.074026) (xy 155.189784 -10.158718)
			(xy 155.158452 -10.240901) (xy 155.119776 -10.319894) (xy 155.074077 -10.395043) (xy 155.021733 -10.465725)
			(xy 154.963179 -10.531354) (xy 154.8989 -10.591387) (xy 154.829428 -10.645326) (xy 154.755339 -10.692724)
			(xy 154.677246 -10.733188) (xy 154.595798 -10.766383) (xy 154.511668 -10.792034) (xy 154.425555 -10.809929)
			(xy 154.33817 -10.819919) (xy 154.25024 -10.821921) (xy 154.162492 -10.815918) (xy 154.075653 -10.801962)
			(xy 153.990443 -10.780166) (xy 153.907568 -10.750713) (xy 153.827715 -10.713845) (xy 153.751545 -10.669868)
			(xy 153.67969 -10.619147) (xy 153.612745 -10.562102) (xy 153.551265 -10.499206) (xy 153.495758 -10.43098)
			(xy 153.446686 -10.357989) (xy 153.404455 -10.280838) (xy 153.369414 -10.200166) (xy 153.341855 -10.116642)
			(xy 153.322004 -10.030958) (xy 153.310028 -9.943824) (xy 153.306025 -9.855962) (xy 152.697942 -9.855962)
			(xy 152.697442 -9.899939) (xy 152.689444 -9.987527) (xy 152.673514 -10.074026) (xy 152.649784 -10.158718)
			(xy 152.618452 -10.240901) (xy 152.579776 -10.319894) (xy 152.534077 -10.395043) (xy 152.481733 -10.465725)
			(xy 152.423179 -10.531354) (xy 152.3589 -10.591387) (xy 152.289428 -10.645326) (xy 152.215339 -10.692724)
			(xy 152.137246 -10.733188) (xy 152.055798 -10.766383) (xy 151.971668 -10.792034) (xy 151.885555 -10.809929)
			(xy 151.79817 -10.819919) (xy 151.71024 -10.821921) (xy 151.622492 -10.815918) (xy 151.535653 -10.801962)
			(xy 151.450443 -10.780166) (xy 151.367568 -10.750713) (xy 151.287715 -10.713845) (xy 151.211545 -10.669868)
			(xy 151.13969 -10.619147) (xy 151.072745 -10.562102) (xy 151.011265 -10.499206) (xy 150.955758 -10.43098)
			(xy 150.906686 -10.357989) (xy 150.864455 -10.280838) (xy 150.829414 -10.200166) (xy 150.801855 -10.116642)
			(xy 150.782004 -10.030958) (xy 150.770028 -9.943824) (xy 150.766025 -9.855962) (xy 150.157942 -9.855962)
			(xy 150.157442 -9.899939) (xy 150.149444 -9.987527) (xy 150.133514 -10.074026) (xy 150.109784 -10.158718)
			(xy 150.078452 -10.240901) (xy 150.039776 -10.319894) (xy 149.994077 -10.395043) (xy 149.941733 -10.465725)
			(xy 149.883179 -10.531354) (xy 149.8189 -10.591387) (xy 149.749428 -10.645326) (xy 149.675339 -10.692724)
			(xy 149.597246 -10.733188) (xy 149.515798 -10.766383) (xy 149.431668 -10.792034) (xy 149.345555 -10.809929)
			(xy 149.25817 -10.819919) (xy 149.17024 -10.821921) (xy 149.082492 -10.815918) (xy 148.995653 -10.801962)
			(xy 148.910443 -10.780166) (xy 148.827568 -10.750713) (xy 148.747715 -10.713845) (xy 148.671545 -10.669868)
			(xy 148.59969 -10.619147) (xy 148.532745 -10.562102) (xy 148.471265 -10.499206) (xy 148.415758 -10.43098)
			(xy 148.366686 -10.357989) (xy 148.324455 -10.280838) (xy 148.289414 -10.200166) (xy 148.261855 -10.116642)
			(xy 148.242004 -10.030958) (xy 148.230028 -9.943824) (xy 148.226025 -9.855962) (xy 147.617942 -9.855962)
			(xy 147.617442 -9.899939) (xy 147.609444 -9.987527) (xy 147.593514 -10.074026) (xy 147.569784 -10.158718)
			(xy 147.538452 -10.240901) (xy 147.499776 -10.319894) (xy 147.454077 -10.395043) (xy 147.401733 -10.465725)
			(xy 147.343179 -10.531354) (xy 147.2789 -10.591387) (xy 147.209428 -10.645326) (xy 147.135339 -10.692724)
			(xy 147.057246 -10.733188) (xy 146.975798 -10.766383) (xy 146.891668 -10.792034) (xy 146.805555 -10.809929)
			(xy 146.71817 -10.819919) (xy 146.63024 -10.821921) (xy 146.542492 -10.815918) (xy 146.455653 -10.801962)
			(xy 146.370443 -10.780166) (xy 146.287568 -10.750713) (xy 146.207715 -10.713845) (xy 146.131545 -10.669868)
			(xy 146.05969 -10.619147) (xy 145.992745 -10.562102) (xy 145.931265 -10.499206) (xy 145.875758 -10.43098)
			(xy 145.826686 -10.357989) (xy 145.784455 -10.280838) (xy 145.749414 -10.200166) (xy 145.721855 -10.116642)
			(xy 145.702004 -10.030958) (xy 145.690028 -9.943824) (xy 145.686025 -9.855962) (xy 141.879828 -9.855962)
			(xy 141.879328 -9.899939) (xy 141.87133 -9.987527) (xy 141.8554 -10.074026) (xy 141.83167 -10.158718)
			(xy 141.800338 -10.240901) (xy 141.761662 -10.319894) (xy 141.715963 -10.395043) (xy 141.663619 -10.465725)
			(xy 141.605065 -10.531354) (xy 141.540786 -10.591387) (xy 141.471314 -10.645326) (xy 141.397225 -10.692724)
			(xy 141.319132 -10.733188) (xy 141.237684 -10.766383) (xy 141.153554 -10.792034) (xy 141.067441 -10.809929)
			(xy 140.980056 -10.819919) (xy 140.892126 -10.821921) (xy 140.804378 -10.815918) (xy 140.717539 -10.801962)
			(xy 140.632329 -10.780166) (xy 140.549454 -10.750713) (xy 140.469601 -10.713845) (xy 140.393431 -10.669868)
			(xy 140.321576 -10.619147) (xy 140.254631 -10.562102) (xy 140.193151 -10.499206) (xy 140.137644 -10.43098)
			(xy 140.088572 -10.357989) (xy 140.046341 -10.280838) (xy 140.0113 -10.200166) (xy 139.983741 -10.116642)
			(xy 139.96389 -10.030958) (xy 139.951914 -9.943824) (xy 139.947911 -9.855962) (xy 139.339828 -9.855962)
			(xy 139.339328 -9.899939) (xy 139.33133 -9.987527) (xy 139.3154 -10.074026) (xy 139.29167 -10.158718)
			(xy 139.260338 -10.240901) (xy 139.221662 -10.319894) (xy 139.175963 -10.395043) (xy 139.123619 -10.465725)
			(xy 139.065065 -10.531354) (xy 139.000786 -10.591387) (xy 138.931314 -10.645326) (xy 138.857225 -10.692724)
			(xy 138.779132 -10.733188) (xy 138.697684 -10.766383) (xy 138.613554 -10.792034) (xy 138.527441 -10.809929)
			(xy 138.440056 -10.819919) (xy 138.352126 -10.821921) (xy 138.264378 -10.815918) (xy 138.177539 -10.801962)
			(xy 138.092329 -10.780166) (xy 138.009454 -10.750713) (xy 137.929601 -10.713845) (xy 137.853431 -10.669868)
			(xy 137.781576 -10.619147) (xy 137.714631 -10.562102) (xy 137.653151 -10.499206) (xy 137.597644 -10.43098)
			(xy 137.548572 -10.357989) (xy 137.506341 -10.280838) (xy 137.4713 -10.200166) (xy 137.443741 -10.116642)
			(xy 137.42389 -10.030958) (xy 137.411914 -9.943824) (xy 137.407911 -9.855962) (xy 136.799828 -9.855962)
			(xy 136.799328 -9.899939) (xy 136.79133 -9.987527) (xy 136.7754 -10.074026) (xy 136.75167 -10.158718)
			(xy 136.720338 -10.240901) (xy 136.681662 -10.319894) (xy 136.635963 -10.395043) (xy 136.583619 -10.465725)
			(xy 136.525065 -10.531354) (xy 136.460786 -10.591387) (xy 136.391314 -10.645326) (xy 136.317225 -10.692724)
			(xy 136.239132 -10.733188) (xy 136.157684 -10.766383) (xy 136.073554 -10.792034) (xy 135.987441 -10.809929)
			(xy 135.900056 -10.819919) (xy 135.812126 -10.821921) (xy 135.724378 -10.815918) (xy 135.637539 -10.801962)
			(xy 135.552329 -10.780166) (xy 135.469454 -10.750713) (xy 135.389601 -10.713845) (xy 135.313431 -10.669868)
			(xy 135.241576 -10.619147) (xy 135.174631 -10.562102) (xy 135.113151 -10.499206) (xy 135.057644 -10.43098)
			(xy 135.008572 -10.357989) (xy 134.966341 -10.280838) (xy 134.9313 -10.200166) (xy 134.903741 -10.116642)
			(xy 134.88389 -10.030958) (xy 134.871914 -9.943824) (xy 134.867911 -9.855962) (xy 134.259828 -9.855962)
			(xy 134.259328 -9.899939) (xy 134.25133 -9.987527) (xy 134.2354 -10.074026) (xy 134.21167 -10.158718)
			(xy 134.180338 -10.240901) (xy 134.141662 -10.319894) (xy 134.095963 -10.395043) (xy 134.043619 -10.465725)
			(xy 133.985065 -10.531354) (xy 133.920786 -10.591387) (xy 133.851314 -10.645326) (xy 133.777225 -10.692724)
			(xy 133.699132 -10.733188) (xy 133.617684 -10.766383) (xy 133.533554 -10.792034) (xy 133.447441 -10.809929)
			(xy 133.360056 -10.819919) (xy 133.272126 -10.821921) (xy 133.184378 -10.815918) (xy 133.097539 -10.801962)
			(xy 133.012329 -10.780166) (xy 132.929454 -10.750713) (xy 132.849601 -10.713845) (xy 132.773431 -10.669868)
			(xy 132.701576 -10.619147) (xy 132.634631 -10.562102) (xy 132.573151 -10.499206) (xy 132.517644 -10.43098)
			(xy 132.468572 -10.357989) (xy 132.426341 -10.280838) (xy 132.3913 -10.200166) (xy 132.363741 -10.116642)
			(xy 132.34389 -10.030958) (xy 132.331914 -9.943824) (xy 132.327911 -9.855962) (xy 131.719828 -9.855962)
			(xy 131.719328 -9.899939) (xy 131.71133 -9.987527) (xy 131.6954 -10.074026) (xy 131.67167 -10.158718)
			(xy 131.640338 -10.240901) (xy 131.601662 -10.319894) (xy 131.555963 -10.395043) (xy 131.503619 -10.465725)
			(xy 131.445065 -10.531354) (xy 131.380786 -10.591387) (xy 131.311314 -10.645326) (xy 131.237225 -10.692724)
			(xy 131.159132 -10.733188) (xy 131.077684 -10.766383) (xy 130.993554 -10.792034) (xy 130.907441 -10.809929)
			(xy 130.820056 -10.819919) (xy 130.732126 -10.821921) (xy 130.644378 -10.815918) (xy 130.557539 -10.801962)
			(xy 130.472329 -10.780166) (xy 130.389454 -10.750713) (xy 130.309601 -10.713845) (xy 130.233431 -10.669868)
			(xy 130.161576 -10.619147) (xy 130.094631 -10.562102) (xy 130.033151 -10.499206) (xy 129.977644 -10.43098)
			(xy 129.928572 -10.357989) (xy 129.886341 -10.280838) (xy 129.8513 -10.200166) (xy 129.823741 -10.116642)
			(xy 129.80389 -10.030958) (xy 129.791914 -9.943824) (xy 129.787911 -9.855962) (xy 128.74244 -9.855962)
			(xy 128.74244 -12.845796) (xy 179.240686 -12.845796) (xy 179.244757 -12.790174) (xy 179.256883 -12.735737)
			(xy 179.276806 -12.683646) (xy 179.304102 -12.635011) (xy 179.338188 -12.590868) (xy 179.378337 -12.552159)
			(xy 179.423695 -12.519708) (xy 179.473295 -12.494207) (xy 179.526079 -12.4762) (xy 179.580922 -12.46607)
			(xy 179.636656 -12.464033) (xy 179.692093 -12.470133) (xy 179.74605 -12.484239) (xy 179.797379 -12.506051)
			(xy 179.844985 -12.535105) (xy 179.887853 -12.57078) (xy 179.92507 -12.612317) (xy 179.955843 -12.65883)
			(xy 179.979515 -12.709327) (xy 179.995583 -12.762734) (xy 180.003703 -12.81791) (xy 180.004212 -12.845796)
			(xy 180.003703 -12.873682) (xy 179.995583 -12.928858) (xy 179.986567 -12.958826) (xy 180.383686 -12.958826)
			(xy 180.387757 -12.903204) (xy 180.399883 -12.848767) (xy 180.419806 -12.796676) (xy 180.447102 -12.748041)
			(xy 180.481188 -12.703898) (xy 180.521337 -12.665189) (xy 180.566695 -12.632738) (xy 180.616295 -12.607237)
			(xy 180.669079 -12.58923) (xy 180.723922 -12.5791) (xy 180.779656 -12.577063) (xy 180.835093 -12.583163)
			(xy 180.88905 -12.597269) (xy 180.940379 -12.619081) (xy 180.987985 -12.648135) (xy 181.030853 -12.68381)
			(xy 181.06807 -12.725347) (xy 181.098843 -12.77186) (xy 181.122515 -12.822357) (xy 181.138583 -12.875764)
			(xy 181.146703 -12.93094) (xy 181.147212 -12.958826) (xy 181.146703 -12.986712) (xy 181.138583 -13.041888)
			(xy 181.122515 -13.095295) (xy 181.098843 -13.145792) (xy 181.06807 -13.192305) (xy 181.030853 -13.233842)
			(xy 180.987985 -13.269517) (xy 180.940379 -13.298571) (xy 180.88905 -13.320383) (xy 180.835093 -13.334489)
			(xy 180.779656 -13.340589) (xy 180.723922 -13.338552) (xy 180.669079 -13.328422) (xy 180.616295 -13.310415)
			(xy 180.566695 -13.284914) (xy 180.521337 -13.252463) (xy 180.481188 -13.213754) (xy 180.447102 -13.169611)
			(xy 180.419806 -13.120976) (xy 180.399883 -13.068885) (xy 180.387757 -13.014448) (xy 180.383686 -12.958826)
			(xy 179.986567 -12.958826) (xy 179.979515 -12.982265) (xy 179.955843 -13.032762) (xy 179.92507 -13.079275)
			(xy 179.887853 -13.120812) (xy 179.844985 -13.156487) (xy 179.797379 -13.185541) (xy 179.74605 -13.207353)
			(xy 179.692093 -13.221459) (xy 179.636656 -13.227559) (xy 179.580922 -13.225522) (xy 179.526079 -13.215392)
			(xy 179.473295 -13.197385) (xy 179.423695 -13.171884) (xy 179.378337 -13.139433) (xy 179.338188 -13.100724)
			(xy 179.304102 -13.056581) (xy 179.276806 -13.007946) (xy 179.256883 -12.955855) (xy 179.244757 -12.901418)
			(xy 179.240686 -12.845796) (xy 128.74244 -12.845796) (xy 128.74244 -13.665123) (xy 162.16729 -13.665123)
			(xy 162.173246 -13.609356) (xy 162.187303 -13.555063) (xy 162.209157 -13.503413) (xy 162.238338 -13.455519)
			(xy 162.274217 -13.412414) (xy 162.31602 -13.375027) (xy 162.362847 -13.344163) (xy 162.413688 -13.320487)
			(xy 162.467448 -13.304511) (xy 162.522967 -13.296578) (xy 162.57905 -13.296859) (xy 162.634487 -13.305348)
			(xy 162.688084 -13.321862) (xy 162.738685 -13.346046) (xy 162.785201 -13.377378) (xy 162.826627 -13.415182)
			(xy 162.844734 -13.4366) (xy 162.860016 -13.454559) (xy 162.896031 -13.484995) (xy 162.937038 -13.508269)
			(xy 162.981634 -13.523585) (xy 163.028289 -13.530416) (xy 163.075404 -13.52853) (xy 163.121363 -13.517989)
			(xy 163.164591 -13.499157) (xy 163.203606 -13.472678) (xy 163.237072 -13.43946) (xy 163.25088 -13.420344)
			(xy 163.267183 -13.397519) (xy 163.305413 -13.356477) (xy 163.349241 -13.321474) (xy 163.397722 -13.293266)
			(xy 163.44981 -13.27246) (xy 163.504383 -13.259506) (xy 163.560265 -13.254681) (xy 163.616251 -13.25809)
			(xy 163.671134 -13.269659) (xy 163.723733 -13.28914) (xy 163.772911 -13.316112) (xy 163.817611 -13.349994)
			(xy 163.856868 -13.390056) (xy 163.889837 -13.435433) (xy 163.915806 -13.485149) (xy 163.934216 -13.538132)
			(xy 163.94467 -13.593239) (xy 163.946943 -13.649282) (xy 163.946079 -13.657368) (xy 166.229177 -13.657368)
			(xy 166.229833 -13.601305) (xy 166.238688 -13.545942) (xy 166.25555 -13.492471) (xy 166.280057 -13.442044)
			(xy 166.31168 -13.395747) (xy 166.349738 -13.354576) (xy 166.393412 -13.319418) (xy 166.441761 -13.291032)
			(xy 166.493744 -13.270027) (xy 166.548242 -13.256856) (xy 166.60408 -13.251803) (xy 166.660057 -13.254977)
			(xy 166.714966 -13.266309) (xy 166.767626 -13.285555) (xy 166.816902 -13.312302) (xy 166.861733 -13.345972)
			(xy 166.901153 -13.38584) (xy 166.918132 -13.408152) (xy 166.932454 -13.42686) (xy 166.966846 -13.459058)
			(xy 167.006582 -13.484367) (xy 167.050301 -13.501922) (xy 167.096505 -13.51112) (xy 167.143614 -13.511648)
			(xy 167.190013 -13.503487) (xy 167.234115 -13.486917) (xy 167.274408 -13.462504) (xy 167.309513 -13.431085)
			(xy 167.324278 -13.412724) (xy 167.341768 -13.390806) (xy 167.382112 -13.351861) (xy 167.427721 -13.31924)
			(xy 167.477613 -13.293646) (xy 167.530714 -13.275629) (xy 167.585881 -13.265578) (xy 167.641924 -13.26371)
			(xy 167.697637 -13.270064) (xy 167.75182 -13.284503) (xy 167.803306 -13.306718) (xy 167.850987 -13.336228)
			(xy 167.893835 -13.372399) (xy 167.930928 -13.414452) (xy 167.961467 -13.461481) (xy 167.984793 -13.512473)
			(xy 168.000406 -13.56633) (xy 168.007968 -13.621892) (xy 168.007842 -13.632688) (xy 169.79468 -13.632688)
			(xy 169.798751 -13.577066) (xy 169.810877 -13.522629) (xy 169.8308 -13.470538) (xy 169.858096 -13.421903)
			(xy 169.892182 -13.37776) (xy 169.932331 -13.339051) (xy 169.977689 -13.3066) (xy 170.027289 -13.281099)
			(xy 170.080073 -13.263092) (xy 170.134916 -13.252962) (xy 170.19065 -13.250925) (xy 170.246087 -13.257025)
			(xy 170.300044 -13.271131) (xy 170.351373 -13.292943) (xy 170.398979 -13.321997) (xy 170.441847 -13.357672)
			(xy 170.479064 -13.399209) (xy 170.509837 -13.445722) (xy 170.533509 -13.496219) (xy 170.549577 -13.549626)
			(xy 170.557697 -13.604802) (xy 170.558206 -13.632688) (xy 170.557697 -13.660574) (xy 170.555119 -13.678095)
			(xy 171.303717 -13.678095) (xy 171.305152 -13.62202) (xy 171.31478 -13.566758) (xy 171.332394 -13.513502)
			(xy 171.357616 -13.463398) (xy 171.389901 -13.417526) (xy 171.428554 -13.376875) (xy 171.472741 -13.342321)
			(xy 171.521512 -13.314609) (xy 171.573814 -13.294335) (xy 171.62852 -13.281936) (xy 171.684453 -13.27768)
			(xy 171.740405 -13.281659) (xy 171.795173 -13.293786) (xy 171.847574 -13.3138) (xy 171.896482 -13.341271)
			(xy 171.94084 -13.375605) (xy 171.979694 -13.416064) (xy 171.996354 -13.438632) (xy 172.010412 -13.457531)
			(xy 172.044317 -13.490221) (xy 172.083667 -13.516101) (xy 172.127113 -13.534285) (xy 172.173166 -13.544149)
			(xy 172.220249 -13.545356) (xy 172.266747 -13.537864) (xy 172.311067 -13.521931) (xy 172.351691 -13.498101)
			(xy 172.387227 -13.467191) (xy 172.402246 -13.449046) (xy 172.420027 -13.427349) (xy 172.460896 -13.388927)
			(xy 172.50695 -13.356901) (xy 172.557197 -13.331963) (xy 172.610553 -13.31465) (xy 172.665869 -13.305334)
			(xy 172.721953 -13.304217) (xy 172.777596 -13.311322) (xy 172.831599 -13.326497) (xy 172.882799 -13.349415)
			(xy 172.930092 -13.379581) (xy 172.972459 -13.416346) (xy 173.008987 -13.458917) (xy 173.038889 -13.506378)
			(xy 173.061522 -13.557704) (xy 173.076396 -13.611791) (xy 173.083191 -13.667473) (xy 173.081762 -13.723549)
			(xy 173.072138 -13.778813) (xy 173.054528 -13.832071) (xy 173.02931 -13.882178) (xy 172.997029 -13.928054)
			(xy 172.958379 -13.968708) (xy 172.914194 -14.003267) (xy 172.865425 -14.030985) (xy 172.813124 -14.051264)
			(xy 172.758418 -14.063668) (xy 172.702486 -14.06793) (xy 172.646532 -14.063957) (xy 172.591762 -14.051835)
			(xy 172.539357 -14.031826) (xy 172.490447 -14.00436) (xy 172.446084 -13.97003) (xy 172.407225 -13.929575)
			(xy 172.390562 -13.907008) (xy 172.376485 -13.888123) (xy 172.342585 -13.855429) (xy 172.303238 -13.829544)
			(xy 172.259794 -13.811357) (xy 172.213743 -13.80149) (xy 172.166661 -13.800281) (xy 172.120163 -13.807772)
			(xy 172.075844 -13.823706) (xy 172.035221 -13.847537) (xy 171.999687 -13.878448) (xy 171.98467 -13.896594)
			(xy 171.966851 -13.91826) (xy 171.92598 -13.95668) (xy 171.879925 -13.988702) (xy 171.829677 -14.013637)
			(xy 171.776321 -14.030946) (xy 171.721005 -14.040258) (xy 171.664923 -14.041372) (xy 171.609281 -14.034262)
			(xy 171.55528 -14.019084) (xy 171.504082 -13.996163) (xy 171.456792 -13.965994) (xy 171.414428 -13.929227)
			(xy 171.377904 -13.886653) (xy 171.348006 -13.839191) (xy 171.325378 -13.787864) (xy 171.310508 -13.733777)
			(xy 171.303717 -13.678095) (xy 170.555119 -13.678095) (xy 170.549577 -13.71575) (xy 170.533509 -13.769157)
			(xy 170.509837 -13.819654) (xy 170.479064 -13.866167) (xy 170.441847 -13.907704) (xy 170.398979 -13.943379)
			(xy 170.351373 -13.972433) (xy 170.300044 -13.994245) (xy 170.246087 -14.008351) (xy 170.19065 -14.014451)
			(xy 170.134916 -14.012414) (xy 170.080073 -14.002284) (xy 170.027289 -13.984277) (xy 169.977689 -13.958776)
			(xy 169.932331 -13.926325) (xy 169.892182 -13.887616) (xy 169.858096 -13.843473) (xy 169.8308 -13.794838)
			(xy 169.810877 -13.742747) (xy 169.798751 -13.68831) (xy 169.79468 -13.632688) (xy 168.007842 -13.632688)
			(xy 168.007316 -13.677963) (xy 167.998465 -13.733334) (xy 167.981606 -13.786814) (xy 167.957101 -13.83725)
			(xy 167.925477 -13.883556) (xy 167.887418 -13.924736) (xy 167.843741 -13.959902) (xy 167.795387 -13.988297)
			(xy 167.743398 -14.009309) (xy 167.688894 -14.022485) (xy 167.633049 -14.027543) (xy 167.577064 -14.024373)
			(xy 167.522146 -14.013043) (xy 167.469478 -13.993798) (xy 167.420194 -13.967051) (xy 167.375355 -13.933379)
			(xy 167.335927 -13.893508) (xy 167.318944 -13.871194) (xy 167.304652 -13.85246) (xy 167.270258 -13.820257)
			(xy 167.230518 -13.794943) (xy 167.186794 -13.777386) (xy 167.140583 -13.768187) (xy 167.093469 -13.767662)
			(xy 167.047065 -13.775828) (xy 167.00296 -13.792406) (xy 166.962665 -13.816827) (xy 166.927562 -13.848256)
			(xy 166.912798 -13.866622) (xy 166.895264 -13.888501) (xy 166.85492 -13.927435) (xy 166.809313 -13.960046)
			(xy 166.759424 -13.98563) (xy 166.706328 -14.003638) (xy 166.651168 -14.01368) (xy 166.595133 -14.015542)
			(xy 166.539428 -14.009182) (xy 166.485254 -13.994738) (xy 166.433777 -13.972521) (xy 166.386106 -13.943009)
			(xy 166.343268 -13.906838) (xy 166.306184 -13.864787) (xy 166.275655 -13.817761) (xy 166.252337 -13.766774)
			(xy 166.236732 -13.712923) (xy 166.229177 -13.657368) (xy 163.946079 -13.657368) (xy 163.940985 -13.705055)
			(xy 163.926926 -13.759354) (xy 163.905068 -13.811009) (xy 163.875883 -13.858908) (xy 163.839999 -13.902017)
			(xy 163.798189 -13.939407) (xy 163.751356 -13.970273) (xy 163.700508 -13.993949) (xy 163.646742 -14.009925)
			(xy 163.591216 -14.017856) (xy 163.535126 -14.017572) (xy 163.479684 -14.009079) (xy 163.426082 -13.99256)
			(xy 163.375476 -13.96837) (xy 163.328958 -13.937032) (xy 163.287529 -13.89922) (xy 163.269422 -13.877798)
			(xy 163.254075 -13.859896) (xy 163.218071 -13.829461) (xy 163.177074 -13.806186) (xy 163.132488 -13.790867)
			(xy 163.085842 -13.78403) (xy 163.038736 -13.78591) (xy 162.992783 -13.796443) (xy 162.94956 -13.815266)
			(xy 162.910548 -13.841735) (xy 162.877084 -13.874943) (xy 162.863276 -13.894054) (xy 162.846978 -13.916878)
			(xy 162.808749 -13.957913) (xy 162.764924 -13.99291) (xy 162.716448 -14.021112) (xy 162.664365 -14.041913)
			(xy 162.609797 -14.054864) (xy 162.553921 -14.059687) (xy 162.497942 -14.056276) (xy 162.443065 -14.044706)
			(xy 162.390473 -14.025227) (xy 162.3413 -13.998257) (xy 162.296606 -13.964378) (xy 162.257354 -13.92432)
			(xy 162.22439 -13.878947) (xy 162.198424 -13.829237) (xy 162.180016 -13.776261) (xy 162.169563 -13.72116)
			(xy 162.16729 -13.665123) (xy 128.74244 -13.665123) (xy 128.74244 -16.372586) (xy 174.410622 -16.372586)
			(xy 174.414693 -16.316964) (xy 174.426819 -16.262527) (xy 174.446742 -16.210436) (xy 174.474038 -16.161801)
			(xy 174.508124 -16.117658) (xy 174.548273 -16.078949) (xy 174.593631 -16.046498) (xy 174.643231 -16.020997)
			(xy 174.696015 -16.00299) (xy 174.750858 -15.99286) (xy 174.806592 -15.990823) (xy 174.862029 -15.996923)
			(xy 174.915986 -16.011029) (xy 174.967315 -16.032841) (xy 175.014921 -16.061895) (xy 175.057789 -16.09757)
			(xy 175.095006 -16.139107) (xy 175.125779 -16.18562) (xy 175.149451 -16.236117) (xy 175.165519 -16.289524)
			(xy 175.173639 -16.3447) (xy 175.174148 -16.372586) (xy 175.173639 -16.400472) (xy 175.165519 -16.455648)
			(xy 175.149451 -16.509055) (xy 175.125779 -16.559552) (xy 175.095006 -16.606065) (xy 175.057789 -16.647602)
			(xy 175.014921 -16.683277) (xy 174.967315 -16.712331) (xy 174.915986 -16.734143) (xy 174.862029 -16.748249)
			(xy 174.806592 -16.754349) (xy 174.750858 -16.752312) (xy 174.696015 -16.742182) (xy 174.643231 -16.724175)
			(xy 174.593631 -16.698674) (xy 174.548273 -16.666223) (xy 174.508124 -16.627514) (xy 174.474038 -16.583371)
			(xy 174.446742 -16.534736) (xy 174.426819 -16.482645) (xy 174.414693 -16.428208) (xy 174.410622 -16.372586)
			(xy 128.74244 -16.372586) (xy 128.74244 -17.571212) (xy 147.308316 -17.571212) (xy 147.308773 -17.52685)
			(xy 147.316505 -17.438465) (xy 147.331911 -17.351089) (xy 147.354874 -17.265389) (xy 147.385219 -17.182016)
			(xy 147.422715 -17.101605) (xy 147.467076 -17.024769) (xy 147.517966 -16.952091) (xy 147.574997 -16.884125)
			(xy 147.637734 -16.821389) (xy 147.7057 -16.764359) (xy 147.778379 -16.71347) (xy 147.855216 -16.669109)
			(xy 147.935627 -16.631614) (xy 148.019 -16.60127) (xy 148.104701 -16.578309) (xy 148.192076 -16.562904)
			(xy 148.280462 -16.555173) (xy 148.324824 -16.554704) (xy 148.368922 -16.555205) (xy 148.456769 -16.563042)
			(xy 148.543572 -16.578651) (xy 148.628646 -16.601909) (xy 148.711317 -16.632632) (xy 148.790932 -16.670577)
			(xy 148.866862 -16.715445) (xy 148.938507 -16.76688) (xy 149.005299 -16.824476) (xy 149.06671 -16.887777)
			(xy 149.122256 -16.956284) (xy 149.147276 -16.9926) (xy 149.160394 -17.011225) (xy 149.192087 -17.043939)
			(xy 149.229106 -17.070476) (xy 149.270264 -17.089985) (xy 149.314243 -17.101841) (xy 149.35963 -17.105664)
			(xy 149.404972 -17.101331) (xy 149.448814 -17.088981) (xy 149.489751 -17.06901) (xy 149.526469 -17.042058)
			(xy 149.5425 -17.025874) (xy 149.570372 -16.997157) (xy 149.631082 -16.945009) (xy 149.696766 -16.899285)
			(xy 149.766748 -16.860454) (xy 149.840305 -16.828919) (xy 149.91668 -16.805002) (xy 149.995086 -16.788952)
			(xy 150.074716 -16.780933) (xy 150.154748 -16.781027) (xy 150.234358 -16.789235) (xy 150.312726 -16.805471)
			(xy 150.389045 -16.829568) (xy 150.462527 -16.861278) (xy 150.532416 -16.900273) (xy 150.597992 -16.946154)
			(xy 150.658579 -16.998445) (xy 150.713552 -17.056609) (xy 150.762346 -17.120047) (xy 150.804457 -17.188104)
			(xy 150.839452 -17.26008) (xy 150.86697 -17.335233) (xy 150.886728 -17.412788) (xy 150.898521 -17.491946)
			(xy 150.902197 -17.571212) (xy 153.571448 -17.571212) (xy 153.571987 -17.526853) (xy 153.579718 -17.438472)
			(xy 153.595123 -17.351101) (xy 153.618083 -17.265406) (xy 153.648425 -17.182037) (xy 153.685918 -17.10163)
			(xy 153.730275 -17.024797) (xy 153.78116 -16.952122) (xy 153.838185 -16.884158) (xy 153.900917 -16.821423)
			(xy 153.968877 -16.764394) (xy 154.04155 -16.713505) (xy 154.118381 -16.669144) (xy 154.198785 -16.631647)
			(xy 154.282152 -16.6013) (xy 154.367847 -16.578335) (xy 154.455216 -16.562926) (xy 154.543597 -16.55519)
			(xy 154.587956 -16.554704) (xy 154.632054 -16.55518) (xy 154.719902 -16.563019) (xy 154.806706 -16.578631)
			(xy 154.89178 -16.601892) (xy 154.974452 -16.632618) (xy 155.054067 -16.670565) (xy 155.129997 -16.715436)
			(xy 155.201641 -16.766873) (xy 155.268432 -16.824471) (xy 155.329843 -16.887775) (xy 155.385389 -16.956283)
			(xy 155.410408 -16.9926) (xy 155.423487 -17.011253) (xy 155.455185 -17.043968) (xy 155.49221 -17.070505)
			(xy 155.533375 -17.090014) (xy 155.577358 -17.101868) (xy 155.622751 -17.105688) (xy 155.668096 -17.10135)
			(xy 155.711942 -17.088995) (xy 155.752881 -17.069019) (xy 155.789601 -17.042061) (xy 155.805632 -17.025874)
			(xy 155.833503 -16.997159) (xy 155.894213 -16.945015) (xy 155.959895 -16.899294) (xy 156.029875 -16.860467)
			(xy 156.10343 -16.828934) (xy 156.179802 -16.805021) (xy 156.258206 -16.788973) (xy 156.337832 -16.780955)
			(xy 156.417861 -16.781051) (xy 156.497468 -16.78926) (xy 156.575832 -16.805497) (xy 156.652147 -16.829594)
			(xy 156.725626 -16.861303) (xy 156.795512 -16.900298) (xy 156.861084 -16.946177) (xy 156.921668 -16.998467)
			(xy 156.976639 -17.05663) (xy 157.02543 -17.120065) (xy 157.067539 -17.18812) (xy 157.102532 -17.260093)
			(xy 157.130049 -17.335242) (xy 157.149805 -17.412794) (xy 157.161598 -17.49195) (xy 157.165306 -17.571893)
			(xy 157.16089 -17.6518) (xy 157.148396 -17.730848) (xy 157.127953 -17.808221) (xy 157.099772 -17.883124)
			(xy 157.064143 -17.954785) (xy 157.021432 -18.022464) (xy 156.972081 -18.085464) (xy 156.916597 -18.143137)
			(xy 156.855552 -18.194888) (xy 156.789576 -18.240184) (xy 156.719347 -18.278559) (xy 156.64559 -18.309616)
			(xy 156.569065 -18.333036) (xy 156.49056 -18.348578) (xy 156.410883 -18.356081) (xy 156.330857 -18.355468)
			(xy 156.251304 -18.346745) (xy 156.173046 -18.330003) (xy 156.096889 -18.305414) (xy 156.023616 -18.27323)
			(xy 155.953983 -18.233785) (xy 155.888708 -18.187484) (xy 155.828464 -18.134804) (xy 155.800806 -18.105882)
			(xy 155.784897 -18.089548) (xy 155.748372 -18.062264) (xy 155.707563 -18.041937) (xy 155.663781 -18.029221)
			(xy 155.618433 -18.024523) (xy 155.572975 -18.027995) (xy 155.528866 -18.039526) (xy 155.487523 -18.058743)
			(xy 155.450275 -18.085032) (xy 155.418317 -18.117547) (xy 155.405074 -18.136108) (xy 155.379011 -18.17354)
			(xy 155.321048 -18.243974) (xy 155.256933 -18.308859) (xy 155.187196 -18.367659) (xy 155.112412 -18.41989)
			(xy 155.033198 -18.46512) (xy 154.950206 -18.502977) (xy 154.864123 -18.533149) (xy 154.775657 -18.555386)
			(xy 154.685538 -18.569504) (xy 154.59451 -18.575389) (xy 154.503324 -18.57299) (xy 154.412731 -18.562328)
			(xy 154.323479 -18.543491) (xy 154.236304 -18.516634) (xy 154.151926 -18.481979) (xy 154.071039 -18.439811)
			(xy 153.994313 -18.390479) (xy 153.922378 -18.334389) (xy 153.855829 -18.272003) (xy 153.795214 -18.203837)
			(xy 153.741034 -18.130453) (xy 153.693735 -18.052456) (xy 153.653708 -17.970489) (xy 153.621282 -17.885229)
			(xy 153.596726 -17.797379) (xy 153.580241 -17.707663) (xy 153.571964 -17.616821) (xy 153.571448 -17.571212)
			(xy 150.902197 -17.571212) (xy 150.902229 -17.571893) (xy 150.897813 -17.651803) (xy 150.885319 -17.730854)
			(xy 150.864875 -17.808231) (xy 150.836692 -17.883137) (xy 150.801061 -17.9548) (xy 150.758348 -18.022482)
			(xy 150.708994 -18.085484) (xy 150.653508 -18.143159) (xy 150.59246 -18.194912) (xy 150.52648 -18.240209)
			(xy 150.456248 -18.278584) (xy 150.382488 -18.309642) (xy 150.305959 -18.333062) (xy 150.22745 -18.348603)
			(xy 150.14777 -18.356105) (xy 150.06774 -18.35549) (xy 149.988185 -18.346766) (xy 149.909924 -18.330021)
			(xy 149.833764 -18.305429) (xy 149.760489 -18.273243) (xy 149.690854 -18.233794) (xy 149.625578 -18.187489)
			(xy 149.565332 -18.134806) (xy 149.537674 -18.105882) (xy 149.521799 -18.089514) (xy 149.485267 -18.06223)
			(xy 149.444453 -18.041905) (xy 149.400666 -18.029191) (xy 149.355313 -18.024497) (xy 149.309851 -18.027973)
			(xy 149.265739 -18.039507) (xy 149.224394 -18.05873) (xy 149.187143 -18.085024) (xy 149.155185 -18.117544)
			(xy 149.141942 -18.136108) (xy 149.115926 -18.173573) (xy 149.05796 -18.244008) (xy 148.993843 -18.308893)
			(xy 148.924103 -18.367694) (xy 148.849317 -18.419925) (xy 148.770099 -18.465156) (xy 148.687106 -18.503012)
			(xy 148.601019 -18.533183) (xy 148.512551 -18.555419) (xy 148.42243 -18.569538) (xy 148.331399 -18.575421)
			(xy 148.240211 -18.573021) (xy 148.149616 -18.562358) (xy 148.060362 -18.54352) (xy 147.973185 -18.516661)
			(xy 147.888805 -18.482005) (xy 147.807917 -18.439835) (xy 147.731188 -18.390501) (xy 147.659252 -18.334409)
			(xy 147.592702 -18.272022) (xy 147.532086 -18.203854) (xy 147.477905 -18.130468) (xy 147.430605 -18.052468)
			(xy 147.390577 -17.970499) (xy 147.358151 -17.885237) (xy 147.333594 -17.797384) (xy 147.317109 -17.707666)
			(xy 147.308832 -17.616822) (xy 147.308316 -17.571212) (xy 128.74244 -17.571212) (xy 128.74244 -18.305526)
			(xy 129.950462 -18.305526) (xy 129.954533 -18.249904) (xy 129.966659 -18.195467) (xy 129.986582 -18.143376)
			(xy 130.013878 -18.094741) (xy 130.047964 -18.050598) (xy 130.088113 -18.011889) (xy 130.133471 -17.979438)
			(xy 130.183071 -17.953937) (xy 130.235855 -17.93593) (xy 130.290698 -17.9258) (xy 130.346432 -17.923763)
			(xy 130.401869 -17.929863) (xy 130.455826 -17.943969) (xy 130.507155 -17.965781) (xy 130.554761 -17.994835)
			(xy 130.597629 -18.03051) (xy 130.634846 -18.072047) (xy 130.665619 -18.11856) (xy 130.689291 -18.169057)
			(xy 130.705359 -18.222464) (xy 130.713479 -18.27764) (xy 130.713988 -18.305526) (xy 130.713479 -18.333412)
			(xy 130.705359 -18.388588) (xy 130.689291 -18.441995) (xy 130.665619 -18.492492) (xy 130.634846 -18.539005)
			(xy 130.597629 -18.580542) (xy 130.554761 -18.616217) (xy 130.507155 -18.645271) (xy 130.455826 -18.667083)
			(xy 130.401869 -18.681189) (xy 130.346432 -18.687289) (xy 130.290698 -18.685252) (xy 130.235855 -18.675122)
			(xy 130.183071 -18.657115) (xy 130.133471 -18.631614) (xy 130.088113 -18.599163) (xy 130.047964 -18.560454)
			(xy 130.013878 -18.516311) (xy 129.986582 -18.467676) (xy 129.966659 -18.415585) (xy 129.954533 -18.361148)
			(xy 129.950462 -18.305526) (xy 128.74244 -18.305526) (xy 128.74244 -20.799806) (xy 137.82727 -20.799806)
			(xy 137.831236 -20.715275) (xy 137.843101 -20.631488) (xy 137.862759 -20.549179) (xy 137.890039 -20.469073)
			(xy 137.9247 -20.391874) (xy 137.966438 -20.318259) (xy 138.014885 -20.248876) (xy 138.069617 -20.184335)
			(xy 138.130153 -20.125203) (xy 138.195959 -20.071999) (xy 138.266459 -20.025191) (xy 138.341031 -19.98519)
			(xy 138.419022 -19.952348) (xy 138.499746 -19.926954) (xy 138.582493 -19.909231) (xy 138.666535 -19.899333)
			(xy 138.751136 -19.89735) (xy 138.83555 -19.903297) (xy 138.919037 -19.917122) (xy 139.000862 -19.938705)
			(xy 139.080306 -19.967855) (xy 139.156672 -20.004316) (xy 139.229288 -20.047768) (xy 139.297516 -20.097829)
			(xy 139.360756 -20.154059) (xy 139.418453 -20.215964) (xy 139.4701 -20.283) (xy 139.515242 -20.354577)
			(xy 139.553484 -20.430067) (xy 139.584488 -20.508806) (xy 139.607983 -20.590103) (xy 139.623762 -20.673242)
			(xy 139.631686 -20.757494) (xy 139.632182 -20.799806) (xy 139.631686 -20.842118) (xy 139.623762 -20.92637)
			(xy 139.607983 -21.009509) (xy 139.584488 -21.090806) (xy 139.553484 -21.169545) (xy 139.515242 -21.245035)
			(xy 139.4701 -21.316612) (xy 139.418453 -21.383648) (xy 139.360756 -21.445553) (xy 139.297516 -21.501783)
			(xy 139.229288 -21.551844) (xy 139.156672 -21.595296) (xy 139.080306 -21.631757) (xy 139.000862 -21.660907)
			(xy 138.919037 -21.68249) (xy 138.83555 -21.696315) (xy 138.751136 -21.702262) (xy 138.666535 -21.700279)
			(xy 138.582493 -21.690381) (xy 138.499746 -21.672658) (xy 138.419022 -21.647264) (xy 138.341031 -21.614422)
			(xy 138.266459 -21.574421) (xy 138.195959 -21.527613) (xy 138.130153 -21.474409) (xy 138.069617 -21.415277)
			(xy 138.014885 -21.350736) (xy 137.966438 -21.281353) (xy 137.9247 -21.207738) (xy 137.890039 -21.130539)
			(xy 137.862759 -21.050433) (xy 137.843101 -20.968124) (xy 137.831236 -20.884337) (xy 137.82727 -20.799806)
			(xy 128.74244 -20.799806) (xy 128.74244 -24.677116) (xy 139.687298 -24.677116) (xy 139.691369 -24.621494)
			(xy 139.703495 -24.567057) (xy 139.723418 -24.514966) (xy 139.750714 -24.466331) (xy 139.7848 -24.422188)
			(xy 139.824949 -24.383479) (xy 139.870307 -24.351028) (xy 139.919907 -24.325527) (xy 139.972691 -24.30752)
			(xy 140.027534 -24.29739) (xy 140.083268 -24.295353) (xy 140.138705 -24.301453) (xy 140.192662 -24.315559)
			(xy 140.243991 -24.337371) (xy 140.291597 -24.366425) (xy 140.334465 -24.4021) (xy 140.371682 -24.443637)
			(xy 140.402455 -24.49015) (xy 140.426127 -24.540647) (xy 140.442195 -24.594054) (xy 140.450315 -24.64923)
			(xy 140.450824 -24.677116) (xy 140.450315 -24.705002) (xy 140.44926 -24.712168) (xy 140.826234 -24.712168)
			(xy 140.830305 -24.656546) (xy 140.842431 -24.602109) (xy 140.862354 -24.550018) (xy 140.88965 -24.501383)
			(xy 140.923736 -24.45724) (xy 140.963885 -24.418531) (xy 141.009243 -24.38608) (xy 141.058843 -24.360579)
			(xy 141.111627 -24.342572) (xy 141.16647 -24.332442) (xy 141.222204 -24.330405) (xy 141.277641 -24.336505)
			(xy 141.331598 -24.350611) (xy 141.382927 -24.372423) (xy 141.430533 -24.401477) (xy 141.473401 -24.437152)
			(xy 141.510618 -24.478689) (xy 141.541391 -24.525202) (xy 141.565063 -24.575699) (xy 141.581131 -24.629106)
			(xy 141.589251 -24.684282) (xy 141.58931 -24.68753) (xy 142.096234 -24.68753) (xy 142.100305 -24.631908)
			(xy 142.112431 -24.577471) (xy 142.132354 -24.52538) (xy 142.15965 -24.476745) (xy 142.193736 -24.432602)
			(xy 142.233885 -24.393893) (xy 142.279243 -24.361442) (xy 142.328843 -24.335941) (xy 142.381627 -24.317934)
			(xy 142.43647 -24.307804) (xy 142.492204 -24.305767) (xy 142.547641 -24.311867) (xy 142.601598 -24.325973)
			(xy 142.652927 -24.347785) (xy 142.700533 -24.376839) (xy 142.743401 -24.412514) (xy 142.780618 -24.454051)
			(xy 142.811391 -24.500564) (xy 142.835063 -24.551061) (xy 142.851131 -24.604468) (xy 142.859251 -24.659644)
			(xy 142.85976 -24.68753) (xy 142.859251 -24.715416) (xy 142.851131 -24.770592) (xy 142.835063 -24.823999)
			(xy 142.811391 -24.874496) (xy 142.780618 -24.921009) (xy 142.743401 -24.962546) (xy 142.700533 -24.998221)
			(xy 142.652927 -25.027275) (xy 142.601598 -25.049087) (xy 142.547641 -25.063193) (xy 142.492204 -25.069293)
			(xy 142.43647 -25.067256) (xy 142.381627 -25.057126) (xy 142.328843 -25.039119) (xy 142.279243 -25.013618)
			(xy 142.233885 -24.981167) (xy 142.193736 -24.942458) (xy 142.15965 -24.898315) (xy 142.132354 -24.84968)
			(xy 142.112431 -24.797589) (xy 142.100305 -24.743152) (xy 142.096234 -24.68753) (xy 141.58931 -24.68753)
			(xy 141.58976 -24.712168) (xy 141.589251 -24.740054) (xy 141.581131 -24.79523) (xy 141.565063 -24.848637)
			(xy 141.541391 -24.899134) (xy 141.510618 -24.945647) (xy 141.473401 -24.987184) (xy 141.430533 -25.022859)
			(xy 141.382927 -25.051913) (xy 141.331598 -25.073725) (xy 141.277641 -25.087831) (xy 141.222204 -25.093931)
			(xy 141.16647 -25.091894) (xy 141.111627 -25.081764) (xy 141.058843 -25.063757) (xy 141.009243 -25.038256)
			(xy 140.963885 -25.005805) (xy 140.923736 -24.967096) (xy 140.88965 -24.922953) (xy 140.862354 -24.874318)
			(xy 140.842431 -24.822227) (xy 140.830305 -24.76779) (xy 140.826234 -24.712168) (xy 140.44926 -24.712168)
			(xy 140.442195 -24.760178) (xy 140.426127 -24.813585) (xy 140.402455 -24.864082) (xy 140.371682 -24.910595)
			(xy 140.334465 -24.952132) (xy 140.291597 -24.987807) (xy 140.243991 -25.016861) (xy 140.192662 -25.038673)
			(xy 140.138705 -25.052779) (xy 140.083268 -25.058879) (xy 140.027534 -25.056842) (xy 139.972691 -25.046712)
			(xy 139.919907 -25.028705) (xy 139.870307 -25.003204) (xy 139.824949 -24.970753) (xy 139.7848 -24.932044)
			(xy 139.750714 -24.887901) (xy 139.723418 -24.839266) (xy 139.703495 -24.787175) (xy 139.691369 -24.732738)
			(xy 139.687298 -24.677116) (xy 128.74244 -24.677116) (xy 128.74244 -24.822912) (xy 128.742974 -24.846296)
			(xy 128.751534 -24.892274) (xy 128.768362 -24.935909) (xy 128.792891 -24.975729) (xy 128.824293 -25.010387)
			(xy 128.861506 -25.038714) (xy 128.903274 -25.059754) (xy 128.948187 -25.072796) (xy 128.994728 -25.077399)
			(xy 129.041325 -25.073407) (xy 129.086406 -25.060957) (xy 129.107692 -25.051258) (xy 129.132715 -25.039628)
			(xy 129.185293 -25.022891) (xy 129.239734 -25.013902) (xy 129.294902 -25.012847) (xy 129.349646 -25.01975)
			(xy 129.402826 -25.034466) (xy 129.453331 -25.056687) (xy 129.500109 -25.085952) (xy 129.542184 -25.121649)
			(xy 129.578679 -25.163034) (xy 129.608833 -25.209244) (xy 129.632017 -25.259315) (xy 129.647746 -25.312203)
			(xy 129.655695 -25.366806) (xy 129.655695 -25.421984) (xy 129.647749 -25.476586) (xy 129.643842 -25.489725)
			(xy 129.90915 -25.489725) (xy 129.916036 -25.434093) (xy 129.930992 -25.380068) (xy 129.953695 -25.328814)
			(xy 129.983656 -25.281435) (xy 130.020229 -25.238952) (xy 130.062628 -25.202281) (xy 130.109937 -25.172211)
			(xy 130.161139 -25.14939) (xy 130.215129 -25.134309) (xy 130.270746 -25.127295) (xy 130.32679 -25.128497)
			(xy 130.382054 -25.13789) (xy 130.435349 -25.155271) (xy 130.485524 -25.180266) (xy 130.531501 -25.212337)
			(xy 130.572288 -25.250793) (xy 130.590036 -25.272492) (xy 130.605053 -25.29065) (xy 130.640553 -25.321627)
			(xy 130.681153 -25.345533) (xy 130.725462 -25.36155) (xy 130.771963 -25.36913) (xy 130.819065 -25.368012)
			(xy 130.865154 -25.358236) (xy 130.908653 -25.340136) (xy 130.948073 -25.314331) (xy 130.982065 -25.281706)
			(xy 130.996182 -25.26284) (xy 131.012802 -25.240335) (xy 131.051614 -25.200042) (xy 131.095895 -25.165851)
			(xy 131.144695 -25.138493) (xy 131.196968 -25.118556) (xy 131.251592 -25.106468) (xy 131.307396 -25.102488)
			(xy 131.363182 -25.106701) (xy 131.417756 -25.119016) (xy 131.469945 -25.13917) (xy 131.51863 -25.166731)
			(xy 131.562769 -25.201107) (xy 131.601413 -25.241561) (xy 131.617974 -25.26411) (xy 131.631992 -25.283033)
			(xy 131.665853 -25.315757) (xy 131.70516 -25.341686) (xy 131.748571 -25.359933) (xy 131.794599 -25.369873)
			(xy 131.841671 -25.371167) (xy 131.888176 -25.36377) (xy 131.932523 -25.347935) (xy 131.973196 -25.324204)
			(xy 132.008803 -25.293389) (xy 132.023866 -25.275286) (xy 132.04168 -25.253615) (xy 132.082636 -25.215281)
			(xy 132.128763 -25.183355) (xy 132.179067 -25.158526) (xy 132.232463 -25.141329) (xy 132.287802 -25.132134)
			(xy 132.343891 -25.13114) (xy 132.399521 -25.138368) (xy 132.453494 -25.153662) (xy 132.504646 -25.176693)
			(xy 132.551875 -25.206965) (xy 132.586548 -25.237186) (xy 132.956552 -25.237186) (xy 132.960623 -25.181564)
			(xy 132.972749 -25.127127) (xy 132.992672 -25.075036) (xy 133.019968 -25.026401) (xy 133.054054 -24.982258)
			(xy 133.094203 -24.943549) (xy 133.139561 -24.911098) (xy 133.189161 -24.885597) (xy 133.241945 -24.86759)
			(xy 133.296788 -24.85746) (xy 133.352522 -24.855423) (xy 133.407959 -24.861523) (xy 133.461916 -24.875629)
			(xy 133.513245 -24.897441) (xy 133.560851 -24.926495) (xy 133.603719 -24.96217) (xy 133.640936 -25.003707)
			(xy 133.671709 -25.05022) (xy 133.695381 -25.100717) (xy 133.711449 -25.154124) (xy 133.719569 -25.2093)
			(xy 133.720078 -25.237186) (xy 133.719569 -25.265072) (xy 133.711449 -25.320248) (xy 133.70419 -25.344374)
			(xy 133.972552 -25.344374) (xy 133.976623 -25.288752) (xy 133.988749 -25.234315) (xy 134.008672 -25.182224)
			(xy 134.035968 -25.133589) (xy 134.070054 -25.089446) (xy 134.110203 -25.050737) (xy 134.155561 -25.018286)
			(xy 134.205161 -24.992785) (xy 134.257945 -24.974778) (xy 134.312788 -24.964648) (xy 134.368522 -24.962611)
			(xy 134.423959 -24.968711) (xy 134.477916 -24.982817) (xy 134.529245 -25.004629) (xy 134.576851 -25.033683)
			(xy 134.619719 -25.069358) (xy 134.656936 -25.110895) (xy 134.687709 -25.157408) (xy 134.711381 -25.207905)
			(xy 134.727449 -25.261312) (xy 134.735569 -25.316488) (xy 134.736078 -25.344374) (xy 134.735569 -25.37226)
			(xy 134.727449 -25.427436) (xy 134.711381 -25.480843) (xy 134.687709 -25.53134) (xy 134.673104 -25.553416)
			(xy 134.988552 -25.553416) (xy 134.992623 -25.497794) (xy 135.004749 -25.443357) (xy 135.024672 -25.391266)
			(xy 135.051968 -25.342631) (xy 135.086054 -25.298488) (xy 135.126203 -25.259779) (xy 135.171561 -25.227328)
			(xy 135.221161 -25.201827) (xy 135.273945 -25.18382) (xy 135.328788 -25.17369) (xy 135.384522 -25.171653)
			(xy 135.439959 -25.177753) (xy 135.493916 -25.191859) (xy 135.545245 -25.213671) (xy 135.592851 -25.242725)
			(xy 135.635719 -25.2784) (xy 135.672936 -25.319937) (xy 135.703709 -25.36645) (xy 135.727381 -25.416947)
			(xy 135.741922 -25.465278) (xy 136.004552 -25.465278) (xy 136.008623 -25.409656) (xy 136.020749 -25.355219)
			(xy 136.040672 -25.303128) (xy 136.067968 -25.254493) (xy 136.102054 -25.21035) (xy 136.142203 -25.171641)
			(xy 136.187561 -25.13919) (xy 136.237161 -25.113689) (xy 136.289945 -25.095682) (xy 136.344788 -25.085552)
			(xy 136.400522 -25.083515) (xy 136.455959 -25.089615) (xy 136.509916 -25.103721) (xy 136.561245 -25.125533)
			(xy 136.608851 -25.154587) (xy 136.651719 -25.190262) (xy 136.688936 -25.231799) (xy 136.719709 -25.278312)
			(xy 136.743381 -25.328809) (xy 136.759449 -25.382216) (xy 136.767569 -25.437392) (xy 136.768078 -25.465278)
			(xy 136.767569 -25.493164) (xy 136.759449 -25.54834) (xy 136.743381 -25.601747) (xy 136.719709 -25.652244)
			(xy 136.688936 -25.698757) (xy 136.651719 -25.740294) (xy 136.608851 -25.775969) (xy 136.561245 -25.805023)
			(xy 136.509916 -25.826835) (xy 136.455959 -25.840941) (xy 136.400522 -25.847041) (xy 136.344788 -25.845004)
			(xy 136.289945 -25.834874) (xy 136.237161 -25.816867) (xy 136.187561 -25.791366) (xy 136.142203 -25.758915)
			(xy 136.102054 -25.720206) (xy 136.067968 -25.676063) (xy 136.040672 -25.627428) (xy 136.020749 -25.575337)
			(xy 136.008623 -25.5209) (xy 136.004552 -25.465278) (xy 135.741922 -25.465278) (xy 135.743449 -25.470354)
			(xy 135.751569 -25.52553) (xy 135.752078 -25.553416) (xy 135.751569 -25.581302) (xy 135.743449 -25.636478)
			(xy 135.727381 -25.689885) (xy 135.703709 -25.740382) (xy 135.672936 -25.786895) (xy 135.635719 -25.828432)
			(xy 135.592851 -25.864107) (xy 135.545245 -25.893161) (xy 135.493916 -25.914973) (xy 135.439959 -25.929079)
			(xy 135.384522 -25.935179) (xy 135.328788 -25.933142) (xy 135.273945 -25.923012) (xy 135.221161 -25.905005)
			(xy 135.171561 -25.879504) (xy 135.126203 -25.847053) (xy 135.086054 -25.808344) (xy 135.051968 -25.764201)
			(xy 135.024672 -25.715566) (xy 135.004749 -25.663475) (xy 134.992623 -25.609038) (xy 134.988552 -25.553416)
			(xy 134.673104 -25.553416) (xy 134.656936 -25.577853) (xy 134.619719 -25.61939) (xy 134.576851 -25.655065)
			(xy 134.529245 -25.684119) (xy 134.477916 -25.705931) (xy 134.423959 -25.720037) (xy 134.368522 -25.726137)
			(xy 134.312788 -25.7241) (xy 134.257945 -25.71397) (xy 134.205161 -25.695963) (xy 134.155561 -25.670462)
			(xy 134.110203 -25.638011) (xy 134.070054 -25.599302) (xy 134.035968 -25.555159) (xy 134.008672 -25.506524)
			(xy 133.988749 -25.454433) (xy 133.976623 -25.399996) (xy 133.972552 -25.344374) (xy 133.70419 -25.344374)
			(xy 133.695381 -25.373655) (xy 133.671709 -25.424152) (xy 133.640936 -25.470665) (xy 133.603719 -25.512202)
			(xy 133.560851 -25.547877) (xy 133.513245 -25.576931) (xy 133.461916 -25.598743) (xy 133.407959 -25.612849)
			(xy 133.352522 -25.618949) (xy 133.296788 -25.616912) (xy 133.241945 -25.606782) (xy 133.189161 -25.588775)
			(xy 133.139561 -25.563274) (xy 133.094203 -25.530823) (xy 133.054054 -25.492114) (xy 133.019968 -25.447971)
			(xy 132.992672 -25.399336) (xy 132.972749 -25.347245) (xy 132.960623 -25.292808) (xy 132.956552 -25.237186)
			(xy 132.586548 -25.237186) (xy 132.594164 -25.243824) (xy 132.630601 -25.286477) (xy 132.660401 -25.334005)
			(xy 132.682922 -25.385384) (xy 132.697678 -25.439506) (xy 132.704353 -25.495205) (xy 132.702801 -25.551281)
			(xy 132.693056 -25.606526) (xy 132.675329 -25.659749) (xy 132.650001 -25.709804) (xy 132.617618 -25.755611)
			(xy 132.578878 -25.796183) (xy 132.534615 -25.830648) (xy 132.485784 -25.858261) (xy 132.433437 -25.878427)
			(xy 132.378701 -25.890713) (xy 132.322756 -25.894853) (xy 132.266808 -25.890759) (xy 132.212062 -25.878518)
			(xy 132.159698 -25.858394) (xy 132.110845 -25.830821) (xy 132.066554 -25.796393) (xy 132.027781 -25.755852)
			(xy 132.011166 -25.733248) (xy 131.997099 -25.714365) (xy 131.963244 -25.681646) (xy 131.923943 -25.655721)
			(xy 131.88054 -25.637476) (xy 131.83452 -25.627535) (xy 131.787456 -25.626237) (xy 131.740958 -25.633627)
			(xy 131.696616 -25.649453) (xy 131.655946 -25.673172) (xy 131.620339 -25.703975) (xy 131.605274 -25.722072)
			(xy 131.58703 -25.744175) (xy 131.545026 -25.783165) (xy 131.497665 -25.815438) (xy 131.446012 -25.840267)
			(xy 131.391227 -25.857094) (xy 131.334542 -25.865541) (xy 131.277231 -25.865419) (xy 131.220582 -25.856729)
			(xy 131.165869 -25.839668) (xy 131.114322 -25.814619) (xy 131.0671 -25.782145) (xy 131.025263 -25.742975)
			(xy 131.007104 -25.720802) (xy 130.992156 -25.702584) (xy 130.956645 -25.671607) (xy 130.916034 -25.647703)
			(xy 130.871715 -25.63169) (xy 130.825204 -25.624116) (xy 130.778094 -25.62524) (xy 130.731998 -25.635024)
			(xy 130.688493 -25.653134) (xy 130.649069 -25.678948) (xy 130.615076 -25.711583) (xy 130.600958 -25.730454)
			(xy 130.584217 -25.75294) (xy 130.545302 -25.793289) (xy 130.5009 -25.827507) (xy 130.451968 -25.854857)
			(xy 130.399559 -25.874749) (xy 130.344803 -25.886756) (xy 130.288879 -25.890618) (xy 130.232992 -25.886252)
			(xy 130.178346 -25.873752) (xy 130.126119 -25.853388) (xy 130.077435 -25.825599) (xy 130.033343 -25.790982)
			(xy 129.994794 -25.750284) (xy 129.962617 -25.704381) (xy 129.937506 -25.654263) (xy 129.920002 -25.601009)
			(xy 129.910481 -25.545766) (xy 129.90915 -25.489725) (xy 129.643842 -25.489725) (xy 129.63202 -25.529475)
			(xy 129.608838 -25.579547) (xy 129.578686 -25.625758) (xy 129.542192 -25.667144) (xy 129.500118 -25.702842)
			(xy 129.45334 -25.732108) (xy 129.402835 -25.754331) (xy 129.349656 -25.769048) (xy 129.294912 -25.775952)
			(xy 129.239744 -25.774899) (xy 129.185303 -25.765911) (xy 129.132724 -25.749176) (xy 129.107692 -25.737566)
			(xy 129.086433 -25.727797) (xy 129.04134 -25.715342) (xy 128.99473 -25.711349) (xy 128.948177 -25.715953)
			(xy 128.903251 -25.728998) (xy 128.861472 -25.750045) (xy 128.82425 -25.778381) (xy 128.792842 -25.81305)
			(xy 128.768308 -25.852882) (xy 128.751478 -25.89653) (xy 128.742919 -25.942522) (xy 128.74244 -25.965912)
			(xy 128.74244 -26.193242) (xy 144.285968 -26.193242) (xy 144.290039 -26.13762) (xy 144.302165 -26.083183)
			(xy 144.322088 -26.031092) (xy 144.349384 -25.982457) (xy 144.38347 -25.938314) (xy 144.423619 -25.899605)
			(xy 144.468977 -25.867154) (xy 144.518577 -25.841653) (xy 144.571361 -25.823646) (xy 144.626204 -25.813516)
			(xy 144.681938 -25.811479) (xy 144.737375 -25.817579) (xy 144.791332 -25.831685) (xy 144.842661 -25.853497)
			(xy 144.890267 -25.882551) (xy 144.933135 -25.918226) (xy 144.970352 -25.959763) (xy 145.001125 -26.006276)
			(xy 145.024797 -26.056773) (xy 145.040865 -26.11018) (xy 145.048985 -26.165356) (xy 145.049494 -26.193242)
			(xy 146.668234 -26.193242) (xy 146.672305 -26.13762) (xy 146.684431 -26.083183) (xy 146.704354 -26.031092)
			(xy 146.73165 -25.982457) (xy 146.765736 -25.938314) (xy 146.805885 -25.899605) (xy 146.851243 -25.867154)
			(xy 146.900843 -25.841653) (xy 146.953627 -25.823646) (xy 147.00847 -25.813516) (xy 147.064204 -25.811479)
			(xy 147.119641 -25.817579) (xy 147.173598 -25.831685) (xy 147.224927 -25.853497) (xy 147.272533 -25.882551)
			(xy 147.315401 -25.918226) (xy 147.352618 -25.959763) (xy 147.383391 -26.006276) (xy 147.407063 -26.056773)
			(xy 147.423131 -26.11018) (xy 147.431251 -26.165356) (xy 147.43176 -26.193242) (xy 147.431251 -26.221128)
			(xy 147.423131 -26.276304) (xy 147.407063 -26.329711) (xy 147.383391 -26.380208) (xy 147.352618 -26.426721)
			(xy 147.315401 -26.468258) (xy 147.272533 -26.503933) (xy 147.224927 -26.532987) (xy 147.173598 -26.554799)
			(xy 147.119641 -26.568905) (xy 147.064204 -26.575005) (xy 147.00847 -26.572968) (xy 146.953627 -26.562838)
			(xy 146.900843 -26.544831) (xy 146.851243 -26.51933) (xy 146.805885 -26.486879) (xy 146.765736 -26.44817)
			(xy 146.73165 -26.404027) (xy 146.704354 -26.355392) (xy 146.684431 -26.303301) (xy 146.672305 -26.248864)
			(xy 146.668234 -26.193242) (xy 145.049494 -26.193242) (xy 145.048985 -26.221128) (xy 145.040865 -26.276304)
			(xy 145.024797 -26.329711) (xy 145.001125 -26.380208) (xy 144.970352 -26.426721) (xy 144.933135 -26.468258)
			(xy 144.890267 -26.503933) (xy 144.842661 -26.532987) (xy 144.791332 -26.554799) (xy 144.737375 -26.568905)
			(xy 144.681938 -26.575005) (xy 144.626204 -26.572968) (xy 144.571361 -26.562838) (xy 144.518577 -26.544831)
			(xy 144.468977 -26.51933) (xy 144.423619 -26.486879) (xy 144.38347 -26.44817) (xy 144.349384 -26.404027)
			(xy 144.322088 -26.355392) (xy 144.302165 -26.303301) (xy 144.290039 -26.248864) (xy 144.285968 -26.193242)
			(xy 128.74244 -26.193242) (xy 128.74244 -26.384758) (xy 129.66192 -27.304238) (xy 129.677365 -27.319083)
			(xy 129.712283 -27.343892) (xy 129.750871 -27.362489) (xy 129.792032 -27.374346) (xy 129.834599 -27.379127)
			(xy 129.877365 -27.376696) (xy 129.919116 -27.367122) (xy 129.958669 -27.350677) (xy 129.9949 -27.327827)
			(xy 130.01117 -27.31389) (xy 130.031927 -27.295249) (xy 130.077879 -27.263612) (xy 130.127948 -27.239003)
			(xy 130.181067 -27.221948) (xy 130.236103 -27.21281) (xy 130.291883 -27.211785) (xy 130.347218 -27.218893)
			(xy 130.400928 -27.233983) (xy 130.451868 -27.256734) (xy 130.498952 -27.28666) (xy 130.541176 -27.323124)
			(xy 130.57764 -27.365348) (xy 130.607566 -27.412432) (xy 130.630317 -27.463372) (xy 130.645407 -27.517082)
			(xy 130.652195 -27.569922) (xy 131.602732 -27.569922) (xy 131.606803 -27.5143) (xy 131.618929 -27.459863)
			(xy 131.638852 -27.407772) (xy 131.666148 -27.359137) (xy 131.700234 -27.314994) (xy 131.740383 -27.276285)
			(xy 131.785741 -27.243834) (xy 131.835341 -27.218333) (xy 131.888125 -27.200326) (xy 131.942968 -27.190196)
			(xy 131.998702 -27.188159) (xy 132.054139 -27.194259) (xy 132.108096 -27.208365) (xy 132.159425 -27.230177)
			(xy 132.207031 -27.259231) (xy 132.249899 -27.294906) (xy 132.287116 -27.336443) (xy 132.317889 -27.382956)
			(xy 132.341561 -27.433453) (xy 132.357629 -27.48686) (xy 132.361293 -27.511756) (xy 133.434072 -27.511756)
			(xy 133.438143 -27.456134) (xy 133.450269 -27.401697) (xy 133.470192 -27.349606) (xy 133.497488 -27.300971)
			(xy 133.531574 -27.256828) (xy 133.571723 -27.218119) (xy 133.617081 -27.185668) (xy 133.666681 -27.160167)
			(xy 133.719465 -27.14216) (xy 133.774308 -27.13203) (xy 133.830042 -27.129993) (xy 133.885479 -27.136093)
			(xy 133.939436 -27.150199) (xy 133.990765 -27.172011) (xy 134.038371 -27.201065) (xy 134.081239 -27.23674)
			(xy 134.118456 -27.278277) (xy 134.149229 -27.32479) (xy 134.172901 -27.375287) (xy 134.188969 -27.428694)
			(xy 134.197089 -27.48387) (xy 134.197598 -27.511756) (xy 134.197089 -27.539642) (xy 134.188969 -27.594818)
			(xy 134.18683 -27.601926) (xy 134.988552 -27.601926) (xy 134.992623 -27.546304) (xy 135.004749 -27.491867)
			(xy 135.024672 -27.439776) (xy 135.051968 -27.391141) (xy 135.086054 -27.346998) (xy 135.126203 -27.308289)
			(xy 135.171561 -27.275838) (xy 135.221161 -27.250337) (xy 135.273945 -27.23233) (xy 135.328788 -27.2222)
			(xy 135.384522 -27.220163) (xy 135.439959 -27.226263) (xy 135.493916 -27.240369) (xy 135.545245 -27.262181)
			(xy 135.592851 -27.291235) (xy 135.635719 -27.32691) (xy 135.672936 -27.368447) (xy 135.703709 -27.41496)
			(xy 135.727381 -27.465457) (xy 135.743449 -27.518864) (xy 135.751569 -27.57404) (xy 135.752078 -27.601926)
			(xy 135.75175 -27.619913) (xy 136.653625 -27.619913) (xy 136.6577 -27.564849) (xy 136.669672 -27.510947)
			(xy 136.68929 -27.459334) (xy 136.716144 -27.411089) (xy 136.749673 -27.36722) (xy 136.789176 -27.328643)
			(xy 136.833829 -27.296164) (xy 136.882698 -27.270463) (xy 136.934761 -27.252075) (xy 136.988932 -27.241386)
			(xy 137.044078 -27.238619) (xy 137.071608 -27.240738) (xy 137.094619 -27.242517) (xy 137.1406 -27.238531)
			(xy 137.185106 -27.226313) (xy 137.226677 -27.206265) (xy 137.263948 -27.179045) (xy 137.295696 -27.145546)
			(xy 137.320877 -27.106868) (xy 137.338666 -27.064281) (xy 137.348478 -27.019183) (xy 137.349738 -26.996136)
			(xy 137.351172 -26.968563) (xy 137.360913 -26.91422) (xy 137.378387 -26.861848) (xy 137.403229 -26.812543)
			(xy 137.43492 -26.767335) (xy 137.472798 -26.727168) (xy 137.516071 -26.692882) (xy 137.563836 -26.665193)
			(xy 137.615093 -26.64468) (xy 137.668772 -26.631772) (xy 137.723752 -26.626737) (xy 137.778883 -26.629682)
			(xy 137.833014 -26.640544) (xy 137.885012 -26.659097) (xy 137.933793 -26.684954) (xy 137.978336 -26.717573)
			(xy 138.017711 -26.756273) (xy 138.051095 -26.800246) (xy 138.07779 -26.848573) (xy 138.097239 -26.900244)
			(xy 138.109035 -26.954178) (xy 138.112931 -27.00925) (xy 138.108847 -27.064309) (xy 138.096868 -27.118203)
			(xy 138.077243 -27.169807) (xy 138.050383 -27.218043) (xy 138.01685 -27.261902) (xy 137.977344 -27.300468)
			(xy 137.93269 -27.332935) (xy 137.883821 -27.358625) (xy 137.831759 -27.377001) (xy 137.777592 -27.387679)
			(xy 137.722451 -27.390436) (xy 137.694924 -27.388312) (xy 137.671909 -27.386614) (xy 137.625936 -27.390594)
			(xy 137.581436 -27.402804) (xy 137.53987 -27.422842) (xy 137.502601 -27.450052) (xy 137.470854 -27.48354)
			(xy 137.445671 -27.522207) (xy 137.427877 -27.564783) (xy 137.418058 -27.609871) (xy 137.416794 -27.632914)
			(xy 137.415476 -27.660493) (xy 137.405741 -27.714844) (xy 137.388272 -27.767222) (xy 137.363434 -27.816536)
			(xy 137.331746 -27.861753) (xy 137.29387 -27.901928) (xy 137.250597 -27.936224) (xy 137.202831 -27.963922)
			(xy 137.151572 -27.984445) (xy 137.13307 -27.988897) (xy 138.379902 -27.988897) (xy 138.383991 -27.933261)
			(xy 138.396142 -27.878814) (xy 138.416096 -27.826719) (xy 138.443427 -27.778086) (xy 138.477551 -27.733953)
			(xy 138.51774 -27.695263) (xy 138.563137 -27.662841) (xy 138.587734 -27.649678) (xy 138.608632 -27.638316)
			(xy 138.646161 -27.609097) (xy 138.677603 -27.573411) (xy 138.701863 -27.532501) (xy 138.718095 -27.487795)
			(xy 138.725732 -27.44085) (xy 138.724509 -27.393304) (xy 138.714468 -27.346814) (xy 138.695959 -27.303002)
			(xy 138.683238 -27.282902) (xy 138.668196 -27.259402) (xy 138.644414 -27.208928) (xy 138.628239 -27.155528)
			(xy 138.620017 -27.100342) (xy 138.619923 -27.044546) (xy 138.627959 -26.989332) (xy 138.643953 -26.935878)
			(xy 138.667564 -26.885324) (xy 138.698288 -26.83875) (xy 138.73547 -26.797149) (xy 138.778316 -26.761409)
			(xy 138.825913 -26.732292) (xy 138.877243 -26.71042) (xy 138.931212 -26.696261) (xy 138.986668 -26.690115)
			(xy 139.042428 -26.692114) (xy 139.097302 -26.702215) (xy 139.150118 -26.720203) (xy 139.19975 -26.745694)
			(xy 139.245139 -26.778145) (xy 139.285316 -26.816861) (xy 139.319424 -26.861018) (xy 139.346734 -26.909673)
			(xy 139.366664 -26.961788) (xy 139.37879 -27.01625) (xy 139.382851 -27.071898) (xy 139.378761 -27.127544)
			(xy 139.366608 -27.182) (xy 139.346651 -27.234104) (xy 139.319316 -27.282745) (xy 139.285185 -27.326884)
			(xy 139.244989 -27.365581) (xy 139.199583 -27.398007) (xy 139.174982 -27.411172) (xy 139.154051 -27.422478)
			(xy 139.116518 -27.451703) (xy 139.085073 -27.487397) (xy 139.060813 -27.528315) (xy 139.044584 -27.57303)
			(xy 139.036951 -27.619983) (xy 139.038182 -27.667536) (xy 139.048232 -27.714031) (xy 139.066752 -27.757847)
			(xy 139.079478 -27.777948) (xy 139.094483 -27.801467) (xy 139.118254 -27.851935) (xy 139.13442 -27.905328)
			(xy 139.142634 -27.960506) (xy 139.142699 -28.001976) (xy 141.348712 -28.001976) (xy 141.352783 -27.946354)
			(xy 141.364909 -27.891917) (xy 141.384832 -27.839826) (xy 141.412128 -27.791191) (xy 141.446214 -27.747048)
			(xy 141.486363 -27.708339) (xy 141.531721 -27.675888) (xy 141.581321 -27.650387) (xy 141.634105 -27.63238)
			(xy 141.688948 -27.62225) (xy 141.744682 -27.620213) (xy 141.800119 -27.626313) (xy 141.854076 -27.640419)
			(xy 141.905405 -27.662231) (xy 141.953011 -27.691285) (xy 141.988169 -27.720544) (xy 143.404842 -27.720544)
			(xy 143.408913 -27.664922) (xy 143.421039 -27.610485) (xy 143.440962 -27.558394) (xy 143.468258 -27.509759)
			(xy 143.502344 -27.465616) (xy 143.542493 -27.426907) (xy 143.587851 -27.394456) (xy 143.637451 -27.368955)
			(xy 143.690235 -27.350948) (xy 143.745078 -27.340818) (xy 143.800812 -27.338781) (xy 143.856249 -27.344881)
			(xy 143.910206 -27.358987) (xy 143.961535 -27.380799) (xy 144.009141 -27.409853) (xy 144.052009 -27.445528)
			(xy 144.089226 -27.487065) (xy 144.119999 -27.533578) (xy 144.143671 -27.584075) (xy 144.159739 -27.637482)
			(xy 144.167859 -27.692658) (xy 144.168368 -27.720544) (xy 144.167859 -27.74843) (xy 144.159739 -27.803606)
			(xy 144.143671 -27.857013) (xy 144.119999 -27.90751) (xy 144.089226 -27.954023) (xy 144.052009 -27.99556)
			(xy 144.009141 -28.031235) (xy 143.961535 -28.060289) (xy 143.910206 -28.082101) (xy 143.856249 -28.096207)
			(xy 143.800812 -28.102307) (xy 143.745078 -28.10027) (xy 143.690235 -28.09014) (xy 143.637451 -28.072133)
			(xy 143.587851 -28.046632) (xy 143.542493 -28.014181) (xy 143.502344 -27.975472) (xy 143.468258 -27.931329)
			(xy 143.440962 -27.882694) (xy 143.421039 -27.830603) (xy 143.408913 -27.776166) (xy 143.404842 -27.720544)
			(xy 141.988169 -27.720544) (xy 141.995879 -27.72696) (xy 142.033096 -27.768497) (xy 142.063869 -27.81501)
			(xy 142.087541 -27.865507) (xy 142.103609 -27.918914) (xy 142.111729 -27.97409) (xy 142.112238 -28.001976)
			(xy 142.111729 -28.029862) (xy 142.103609 -28.085038) (xy 142.087541 -28.138445) (xy 142.063869 -28.188942)
			(xy 142.033096 -28.235455) (xy 141.995879 -28.276992) (xy 141.953011 -28.312667) (xy 141.905405 -28.341721)
			(xy 141.854076 -28.363533) (xy 141.800119 -28.377639) (xy 141.744682 -28.383739) (xy 141.688948 -28.381702)
			(xy 141.634105 -28.371572) (xy 141.581321 -28.353565) (xy 141.531721 -28.328064) (xy 141.486363 -28.295613)
			(xy 141.446214 -28.256904) (xy 141.412128 -28.212761) (xy 141.384832 -28.164126) (xy 141.364909 -28.112035)
			(xy 141.352783 -28.057598) (xy 141.348712 -28.001976) (xy 139.142699 -28.001976) (xy 139.142722 -28.016292)
			(xy 139.134682 -28.071496) (xy 139.118685 -28.12494) (xy 139.095073 -28.175483) (xy 139.064349 -28.222046)
			(xy 139.027169 -28.263637) (xy 138.984327 -28.299367) (xy 138.936737 -28.328475) (xy 138.885414 -28.350339)
			(xy 138.831453 -28.364493) (xy 138.776005 -28.370634) (xy 138.720255 -28.368632) (xy 138.665391 -28.358529)
			(xy 138.612585 -28.340541) (xy 138.562962 -28.315052) (xy 138.517582 -28.282605) (xy 138.477414 -28.243894)
			(xy 138.443313 -28.199743) (xy 138.416009 -28.151095) (xy 138.396083 -28.098989) (xy 138.383961 -28.044536)
			(xy 138.379902 -27.988897) (xy 137.13307 -27.988897) (xy 137.097889 -27.997362) (xy 137.042905 -28.002405)
			(xy 136.987768 -27.999469) (xy 136.93363 -27.988613) (xy 136.881623 -27.970066) (xy 136.832834 -27.944214)
			(xy 136.788281 -27.911599) (xy 136.748896 -27.8729) (xy 136.715502 -27.828928) (xy 136.688796 -27.780601)
			(xy 136.669337 -27.728928) (xy 136.657531 -27.67499) (xy 136.653625 -27.619913) (xy 135.75175 -27.619913)
			(xy 135.751569 -27.629812) (xy 135.743449 -27.684988) (xy 135.727381 -27.738395) (xy 135.703709 -27.788892)
			(xy 135.672936 -27.835405) (xy 135.635719 -27.876942) (xy 135.592851 -27.912617) (xy 135.545245 -27.941671)
			(xy 135.493916 -27.963483) (xy 135.439959 -27.977589) (xy 135.384522 -27.983689) (xy 135.328788 -27.981652)
			(xy 135.273945 -27.971522) (xy 135.221161 -27.953515) (xy 135.171561 -27.928014) (xy 135.126203 -27.895563)
			(xy 135.086054 -27.856854) (xy 135.051968 -27.812711) (xy 135.024672 -27.764076) (xy 135.004749 -27.711985)
			(xy 134.992623 -27.657548) (xy 134.988552 -27.601926) (xy 134.18683 -27.601926) (xy 134.172901 -27.648225)
			(xy 134.149229 -27.698722) (xy 134.118456 -27.745235) (xy 134.081239 -27.786772) (xy 134.038371 -27.822447)
			(xy 133.990765 -27.851501) (xy 133.939436 -27.873313) (xy 133.885479 -27.887419) (xy 133.830042 -27.893519)
			(xy 133.774308 -27.891482) (xy 133.719465 -27.881352) (xy 133.666681 -27.863345) (xy 133.617081 -27.837844)
			(xy 133.571723 -27.805393) (xy 133.531574 -27.766684) (xy 133.497488 -27.722541) (xy 133.470192 -27.673906)
			(xy 133.450269 -27.621815) (xy 133.438143 -27.567378) (xy 133.434072 -27.511756) (xy 132.361293 -27.511756)
			(xy 132.365749 -27.542036) (xy 132.366258 -27.569922) (xy 132.365749 -27.597808) (xy 132.357629 -27.652984)
			(xy 132.341561 -27.706391) (xy 132.317889 -27.756888) (xy 132.287116 -27.803401) (xy 132.249899 -27.844938)
			(xy 132.207031 -27.880613) (xy 132.159425 -27.909667) (xy 132.108096 -27.931479) (xy 132.054139 -27.945585)
			(xy 131.998702 -27.951685) (xy 131.942968 -27.949648) (xy 131.888125 -27.939518) (xy 131.835341 -27.921511)
			(xy 131.785741 -27.89601) (xy 131.740383 -27.863559) (xy 131.700234 -27.82485) (xy 131.666148 -27.780707)
			(xy 131.638852 -27.732072) (xy 131.618929 -27.679981) (xy 131.606803 -27.625544) (xy 131.602732 -27.569922)
			(xy 130.652195 -27.569922) (xy 130.652515 -27.572417) (xy 130.65149 -27.628197) (xy 130.642352 -27.683233)
			(xy 130.625297 -27.736352) (xy 130.600688 -27.786421) (xy 130.569051 -27.832373) (xy 130.550412 -27.853132)
			(xy 130.536461 -27.869385) (xy 130.513651 -27.905635) (xy 130.497236 -27.945193) (xy 130.487681 -27.986943)
			(xy 130.485255 -28.029704) (xy 130.490028 -28.072266) (xy 130.501863 -28.113428) (xy 130.520428 -28.152024)
			(xy 130.545196 -28.186966) (xy 130.560064 -28.202382) (xy 130.742182 -28.3845) (xy 130.754361 -28.395969)
			(xy 130.783338 -28.412663) (xy 130.815658 -28.421255) (xy 130.849101 -28.421155) (xy 130.865372 -28.417266)
			(xy 130.901694 -28.407106) (xy 130.914902 -28.39974) (xy 130.938923 -28.386835) (xy 130.989818 -28.367263)
			(xy 131.042982 -28.355139) (xy 131.09733 -28.350709) (xy 131.151755 -28.354065) (xy 131.205147 -28.365137)
			(xy 131.256419 -28.383701) (xy 131.304524 -28.409376) (xy 131.348482 -28.441642) (xy 131.387397 -28.479838)
			(xy 131.420476 -28.523187) (xy 131.447044 -28.570805) (xy 131.46656 -28.621722) (xy 131.478625 -28.674899)
			(xy 131.482995 -28.729252) (xy 131.479763 -28.78074) (xy 132.234176 -28.78074) (xy 132.238247 -28.725118)
			(xy 132.250373 -28.670681) (xy 132.270296 -28.61859) (xy 132.297592 -28.569955) (xy 132.331678 -28.525812)
			(xy 132.371827 -28.487103) (xy 132.417185 -28.454652) (xy 132.466785 -28.429151) (xy 132.519569 -28.411144)
			(xy 132.574412 -28.401014) (xy 132.630146 -28.398977) (xy 132.685583 -28.405077) (xy 132.73954 -28.419183)
			(xy 132.790869 -28.440995) (xy 132.838475 -28.470049) (xy 132.881343 -28.505724) (xy 132.91856 -28.547261)
			(xy 132.949333 -28.593774) (xy 132.973005 -28.644271) (xy 132.989073 -28.697678) (xy 132.997193 -28.752854)
			(xy 132.997702 -28.78074) (xy 132.99741 -28.796742) (xy 133.631684 -28.796742) (xy 133.635755 -28.74112)
			(xy 133.647881 -28.686683) (xy 133.667804 -28.634592) (xy 133.6951 -28.585957) (xy 133.729186 -28.541814)
			(xy 133.769335 -28.503105) (xy 133.814693 -28.470654) (xy 133.864293 -28.445153) (xy 133.917077 -28.427146)
			(xy 133.97192 -28.417016) (xy 134.027654 -28.414979) (xy 134.083091 -28.421079) (xy 134.137048 -28.435185)
			(xy 134.188377 -28.456997) (xy 134.235983 -28.486051) (xy 134.278851 -28.521726) (xy 134.316068 -28.563263)
			(xy 134.346841 -28.609776) (xy 134.370513 -28.660273) (xy 134.371604 -28.6639) (xy 135.751822 -28.6639)
			(xy 135.755893 -28.608278) (xy 135.768019 -28.553841) (xy 135.787942 -28.50175) (xy 135.815238 -28.453115)
			(xy 135.849324 -28.408972) (xy 135.889473 -28.370263) (xy 135.934831 -28.337812) (xy 135.984431 -28.312311)
			(xy 136.037215 -28.294304) (xy 136.092058 -28.284174) (xy 136.147792 -28.282137) (xy 136.203229 -28.288237)
			(xy 136.257186 -28.302343) (xy 136.308515 -28.324155) (xy 136.356121 -28.353209) (xy 136.398989 -28.388884)
			(xy 136.436206 -28.430421) (xy 136.466979 -28.476934) (xy 136.490651 -28.527431) (xy 136.506719 -28.580838)
			(xy 136.514839 -28.636014) (xy 136.515348 -28.6639) (xy 136.515204 -28.671774) (xy 137.463782 -28.671774)
			(xy 137.467853 -28.616152) (xy 137.479979 -28.561715) (xy 137.499902 -28.509624) (xy 137.527198 -28.460989)
			(xy 137.561284 -28.416846) (xy 137.601433 -28.378137) (xy 137.646791 -28.345686) (xy 137.696391 -28.320185)
			(xy 137.749175 -28.302178) (xy 137.804018 -28.292048) (xy 137.859752 -28.290011) (xy 137.915189 -28.296111)
			(xy 137.969146 -28.310217) (xy 138.020475 -28.332029) (xy 138.068081 -28.361083) (xy 138.110949 -28.396758)
			(xy 138.148166 -28.438295) (xy 138.178939 -28.484808) (xy 138.202611 -28.535305) (xy 138.218679 -28.588712)
			(xy 138.226799 -28.643888) (xy 138.227308 -28.671774) (xy 138.226807 -28.699206) (xy 139.442442 -28.699206)
			(xy 139.446513 -28.643584) (xy 139.458639 -28.589147) (xy 139.478562 -28.537056) (xy 139.505858 -28.488421)
			(xy 139.539944 -28.444278) (xy 139.580093 -28.405569) (xy 139.625451 -28.373118) (xy 139.675051 -28.347617)
			(xy 139.727835 -28.32961) (xy 139.782678 -28.31948) (xy 139.838412 -28.317443) (xy 139.893849 -28.323543)
			(xy 139.947806 -28.337649) (xy 139.999135 -28.359461) (xy 140.046741 -28.388515) (xy 140.089609 -28.42419)
			(xy 140.126826 -28.465727) (xy 140.157599 -28.51224) (xy 140.181271 -28.562737) (xy 140.197339 -28.616144)
			(xy 140.205459 -28.67132) (xy 140.205968 -28.699206) (xy 140.205459 -28.727092) (xy 140.197339 -28.782268)
			(xy 140.181271 -28.835675) (xy 140.157599 -28.886172) (xy 140.126826 -28.932685) (xy 140.089609 -28.974222)
			(xy 140.046741 -29.009897) (xy 139.999135 -29.038951) (xy 139.947806 -29.060763) (xy 139.893849 -29.074869)
			(xy 139.838412 -29.080969) (xy 139.782678 -29.078932) (xy 139.727835 -29.068802) (xy 139.675051 -29.050795)
			(xy 139.625451 -29.025294) (xy 139.580093 -28.992843) (xy 139.539944 -28.954134) (xy 139.505858 -28.909991)
			(xy 139.478562 -28.861356) (xy 139.458639 -28.809265) (xy 139.446513 -28.754828) (xy 139.442442 -28.699206)
			(xy 138.226807 -28.699206) (xy 138.226799 -28.69966) (xy 138.218679 -28.754836) (xy 138.202611 -28.808243)
			(xy 138.178939 -28.85874) (xy 138.148166 -28.905253) (xy 138.110949 -28.94679) (xy 138.068081 -28.982465)
			(xy 138.020475 -29.011519) (xy 137.969146 -29.033331) (xy 137.915189 -29.047437) (xy 137.859752 -29.053537)
			(xy 137.804018 -29.0515) (xy 137.749175 -29.04137) (xy 137.696391 -29.023363) (xy 137.646791 -28.997862)
			(xy 137.601433 -28.965411) (xy 137.561284 -28.926702) (xy 137.527198 -28.882559) (xy 137.499902 -28.833924)
			(xy 137.479979 -28.781833) (xy 137.467853 -28.727396) (xy 137.463782 -28.671774) (xy 136.515204 -28.671774)
			(xy 136.514839 -28.691786) (xy 136.506719 -28.746962) (xy 136.490651 -28.800369) (xy 136.466979 -28.850866)
			(xy 136.436206 -28.897379) (xy 136.398989 -28.938916) (xy 136.356121 -28.974591) (xy 136.308515 -29.003645)
			(xy 136.257186 -29.025457) (xy 136.203229 -29.039563) (xy 136.147792 -29.045663) (xy 136.092058 -29.043626)
			(xy 136.037215 -29.033496) (xy 135.984431 -29.015489) (xy 135.934831 -28.989988) (xy 135.889473 -28.957537)
			(xy 135.849324 -28.918828) (xy 135.815238 -28.874685) (xy 135.787942 -28.82605) (xy 135.768019 -28.773959)
			(xy 135.755893 -28.719522) (xy 135.751822 -28.6639) (xy 134.371604 -28.6639) (xy 134.386581 -28.71368)
			(xy 134.394701 -28.768856) (xy 134.39521 -28.796742) (xy 134.394701 -28.824628) (xy 134.386581 -28.879804)
			(xy 134.370513 -28.933211) (xy 134.346841 -28.983708) (xy 134.316068 -29.030221) (xy 134.278851 -29.071758)
			(xy 134.235983 -29.107433) (xy 134.188377 -29.136487) (xy 134.137048 -29.158299) (xy 134.083091 -29.172405)
			(xy 134.027654 -29.178505) (xy 133.97192 -29.176468) (xy 133.917077 -29.166338) (xy 133.864293 -29.148331)
			(xy 133.814693 -29.12283) (xy 133.769335 -29.090379) (xy 133.729186 -29.05167) (xy 133.6951 -29.007527)
			(xy 133.667804 -28.958892) (xy 133.647881 -28.906801) (xy 133.635755 -28.852364) (xy 133.631684 -28.796742)
			(xy 132.99741 -28.796742) (xy 132.997193 -28.808626) (xy 132.989073 -28.863802) (xy 132.973005 -28.917209)
			(xy 132.949333 -28.967706) (xy 132.91856 -29.014219) (xy 132.881343 -29.055756) (xy 132.838475 -29.091431)
			(xy 132.790869 -29.120485) (xy 132.73954 -29.142297) (xy 132.685583 -29.156403) (xy 132.630146 -29.162503)
			(xy 132.574412 -29.160466) (xy 132.519569 -29.150336) (xy 132.466785 -29.132329) (xy 132.417185 -29.106828)
			(xy 132.371827 -29.074377) (xy 132.331678 -29.035668) (xy 132.297592 -28.991525) (xy 132.270296 -28.94289)
			(xy 132.250373 -28.890799) (xy 132.238247 -28.836362) (xy 132.234176 -28.78074) (xy 131.479763 -28.78074)
			(xy 131.479579 -28.783673) (xy 131.468448 -28.837054) (xy 131.449828 -28.888304) (xy 131.43738 -28.912566)
			(xy 131.426712 -28.931616) (xy 131.403852 -28.969208) (xy 131.414266 -29.056584) (xy 132.992114 -30.634432)
			(xy 143.08328 -30.634432) (xy 143.700754 -31.251906) (xy 143.712886 -31.263367) (xy 143.741765 -31.280076)
			(xy 143.773988 -31.288727) (xy 143.807352 -31.288727) (xy 143.839575 -31.280076) (xy 143.868454 -31.263367)
			(xy 143.880586 -31.251906) (xy 148.254974 -26.877518) (xy 148.264779 -26.866328) (xy 148.27939 -26.840418)
			(xy 148.287629 -26.811836) (xy 148.288756 -26.797) (xy 148.288756 -20.952968) (xy 148.445474 -20.795996)
			(xy 149.346412 -19.895058) (xy 149.365208 -19.836638) (xy 149.357588 -19.790664) (xy 149.35581 -19.783552)
			(xy 149.3454 -19.745034) (xy 149.33148 -19.666464) (xy 149.325574 -19.58689) (xy 149.327742 -19.507126)
			(xy 149.337962 -19.42799) (xy 149.356129 -19.350292) (xy 149.382057 -19.274829) (xy 149.415481 -19.202373)
			(xy 149.456058 -19.133668) (xy 149.503372 -19.069416) (xy 149.556939 -19.010276) (xy 149.61621 -18.956853)
			(xy 149.680578 -18.909696) (xy 149.749383 -18.869288) (xy 149.82192 -18.836041) (xy 149.897447 -18.810297)
			(xy 149.975188 -18.79232) (xy 150.054349 -18.782294) (xy 150.134118 -18.780321) (xy 150.213678 -18.786422)
			(xy 150.292214 -18.800534) (xy 150.36892 -18.822513) (xy 150.443012 -18.852133) (xy 150.51373 -18.889091)
			(xy 150.580351 -18.933008) (xy 150.64219 -18.983435) (xy 150.698615 -19.039855) (xy 150.749048 -19.10169)
			(xy 150.792971 -19.168306) (xy 150.829936 -19.23902) (xy 150.859563 -19.31311) (xy 150.881549 -19.389814)
			(xy 150.895669 -19.468348) (xy 150.901777 -19.547908) (xy 150.899812 -19.627677) (xy 150.889793 -19.706839)
			(xy 150.871823 -19.784582) (xy 150.846086 -19.860111) (xy 150.812847 -19.932651) (xy 150.772444 -20.00146)
			(xy 150.725293 -20.065832) (xy 150.671877 -20.125108) (xy 150.612742 -20.178681) (xy 150.548494 -20.226001)
			(xy 150.479792 -20.266585) (xy 150.40734 -20.300015) (xy 150.331879 -20.325951) (xy 150.254183 -20.344125)
			(xy 150.175048 -20.354353) (xy 150.095284 -20.356528) (xy 150.015709 -20.350629) (xy 149.937138 -20.336717)
			(xy 149.898608 -20.32635) (xy 149.891496 -20.324572) (xy 149.87524 -20.321778) (xy 149.860327 -20.319809)
			(xy 149.830344 -20.322135) (xy 149.801748 -20.331441) (xy 149.776138 -20.347205) (xy 149.765258 -20.357592)
			(xy 148.945346 -21.177504) (xy 148.935952 -21.18817) (xy 148.921656 -21.212728) (xy 148.913116 -21.23983)
			(xy 148.911564 -21.253958) (xy 148.911564 -22.02307) (xy 148.912115 -22.039724) (xy 148.920748 -22.071894)
			(xy 148.937407 -22.100737) (xy 148.96096 -22.12429) (xy 148.989802 -22.140951) (xy 149.021972 -22.149584)
			(xy 149.055281 -22.149603) (xy 149.087461 -22.141007) (xy 149.116323 -22.124381) (xy 149.12848 -22.112986)
			(xy 149.346412 -21.895054) (xy 149.365208 -21.836634) (xy 149.357588 -21.79066) (xy 149.35581 -21.783548)
			(xy 149.3454 -21.74503) (xy 149.33148 -21.666461) (xy 149.325575 -21.586886) (xy 149.327743 -21.507122)
			(xy 149.337963 -21.427987) (xy 149.356131 -21.350289) (xy 149.382059 -21.274826) (xy 149.415484 -21.202371)
			(xy 149.456061 -21.133665) (xy 149.503375 -21.069414) (xy 149.556943 -21.010274) (xy 149.616214 -20.956852)
			(xy 149.680581 -20.909695) (xy 149.749386 -20.869287) (xy 149.821923 -20.836041) (xy 149.89745 -20.810298)
			(xy 149.975192 -20.792321) (xy 150.054352 -20.782295) (xy 150.134121 -20.780322) (xy 150.213681 -20.786423)
			(xy 150.292216 -20.800536) (xy 150.368922 -20.822515) (xy 150.443014 -20.852135) (xy 150.513732 -20.889093)
			(xy 150.580352 -20.933011) (xy 150.642191 -20.983438) (xy 150.698616 -21.039858) (xy 150.749048 -21.101692)
			(xy 150.792972 -21.168308) (xy 150.829936 -21.239023) (xy 150.859563 -21.313112) (xy 150.881549 -21.389817)
			(xy 150.895668 -21.468351) (xy 150.901776 -21.54791) (xy 150.89981 -21.627679) (xy 150.889791 -21.70684)
			(xy 150.871821 -21.784584) (xy 150.846085 -21.860112) (xy 150.812845 -21.932652) (xy 150.772443 -22.001461)
			(xy 150.725292 -22.065833) (xy 150.671875 -22.125108) (xy 150.61274 -22.178681) (xy 150.548492 -22.226001)
			(xy 150.47979 -22.266584) (xy 150.407338 -22.300015) (xy 150.331877 -22.32595) (xy 150.254182 -22.344124)
			(xy 150.175047 -22.354352) (xy 150.095283 -22.356527) (xy 150.015708 -22.350628) (xy 149.937137 -22.336716)
			(xy 149.898608 -22.326346) (xy 149.891496 -22.324568) (xy 149.87524 -22.321774) (xy 149.860327 -22.319805)
			(xy 149.830344 -22.322131) (xy 149.801747 -22.331437) (xy 149.776137 -22.347201) (xy 149.765258 -22.357588)
			(xy 149.398482 -22.724364) (xy 149.387078 -22.73649) (xy 149.370379 -22.765271) (xy 149.361684 -22.79739)
			(xy 149.361144 -22.814026) (xy 149.361144 -22.90064) (xy 149.361644 -22.917289) (xy 149.370272 -22.94945)
			(xy 149.386931 -22.978283) (xy 149.410484 -23.00182) (xy 149.439327 -23.01846) (xy 149.471494 -23.027067)
			(xy 149.488144 -23.02764) (xy 149.538436 -23.02764) (xy 149.575012 -22.99335) (xy 149.604979 -22.965966)
			(xy 149.669615 -22.916846) (xy 149.738959 -22.874633) (xy 149.812277 -22.839775) (xy 149.88879 -22.812641)
			(xy 149.967688 -22.79352) (xy 150.048134 -22.782612) (xy 150.129276 -22.780035) (xy 150.210252 -22.785816)
			(xy 150.290204 -22.799892) (xy 150.368286 -22.822116) (xy 150.443668 -22.852251) (xy 150.515551 -22.889978)
			(xy 150.583174 -22.934898) (xy 150.645819 -22.986532) (xy 150.702822 -23.044335) (xy 150.753579 -23.107693)
			(xy 150.797552 -23.175935) (xy 150.834275 -23.248337) (xy 150.863357 -23.324131) (xy 150.874476 -23.363174)
			(xy 150.884357 -23.401714) (xy 150.897232 -23.480233) (xy 150.902129 -23.559649) (xy 150.898996 -23.639154)
			(xy 150.887867 -23.717939) (xy 150.868854 -23.795202) (xy 150.842151 -23.870154) (xy 150.80803 -23.942034)
			(xy 150.787862 -23.97633) (xy 150.767042 -24.009807) (xy 150.719689 -24.072844) (xy 150.666277 -24.130836)
			(xy 150.607339 -24.183204) (xy 150.543467 -24.229423) (xy 150.475297 -24.269032) (xy 150.403512 -24.301634)
			(xy 150.32883 -24.326903) (xy 150.251998 -24.344587) (xy 150.173784 -24.354509) (xy 150.094969 -24.356569)
			(xy 150.016343 -24.350747) (xy 149.938692 -24.337102) (xy 149.862792 -24.315769) (xy 149.789402 -24.286961)
			(xy 149.754082 -24.269446) (xy 149.73681 -24.260302) (xy 149.716107 -24.249582) (xy 149.671814 -24.23505)
			(xy 149.625614 -24.228835) (xy 149.579055 -24.231145) (xy 149.533698 -24.241901) (xy 149.49106 -24.260745)
			(xy 149.452571 -24.287044) (xy 149.41952 -24.319918) (xy 149.393014 -24.358265) (xy 149.373941 -24.4008)
			(xy 149.362941 -24.4461) (xy 149.361144 -24.469344) (xy 149.361144 -24.515318) (xy 149.362951 -24.538779)
			(xy 149.374137 -24.58448) (xy 149.393536 -24.627345) (xy 149.420484 -24.665913) (xy 149.454064 -24.698868)
			(xy 149.493131 -24.725089) (xy 149.536352 -24.74368) (xy 149.582254 -24.754008) (xy 149.605746 -24.755348)
			(xy 149.632904 -24.756845) (xy 149.686417 -24.766574) (xy 149.738006 -24.783805) (xy 149.786625 -24.808188)
			(xy 149.831288 -24.839228) (xy 149.87109 -24.876297) (xy 149.905224 -24.918643) (xy 149.932999 -24.965407)
			(xy 149.95385 -25.015642) (xy 149.961092 -25.04186) (xy 149.967073 -25.063164) (xy 149.985361 -25.103452)
			(xy 150.01035 -25.139964) (xy 150.041285 -25.171597) (xy 150.07723 -25.197394) (xy 150.117099 -25.216578)
			(xy 150.159688 -25.228566) (xy 150.20371 -25.232999) (xy 150.247835 -25.22974) (xy 150.290728 -25.21889)
			(xy 150.311104 -25.210262) (xy 150.312882 -25.2095) (xy 150.337124 -25.199234) (xy 150.387725 -25.184708)
			(xy 150.41372 -25.180544) (xy 150.425344 -25.178961) (xy 150.448729 -25.177057) (xy 150.460456 -25.176734)
			(xy 150.483565 -25.176655) (xy 150.529538 -25.181365) (xy 150.55215 -25.186132) (xy 150.575387 -25.189959)
			(xy 150.622476 -25.189953) (xy 150.668759 -25.18128) (xy 150.712656 -25.164237) (xy 150.752665 -25.139406)
			(xy 150.787421 -25.107635) (xy 150.815735 -25.07001) (xy 150.836641 -25.027816) (xy 150.843488 -25.005284)
			(xy 150.851715 -24.977907) (xy 150.875227 -24.925804) (xy 150.906252 -24.877793) (xy 150.944096 -24.834952)
			(xy 150.987911 -24.798238) (xy 151.036714 -24.768475) (xy 151.089413 -24.746331) (xy 151.144827 -24.732299)
			(xy 151.201715 -24.726696) (xy 151.258801 -24.729647) (xy 151.314808 -24.741085) (xy 151.36848 -24.760755)
			(xy 151.418615 -24.788215) (xy 151.441658 -24.805132) (xy 151.454009 -24.814701) (xy 151.477277 -24.835558)
			(xy 151.48814 -24.846788) (xy 151.508136 -24.868771) (xy 151.541761 -24.917766) (xy 151.567381 -24.971382)
			(xy 151.584378 -25.028322) (xy 151.59234 -25.087209) (xy 151.591074 -25.146618) (xy 151.586438 -25.175972)
			(xy 151.581014 -25.203519) (xy 151.563153 -25.256746) (xy 151.537686 -25.306781) (xy 151.505162 -25.352544)
			(xy 151.466283 -25.393047) (xy 151.421888 -25.427417) (xy 151.372937 -25.45491) (xy 151.320486 -25.474933)
			(xy 151.265666 -25.487054) (xy 151.209663 -25.491012) (xy 151.153683 -25.486721) (xy 151.12619 -25.481026)
			(xy 151.102955 -25.477205) (xy 151.055872 -25.477221) (xy 151.009596 -25.485901) (xy 150.965707 -25.502948)
			(xy 150.925704 -25.527779) (xy 150.890954 -25.559548) (xy 150.862643 -25.597168) (xy 150.841738 -25.639356)
			(xy 150.834852 -25.661874) (xy 150.82901 -25.68067) (xy 150.822563 -25.70118) (xy 150.815869 -25.743646)
			(xy 150.816418 -25.786632) (xy 150.824195 -25.828912) (xy 150.838978 -25.869281) (xy 150.860344 -25.906585)
			(xy 150.887685 -25.93976) (xy 150.92022 -25.967859) (xy 150.957021 -25.990082) (xy 150.976838 -25.998424)
			(xy 150.991002 -26.004128) (xy 151.018467 -26.017478) (xy 151.031702 -26.025094) (xy 151.056473 -26.040336)
			(xy 151.101509 -26.077137) (xy 151.140441 -26.120344) (xy 151.172369 -26.168956) (xy 151.196552 -26.22185)
			(xy 151.212432 -26.2778) (xy 151.219641 -26.335511) (xy 151.218011 -26.393648) (xy 151.213312 -26.42235)
			(xy 151.212296 -26.427684) (xy 151.211026 -26.439622) (xy 151.209935 -26.456631) (xy 151.215752 -26.490201)
			(xy 151.230235 -26.521041) (xy 151.252353 -26.546955) (xy 151.266144 -26.55697) (xy 151.3078 -26.585164)
			(xy 151.320154 -26.593054) (xy 151.347517 -26.603547) (xy 151.376552 -26.607517) (xy 151.405728 -26.604755)
			(xy 151.433502 -26.595407) (xy 151.45841 -26.579966) (xy 151.46909 -26.569924) (xy 151.586692 -26.452322)
			(xy 151.601076 -26.436474) (xy 151.624862 -26.400898) (xy 151.642352 -26.361841) (xy 151.653052 -26.320405)
			(xy 151.65666 -26.277762) (xy 151.653073 -26.235118) (xy 151.642393 -26.193677) (xy 151.624922 -26.15461)
			(xy 151.613362 -26.1366) (xy 151.597252 -26.113314) (xy 151.571351 -26.062964) (xy 151.553173 -26.00934)
			(xy 151.543118 -25.953618) (xy 151.541406 -25.897023) (xy 151.548075 -25.840796) (xy 151.562979 -25.786171)
			(xy 151.585791 -25.734348) (xy 151.616009 -25.686464) (xy 151.65297 -25.64357) (xy 151.695864 -25.606609)
			(xy 151.743748 -25.576391) (xy 151.795571 -25.553579) (xy 151.850196 -25.538675) (xy 151.906423 -25.532006)
			(xy 151.963018 -25.533718) (xy 152.01874 -25.543773) (xy 152.072364 -25.561951) (xy 152.122714 -25.587852)
			(xy 152.146 -25.603962) (xy 152.16403 -25.615501) (xy 152.203086 -25.633013) (xy 152.244528 -25.643724)
			(xy 152.287179 -25.647331) (xy 152.32983 -25.643731) (xy 152.371273 -25.633027) (xy 152.410333 -25.615522)
			(xy 152.445903 -25.591712) (xy 152.461722 -25.577292) (xy 153.3017 -24.737314) (xy 153.316444 -24.721054)
			(xy 153.340679 -24.684464) (xy 153.35827 -24.644255) (xy 153.368693 -24.601622) (xy 153.37164 -24.557833)
			(xy 153.367022 -24.514188) (xy 153.354976 -24.471985) (xy 153.335861 -24.432478) (xy 153.310245 -24.396841)
			(xy 153.294842 -24.381206) (xy 153.287599 -24.374414) (xy 153.27375 -24.360182) (xy 153.267156 -24.352758)
			(xy 153.258528 -24.342775) (xy 153.242514 -24.321799) (xy 153.235152 -24.310848) (xy 153.221773 -24.292979)
			(xy 153.189835 -24.261799) (xy 153.152937 -24.236682) (xy 153.112218 -24.218401) (xy 153.06893 -24.207519)
			(xy 153.024406 -24.204372) (xy 152.980018 -24.209056) (xy 152.937131 -24.221426) (xy 152.91689 -24.230838)
			(xy 152.890662 -24.243102) (xy 152.835423 -24.260443) (xy 152.778198 -24.269233) (xy 152.720301 -24.269271)
			(xy 152.663064 -24.260556) (xy 152.607803 -24.243287) (xy 152.555788 -24.217862) (xy 152.508214 -24.184866)
			(xy 152.486868 -24.165306) (xy 152.467027 -24.14584) (xy 152.432625 -24.102183) (xy 152.40492 -24.053998)
			(xy 152.384497 -24.002304) (xy 152.371788 -23.948195) (xy 152.367063 -23.892814) (xy 152.37042 -23.837333)
			(xy 152.381791 -23.782927) (xy 152.400932 -23.730744) (xy 152.427441 -23.681891) (xy 152.443688 -23.659338)
			(xy 152.443942 -23.659084) (xy 152.463096 -23.634575) (xy 152.507997 -23.591534) (xy 152.559284 -23.556344)
			(xy 152.615598 -23.529937) (xy 152.645364 -23.520908) (xy 152.66729 -23.513294) (xy 152.708136 -23.491264)
			(xy 152.744304 -23.462183) (xy 152.774589 -23.427018) (xy 152.797986 -23.386939) (xy 152.813717 -23.343277)
			(xy 152.821257 -23.297485) (xy 152.821386 -23.274274) (xy 152.820198 -23.249298) (xy 152.823546 -23.199408)
			(xy 152.833374 -23.150381) (xy 152.849516 -23.103056) (xy 152.860248 -23.080472) (xy 152.876195 -23.049952)
			(xy 152.917348 -22.99475) (xy 152.942036 -22.970744) (xy 152.962533 -22.952316) (xy 153.007848 -22.920941)
			(xy 153.057204 -22.896406) (xy 153.109574 -22.879221) (xy 153.163871 -22.869745) (xy 153.218965 -22.868172)
			(xy 153.273714 -22.874536) (xy 153.326979 -22.888705) (xy 153.3525 -22.899116) (xy 153.373087 -22.907461)
			(xy 153.416326 -22.917633) (xy 153.460675 -22.920137) (xy 153.504785 -22.914896) (xy 153.547312 -22.902071)
			(xy 153.586964 -22.882051) (xy 153.622534 -22.855445) (xy 153.652941 -22.823064) (xy 153.677257 -22.785891)
			(xy 153.694745 -22.745059) (xy 153.704871 -22.701809) (xy 153.706576 -22.67966) (xy 153.706576 -21.79828)
			(xy 155.396184 -20.108418) (xy 155.587954 -19.916648) (xy 155.598231 -19.905739) (xy 155.613846 -19.880165)
			(xy 155.623079 -19.851659) (xy 155.625421 -19.821787) (xy 155.623514 -19.80692) (xy 155.62072 -19.790664)
			(xy 155.618942 -19.783552) (xy 155.608531 -19.74503) (xy 155.594612 -19.666453) (xy 155.588707 -19.586871)
			(xy 155.590878 -19.507099) (xy 155.601101 -19.427956) (xy 155.619272 -19.350251) (xy 155.645205 -19.274782)
			(xy 155.678634 -19.20232) (xy 155.719218 -19.133609) (xy 155.766539 -19.069353) (xy 155.820113 -19.010209)
			(xy 155.879391 -18.956784) (xy 155.943767 -18.909625) (xy 156.01258 -18.869215) (xy 156.085125 -18.835968)
			(xy 156.16066 -18.810225) (xy 156.23841 -18.79225) (xy 156.317579 -18.782226) (xy 156.397355 -18.780256)
			(xy 156.476922 -18.786361) (xy 156.555465 -18.800478) (xy 156.632177 -18.822463) (xy 156.706275 -18.852089)
			(xy 156.776998 -18.889054) (xy 156.843622 -18.932979) (xy 156.905465 -18.983414) (xy 156.961892 -19.039842)
			(xy 157.012326 -19.101686) (xy 157.056251 -19.16831) (xy 157.093215 -19.239034) (xy 157.122841 -19.313132)
			(xy 157.144824 -19.389845) (xy 157.15894 -19.468388) (xy 157.165044 -19.547955) (xy 157.164413 -19.573494)
			(xy 170.046902 -19.573494) (xy 170.050973 -19.517872) (xy 170.063099 -19.463435) (xy 170.083022 -19.411344)
			(xy 170.110318 -19.362709) (xy 170.144404 -19.318566) (xy 170.184553 -19.279857) (xy 170.229911 -19.247406)
			(xy 170.279511 -19.221905) (xy 170.332295 -19.203898) (xy 170.387138 -19.193768) (xy 170.442872 -19.191731)
			(xy 170.498309 -19.197831) (xy 170.552266 -19.211937) (xy 170.603595 -19.233749) (xy 170.651201 -19.262803)
			(xy 170.694069 -19.298478) (xy 170.731286 -19.340015) (xy 170.762059 -19.386528) (xy 170.785731 -19.437025)
			(xy 170.801799 -19.490432) (xy 170.809919 -19.545608) (xy 170.810428 -19.573494) (xy 170.809919 -19.60138)
			(xy 170.801799 -19.656556) (xy 170.785731 -19.709963) (xy 170.762059 -19.76046) (xy 170.731286 -19.806973)
			(xy 170.694069 -19.84851) (xy 170.651201 -19.884185) (xy 170.603595 -19.913239) (xy 170.552266 -19.935051)
			(xy 170.498309 -19.949157) (xy 170.442872 -19.955257) (xy 170.387138 -19.95322) (xy 170.332295 -19.94309)
			(xy 170.279511 -19.925083) (xy 170.229911 -19.899582) (xy 170.184553 -19.867131) (xy 170.144404 -19.828422)
			(xy 170.110318 -19.784279) (xy 170.083022 -19.735644) (xy 170.063099 -19.683553) (xy 170.050973 -19.629116)
			(xy 170.046902 -19.573494) (xy 157.164413 -19.573494) (xy 157.163074 -19.627731) (xy 157.153049 -19.7069)
			(xy 157.135072 -19.78465) (xy 157.109328 -19.860184) (xy 157.076081 -19.932729) (xy 157.03567 -20.001541)
			(xy 156.98851 -20.065916) (xy 156.935084 -20.125194) (xy 156.875939 -20.178768) (xy 156.811682 -20.226088)
			(xy 156.742971 -20.26667) (xy 156.670509 -20.300099) (xy 156.595039 -20.326031) (xy 156.517334 -20.344201)
			(xy 156.438191 -20.354423) (xy 156.358419 -20.356593) (xy 156.278837 -20.350687) (xy 156.20026 -20.336767)
			(xy 156.16174 -20.32635) (xy 156.154628 -20.324572) (xy 156.138372 -20.321778) (xy 156.123462 -20.319817)
			(xy 156.093488 -20.322158) (xy 156.064902 -20.331474) (xy 156.039305 -20.347245) (xy 156.02839 -20.357592)
			(xy 154.363166 -22.022816) (xy 154.353772 -22.033482) (xy 154.339475 -22.05804) (xy 154.330937 -22.085142)
			(xy 154.329384 -22.09927) (xy 154.329384 -22.576028) (xy 154.331055 -22.598027) (xy 154.34102 -22.641001)
			(xy 154.358251 -22.68161) (xy 154.382232 -22.718637) (xy 154.412242 -22.75097) (xy 154.447382 -22.77764)
			(xy 154.486597 -22.797845) (xy 154.52871 -22.81098) (xy 154.572458 -22.816651) (xy 154.616528 -22.814688)
			(xy 154.659599 -22.805149) (xy 154.700377 -22.78832) (xy 154.73764 -22.764707) (xy 154.754326 -22.750272)
			(xy 155.103576 -22.401276) (xy 155.407868 -22.09673) (xy 155.587954 -21.916644) (xy 155.59823 -21.905734)
			(xy 155.613845 -21.880161) (xy 155.623076 -21.851655) (xy 155.625418 -21.821783) (xy 155.623514 -21.806916)
			(xy 155.62072 -21.789898) (xy 155.618688 -21.78304) (xy 155.61437 -21.767038) (xy 155.613354 -21.762974)
			(xy 155.6131 -21.76145) (xy 155.603976 -21.723379) (xy 155.592416 -21.645944) (xy 155.588594 -21.567744)
			(xy 155.592546 -21.489551) (xy 155.604235 -21.412135) (xy 155.623544 -21.33626) (xy 155.650283 -21.262675)
			(xy 155.684189 -21.192105) (xy 155.724928 -21.125245) (xy 155.772096 -21.062756) (xy 155.82523 -21.005253)
			(xy 155.883806 -20.953303) (xy 155.947244 -20.90742) (xy 156.014921 -20.868054) (xy 156.086169 -20.835596)
			(xy 156.160285 -20.810364) (xy 156.198316 -20.801076) (xy 156.240223 -20.791894) (xy 156.325399 -20.781616)
			(xy 156.411189 -20.780656) (xy 156.496574 -20.789025) (xy 156.538676 -20.797266) (xy 156.577574 -20.805903)
			(xy 156.653532 -20.829988) (xy 156.72667 -20.861618) (xy 156.796241 -20.90047) (xy 156.861534 -20.946148)
			(xy 156.921883 -20.998183) (xy 156.976669 -21.056046) (xy 157.025334 -21.119144) (xy 157.06738 -21.186833)
			(xy 157.102378 -21.25842) (xy 157.12997 -21.333176) (xy 157.149873 -21.410335) (xy 157.161885 -21.489109)
			(xy 157.165883 -21.568693) (xy 157.161826 -21.648274) (xy 157.149756 -21.727039) (xy 157.129795 -21.804183)
			(xy 157.102148 -21.878918) (xy 157.067097 -21.95048) (xy 157.025 -22.018137) (xy 156.976288 -22.081199)
			(xy 156.921459 -22.139021) (xy 156.861072 -22.191012) (xy 156.795745 -22.236641) (xy 156.726145 -22.275441)
			(xy 156.652983 -22.307017) (xy 156.577007 -22.331045) (xy 156.498994 -22.34728) (xy 156.459428 -22.352)
			(xy 156.445175 -22.353411) (xy 156.416593 -22.355318) (xy 156.402278 -22.35581) (xy 156.36058 -22.356636)
			(xy 156.277395 -22.350564) (xy 156.195315 -22.335752) (xy 156.155136 -22.324568) (xy 156.138627 -22.320292)
			(xy 156.104541 -22.319678) (xy 156.071502 -22.328085) (xy 156.041856 -22.344917) (xy 156.029406 -22.356572)
			(xy 154.886406 -23.499572) (xy 154.876601 -23.510763) (xy 154.861991 -23.536673) (xy 154.853751 -23.565254)
			(xy 154.852624 -23.58009) (xy 154.852624 -23.608339) (xy 155.589475 -23.608339) (xy 155.589475 -23.528473)
			(xy 155.597555 -23.449018) (xy 155.613632 -23.370788) (xy 155.637541 -23.294586) (xy 155.669036 -23.221193)
			(xy 155.707795 -23.151363) (xy 155.753419 -23.085813) (xy 155.805441 -23.025214) (xy 155.863326 -22.97019)
			(xy 155.926482 -22.921304) (xy 155.994259 -22.879058) (xy 156.065962 -22.843886) (xy 156.140856 -22.816149)
			(xy 156.218171 -22.79613) (xy 156.297115 -22.784037) (xy 156.376878 -22.779992) (xy 156.456641 -22.784037)
			(xy 156.535585 -22.79613) (xy 156.6129 -22.816149) (xy 156.687794 -22.843886) (xy 156.759497 -22.879058)
			(xy 156.827274 -22.921304) (xy 156.89043 -22.97019) (xy 156.948315 -23.025214) (xy 157.000337 -23.085813)
			(xy 157.045961 -23.151363) (xy 157.08472 -23.221193) (xy 157.116215 -23.294586) (xy 157.140124 -23.370788)
			(xy 157.156201 -23.449018) (xy 157.164281 -23.528473) (xy 157.164786 -23.568406) (xy 157.164281 -23.608339)
			(xy 157.156201 -23.687794) (xy 157.140124 -23.766024) (xy 157.116215 -23.842226) (xy 157.08472 -23.915619)
			(xy 157.045961 -23.985449) (xy 157.000337 -24.050999) (xy 156.948315 -24.111598) (xy 156.89043 -24.166622)
			(xy 156.827274 -24.215508) (xy 156.759497 -24.257754) (xy 156.687794 -24.292926) (xy 156.6129 -24.320663)
			(xy 156.535585 -24.340682) (xy 156.456641 -24.352775) (xy 156.376878 -24.356821) (xy 156.297115 -24.352775)
			(xy 156.218171 -24.340682) (xy 156.140856 -24.320663) (xy 156.065962 -24.292926) (xy 155.994259 -24.257754)
			(xy 155.926482 -24.215508) (xy 155.863326 -24.166622) (xy 155.805441 -24.111598) (xy 155.753419 -24.050999)
			(xy 155.707795 -23.985449) (xy 155.669036 -23.915619) (xy 155.637541 -23.842226) (xy 155.613632 -23.766024)
			(xy 155.597555 -23.687794) (xy 155.589475 -23.608339) (xy 154.852624 -23.608339) (xy 154.852624 -24.626316)
			(xy 154.824562 -24.654378) (xy 158.015243 -24.654378) (xy 158.021361 -24.600005) (xy 158.035182 -24.547064)
			(xy 158.056424 -24.49664) (xy 158.084651 -24.449768) (xy 158.119284 -24.407408) (xy 158.13913 -24.388572)
			(xy 158.154838 -24.373605) (xy 158.181362 -24.33927) (xy 158.201668 -24.300929) (xy 158.215169 -24.259697)
			(xy 158.22147 -24.21677) (xy 158.220389 -24.173397) (xy 158.211958 -24.130838) (xy 158.196422 -24.090329)
			(xy 158.174231 -24.053047) (xy 158.160466 -24.036274) (xy 158.143613 -24.016001) (xy 158.115157 -23.971619)
			(xy 158.093087 -23.92374) (xy 158.077827 -23.873276) (xy 158.069667 -23.821191) (xy 158.068762 -23.768478)
			(xy 158.07513 -23.716143) (xy 158.088649 -23.665186) (xy 158.109062 -23.616577) (xy 158.135979 -23.571245)
			(xy 158.152084 -23.550372) (xy 158.16563 -23.532623) (xy 158.186917 -23.493378) (xy 158.201026 -23.45102)
			(xy 158.207524 -23.406849) (xy 158.206211 -23.362222) (xy 158.197127 -23.31851) (xy 158.180552 -23.277055)
			(xy 158.156994 -23.23913) (xy 158.142432 -23.222204) (xy 158.124175 -23.201197) (xy 158.093354 -23.154857)
			(xy 158.069595 -23.104528) (xy 158.053404 -23.051281) (xy 158.045125 -22.996246) (xy 158.044932 -22.940592)
			(xy 158.05283 -22.885501) (xy 158.068652 -22.832143) (xy 158.092061 -22.781651) (xy 158.122561 -22.735098)
			(xy 158.140654 -22.71395) (xy 158.155437 -22.696581) (xy 158.179127 -22.657609) (xy 158.195477 -22.615034)
			(xy 158.203961 -22.570223) (xy 158.204307 -22.524617) (xy 158.196503 -22.479683) (xy 158.1808 -22.436864)
			(xy 158.157704 -22.397538) (xy 158.143194 -22.37994) (xy 158.126166 -22.359502) (xy 158.097436 -22.314729)
			(xy 158.075201 -22.266401) (xy 158.059891 -22.215454) (xy 158.051804 -22.162874) (xy 158.051096 -22.109681)
			(xy 158.05778 -22.056904) (xy 158.071727 -22.005567) (xy 158.092667 -21.956664) (xy 158.120195 -21.911142)
			(xy 158.153776 -21.869883) (xy 158.192761 -21.833686) (xy 158.214314 -21.818092) (xy 158.232661 -21.804734)
			(xy 158.264667 -21.772563) (xy 158.290458 -21.735224) (xy 158.309214 -21.693901) (xy 158.320339 -21.649906)
			(xy 158.323482 -21.604635) (xy 158.318542 -21.559524) (xy 158.305676 -21.516006) (xy 158.285292 -21.475462)
			(xy 158.258037 -21.439178) (xy 158.241746 -21.423376) (xy 158.222112 -21.404489) (xy 158.187834 -21.362145)
			(xy 158.159929 -21.315356) (xy 158.138965 -21.265073) (xy 158.125367 -21.212319) (xy 158.119412 -21.158167)
			(xy 158.121222 -21.103718) (xy 158.13076 -21.050081) (xy 158.147831 -20.998346) (xy 158.172089 -20.949566)
			(xy 158.203039 -20.904733) (xy 158.240053 -20.86476) (xy 158.282377 -20.830458) (xy 158.32915 -20.802527)
			(xy 158.379422 -20.781534) (xy 158.432168 -20.767906) (xy 158.486317 -20.761921) (xy 158.540766 -20.7637)
			(xy 158.594409 -20.773207) (xy 158.646154 -20.790249) (xy 158.694947 -20.814479) (xy 158.739798 -20.845404)
			(xy 158.779792 -20.882395) (xy 158.814118 -20.924699) (xy 158.842076 -20.971457) (xy 158.863097 -21.021716)
			(xy 158.870396 -21.047964) (xy 158.876796 -21.070546) (xy 158.89669 -21.113051) (xy 158.924053 -21.151179)
			(xy 158.957953 -21.183632) (xy 158.997237 -21.209308) (xy 159.040569 -21.227331) (xy 159.086473 -21.237089)
			(xy 159.109918 -21.23821) (xy 159.13726 -21.239356) (xy 159.191214 -21.248507) (xy 159.243307 -21.265272)
			(xy 159.292471 -21.289306) (xy 159.337697 -21.320116) (xy 159.378059 -21.357071) (xy 159.412728 -21.399413)
			(xy 159.440993 -21.446272) (xy 159.462275 -21.496689) (xy 159.476137 -21.549628) (xy 159.482294 -21.604005)
			(xy 159.480621 -21.658703) (xy 159.471151 -21.712602) (xy 159.462855 -21.737868) (xy 170.990949 -21.737868)
			(xy 170.995517 -21.558362) (xy 171.008117 -21.37924) (xy 171.028726 -21.200862) (xy 171.057302 -21.023586)
			(xy 171.093787 -20.847767) (xy 171.138108 -20.673758) (xy 171.190177 -20.501909) (xy 171.249888 -20.332563)
			(xy 171.317123 -20.166061) (xy 171.391745 -20.002737) (xy 171.473606 -19.842918) (xy 171.562542 -19.686924)
			(xy 171.658373 -19.53507) (xy 171.760908 -19.387659) (xy 171.869941 -19.244987) (xy 171.985253 -19.107341)
			(xy 172.106613 -18.974996) (xy 172.233777 -18.848218) (xy 172.36649 -18.727261) (xy 172.504487 -18.612368)
			(xy 172.64749 -18.50377) (xy 172.795212 -18.401684) (xy 172.947358 -18.306316) (xy 173.103621 -18.217855)
			(xy 173.263688 -18.136481) (xy 173.427239 -18.062355) (xy 173.593945 -17.995628) (xy 173.763471 -17.936432)
			(xy 173.935478 -17.884886) (xy 174.109621 -17.841095) (xy 174.28555 -17.805145) (xy 174.462912 -17.777109)
			(xy 174.641352 -17.757043) (xy 174.820512 -17.744987) (xy 175.000031 -17.740966) (xy 175.17955 -17.744987)
			(xy 175.35871 -17.757043) (xy 175.53715 -17.777109) (xy 175.714512 -17.805145) (xy 175.890441 -17.841095)
			(xy 176.064584 -17.884886) (xy 176.236591 -17.936432) (xy 176.406117 -17.995628) (xy 176.572823 -18.062355)
			(xy 176.736374 -18.136481) (xy 176.896441 -18.217855) (xy 177.052704 -18.306316) (xy 177.20485 -18.401684)
			(xy 177.352572 -18.50377) (xy 177.495575 -18.612368) (xy 177.633572 -18.727261) (xy 177.766285 -18.848218)
			(xy 177.893449 -18.974996) (xy 178.014809 -19.107341) (xy 178.069335 -19.172428) (xy 179.038502 -19.172428)
			(xy 179.042573 -19.116806) (xy 179.054699 -19.062369) (xy 179.074622 -19.010278) (xy 179.101918 -18.961643)
			(xy 179.136004 -18.9175) (xy 179.176153 -18.878791) (xy 179.221511 -18.84634) (xy 179.271111 -18.820839)
			(xy 179.323895 -18.802832) (xy 179.378738 -18.792702) (xy 179.434472 -18.790665) (xy 179.489909 -18.796765)
			(xy 179.543866 -18.810871) (xy 179.595195 -18.832683) (xy 179.642801 -18.861737) (xy 179.685669 -18.897412)
			(xy 179.722886 -18.938949) (xy 179.753659 -18.985462) (xy 179.777331 -19.035959) (xy 179.793399 -19.089366)
			(xy 179.801519 -19.144542) (xy 179.802028 -19.172428) (xy 179.801519 -19.200314) (xy 179.793399 -19.25549)
			(xy 179.777331 -19.308897) (xy 179.753659 -19.359394) (xy 179.722886 -19.405907) (xy 179.685669 -19.447444)
			(xy 179.642801 -19.483119) (xy 179.595195 -19.512173) (xy 179.543866 -19.533985) (xy 179.489909 -19.548091)
			(xy 179.434472 -19.554191) (xy 179.378738 -19.552154) (xy 179.323895 -19.542024) (xy 179.271111 -19.524017)
			(xy 179.221511 -19.498516) (xy 179.176153 -19.466065) (xy 179.136004 -19.427356) (xy 179.101918 -19.383213)
			(xy 179.074622 -19.334578) (xy 179.054699 -19.282487) (xy 179.042573 -19.22805) (xy 179.038502 -19.172428)
			(xy 178.069335 -19.172428) (xy 178.130121 -19.244987) (xy 178.239154 -19.387659) (xy 178.341689 -19.53507)
			(xy 178.43752 -19.686924) (xy 178.526456 -19.842918) (xy 178.608317 -20.002737) (xy 178.682939 -20.166061)
			(xy 178.750174 -20.332563) (xy 178.809885 -20.501909) (xy 178.861954 -20.673758) (xy 178.906275 -20.847767)
			(xy 178.94276 -21.023586) (xy 178.971336 -21.200862) (xy 178.991945 -21.37924) (xy 179.004545 -21.558362)
			(xy 179.009113 -21.737868) (xy 179.005638 -21.917399) (xy 178.994127 -22.096594) (xy 178.974604 -22.275094)
			(xy 178.947108 -22.452541) (xy 178.911693 -22.628579) (xy 178.868432 -22.802854) (xy 178.81741 -22.975017)
			(xy 178.75873 -23.144723) (xy 178.69251 -23.311631) (xy 178.618882 -23.475406) (xy 178.537995 -23.635721)
			(xy 178.450011 -23.792252) (xy 178.355105 -23.944687) (xy 178.253469 -24.092719) (xy 178.145307 -24.236052)
			(xy 178.030835 -24.374398) (xy 177.910282 -24.507478) (xy 177.783892 -24.635028) (xy 177.651917 -24.75679)
			(xy 177.583592 -24.815038) (xy 177.560523 -24.835116) (xy 177.518994 -24.880011) (xy 177.483362 -24.929715)
			(xy 177.454178 -24.98346) (xy 177.431893 -25.040412) (xy 177.416853 -25.099691) (xy 177.40929 -25.160379)
			(xy 177.40884 -25.190958) (xy 177.40884 -26.75001) (xy 177.408349 -26.818806) (xy 177.400494 -26.956175)
			(xy 177.392849 -27.022806) (xy 179.483002 -27.022806) (xy 179.487073 -26.967184) (xy 179.499199 -26.912747)
			(xy 179.519122 -26.860656) (xy 179.546418 -26.812021) (xy 179.580504 -26.767878) (xy 179.620653 -26.729169)
			(xy 179.666011 -26.696718) (xy 179.715611 -26.671217) (xy 179.768395 -26.65321) (xy 179.823238 -26.64308)
			(xy 179.878972 -26.641043) (xy 179.934409 -26.647143) (xy 179.988366 -26.661249) (xy 180.039695 -26.683061)
			(xy 180.087301 -26.712115) (xy 180.130169 -26.74779) (xy 180.167386 -26.789327) (xy 180.198159 -26.83584)
			(xy 180.221831 -26.886337) (xy 180.237899 -26.939744) (xy 180.246019 -26.99492) (xy 180.246528 -27.022806)
			(xy 180.246019 -27.050692) (xy 180.237899 -27.105868) (xy 180.221831 -27.159275) (xy 180.198159 -27.209772)
			(xy 180.167386 -27.256285) (xy 180.130169 -27.297822) (xy 180.087301 -27.333497) (xy 180.039695 -27.362551)
			(xy 179.988366 -27.384363) (xy 179.934409 -27.398469) (xy 179.878972 -27.404569) (xy 179.823238 -27.402532)
			(xy 179.768395 -27.392402) (xy 179.715611 -27.374395) (xy 179.666011 -27.348894) (xy 179.620653 -27.316443)
			(xy 179.580504 -27.277734) (xy 179.546418 -27.233591) (xy 179.519122 -27.184956) (xy 179.499199 -27.132865)
			(xy 179.487073 -27.078428) (xy 179.483002 -27.022806) (xy 177.392849 -27.022806) (xy 177.38481 -27.092871)
			(xy 177.361347 -27.228449) (xy 177.330183 -27.362466) (xy 177.291418 -27.494486) (xy 177.24518 -27.624077)
			(xy 177.191619 -27.750817) (xy 177.178803 -27.776883) (xy 184.062728 -27.776883) (xy 184.065306 -27.720639)
			(xy 184.076121 -27.665386) (xy 184.094941 -27.612322) (xy 184.121355 -27.5626) (xy 184.154791 -27.517301)
			(xy 184.194521 -27.477408) (xy 184.216802 -27.460194) (xy 184.235329 -27.445777) (xy 184.267196 -27.411313)
			(xy 184.292193 -27.371583) (xy 184.309467 -27.327937) (xy 184.318432 -27.281862) (xy 184.318783 -27.234924)
			(xy 184.310507 -27.188719) (xy 184.293886 -27.144821) (xy 184.269486 -27.104721) (xy 184.238137 -27.069785)
			(xy 184.21985 -27.055064) (xy 184.197923 -27.037636) (xy 184.158972 -26.997385) (xy 184.126323 -26.951872)
			(xy 184.100679 -26.902075) (xy 184.08259 -26.849065) (xy 184.072446 -26.793979) (xy 184.070463 -26.738003)
			(xy 184.076684 -26.682337) (xy 184.090977 -26.62818) (xy 184.113033 -26.576693) (xy 184.142379 -26.528985)
			(xy 184.178385 -26.486079) (xy 184.220276 -26.448897) (xy 184.267152 -26.418239) (xy 184.318007 -26.394763)
			(xy 184.371748 -26.378975) (xy 184.427219 -26.371212) (xy 184.483229 -26.371641) (xy 184.538575 -26.380255)
			(xy 184.592067 -26.396866) (xy 184.642555 -26.42112) (xy 184.688956 -26.452493) (xy 184.730271 -26.490313)
			(xy 184.765614 -26.533767) (xy 184.794225 -26.58192) (xy 184.815488 -26.633739) (xy 184.828948 -26.68811)
			(xy 184.834315 -26.743864) (xy 184.831473 -26.799803) (xy 184.820484 -26.854727) (xy 184.801584 -26.907454)
			(xy 184.775179 -26.956851) (xy 184.741836 -27.001857) (xy 184.702272 -27.041505) (xy 184.680098 -27.05862)
			(xy 184.661558 -27.07302) (xy 184.62969 -27.107487) (xy 184.604694 -27.14722) (xy 184.58742 -27.190868)
			(xy 184.578456 -27.236946) (xy 184.578107 -27.283886) (xy 184.586385 -27.330092) (xy 184.603007 -27.373992)
			(xy 184.62741 -27.414092) (xy 184.658762 -27.449029) (xy 184.67705 -27.46375) (xy 184.698872 -27.481121)
			(xy 184.73769 -27.521173) (xy 184.770262 -27.56645) (xy 184.795893 -27.615988) (xy 184.814038 -27.668729)
			(xy 184.824309 -27.723551) (xy 184.826488 -27.779285) (xy 184.82579 -27.785774) (xy 187.227584 -27.785774)
			(xy 187.230162 -27.729532) (xy 187.240977 -27.67428) (xy 187.259795 -27.621217) (xy 187.286206 -27.571495)
			(xy 187.319638 -27.526195) (xy 187.359364 -27.4863) (xy 187.381642 -27.469084) (xy 187.400176 -27.454678)
			(xy 187.432039 -27.42021) (xy 187.457031 -27.380477) (xy 187.474302 -27.336831) (xy 187.483265 -27.290756)
			(xy 187.483615 -27.243818) (xy 187.475339 -27.197614) (xy 187.45872 -27.153715) (xy 187.434322 -27.113615)
			(xy 187.402975 -27.078677) (xy 187.38469 -27.063954) (xy 187.362812 -27.046467) (xy 187.323871 -27.006216)
			(xy 187.291233 -26.960704) (xy 187.265599 -26.91091) (xy 187.24752 -26.857903) (xy 187.237383 -26.802823)
			(xy 187.235408 -26.746853) (xy 187.241637 -26.691195) (xy 187.255935 -26.637046) (xy 187.277995 -26.585569)
			(xy 187.307344 -26.53787) (xy 187.343351 -26.494973) (xy 187.385242 -26.457802) (xy 187.432117 -26.427154)
			(xy 187.482968 -26.403687) (xy 187.536704 -26.387907) (xy 187.59217 -26.380152) (xy 187.648173 -26.380589)
			(xy 187.703511 -26.389208) (xy 187.756994 -26.405824) (xy 187.807474 -26.430081) (xy 187.853865 -26.461457)
			(xy 187.895171 -26.499277) (xy 187.930504 -26.542729) (xy 187.959106 -26.590881) (xy 187.980361 -26.642696)
			(xy 187.993812 -26.697061) (xy 187.999172 -26.752809) (xy 187.996324 -26.808742) (xy 187.98533 -26.863657)
			(xy 187.966426 -26.916375) (xy 187.940019 -26.965764) (xy 187.906675 -27.010761) (xy 187.879701 -27.037786)
			(xy 193.316271 -27.037786) (xy 193.323371 -26.982291) (xy 193.3385 -26.928427) (xy 193.361332 -26.87735)
			(xy 193.391379 -26.830156) (xy 193.409316 -26.808684) (xy 193.423608 -26.791583) (xy 193.446471 -26.753328)
			(xy 193.462305 -26.711669) (xy 193.470623 -26.667886) (xy 193.471169 -26.623323) (xy 193.463927 -26.579349)
			(xy 193.449119 -26.537314) (xy 193.4272 -26.498511) (xy 193.41338 -26.481024) (xy 193.396019 -26.459087)
			(xy 193.367181 -26.411151) (xy 193.345652 -26.359517) (xy 193.331895 -26.305294) (xy 193.326203 -26.249642)
			(xy 193.328699 -26.193756) (xy 193.339329 -26.138834) (xy 193.357866 -26.086052) (xy 193.383912 -26.036544)
			(xy 193.416908 -25.991369) (xy 193.456148 -25.951498) (xy 193.500789 -25.917784) (xy 193.549875 -25.89095)
			(xy 193.602354 -25.871572) (xy 193.6571 -25.860066) (xy 193.712939 -25.856677) (xy 193.768674 -25.861479)
			(xy 193.823111 -25.874368) (xy 193.875081 -25.895069) (xy 193.923472 -25.923137) (xy 193.967245 -25.957971)
			(xy 194.005462 -25.998824) (xy 194.037304 -26.044819) (xy 194.062088 -26.094972) (xy 194.079282 -26.148206)
			(xy 194.088518 -26.20338) (xy 194.089597 -26.259311) (xy 194.082498 -26.314801) (xy 194.067371 -26.368659)
			(xy 194.044542 -26.41973) (xy 194.014499 -26.46692) (xy 193.996564 -26.48839) (xy 193.982298 -26.505511)
			(xy 193.959435 -26.543762) (xy 193.9436 -26.585417) (xy 193.93528 -26.629196) (xy 193.934731 -26.673756)
			(xy 193.941968 -26.717727) (xy 193.956771 -26.75976) (xy 193.978684 -26.798563) (xy 193.9925 -26.81605)
			(xy 194.009889 -26.837968) (xy 194.038734 -26.885907) (xy 194.060269 -26.937544) (xy 194.074032 -26.991773)
			(xy 194.079728 -27.04743) (xy 194.077236 -27.103322) (xy 194.066608 -27.158251) (xy 194.048073 -27.211039)
			(xy 194.022027 -27.260555) (xy 193.98903 -27.305736) (xy 193.949788 -27.345614) (xy 193.905143 -27.379334)
			(xy 193.856053 -27.406172) (xy 193.80357 -27.425554) (xy 193.748819 -27.437064) (xy 193.692974 -27.440455)
			(xy 193.637233 -27.435655) (xy 193.58279 -27.422766) (xy 193.530813 -27.402064) (xy 193.482416 -27.373994)
			(xy 193.438638 -27.339157) (xy 193.400416 -27.298301) (xy 193.36857 -27.252301) (xy 193.343784 -27.202143)
			(xy 193.326587 -27.148904) (xy 193.31735 -27.093724) (xy 193.316271 -27.037786) (xy 187.879701 -27.037786)
			(xy 187.867111 -27.0504) (xy 187.844938 -27.06751) (xy 187.826411 -27.081924) (xy 187.79455 -27.116391)
			(xy 187.76956 -27.156123) (xy 187.75229 -27.199768) (xy 187.743328 -27.245842) (xy 187.742978 -27.292778)
			(xy 187.751252 -27.33898) (xy 187.767869 -27.382878) (xy 187.792263 -27.422978) (xy 187.823606 -27.457917)
			(xy 187.84189 -27.47264) (xy 187.8637 -27.490027) (xy 187.902522 -27.530074) (xy 187.935099 -27.575348)
			(xy 187.960734 -27.624883) (xy 187.978882 -27.677624) (xy 187.989155 -27.732446) (xy 187.991335 -27.788179)
			(xy 187.985375 -27.843635) (xy 187.971402 -27.897632) (xy 187.949714 -27.949019) (xy 187.920773 -27.996699)
			(xy 187.903358 -28.018486) (xy 187.889653 -28.035682) (xy 187.867848 -28.073864) (xy 187.85294 -28.11523)
			(xy 187.845376 -28.158544) (xy 187.845381 -28.202514) (xy 187.852955 -28.245827) (xy 187.867872 -28.287189)
			(xy 187.889687 -28.325366) (xy 187.903358 -28.34259) (xy 187.920734 -28.36437) (xy 187.949648 -28.411995)
			(xy 187.971327 -28.463319) (xy 187.985311 -28.517251) (xy 187.991302 -28.572643) (xy 187.989174 -28.628317)
			(xy 187.97897 -28.68309) (xy 187.960909 -28.735796) (xy 187.935374 -28.785315) (xy 187.902908 -28.830594)
			(xy 187.864203 -28.870669) (xy 187.82008 -28.904689) (xy 187.771478 -28.931929) (xy 187.719432 -28.951812)
			(xy 187.665047 -28.963913) (xy 187.60948 -28.967975) (xy 187.553913 -28.963913) (xy 187.499528 -28.951812)
			(xy 187.447482 -28.931929) (xy 187.39888 -28.904689) (xy 187.354757 -28.870669) (xy 187.316052 -28.830594)
			(xy 187.283586 -28.785315) (xy 187.258051 -28.735796) (xy 187.23999 -28.68309) (xy 187.229786 -28.628317)
			(xy 187.227658 -28.572643) (xy 187.233649 -28.517251) (xy 187.247633 -28.463319) (xy 187.269312 -28.411995)
			(xy 187.298226 -28.36437) (xy 187.315602 -28.34259) (xy 187.32923 -28.325337) (xy 187.351036 -28.287167)
			(xy 187.365946 -28.245812) (xy 187.373517 -28.202509) (xy 187.373522 -28.158549) (xy 187.365961 -28.115244)
			(xy 187.35106 -28.073887) (xy 187.329264 -28.035711) (xy 187.315602 -28.018486) (xy 187.298083 -27.996444)
			(xy 187.268936 -27.948275) (xy 187.247184 -27.896346) (xy 187.233299 -27.841784) (xy 187.227584 -27.785774)
			(xy 184.82579 -27.785774) (xy 184.820527 -27.834741) (xy 184.806555 -27.888738) (xy 184.784869 -27.940126)
			(xy 184.755931 -27.987807) (xy 184.738518 -28.009596) (xy 184.724806 -28.026785) (xy 184.703004 -28.06497)
			(xy 184.6881 -28.106337) (xy 184.680538 -28.149652) (xy 184.680544 -28.193622) (xy 184.688119 -28.236935)
			(xy 184.703035 -28.278297) (xy 184.724848 -28.316475) (xy 184.738518 -28.3337) (xy 184.755894 -28.35548)
			(xy 184.784808 -28.403105) (xy 184.806487 -28.454429) (xy 184.820471 -28.508361) (xy 184.826462 -28.563753)
			(xy 184.824334 -28.619427) (xy 184.81413 -28.6742) (xy 184.796069 -28.726906) (xy 184.770534 -28.776425)
			(xy 184.738068 -28.821704) (xy 184.699363 -28.861779) (xy 184.65524 -28.895799) (xy 184.606638 -28.923039)
			(xy 184.554592 -28.942922) (xy 184.500207 -28.955023) (xy 184.44464 -28.959085) (xy 184.389073 -28.955023)
			(xy 184.334688 -28.942922) (xy 184.282642 -28.923039) (xy 184.23404 -28.895799) (xy 184.189917 -28.861779)
			(xy 184.151212 -28.821704) (xy 184.118746 -28.776425) (xy 184.093211 -28.726906) (xy 184.07515 -28.6742)
			(xy 184.064946 -28.619427) (xy 184.062818 -28.563753) (xy 184.068809 -28.508361) (xy 184.082793 -28.454429)
			(xy 184.104472 -28.403105) (xy 184.133386 -28.35548) (xy 184.150762 -28.3337) (xy 184.164383 -28.316441)
			(xy 184.186192 -28.278272) (xy 184.201106 -28.23692) (xy 184.208679 -28.193617) (xy 184.208685 -28.149657)
			(xy 184.201125 -28.106352) (xy 184.186223 -28.064995) (xy 184.164425 -28.02682) (xy 184.150762 -28.009596)
			(xy 184.133243 -27.987553) (xy 184.10409 -27.939386) (xy 184.082334 -27.887457) (xy 184.068446 -27.832894)
			(xy 184.062728 -27.776883) (xy 177.178803 -27.776883) (xy 177.13091 -27.874293) (xy 177.063251 -27.994101)
			(xy 176.988863 -28.109852) (xy 176.907988 -28.221167) (xy 176.82089 -28.327683) (xy 176.727853 -28.429054)
			(xy 176.629181 -28.524947) (xy 176.525195 -28.615051) (xy 176.416235 -28.699072) (xy 176.302656 -28.776736)
			(xy 176.184828 -28.847788) (xy 176.063136 -28.911999) (xy 175.937977 -28.969157) (xy 175.809759 -29.019076)
			(xy 175.678901 -29.061595) (xy 175.545828 -29.096574) (xy 175.410976 -29.123898) (xy 175.274783 -29.14348)
			(xy 175.137695 -29.155254) (xy 175.000158 -29.159184) (xy 174.862621 -29.155254) (xy 174.725533 -29.14348)
			(xy 174.58934 -29.123898) (xy 174.454488 -29.096574) (xy 174.321415 -29.061595) (xy 174.190557 -29.019076)
			(xy 174.062339 -28.969157) (xy 173.93718 -28.911999) (xy 173.815488 -28.847788) (xy 173.69766 -28.776736)
			(xy 173.584081 -28.699072) (xy 173.475121 -28.615051) (xy 173.371135 -28.524947) (xy 173.272463 -28.429054)
			(xy 173.179426 -28.327683) (xy 173.092328 -28.221167) (xy 173.011453 -28.109852) (xy 172.937065 -27.994101)
			(xy 172.869406 -27.874293) (xy 172.808697 -27.750817) (xy 172.755136 -27.624077) (xy 172.708898 -27.494486)
			(xy 172.670133 -27.362466) (xy 172.638969 -27.228449) (xy 172.615506 -27.092871) (xy 172.599822 -26.956175)
			(xy 172.591967 -26.818806) (xy 172.591476 -26.75001) (xy 172.591476 -25.190958) (xy 172.590958 -25.160375)
			(xy 172.583343 -25.099683) (xy 172.568261 -25.040405) (xy 172.545945 -24.983454) (xy 172.51674 -24.929709)
			(xy 172.481095 -24.880001) (xy 172.439561 -24.835097) (xy 172.41647 -24.815038) (xy 172.348145 -24.75679)
			(xy 172.21617 -24.635028) (xy 172.08978 -24.507478) (xy 171.969227 -24.374398) (xy 171.854755 -24.236052)
			(xy 171.746593 -24.092719) (xy 171.644957 -23.944687) (xy 171.550051 -23.792252) (xy 171.462067 -23.635721)
			(xy 171.38118 -23.475406) (xy 171.307552 -23.311631) (xy 171.241332 -23.144723) (xy 171.182652 -22.975017)
			(xy 171.13163 -22.802854) (xy 171.088369 -22.628579) (xy 171.052954 -22.452541) (xy 171.025458 -22.275094)
			(xy 171.005935 -22.096594) (xy 170.994424 -21.917399) (xy 170.990949 -21.737868) (xy 159.462855 -21.737868)
			(xy 159.454079 -21.764595) (xy 159.429756 -21.813617) (xy 159.398679 -21.858661) (xy 159.380428 -21.879052)
			(xy 159.364649 -21.896796) (xy 159.33943 -21.937025) (xy 159.322117 -21.981236) (xy 159.31331 -22.027893)
			(xy 159.313316 -22.075373) (xy 159.322135 -22.122027) (xy 159.33946 -22.166234) (xy 159.364689 -22.206457)
			(xy 159.380428 -22.224238) (xy 159.398475 -22.244296) (xy 159.429208 -22.288645) (xy 159.453382 -22.336885)
			(xy 159.470515 -22.38805) (xy 159.480265 -22.441119) (xy 159.482436 -22.495033) (xy 159.476985 -22.548714)
			(xy 159.464022 -22.601091) (xy 159.443804 -22.651118) (xy 159.416737 -22.697795) (xy 159.383359 -22.740191)
			(xy 159.364172 -22.759162) (xy 159.347326 -22.775999) (xy 159.31963 -22.814739) (xy 159.299633 -22.857959)
			(xy 159.288033 -22.904147) (xy 159.285237 -22.951687) (xy 159.291343 -22.998917) (xy 159.306137 -23.044183)
			(xy 159.329101 -23.085903) (xy 159.343852 -23.104602) (xy 159.360644 -23.125577) (xy 159.388711 -23.171395)
			(xy 159.410071 -23.220698) (xy 159.424301 -23.272511) (xy 159.431118 -23.325808) (xy 159.430389 -23.379534)
			(xy 159.422127 -23.432626) (xy 159.406497 -23.484034) (xy 159.383807 -23.532739) (xy 159.354506 -23.577778)
			(xy 159.319176 -23.61826) (xy 159.278513 -23.653383) (xy 159.233325 -23.682452) (xy 159.184504 -23.704892)
			(xy 159.133017 -23.720259) (xy 159.079883 -23.728248) (xy 159.053022 -23.728934) (xy 159.031715 -23.729567)
			(xy 158.98975 -23.737037) (xy 158.94962 -23.751403) (xy 158.912448 -23.772263) (xy 158.879277 -23.79903)
			(xy 158.851036 -23.830956) (xy 158.839408 -23.848822) (xy 158.831732 -23.862011) (xy 158.822289 -23.891022)
			(xy 158.820008 -23.921446) (xy 158.825019 -23.95154) (xy 158.837034 -23.979584) (xy 158.855367 -24.00397)
			(xy 158.878968 -24.023304) (xy 158.906485 -24.036479) (xy 158.936345 -24.042741) (xy 158.966837 -24.041731)
			(xy 158.981648 -24.038052) (xy 159.008109 -24.030983) (xy 159.06241 -24.023807) (xy 159.11718 -24.024467)
			(xy 159.171292 -24.03295) (xy 159.223636 -24.049081) (xy 159.273137 -24.072529) (xy 159.318777 -24.102813)
			(xy 159.359619 -24.13931) (xy 159.394825 -24.181271) (xy 159.42367 -24.227833) (xy 159.445563 -24.278041)
			(xy 159.460054 -24.330862) (xy 159.466845 -24.385213) (xy 159.465797 -24.439976) (xy 159.456931 -24.494028)
			(xy 159.440429 -24.546256) (xy 159.416631 -24.595589) (xy 159.386025 -24.641014) (xy 159.367982 -24.661622)
			(xy 159.353599 -24.67828) (xy 159.330112 -24.715491) (xy 159.313382 -24.75619) (xy 159.303908 -24.799162)
			(xy 159.301973 -24.843122) (xy 159.307634 -24.88676) (xy 159.320723 -24.928772) (xy 159.340849 -24.967903)
			(xy 159.353758 -24.985726) (xy 159.370136 -25.008263) (xy 159.396961 -25.057087) (xy 159.416399 -25.109294)
			(xy 159.428035 -25.163774) (xy 159.431623 -25.219366) (xy 159.427085 -25.274889) (xy 159.414519 -25.329162)
			(xy 159.394191 -25.381029) (xy 159.366535 -25.429387) (xy 159.332138 -25.473208) (xy 159.291733 -25.511559)
			(xy 159.246178 -25.543624) (xy 159.196444 -25.568721) (xy 159.143587 -25.586317) (xy 159.088734 -25.596037)
			(xy 159.033049 -25.597673) (xy 158.97772 -25.591193) (xy 158.923921 -25.576732) (xy 158.872798 -25.554599)
			(xy 158.825439 -25.525264) (xy 158.782851 -25.489353) (xy 158.74594 -25.447628) (xy 158.715491 -25.400978)
			(xy 158.692152 -25.350394) (xy 158.67642 -25.296953) (xy 158.672022 -25.269444) (xy 158.668327 -25.246411)
			(xy 158.653511 -25.202181) (xy 158.630871 -25.161397) (xy 158.601168 -25.125431) (xy 158.5654 -25.095489)
			(xy 158.524768 -25.072578) (xy 158.480638 -25.057467) (xy 158.43449 -25.050664) (xy 158.411164 -25.051004)
			(xy 158.383811 -25.05164) (xy 158.329404 -25.045841) (xy 158.276383 -25.032329) (xy 158.225836 -25.011383)
			(xy 158.178799 -24.983431) (xy 158.136237 -24.949046) (xy 158.099023 -24.908935) (xy 158.06792 -24.86392)
			(xy 158.043566 -24.814923) (xy 158.026461 -24.76295) (xy 158.016955 -24.709066) (xy 158.015243 -24.654378)
			(xy 154.824562 -24.654378) (xy 152.128728 -27.350212) (xy 154.695904 -27.350212) (xy 154.699975 -27.29459)
			(xy 154.712101 -27.240153) (xy 154.732024 -27.188062) (xy 154.75932 -27.139427) (xy 154.793406 -27.095284)
			(xy 154.833555 -27.056575) (xy 154.878913 -27.024124) (xy 154.928513 -26.998623) (xy 154.981297 -26.980616)
			(xy 155.03614 -26.970486) (xy 155.091874 -26.968449) (xy 155.147311 -26.974549) (xy 155.201268 -26.988655)
			(xy 155.252597 -27.010467) (xy 155.300203 -27.039521) (xy 155.30545 -27.043888) (xy 170.257722 -27.043888)
			(xy 170.261793 -26.988266) (xy 170.273919 -26.933829) (xy 170.293842 -26.881738) (xy 170.321138 -26.833103)
			(xy 170.355224 -26.78896) (xy 170.395373 -26.750251) (xy 170.440731 -26.7178) (xy 170.490331 -26.692299)
			(xy 170.543115 -26.674292) (xy 170.597958 -26.664162) (xy 170.653692 -26.662125) (xy 170.709129 -26.668225)
			(xy 170.763086 -26.682331) (xy 170.814415 -26.704143) (xy 170.862021 -26.733197) (xy 170.904889 -26.768872)
			(xy 170.942106 -26.810409) (xy 170.972879 -26.856922) (xy 170.996551 -26.907419) (xy 171.012619 -26.960826)
			(xy 171.020739 -27.016002) (xy 171.021248 -27.043888) (xy 171.020739 -27.071774) (xy 171.012619 -27.12695)
			(xy 170.996551 -27.180357) (xy 170.972879 -27.230854) (xy 170.942106 -27.277367) (xy 170.904889 -27.318904)
			(xy 170.862021 -27.354579) (xy 170.814415 -27.383633) (xy 170.763086 -27.405445) (xy 170.709129 -27.419551)
			(xy 170.653692 -27.425651) (xy 170.597958 -27.423614) (xy 170.543115 -27.413484) (xy 170.490331 -27.395477)
			(xy 170.440731 -27.369976) (xy 170.395373 -27.337525) (xy 170.355224 -27.298816) (xy 170.321138 -27.254673)
			(xy 170.293842 -27.206038) (xy 170.273919 -27.153947) (xy 170.261793 -27.09951) (xy 170.257722 -27.043888)
			(xy 155.30545 -27.043888) (xy 155.343071 -27.075196) (xy 155.380288 -27.116733) (xy 155.411061 -27.163246)
			(xy 155.434733 -27.213743) (xy 155.450801 -27.26715) (xy 155.458921 -27.322326) (xy 155.45943 -27.350212)
			(xy 155.458921 -27.378098) (xy 155.450801 -27.433274) (xy 155.434733 -27.486681) (xy 155.411061 -27.537178)
			(xy 155.380288 -27.583691) (xy 155.343071 -27.625228) (xy 155.300203 -27.660903) (xy 155.293208 -27.665172)
			(xy 156.748224 -27.665172) (xy 156.752295 -27.60955) (xy 156.764421 -27.555113) (xy 156.784344 -27.503022)
			(xy 156.81164 -27.454387) (xy 156.845726 -27.410244) (xy 156.885875 -27.371535) (xy 156.931233 -27.339084)
			(xy 156.980833 -27.313583) (xy 157.033617 -27.295576) (xy 157.08846 -27.285446) (xy 157.144194 -27.283409)
			(xy 157.199631 -27.289509) (xy 157.253588 -27.303615) (xy 157.304917 -27.325427) (xy 157.352523 -27.354481)
			(xy 157.395391 -27.390156) (xy 157.432608 -27.431693) (xy 157.463381 -27.478206) (xy 157.487053 -27.528703)
			(xy 157.503121 -27.58211) (xy 157.511241 -27.637286) (xy 157.51175 -27.665172) (xy 157.511241 -27.693058)
			(xy 157.503121 -27.748234) (xy 157.487053 -27.801641) (xy 157.463381 -27.852138) (xy 157.432608 -27.898651)
			(xy 157.395391 -27.940188) (xy 157.352523 -27.975863) (xy 157.304917 -28.004917) (xy 157.253588 -28.026729)
			(xy 157.199631 -28.040835) (xy 157.144194 -28.046935) (xy 157.08846 -28.044898) (xy 157.033617 -28.034768)
			(xy 156.980833 -28.016761) (xy 156.931233 -27.99126) (xy 156.885875 -27.958809) (xy 156.845726 -27.9201)
			(xy 156.81164 -27.875957) (xy 156.784344 -27.827322) (xy 156.764421 -27.775231) (xy 156.752295 -27.720794)
			(xy 156.748224 -27.665172) (xy 155.293208 -27.665172) (xy 155.252597 -27.689957) (xy 155.201268 -27.711769)
			(xy 155.147311 -27.725875) (xy 155.091874 -27.731975) (xy 155.03614 -27.729938) (xy 154.981297 -27.719808)
			(xy 154.928513 -27.701801) (xy 154.878913 -27.6763) (xy 154.833555 -27.643849) (xy 154.793406 -27.60514)
			(xy 154.75932 -27.560997) (xy 154.732024 -27.512362) (xy 154.712101 -27.460271) (xy 154.699975 -27.405834)
			(xy 154.695904 -27.350212) (xy 152.128728 -27.350212) (xy 151.26462 -28.21432) (xy 149.678898 -28.21432)
			(xy 149.664458 -28.215678) (xy 149.636707 -28.224086) (xy 149.611566 -28.238534) (xy 149.600666 -28.248102)
			(xy 149.256496 -28.592272) (xy 152.047954 -28.592272) (xy 152.052025 -28.53665) (xy 152.064151 -28.482213)
			(xy 152.084074 -28.430122) (xy 152.11137 -28.381487) (xy 152.145456 -28.337344) (xy 152.185605 -28.298635)
			(xy 152.230963 -28.266184) (xy 152.280563 -28.240683) (xy 152.333347 -28.222676) (xy 152.38819 -28.212546)
			(xy 152.443924 -28.210509) (xy 152.499361 -28.216609) (xy 152.553318 -28.230715) (xy 152.604647 -28.252527)
			(xy 152.652253 -28.281581) (xy 152.695121 -28.317256) (xy 152.732338 -28.358793) (xy 152.763111 -28.405306)
			(xy 152.786783 -28.455803) (xy 152.802851 -28.50921) (xy 152.810971 -28.564386) (xy 152.81148 -28.592272)
			(xy 152.810971 -28.620158) (xy 152.802851 -28.675334) (xy 152.786783 -28.728741) (xy 152.763111 -28.779238)
			(xy 152.732338 -28.825751) (xy 152.695121 -28.867288) (xy 152.652253 -28.902963) (xy 152.604647 -28.932017)
			(xy 152.553318 -28.953829) (xy 152.499361 -28.967935) (xy 152.460092 -28.972256) (xy 156.570932 -28.972256)
			(xy 156.575003 -28.916634) (xy 156.587129 -28.862197) (xy 156.607052 -28.810106) (xy 156.634348 -28.761471)
			(xy 156.668434 -28.717328) (xy 156.708583 -28.678619) (xy 156.753941 -28.646168) (xy 156.803541 -28.620667)
			(xy 156.856325 -28.60266) (xy 156.911168 -28.59253) (xy 156.966902 -28.590493) (xy 157.022339 -28.596593)
			(xy 157.076296 -28.610699) (xy 157.127625 -28.632511) (xy 157.175231 -28.661565) (xy 157.218099 -28.69724)
			(xy 157.255316 -28.738777) (xy 157.286089 -28.78529) (xy 157.309761 -28.835787) (xy 157.325829 -28.889194)
			(xy 157.333949 -28.94437) (xy 157.334458 -28.972256) (xy 157.333949 -29.000142) (xy 157.325829 -29.055318)
			(xy 157.309761 -29.108725) (xy 157.286089 -29.159222) (xy 157.255316 -29.205735) (xy 157.218099 -29.247272)
			(xy 157.175231 -29.282947) (xy 157.127625 -29.312001) (xy 157.076296 -29.333813) (xy 157.022339 -29.347919)
			(xy 156.966902 -29.354019) (xy 156.911168 -29.351982) (xy 156.856325 -29.341852) (xy 156.803541 -29.323845)
			(xy 156.753941 -29.298344) (xy 156.708583 -29.265893) (xy 156.668434 -29.227184) (xy 156.634348 -29.183041)
			(xy 156.607052 -29.134406) (xy 156.587129 -29.082315) (xy 156.575003 -29.027878) (xy 156.570932 -28.972256)
			(xy 152.460092 -28.972256) (xy 152.443924 -28.974035) (xy 152.38819 -28.971998) (xy 152.333347 -28.961868)
			(xy 152.280563 -28.943861) (xy 152.230963 -28.91836) (xy 152.185605 -28.885909) (xy 152.145456 -28.8472)
			(xy 152.11137 -28.803057) (xy 152.084074 -28.754422) (xy 152.064151 -28.702331) (xy 152.052025 -28.647894)
			(xy 152.047954 -28.592272) (xy 149.256496 -28.592272) (xy 148.563076 -29.285692) (xy 148.548545 -29.301686)
			(xy 148.524591 -29.337648) (xy 148.507064 -29.377143) (xy 148.496467 -29.419033) (xy 148.493107 -29.462112)
			(xy 148.49708 -29.505138) (xy 148.508271 -29.546873) (xy 148.526359 -29.586114) (xy 148.550823 -29.621732)
			(xy 148.565616 -29.637482) (xy 148.584161 -29.657161) (xy 148.616083 -29.700806) (xy 148.641521 -29.748522)
			(xy 148.659966 -29.799351) (xy 148.671048 -29.852276) (xy 148.67294 -29.881457) (xy 150.224214 -29.881457)
			(xy 150.228813 -29.825601) (xy 150.241533 -29.771019) (xy 150.262101 -29.718885) (xy 150.290074 -29.67032)
			(xy 150.324849 -29.62637) (xy 150.36568 -29.587979) (xy 150.411687 -29.555974) (xy 150.461882 -29.531043)
			(xy 150.515183 -29.513723) (xy 150.570444 -29.504386) (xy 150.626477 -29.503233) (xy 150.682075 -29.510289)
			(xy 150.736044 -29.525402) (xy 150.787221 -29.548246) (xy 150.834506 -29.578332) (xy 150.876882 -29.615011)
			(xy 150.913436 -29.657493) (xy 150.943382 -29.704866) (xy 150.966077 -29.75611) (xy 150.981032 -29.810123)
			(xy 150.987925 -29.865742) (xy 150.98776 -29.893768) (xy 150.987728 -29.915751) (xy 150.994291 -29.959213)
			(xy 151.008228 -30.0009) (xy 151.029126 -30.039569) (xy 151.056362 -30.074069) (xy 151.089123 -30.103373)
			(xy 151.126436 -30.126607) (xy 151.167188 -30.143079) (xy 151.210165 -30.152299) (xy 151.232108 -30.15361)
			(xy 151.260168 -30.155127) (xy 151.315398 -30.165492) (xy 151.368511 -30.183847) (xy 151.418356 -30.209794)
			(xy 151.463857 -30.242772) (xy 151.504028 -30.282067) (xy 151.538 -30.32683) (xy 151.56504 -30.376091)
			(xy 151.58456 -30.428786) (xy 151.596141 -30.483775) (xy 151.599228 -30.534864) (xy 159.342834 -30.534864)
			(xy 159.346905 -30.479242) (xy 159.359031 -30.424805) (xy 159.378954 -30.372714) (xy 159.40625 -30.324079)
			(xy 159.440336 -30.279936) (xy 159.480485 -30.241227) (xy 159.525843 -30.208776) (xy 159.575443 -30.183275)
			(xy 159.628227 -30.165268) (xy 159.68307 -30.155138) (xy 159.738804 -30.153101) (xy 159.794241 -30.159201)
			(xy 159.848198 -30.173307) (xy 159.899527 -30.195119) (xy 159.947133 -30.224173) (xy 159.990001 -30.259848)
			(xy 160.027218 -30.301385) (xy 160.057991 -30.347898) (xy 160.081663 -30.398395) (xy 160.097731 -30.451802)
			(xy 160.105851 -30.506978) (xy 160.10636 -30.534864) (xy 160.105851 -30.56275) (xy 160.097731 -30.617926)
			(xy 160.081663 -30.671333) (xy 160.057991 -30.72183) (xy 160.027218 -30.768343) (xy 159.990001 -30.80988)
			(xy 159.947133 -30.845555) (xy 159.899527 -30.874609) (xy 159.848198 -30.896421) (xy 159.794241 -30.910527)
			(xy 159.738804 -30.916627) (xy 159.68307 -30.91459) (xy 159.628227 -30.90446) (xy 159.575443 -30.886453)
			(xy 159.525843 -30.860952) (xy 159.480485 -30.828501) (xy 159.440336 -30.789792) (xy 159.40625 -30.745649)
			(xy 159.378954 -30.697014) (xy 159.359031 -30.644923) (xy 159.346905 -30.590486) (xy 159.342834 -30.534864)
			(xy 151.599228 -30.534864) (xy 151.59953 -30.539867) (xy 151.594654 -30.59585) (xy 151.581619 -30.650512)
			(xy 151.560708 -30.702671) (xy 151.532372 -30.751198) (xy 151.497224 -30.795044) (xy 151.476964 -30.814518)
			(xy 151.461221 -30.829753) (xy 151.434696 -30.864616) (xy 151.414535 -30.903508) (xy 151.401333 -30.945277)
			(xy 151.395481 -30.988691) (xy 151.397151 -31.032466) (xy 151.406294 -31.075307) (xy 151.42264 -31.11595)
			(xy 151.433784 -31.134812) (xy 151.448001 -31.158732) (xy 151.470167 -31.209768) (xy 151.484683 -31.263482)
			(xy 151.491241 -31.318736) (xy 151.4897 -31.374357) (xy 151.480094 -31.429163) (xy 151.462627 -31.481992)
			(xy 151.456744 -31.493714) (xy 153.305762 -31.493714) (xy 153.309833 -31.438092) (xy 153.321959 -31.383655)
			(xy 153.341882 -31.331564) (xy 153.369178 -31.282929) (xy 153.403264 -31.238786) (xy 153.443413 -31.200077)
			(xy 153.488771 -31.167626) (xy 153.538371 -31.142125) (xy 153.591155 -31.124118) (xy 153.645998 -31.113988)
			(xy 153.701732 -31.111951) (xy 153.757169 -31.118051) (xy 153.811126 -31.132157) (xy 153.862455 -31.153969)
			(xy 153.910061 -31.183023) (xy 153.952929 -31.218698) (xy 153.990146 -31.260235) (xy 154.020919 -31.306748)
			(xy 154.044591 -31.357245) (xy 154.060659 -31.410652) (xy 154.068779 -31.465828) (xy 154.069288 -31.493714)
			(xy 154.068779 -31.5216) (xy 154.060659 -31.576776) (xy 154.044591 -31.630183) (xy 154.020919 -31.68068)
			(xy 153.990146 -31.727193) (xy 153.952929 -31.76873) (xy 153.910061 -31.804405) (xy 153.862455 -31.833459)
			(xy 153.811126 -31.855271) (xy 153.757169 -31.869377) (xy 153.701732 -31.875477) (xy 153.645998 -31.87344)
			(xy 153.591155 -31.86331) (xy 153.538371 -31.845303) (xy 153.488771 -31.819802) (xy 153.443413 -31.787351)
			(xy 153.403264 -31.748642) (xy 153.369178 -31.704499) (xy 153.341882 -31.655864) (xy 153.321959 -31.603773)
			(xy 153.309833 -31.549336) (xy 153.305762 -31.493714) (xy 151.456744 -31.493714) (xy 151.43767 -31.531722)
			(xy 151.405751 -31.577298) (xy 151.36755 -31.617753) (xy 151.323875 -31.652228) (xy 151.275655 -31.679992)
			(xy 151.223913 -31.700454) (xy 151.169746 -31.713181) (xy 151.114305 -31.717903) (xy 151.058767 -31.71452)
			(xy 151.004309 -31.703102) (xy 150.952088 -31.683893) (xy 150.903213 -31.657301) (xy 150.85872 -31.623889)
			(xy 150.819553 -31.584367) (xy 150.786545 -31.539574) (xy 150.760396 -31.49046) (xy 150.74166 -31.438067)
			(xy 150.730735 -31.383509) (xy 150.727854 -31.327942) (xy 150.733077 -31.272546) (xy 150.746293 -31.218497)
			(xy 150.767223 -31.166941) (xy 150.795421 -31.118974) (xy 150.83029 -31.075613) (xy 150.850346 -31.056326)
			(xy 150.866045 -31.041046) (xy 150.892579 -31.006195) (xy 150.912749 -30.967312) (xy 150.925959 -30.925549)
			(xy 150.931818 -30.88214) (xy 150.930153 -30.838369) (xy 150.921013 -30.795531) (xy 150.904669 -30.754892)
			(xy 150.893526 -30.736032) (xy 150.879372 -30.712314) (xy 150.857277 -30.661693) (xy 150.842714 -30.608415)
			(xy 150.835987 -30.553594) (xy 150.836122 -30.525974) (xy 150.836131 -30.503991) (xy 150.829575 -30.460529)
			(xy 150.815643 -30.418841) (xy 150.794749 -30.380171) (xy 150.767516 -30.345669) (xy 150.734756 -30.316365)
			(xy 150.697445 -30.293131) (xy 150.656694 -30.27666) (xy 150.613717 -30.267441) (xy 150.591774 -30.266132)
			(xy 150.563792 -30.264529) (xy 150.508703 -30.254226) (xy 150.455713 -30.235976) (xy 150.405963 -30.21017)
			(xy 150.360523 -30.177365) (xy 150.32037 -30.138266) (xy 150.286369 -30.093713) (xy 150.25925 -30.044666)
			(xy 150.239598 -29.99218) (xy 150.227835 -29.937384) (xy 150.224214 -29.881457) (xy 148.67294 -29.881457)
			(xy 148.674546 -29.906236) (xy 148.670388 -29.960149) (xy 148.65866 -30.012934) (xy 148.639594 -30.063535)
			(xy 148.613574 -30.110935) (xy 148.581121 -30.154187) (xy 148.542886 -30.192422) (xy 148.499634 -30.224875)
			(xy 148.452234 -30.250895) (xy 148.401633 -30.26996) (xy 148.348848 -30.281689) (xy 148.294935 -30.285846)
			(xy 148.240975 -30.282348) (xy 148.18805 -30.271266) (xy 148.137221 -30.25282) (xy 148.089505 -30.227382)
			(xy 148.04586 -30.195461) (xy 148.02612 -30.176978) (xy 148.010347 -30.162203) (xy 147.974745 -30.137704)
			(xy 147.935509 -30.119587) (xy 147.893772 -30.108375) (xy 147.850739 -30.104391) (xy 147.807653 -30.107752)
			(xy 147.765758 -30.118359) (xy 147.726264 -30.135907) (xy 147.690312 -30.159888) (xy 147.67433 -30.174438)
			(xy 146.902424 -30.946344) (xy 147.867876 -30.946344) (xy 147.871947 -30.890722) (xy 147.884073 -30.836285)
			(xy 147.903996 -30.784194) (xy 147.931292 -30.735559) (xy 147.965378 -30.691416) (xy 148.005527 -30.652707)
			(xy 148.050885 -30.620256) (xy 148.100485 -30.594755) (xy 148.153269 -30.576748) (xy 148.208112 -30.566618)
			(xy 148.263846 -30.564581) (xy 148.319283 -30.570681) (xy 148.37324 -30.584787) (xy 148.424569 -30.606599)
			(xy 148.472175 -30.635653) (xy 148.515043 -30.671328) (xy 148.55226 -30.712865) (xy 148.583033 -30.759378)
			(xy 148.606705 -30.809875) (xy 148.622773 -30.863282) (xy 148.630893 -30.918458) (xy 148.631402 -30.946344)
			(xy 148.630893 -30.97423) (xy 148.622773 -31.029406) (xy 148.606705 -31.082813) (xy 148.583033 -31.13331)
			(xy 148.55226 -31.179823) (xy 148.515043 -31.22136) (xy 148.472175 -31.257035) (xy 148.424569 -31.286089)
			(xy 148.37324 -31.307901) (xy 148.319283 -31.322007) (xy 148.263846 -31.328107) (xy 148.208112 -31.32607)
			(xy 148.153269 -31.31594) (xy 148.100485 -31.297933) (xy 148.050885 -31.272432) (xy 148.005527 -31.239981)
			(xy 147.965378 -31.201272) (xy 147.931292 -31.157129) (xy 147.903996 -31.108494) (xy 147.884073 -31.056403)
			(xy 147.871947 -31.001966) (xy 147.867876 -30.946344) (xy 146.902424 -30.946344) (xy 145.541746 -32.307022)
			(xy 145.532141 -32.317897) (xy 145.517668 -32.343038) (xy 145.509269 -32.370804) (xy 145.507964 -32.385254)
			(xy 145.507964 -32.570928) (xy 147.83892 -32.570928) (xy 147.842991 -32.515306) (xy 147.855117 -32.460869)
			(xy 147.87504 -32.408778) (xy 147.902336 -32.360143) (xy 147.936422 -32.316) (xy 147.976571 -32.277291)
			(xy 148.021929 -32.24484) (xy 148.071529 -32.219339) (xy 148.124313 -32.201332) (xy 148.179156 -32.191202)
			(xy 148.23489 -32.189165) (xy 148.290327 -32.195265) (xy 148.344284 -32.209371) (xy 148.395613 -32.231183)
			(xy 148.443219 -32.260237) (xy 148.486087 -32.295912) (xy 148.523304 -32.337449) (xy 148.554077 -32.383962)
			(xy 148.577749 -32.434459) (xy 148.592901 -32.484822) (xy 150.732234 -32.484822) (xy 150.736305 -32.4292)
			(xy 150.748431 -32.374763) (xy 150.768354 -32.322672) (xy 150.79565 -32.274037) (xy 150.829736 -32.229894)
			(xy 150.869885 -32.191185) (xy 150.915243 -32.158734) (xy 150.964843 -32.133233) (xy 151.017627 -32.115226)
			(xy 151.07247 -32.105096) (xy 151.128204 -32.103059) (xy 151.183641 -32.109159) (xy 151.237598 -32.123265)
			(xy 151.288927 -32.145077) (xy 151.336533 -32.174131) (xy 151.379401 -32.209806) (xy 151.416618 -32.251343)
			(xy 151.447391 -32.297856) (xy 151.471063 -32.348353) (xy 151.487131 -32.40176) (xy 151.495251 -32.456936)
			(xy 151.49576 -32.484822) (xy 151.495251 -32.512708) (xy 151.487131 -32.567884) (xy 151.471063 -32.621291)
			(xy 151.447391 -32.671788) (xy 151.416618 -32.718301) (xy 151.379401 -32.759838) (xy 151.336533 -32.795513)
			(xy 151.288927 -32.824567) (xy 151.237598 -32.846379) (xy 151.183641 -32.860485) (xy 151.128204 -32.866585)
			(xy 151.07247 -32.864548) (xy 151.017627 -32.854418) (xy 150.964843 -32.836411) (xy 150.915243 -32.81091)
			(xy 150.869885 -32.778459) (xy 150.829736 -32.73975) (xy 150.79565 -32.695607) (xy 150.768354 -32.646972)
			(xy 150.748431 -32.594881) (xy 150.736305 -32.540444) (xy 150.732234 -32.484822) (xy 148.592901 -32.484822)
			(xy 148.593817 -32.487866) (xy 148.601937 -32.543042) (xy 148.602446 -32.570928) (xy 148.601937 -32.598814)
			(xy 148.593817 -32.65399) (xy 148.577749 -32.707397) (xy 148.554077 -32.757894) (xy 148.523304 -32.804407)
			(xy 148.486087 -32.845944) (xy 148.443219 -32.881619) (xy 148.395613 -32.910673) (xy 148.344284 -32.932485)
			(xy 148.290327 -32.946591) (xy 148.23489 -32.952691) (xy 148.179156 -32.950654) (xy 148.124313 -32.940524)
			(xy 148.071529 -32.922517) (xy 148.021929 -32.897016) (xy 147.976571 -32.864565) (xy 147.936422 -32.825856)
			(xy 147.902336 -32.781713) (xy 147.87504 -32.733078) (xy 147.855117 -32.680987) (xy 147.842991 -32.62655)
			(xy 147.83892 -32.570928) (xy 145.507964 -32.570928) (xy 145.507964 -33.059116) (xy 146.035776 -33.586928)
			(xy 147.910548 -33.586928) (xy 147.914619 -33.531306) (xy 147.926745 -33.476869) (xy 147.946668 -33.424778)
			(xy 147.973964 -33.376143) (xy 148.00805 -33.332) (xy 148.048199 -33.293291) (xy 148.093557 -33.26084)
			(xy 148.143157 -33.235339) (xy 148.195941 -33.217332) (xy 148.250784 -33.207202) (xy 148.306518 -33.205165)
			(xy 148.361955 -33.211265) (xy 148.415912 -33.225371) (xy 148.467241 -33.247183) (xy 148.514847 -33.276237)
			(xy 148.557715 -33.311912) (xy 148.594932 -33.353449) (xy 148.625705 -33.399962) (xy 148.649377 -33.450459)
			(xy 148.665445 -33.503866) (xy 148.673565 -33.559042) (xy 148.674074 -33.586928) (xy 148.673565 -33.614814)
			(xy 148.665445 -33.66999) (xy 148.649377 -33.723397) (xy 148.625705 -33.773894) (xy 148.594932 -33.820407)
			(xy 148.576545 -33.840928) (xy 150.224234 -33.840928) (xy 150.228305 -33.785306) (xy 150.240431 -33.730869)
			(xy 150.260354 -33.678778) (xy 150.28765 -33.630143) (xy 150.321736 -33.586) (xy 150.361885 -33.547291)
			(xy 150.407243 -33.51484) (xy 150.456843 -33.489339) (xy 150.509627 -33.471332) (xy 150.56447 -33.461202)
			(xy 150.620204 -33.459165) (xy 150.675641 -33.465265) (xy 150.729598 -33.479371) (xy 150.780927 -33.501183)
			(xy 150.828533 -33.530237) (xy 150.871401 -33.565912) (xy 150.908618 -33.607449) (xy 150.939391 -33.653962)
			(xy 150.963063 -33.704459) (xy 150.979131 -33.757866) (xy 150.983131 -33.785048) (xy 159.317434 -33.785048)
			(xy 159.321505 -33.729426) (xy 159.333631 -33.674989) (xy 159.353554 -33.622898) (xy 159.38085 -33.574263)
			(xy 159.414936 -33.53012) (xy 159.455085 -33.491411) (xy 159.500443 -33.45896) (xy 159.550043 -33.433459)
			(xy 159.602827 -33.415452) (xy 159.65767 -33.405322) (xy 159.713404 -33.403285) (xy 159.768841 -33.409385)
			(xy 159.822798 -33.423491) (xy 159.874127 -33.445303) (xy 159.921733 -33.474357) (xy 159.964601 -33.510032)
			(xy 160.001818 -33.551569) (xy 160.026724 -33.589214) (xy 161.916362 -33.589214) (xy 161.920433 -33.533592)
			(xy 161.932559 -33.479155) (xy 161.952482 -33.427064) (xy 161.979778 -33.378429) (xy 162.013864 -33.334286)
			(xy 162.054013 -33.295577) (xy 162.099371 -33.263126) (xy 162.148971 -33.237625) (xy 162.201755 -33.219618)
			(xy 162.256598 -33.209488) (xy 162.312332 -33.207451) (xy 162.367769 -33.213551) (xy 162.421726 -33.227657)
			(xy 162.473055 -33.249469) (xy 162.520661 -33.278523) (xy 162.563529 -33.314198) (xy 162.600746 -33.355735)
			(xy 162.631519 -33.402248) (xy 162.655191 -33.452745) (xy 162.671259 -33.506152) (xy 162.679379 -33.561328)
			(xy 162.679888 -33.589214) (xy 162.679379 -33.6171) (xy 162.671259 -33.672276) (xy 162.655191 -33.725683)
			(xy 162.631519 -33.77618) (xy 162.600746 -33.822693) (xy 162.563529 -33.86423) (xy 162.520661 -33.899905)
			(xy 162.473055 -33.928959) (xy 162.421726 -33.950771) (xy 162.367769 -33.964877) (xy 162.312332 -33.970977)
			(xy 162.256598 -33.96894) (xy 162.201755 -33.95881) (xy 162.148971 -33.940803) (xy 162.099371 -33.915302)
			(xy 162.054013 -33.882851) (xy 162.013864 -33.844142) (xy 161.979778 -33.799999) (xy 161.952482 -33.751364)
			(xy 161.932559 -33.699273) (xy 161.920433 -33.644836) (xy 161.916362 -33.589214) (xy 160.026724 -33.589214)
			(xy 160.032591 -33.598082) (xy 160.056263 -33.648579) (xy 160.072331 -33.701986) (xy 160.080451 -33.757162)
			(xy 160.08096 -33.785048) (xy 160.080451 -33.812934) (xy 160.072331 -33.86811) (xy 160.056263 -33.921517)
			(xy 160.032591 -33.972014) (xy 160.001818 -34.018527) (xy 159.964601 -34.060064) (xy 159.921733 -34.095739)
			(xy 159.874127 -34.124793) (xy 159.822798 -34.146605) (xy 159.768841 -34.160711) (xy 159.713404 -34.166811)
			(xy 159.65767 -34.164774) (xy 159.602827 -34.154644) (xy 159.550043 -34.136637) (xy 159.500443 -34.111136)
			(xy 159.455085 -34.078685) (xy 159.414936 -34.039976) (xy 159.38085 -33.995833) (xy 159.353554 -33.947198)
			(xy 159.333631 -33.895107) (xy 159.321505 -33.84067) (xy 159.317434 -33.785048) (xy 150.983131 -33.785048)
			(xy 150.987251 -33.813042) (xy 150.98776 -33.840928) (xy 150.987251 -33.868814) (xy 150.979131 -33.92399)
			(xy 150.963063 -33.977397) (xy 150.939391 -34.027894) (xy 150.908618 -34.074407) (xy 150.871401 -34.115944)
			(xy 150.828533 -34.151619) (xy 150.780927 -34.180673) (xy 150.729598 -34.202485) (xy 150.675641 -34.216591)
			(xy 150.620204 -34.222691) (xy 150.56447 -34.220654) (xy 150.509627 -34.210524) (xy 150.456843 -34.192517)
			(xy 150.407243 -34.167016) (xy 150.361885 -34.134565) (xy 150.321736 -34.095856) (xy 150.28765 -34.051713)
			(xy 150.260354 -34.003078) (xy 150.240431 -33.950987) (xy 150.228305 -33.89655) (xy 150.224234 -33.840928)
			(xy 148.576545 -33.840928) (xy 148.557715 -33.861944) (xy 148.514847 -33.897619) (xy 148.467241 -33.926673)
			(xy 148.415912 -33.948485) (xy 148.361955 -33.962591) (xy 148.306518 -33.968691) (xy 148.250784 -33.966654)
			(xy 148.195941 -33.956524) (xy 148.143157 -33.938517) (xy 148.093557 -33.913016) (xy 148.048199 -33.880565)
			(xy 148.00805 -33.841856) (xy 147.973964 -33.797713) (xy 147.946668 -33.749078) (xy 147.926745 -33.696987)
			(xy 147.914619 -33.64255) (xy 147.910548 -33.586928) (xy 146.035776 -33.586928) (xy 146.51482 -34.065972)
			(xy 146.51482 -35.137344) (xy 147.065236 -35.137344) (xy 147.069307 -35.081722) (xy 147.081433 -35.027285)
			(xy 147.101356 -34.975194) (xy 147.128652 -34.926559) (xy 147.162738 -34.882416) (xy 147.202887 -34.843707)
			(xy 147.248245 -34.811256) (xy 147.297845 -34.785755) (xy 147.350629 -34.767748) (xy 147.405472 -34.757618)
			(xy 147.461206 -34.755581) (xy 147.516643 -34.761681) (xy 147.5706 -34.775787) (xy 147.621929 -34.797599)
			(xy 147.669535 -34.826653) (xy 147.712403 -34.862328) (xy 147.74962 -34.903865) (xy 147.780393 -34.950378)
			(xy 147.804065 -35.000875) (xy 147.820133 -35.054282) (xy 147.828253 -35.109458) (xy 147.828762 -35.137344)
			(xy 147.828253 -35.16523) (xy 147.820133 -35.220406) (xy 147.804065 -35.273813) (xy 147.780393 -35.32431)
			(xy 147.74962 -35.370823) (xy 147.712403 -35.41236) (xy 147.669535 -35.448035) (xy 147.621929 -35.477089)
			(xy 147.5706 -35.498901) (xy 147.516643 -35.513007) (xy 147.461206 -35.519107) (xy 147.405472 -35.51707)
			(xy 147.350629 -35.50694) (xy 147.297845 -35.488933) (xy 147.248245 -35.463432) (xy 147.202887 -35.430981)
			(xy 147.162738 -35.392272) (xy 147.128652 -35.348129) (xy 147.101356 -35.299494) (xy 147.081433 -35.247403)
			(xy 147.069307 -35.192966) (xy 147.065236 -35.137344) (xy 146.51482 -35.137344) (xy 146.51482 -35.710696)
			(xy 150.225062 -35.710696) (xy 150.232453 -35.656441) (xy 150.247525 -35.603799) (xy 150.269968 -35.553853)
			(xy 150.299322 -35.507629) (xy 150.334983 -35.466076) (xy 150.376218 -35.430048) (xy 150.42218 -35.400286)
			(xy 150.471926 -35.377401) (xy 150.524432 -35.361863) (xy 150.57862 -35.353992) (xy 150.605998 -35.353498)
			(xy 150.628491 -35.352919) (xy 150.672771 -35.344979) (xy 150.714961 -35.329364) (xy 150.75374 -35.306563)
			(xy 150.787898 -35.277288) (xy 150.816366 -35.242454) (xy 150.838253 -35.203151) (xy 150.852877 -35.160608)
			(xy 150.859779 -35.116154) (xy 150.859744 -35.093656) (xy 150.859621 -35.066271) (xy 150.866218 -35.011909)
			(xy 150.880521 -34.959048) (xy 150.902234 -34.908775) (xy 150.930911 -34.862123) (xy 150.965964 -34.82005)
			(xy 151.006671 -34.783421) (xy 151.052198 -34.752988) (xy 151.101608 -34.729377) (xy 151.153885 -34.713073)
			(xy 151.207957 -34.70441) (xy 151.262712 -34.703568) (xy 151.317025 -34.710562) (xy 151.36978 -34.725249)
			(xy 151.419893 -34.747328) (xy 151.466335 -34.776345) (xy 151.508151 -34.811704) (xy 151.544482 -34.852678)
			(xy 151.574582 -34.898425) (xy 151.597832 -34.948006) (xy 151.613754 -35.000401) (xy 151.622022 -35.054535)
			(xy 151.622465 -35.109294) (xy 151.615075 -35.163555) (xy 151.600003 -35.216201) (xy 151.577559 -35.266152)
			(xy 151.548204 -35.312381) (xy 151.512541 -35.353937) (xy 151.471304 -35.389969) (xy 151.425338 -35.419734)
			(xy 151.375589 -35.442621) (xy 151.323079 -35.458161) (xy 151.268886 -35.466034) (xy 151.241506 -35.466528)
			(xy 151.219012 -35.467084) (xy 151.174729 -35.475025) (xy 151.132537 -35.490641) (xy 151.093755 -35.513445)
			(xy 151.059597 -35.542723) (xy 151.031129 -35.57756) (xy 151.009243 -35.616866) (xy 150.994622 -35.659413)
			(xy 150.987723 -35.70387) (xy 150.98776 -35.72637) (xy 150.987852 -35.753753) (xy 150.981251 -35.808111)
			(xy 150.966946 -35.860966) (xy 150.945232 -35.911234) (xy 150.916554 -35.95788) (xy 150.881502 -35.999948)
			(xy 150.840795 -36.036571) (xy 150.795271 -36.066999) (xy 150.745864 -36.090605) (xy 150.693589 -36.106906)
			(xy 150.639521 -36.115565) (xy 150.584771 -36.116405) (xy 150.530463 -36.109409) (xy 150.477713 -36.09472)
			(xy 150.427605 -36.072641) (xy 150.381168 -36.043624) (xy 150.339357 -36.008267) (xy 150.303031 -35.967295)
			(xy 150.272935 -35.92155) (xy 150.249689 -35.871973) (xy 150.233769 -35.819581) (xy 150.225504 -35.765452)
			(xy 150.225062 -35.710696) (xy 146.51482 -35.710696) (xy 146.51482 -36.399216) (xy 146.821142 -36.399216)
			(xy 146.825213 -36.343594) (xy 146.837339 -36.289157) (xy 146.857262 -36.237066) (xy 146.884558 -36.188431)
			(xy 146.918644 -36.144288) (xy 146.958793 -36.105579) (xy 147.004151 -36.073128) (xy 147.053751 -36.047627)
			(xy 147.106535 -36.02962) (xy 147.161378 -36.01949) (xy 147.217112 -36.017453) (xy 147.272549 -36.023553)
			(xy 147.326506 -36.037659) (xy 147.377835 -36.059471) (xy 147.425441 -36.088525) (xy 147.468309 -36.1242)
			(xy 147.505526 -36.165737) (xy 147.536299 -36.21225) (xy 147.559971 -36.262747) (xy 147.576039 -36.316154)
			(xy 147.584159 -36.37133) (xy 147.584668 -36.399216) (xy 147.584159 -36.427102) (xy 147.576039 -36.482278)
			(xy 147.559971 -36.535685) (xy 147.536299 -36.586182) (xy 147.505526 -36.632695) (xy 147.468309 -36.674232)
			(xy 147.425441 -36.709907) (xy 147.399718 -36.725606) (xy 147.946362 -36.725606) (xy 147.950433 -36.669984)
			(xy 147.962559 -36.615547) (xy 147.982482 -36.563456) (xy 148.009778 -36.514821) (xy 148.043864 -36.470678)
			(xy 148.084013 -36.431969) (xy 148.129371 -36.399518) (xy 148.178971 -36.374017) (xy 148.231755 -36.35601)
			(xy 148.286598 -36.34588) (xy 148.342332 -36.343843) (xy 148.397769 -36.349943) (xy 148.451726 -36.364049)
			(xy 148.503055 -36.385861) (xy 148.550661 -36.414915) (xy 148.593529 -36.45059) (xy 148.630746 -36.492127)
			(xy 148.661519 -36.53864) (xy 148.685191 -36.589137) (xy 148.701259 -36.642544) (xy 148.709379 -36.69772)
			(xy 148.709888 -36.725606) (xy 148.709379 -36.753492) (xy 148.701259 -36.808668) (xy 148.698026 -36.819414)
			(xy 166.151128 -36.819414) (xy 166.153539 -36.764283) (xy 166.163866 -36.710073) (xy 166.181893 -36.657917)
			(xy 166.207245 -36.608901) (xy 166.239392 -36.564047) (xy 166.277665 -36.524292) (xy 166.321265 -36.490464)
			(xy 166.369282 -36.463268) (xy 166.420716 -36.443272) (xy 166.474494 -36.430893) (xy 166.529494 -36.42639)
			(xy 166.584569 -36.429855) (xy 166.638571 -36.441216) (xy 166.66464 -36.45027) (xy 166.686923 -36.457937)
			(xy 166.733401 -36.465693) (xy 166.780513 -36.464753) (xy 166.826645 -36.45515) (xy 166.870218 -36.437212)
			(xy 166.90974 -36.411553) (xy 166.943858 -36.379052) (xy 166.971405 -36.340821) (xy 166.981886 -36.319714)
			(xy 166.994134 -36.294989) (xy 167.024544 -36.248952) (xy 167.061268 -36.207775) (xy 167.103539 -36.172316)
			(xy 167.150477 -36.143317) (xy 167.201103 -36.12138) (xy 167.25436 -36.106963) (xy 167.309138 -36.100368)
			(xy 167.364295 -36.101732) (xy 167.418681 -36.111025) (xy 167.471161 -36.128055) (xy 167.520641 -36.152467)
			(xy 167.566088 -36.18375) (xy 167.606556 -36.221254) (xy 167.641201 -36.264195) (xy 167.669299 -36.311678)
			(xy 167.690265 -36.362713) (xy 167.703661 -36.416236) (xy 167.709209 -36.471131) (xy 167.706793 -36.526252)
			(xy 167.696462 -36.58045) (xy 167.678432 -36.632595) (xy 167.65308 -36.681599) (xy 167.620934 -36.726441)
			(xy 167.582665 -36.766186) (xy 167.53907 -36.800003) (xy 167.491059 -36.82719) (xy 167.439632 -36.847177)
			(xy 167.385863 -36.859549) (xy 167.330873 -36.864047) (xy 167.275808 -36.860578) (xy 167.221817 -36.849214)
			(xy 167.195754 -36.84016) (xy 167.173478 -36.832471) (xy 167.126997 -36.824714) (xy 167.079882 -36.825655)
			(xy 167.033747 -36.83526) (xy 166.990173 -36.853202) (xy 166.95065 -36.878865) (xy 166.916532 -36.911371)
			(xy 166.888987 -36.949606) (xy 166.878508 -36.970716) (xy 166.866351 -36.99549) (xy 166.835943 -37.04154)
			(xy 166.799219 -37.08273) (xy 166.756945 -37.118201) (xy 166.710002 -37.147214) (xy 166.659371 -37.169162)
			(xy 166.606106 -37.183589) (xy 166.551318 -37.190193) (xy 166.496151 -37.188837) (xy 166.441754 -37.179549)
			(xy 166.389262 -37.162523) (xy 166.33977 -37.138113) (xy 166.29431 -37.10683) (xy 166.25383 -37.069325)
			(xy 166.219174 -37.02638) (xy 166.191065 -36.978891) (xy 166.170089 -36.927849) (xy 166.156683 -36.874318)
			(xy 166.151128 -36.819414) (xy 148.698026 -36.819414) (xy 148.685191 -36.862075) (xy 148.661519 -36.912572)
			(xy 148.630746 -36.959085) (xy 148.593529 -37.000622) (xy 148.550661 -37.036297) (xy 148.503055 -37.065351)
			(xy 148.451726 -37.087163) (xy 148.397769 -37.101269) (xy 148.342332 -37.107369) (xy 148.286598 -37.105332)
			(xy 148.231755 -37.095202) (xy 148.178971 -37.077195) (xy 148.129371 -37.051694) (xy 148.084013 -37.019243)
			(xy 148.043864 -36.980534) (xy 148.009778 -36.936391) (xy 147.982482 -36.887756) (xy 147.962559 -36.835665)
			(xy 147.950433 -36.781228) (xy 147.946362 -36.725606) (xy 147.399718 -36.725606) (xy 147.377835 -36.738961)
			(xy 147.326506 -36.760773) (xy 147.272549 -36.774879) (xy 147.217112 -36.780979) (xy 147.161378 -36.778942)
			(xy 147.106535 -36.768812) (xy 147.053751 -36.750805) (xy 147.004151 -36.725304) (xy 146.958793 -36.692853)
			(xy 146.918644 -36.654144) (xy 146.884558 -36.610001) (xy 146.857262 -36.561366) (xy 146.837339 -36.509275)
			(xy 146.825213 -36.454838) (xy 146.821142 -36.399216) (xy 146.51482 -36.399216) (xy 146.51482 -37.819076)
			(xy 146.983702 -37.819076) (xy 146.987773 -37.763454) (xy 146.999899 -37.709017) (xy 147.019822 -37.656926)
			(xy 147.047118 -37.608291) (xy 147.081204 -37.564148) (xy 147.121353 -37.525439) (xy 147.166711 -37.492988)
			(xy 147.216311 -37.467487) (xy 147.269095 -37.44948) (xy 147.323938 -37.43935) (xy 147.379672 -37.437313)
			(xy 147.435109 -37.443413) (xy 147.489066 -37.457519) (xy 147.540395 -37.479331) (xy 147.588001 -37.508385)
			(xy 147.630869 -37.54406) (xy 147.668086 -37.585597) (xy 147.698859 -37.63211) (xy 147.722531 -37.682607)
			(xy 147.738599 -37.736014) (xy 147.746719 -37.79119) (xy 147.747228 -37.819076) (xy 147.746719 -37.846962)
			(xy 147.738599 -37.902138) (xy 147.722531 -37.955545) (xy 147.698859 -38.006042) (xy 147.668086 -38.052555)
			(xy 147.637701 -38.086467) (xy 166.151148 -38.086467) (xy 166.153929 -38.031811) (xy 166.16449 -37.978114)
			(xy 166.182615 -37.926476) (xy 166.207933 -37.877958) (xy 166.239923 -37.833555) (xy 166.277929 -37.794179)
			(xy 166.321171 -37.760637) (xy 166.368762 -37.733618) (xy 166.419726 -37.713675) (xy 166.473016 -37.701219)
			(xy 166.527539 -37.696505) (xy 166.582176 -37.69963) (xy 166.635806 -37.71053) (xy 166.687328 -37.72898)
			(xy 166.735686 -37.754602) (xy 166.779886 -37.786871) (xy 166.819023 -37.825125) (xy 166.852292 -37.868578)
			(xy 166.866062 -37.892228) (xy 166.877698 -37.912058) (xy 166.906969 -37.947511) (xy 166.94214 -37.977119)
			(xy 166.982063 -37.999917) (xy 167.025437 -38.015162) (xy 167.070845 -38.022355) (xy 167.116807 -38.021262)
			(xy 167.161821 -38.011919) (xy 167.183308 -38.003734) (xy 167.208817 -37.993821) (xy 167.261948 -37.980691)
			(xy 167.31641 -37.975288) (xy 167.371086 -37.977722) (xy 167.424852 -37.987943) (xy 167.476606 -38.005742)
			(xy 167.525286 -38.030753) (xy 167.569894 -38.062463) (xy 167.609512 -38.100221) (xy 167.643329 -38.143252)
			(xy 167.670651 -38.190674) (xy 167.690917 -38.241513) (xy 167.703711 -38.294726) (xy 167.70877 -38.349221)
			(xy 167.705991 -38.40388) (xy 167.69543 -38.45758) (xy 167.677305 -38.509221) (xy 167.651988 -38.557743)
			(xy 167.619997 -38.602149) (xy 167.58199 -38.641528) (xy 167.538746 -38.675073) (xy 167.491153 -38.702095)
			(xy 167.440187 -38.72204) (xy 167.386894 -38.734497) (xy 167.332368 -38.739213) (xy 167.277728 -38.736089)
			(xy 167.224095 -38.725189) (xy 167.172569 -38.706739) (xy 167.124209 -38.681116) (xy 167.080006 -38.648845)
			(xy 167.040867 -38.61059) (xy 167.007595 -38.567136) (xy 166.993824 -38.543484) (xy 166.982198 -38.523647)
			(xy 166.952927 -38.488193) (xy 166.917754 -38.458584) (xy 166.877829 -38.435786) (xy 166.834454 -38.420542)
			(xy 166.789044 -38.41335) (xy 166.743081 -38.414446) (xy 166.698065 -38.423792) (xy 166.676578 -38.431978)
			(xy 166.651061 -38.441868) (xy 166.597932 -38.454994) (xy 166.543473 -38.460394) (xy 166.488801 -38.457958)
			(xy 166.435038 -38.447735) (xy 166.383287 -38.429935) (xy 166.33461 -38.404924) (xy 166.290007 -38.373214)
			(xy 166.250392 -38.335457) (xy 166.216578 -38.292427) (xy 166.189259 -38.245007) (xy 166.168997 -38.19417)
			(xy 166.156205 -38.140959) (xy 166.151148 -38.086467) (xy 147.637701 -38.086467) (xy 147.630869 -38.094092)
			(xy 147.588001 -38.129767) (xy 147.540395 -38.158821) (xy 147.489066 -38.180633) (xy 147.435109 -38.194739)
			(xy 147.379672 -38.200839) (xy 147.323938 -38.198802) (xy 147.269095 -38.188672) (xy 147.216311 -38.170665)
			(xy 147.166711 -38.145164) (xy 147.121353 -38.112713) (xy 147.081204 -38.074004) (xy 147.047118 -38.029861)
			(xy 147.019822 -37.981226) (xy 146.999899 -37.929135) (xy 146.987773 -37.874698) (xy 146.983702 -37.819076)
			(xy 146.51482 -37.819076) (xy 146.51482 -38.372288) (xy 146.3421 -38.545008) (xy 146.3421 -39.362126)
			(xy 147.335492 -39.362126) (xy 147.339563 -39.306504) (xy 147.351689 -39.252067) (xy 147.371612 -39.199976)
			(xy 147.398908 -39.151341) (xy 147.432994 -39.107198) (xy 147.473143 -39.068489) (xy 147.518501 -39.036038)
			(xy 147.568101 -39.010537) (xy 147.620885 -38.99253) (xy 147.675728 -38.9824) (xy 147.731462 -38.980363)
			(xy 147.786899 -38.986463) (xy 147.823807 -38.996112) (xy 155.42971 -38.996112) (xy 155.433781 -38.94049)
			(xy 155.445907 -38.886053) (xy 155.46583 -38.833962) (xy 155.493126 -38.785327) (xy 155.527212 -38.741184)
			(xy 155.567361 -38.702475) (xy 155.612719 -38.670024) (xy 155.662319 -38.644523) (xy 155.715103 -38.626516)
			(xy 155.769946 -38.616386) (xy 155.82568 -38.614349) (xy 155.881117 -38.620449) (xy 155.935074 -38.634555)
			(xy 155.986403 -38.656367) (xy 156.034009 -38.685421) (xy 156.076877 -38.721096) (xy 156.114094 -38.762633)
			(xy 156.144867 -38.809146) (xy 156.168539 -38.859643) (xy 156.184607 -38.91305) (xy 156.192727 -38.968226)
			(xy 156.193236 -38.996112) (xy 156.192727 -39.023998) (xy 156.184607 -39.079174) (xy 156.168539 -39.132581)
			(xy 156.144867 -39.183078) (xy 156.114094 -39.229591) (xy 156.076877 -39.271128) (xy 156.034009 -39.306803)
			(xy 155.986403 -39.335857) (xy 155.935074 -39.357669) (xy 155.881117 -39.371775) (xy 155.82568 -39.377875)
			(xy 155.769946 -39.375838) (xy 155.715103 -39.365708) (xy 155.662319 -39.347701) (xy 155.612719 -39.3222)
			(xy 155.567361 -39.289749) (xy 155.527212 -39.25104) (xy 155.493126 -39.206897) (xy 155.46583 -39.158262)
			(xy 155.445907 -39.106171) (xy 155.433781 -39.051734) (xy 155.42971 -38.996112) (xy 147.823807 -38.996112)
			(xy 147.840856 -39.000569) (xy 147.892185 -39.022381) (xy 147.939791 -39.051435) (xy 147.982659 -39.08711)
			(xy 148.019876 -39.128647) (xy 148.050649 -39.17516) (xy 148.074321 -39.225657) (xy 148.090389 -39.279064)
			(xy 148.098509 -39.33424) (xy 148.099018 -39.362126) (xy 148.098509 -39.390012) (xy 148.090389 -39.445188)
			(xy 148.074321 -39.498595) (xy 148.050649 -39.549092) (xy 148.019876 -39.595605) (xy 147.982659 -39.637142)
			(xy 147.939791 -39.672817) (xy 147.892185 -39.701871) (xy 147.840856 -39.723683) (xy 147.786899 -39.737789)
			(xy 147.731462 -39.743889) (xy 147.675728 -39.741852) (xy 147.620885 -39.731722) (xy 147.568101 -39.713715)
			(xy 147.518501 -39.688214) (xy 147.473143 -39.655763) (xy 147.432994 -39.617054) (xy 147.398908 -39.572911)
			(xy 147.371612 -39.524276) (xy 147.351689 -39.472185) (xy 147.339563 -39.417748) (xy 147.335492 -39.362126)
			(xy 146.3421 -39.362126) (xy 146.3421 -40.98417) (xy 146.91182 -40.98417) (xy 146.915891 -40.928548)
			(xy 146.928017 -40.874111) (xy 146.94794 -40.82202) (xy 146.975236 -40.773385) (xy 147.009322 -40.729242)
			(xy 147.049471 -40.690533) (xy 147.094829 -40.658082) (xy 147.144429 -40.632581) (xy 147.197213 -40.614574)
			(xy 147.252056 -40.604444) (xy 147.30779 -40.602407) (xy 147.363227 -40.608507) (xy 147.417184 -40.622613)
			(xy 147.468513 -40.644425) (xy 147.516119 -40.673479) (xy 147.558987 -40.709154) (xy 147.596204 -40.750691)
			(xy 147.626977 -40.797204) (xy 147.650649 -40.847701) (xy 147.659458 -40.876982) (xy 148.065234 -40.876982)
			(xy 148.069305 -40.82136) (xy 148.081431 -40.766923) (xy 148.101354 -40.714832) (xy 148.12865 -40.666197)
			(xy 148.162736 -40.622054) (xy 148.202885 -40.583345) (xy 148.248243 -40.550894) (xy 148.297843 -40.525393)
			(xy 148.350627 -40.507386) (xy 148.40547 -40.497256) (xy 148.461204 -40.495219) (xy 148.516641 -40.501319)
			(xy 148.570598 -40.515425) (xy 148.598724 -40.527377) (xy 166.164595 -40.527377) (xy 166.169089 -40.471613)
			(xy 166.18168 -40.417104) (xy 166.202096 -40.365018) (xy 166.229901 -40.316472) (xy 166.264499 -40.272508)
			(xy 166.305146 -40.234068) (xy 166.350971 -40.201977) (xy 166.400993 -40.176924) (xy 166.454137 -40.159445)
			(xy 166.509264 -40.149915) (xy 166.565191 -40.148538) (xy 166.62072 -40.155345) (xy 166.67466 -40.170189)
			(xy 166.700454 -40.181022) (xy 166.720678 -40.189388) (xy 166.763152 -40.199928) (xy 166.806802 -40.203038)
			(xy 166.850341 -40.198626) (xy 166.89248 -40.186822) (xy 166.931975 -40.167975) (xy 166.967659 -40.142643)
			(xy 166.998477 -40.111573) (xy 167.023518 -40.075684) (xy 167.033194 -40.056054) (xy 167.045449 -40.030905)
			(xy 167.076276 -39.984219) (xy 167.113592 -39.942536) (xy 167.156594 -39.90675) (xy 167.204363 -39.877629)
			(xy 167.255872 -39.855797) (xy 167.310018 -39.841721) (xy 167.365639 -39.835705) (xy 167.421542 -39.837877)
			(xy 167.476528 -39.84819) (xy 167.529419 -39.866424) (xy 167.579079 -39.892186) (xy 167.624444 -39.924926)
			(xy 167.664541 -39.96394) (xy 167.69851 -40.008392) (xy 167.725622 -40.057329) (xy 167.745297 -40.1097)
			(xy 167.757111 -40.164384) (xy 167.760812 -40.220207) (xy 167.760449 -40.22471) (xy 173.613572 -40.22471)
			(xy 173.613572 -30.25013) (xy 174.022766 -29.840936) (xy 174.545752 -29.840936) (xy 174.577935 -29.84146)
			(xy 174.641785 -29.849588) (xy 174.704099 -29.865709) (xy 174.763881 -29.889564) (xy 174.820175 -29.920772)
			(xy 174.872081 -29.958835) (xy 174.918769 -30.003142) (xy 174.959492 -30.052987) (xy 174.993601 -30.107573)
			(xy 175.007524 -30.136592) (xy 175.014057 -30.149814) (xy 175.032189 -30.173063) (xy 175.055184 -30.191515)
			(xy 175.081808 -30.204181) (xy 175.110633 -30.210381) (xy 175.12538 -30.210506) (xy 175.14062 -30.210506)
			(xy 175.15536 -30.210313) (xy 175.184163 -30.204092) (xy 175.210771 -30.19143) (xy 175.233765 -30.173003)
			(xy 175.251921 -30.149794) (xy 175.258476 -30.136592) (xy 175.272392 -30.107567) (xy 175.306491 -30.05297)
			(xy 175.347209 -30.003115) (xy 175.393895 -29.958798) (xy 175.445802 -29.92073) (xy 175.5021 -29.889519)
			(xy 175.561887 -29.865664) (xy 175.624207 -29.849548) (xy 175.688063 -29.841428) (xy 175.720248 -29.840936)
			(xy 192.2018 -29.840936) (xy 192.229055 -29.841355) (xy 192.28301 -29.849114) (xy 192.335311 -29.864472)
			(xy 192.384894 -29.887118) (xy 192.430749 -29.91659) (xy 192.471943 -29.952288) (xy 192.507637 -29.993486)
			(xy 192.537104 -30.039345) (xy 192.559744 -30.08893) (xy 192.575096 -30.141233) (xy 192.582848 -30.195189)
			(xy 192.583308 -30.222444) (xy 192.583308 -40.08247) (xy 191.89319 -40.772588) (xy 174.16145 -40.772588)
			(xy 173.613572 -40.22471) (xy 167.760449 -40.22471) (xy 167.75632 -40.275971) (xy 167.743732 -40.330482)
			(xy 167.723318 -40.38257) (xy 167.695515 -40.431117) (xy 167.66092 -40.475083) (xy 167.620274 -40.513525)
			(xy 167.574449 -40.545619) (xy 167.524429 -40.570675) (xy 167.471285 -40.588158) (xy 167.416158 -40.597691)
			(xy 167.36023 -40.59907) (xy 167.3047 -40.592266) (xy 167.250759 -40.577425) (xy 167.224964 -40.566594)
			(xy 167.204779 -40.558126) (xy 167.162294 -40.547595) (xy 167.118633 -40.544495) (xy 167.075087 -40.548919)
			(xy 167.032941 -40.560736) (xy 166.993441 -40.579595) (xy 166.957755 -40.604941) (xy 166.926938 -40.636024)
			(xy 166.901898 -40.671926) (xy 166.892224 -40.691562) (xy 166.879941 -40.716698) (xy 166.849113 -40.763383)
			(xy 166.811797 -40.805064) (xy 166.768794 -40.840849) (xy 166.721026 -40.869969) (xy 166.669516 -40.8918)
			(xy 166.615371 -40.905873) (xy 166.55975 -40.911888) (xy 166.503848 -40.909715) (xy 166.448862 -40.8994)
			(xy 166.395973 -40.881165) (xy 166.346314 -40.855401) (xy 166.300951 -40.82266) (xy 166.260855 -40.783645)
			(xy 166.226888 -40.739192) (xy 166.199778 -40.690255) (xy 166.180106 -40.637883) (xy 166.168294 -40.583199)
			(xy 166.164595 -40.527377) (xy 148.598724 -40.527377) (xy 148.621927 -40.537237) (xy 148.669533 -40.566291)
			(xy 148.712401 -40.601966) (xy 148.749618 -40.643503) (xy 148.780391 -40.690016) (xy 148.804063 -40.740513)
			(xy 148.820131 -40.79392) (xy 148.828251 -40.849096) (xy 148.82876 -40.876982) (xy 148.828251 -40.904868)
			(xy 148.820131 -40.960044) (xy 148.804063 -41.013451) (xy 148.780391 -41.063948) (xy 148.749618 -41.110461)
			(xy 148.712401 -41.151998) (xy 148.669533 -41.187673) (xy 148.621927 -41.216727) (xy 148.570598 -41.238539)
			(xy 148.516641 -41.252645) (xy 148.461204 -41.258745) (xy 148.40547 -41.256708) (xy 148.350627 -41.246578)
			(xy 148.297843 -41.228571) (xy 148.248243 -41.20307) (xy 148.202885 -41.170619) (xy 148.162736 -41.13191)
			(xy 148.12865 -41.087767) (xy 148.101354 -41.039132) (xy 148.081431 -40.987041) (xy 148.069305 -40.932604)
			(xy 148.065234 -40.876982) (xy 147.659458 -40.876982) (xy 147.666717 -40.901108) (xy 147.674837 -40.956284)
			(xy 147.675346 -40.98417) (xy 147.674837 -41.012056) (xy 147.666717 -41.067232) (xy 147.650649 -41.120639)
			(xy 147.626977 -41.171136) (xy 147.596204 -41.217649) (xy 147.558987 -41.259186) (xy 147.516119 -41.294861)
			(xy 147.468513 -41.323915) (xy 147.417184 -41.345727) (xy 147.363227 -41.359833) (xy 147.30779 -41.365933)
			(xy 147.252056 -41.363896) (xy 147.197213 -41.353766) (xy 147.144429 -41.335759) (xy 147.094829 -41.310258)
			(xy 147.049471 -41.277807) (xy 147.009322 -41.239098) (xy 146.975236 -41.194955) (xy 146.94794 -41.14632)
			(xy 146.928017 -41.094229) (xy 146.915891 -41.039792) (xy 146.91182 -40.98417) (xy 146.3421 -40.98417)
			(xy 146.3421 -41.95064) (xy 152.77897 -41.95064) (xy 152.783016 -41.856662) (xy 152.795127 -41.76338)
			(xy 152.815212 -41.671484) (xy 152.843122 -41.581655) (xy 152.878651 -41.494558) (xy 152.921536 -41.410837)
			(xy 152.971459 -41.331113) (xy 153.028051 -41.255976) (xy 153.090893 -41.185982) (xy 153.159519 -41.121649)
			(xy 153.233421 -41.063454) (xy 153.312052 -41.011827) (xy 153.394831 -40.96715) (xy 153.481143 -40.929756)
			(xy 153.570351 -40.899919) (xy 153.661793 -40.877862) (xy 153.754793 -40.863747) (xy 153.848662 -40.857679)
			(xy 153.942706 -40.859702) (xy 154.036227 -40.869803) (xy 154.128533 -40.887906) (xy 154.218942 -40.913877)
			(xy 154.306784 -40.947524) (xy 154.391407 -40.988598) (xy 154.472187 -41.036794) (xy 154.548525 -41.091756)
			(xy 154.619855 -41.153077) (xy 154.685649 -41.220303) (xy 154.745421 -41.292936) (xy 154.798728 -41.370438)
			(xy 154.845175 -41.452236) (xy 154.884418 -41.537724) (xy 154.916168 -41.626269) (xy 154.940187 -41.717216)
			(xy 154.9563 -41.809891) (xy 154.957107 -41.819245) (xy 166.164915 -41.819245) (xy 166.166168 -41.763752)
			(xy 166.175449 -41.709025) (xy 166.192561 -41.656222) (xy 166.217145 -41.606455) (xy 166.248679 -41.560775)
			(xy 166.2865 -41.520147) (xy 166.329809 -41.485428) (xy 166.377692 -41.457351) (xy 166.429137 -41.436508)
			(xy 166.48306 -41.423339) (xy 166.538322 -41.418123) (xy 166.593756 -41.420969) (xy 166.648193 -41.431818)
			(xy 166.700483 -41.450439) (xy 166.749524 -41.476442) (xy 166.794279 -41.509275) (xy 166.833804 -41.548247)
			(xy 166.867265 -41.592535) (xy 166.881048 -41.61663) (xy 166.891745 -41.635081) (xy 166.918229 -41.668502)
			(xy 166.949926 -41.697028) (xy 166.985944 -41.719857) (xy 167.025269 -41.736346) (xy 167.066797 -41.746033)
			(xy 167.10936 -41.748645) (xy 167.151761 -41.744108) (xy 167.192808 -41.732551) (xy 167.212264 -41.723818)
			(xy 167.237535 -41.712334) (xy 167.290613 -41.696088) (xy 167.345484 -41.687705) (xy 167.400992 -41.687361)
			(xy 167.455963 -41.695064) (xy 167.509239 -41.71065) (xy 167.559693 -41.733791) (xy 167.606263 -41.763998)
			(xy 167.647964 -41.800634) (xy 167.683916 -41.842926) (xy 167.713362 -41.889981) (xy 167.735678 -41.940806)
			(xy 167.750395 -41.994328) (xy 167.754255 -42.02557) (xy 180.231037 -42.02557) (xy 180.235073 -41.942123)
			(xy 180.247145 -41.859455) (xy 180.267138 -41.778338) (xy 180.294867 -41.699529) (xy 180.330073 -41.623764)
			(xy 180.372427 -41.551751) (xy 180.421533 -41.484162) (xy 180.476934 -41.421628) (xy 180.538111 -41.364733)
			(xy 180.604494 -41.314007) (xy 180.675462 -41.269926) (xy 180.750354 -41.2329) (xy 180.82847 -41.203274)
			(xy 180.90908 -41.181326) (xy 180.991432 -41.167261) (xy 181.074758 -41.161209) (xy 181.158278 -41.163228)
			(xy 181.241214 -41.173298) (xy 181.32279 -41.191326) (xy 181.402246 -41.217143) (xy 181.478839 -41.250508)
			(xy 181.551855 -41.291109) (xy 181.620611 -41.338568) (xy 181.684465 -41.392441) (xy 181.742822 -41.452226)
			(xy 181.795137 -41.517363) (xy 181.84092 -41.587246) (xy 181.879745 -41.661221) (xy 181.91125 -41.738598)
			(xy 181.935139 -41.818655) (xy 181.95119 -41.900643) (xy 181.959253 -41.983798) (xy 181.959758 -42.02557)
			(xy 182.847237 -42.02557) (xy 182.851273 -41.942123) (xy 182.863345 -41.859455) (xy 182.883338 -41.778338)
			(xy 182.911067 -41.699529) (xy 182.946273 -41.623764) (xy 182.988627 -41.551751) (xy 183.037733 -41.484162)
			(xy 183.093134 -41.421628) (xy 183.154311 -41.364733) (xy 183.220694 -41.314007) (xy 183.291662 -41.269926)
			(xy 183.366554 -41.2329) (xy 183.44467 -41.203274) (xy 183.52528 -41.181326) (xy 183.607632 -41.167261)
			(xy 183.690958 -41.161209) (xy 183.774478 -41.163228) (xy 183.857414 -41.173298) (xy 183.93899 -41.191326)
			(xy 184.018446 -41.217143) (xy 184.095039 -41.250508) (xy 184.168055 -41.291109) (xy 184.236811 -41.338568)
			(xy 184.300665 -41.392441) (xy 184.359022 -41.452226) (xy 184.411337 -41.517363) (xy 184.45712 -41.587246)
			(xy 184.495945 -41.661221) (xy 184.52745 -41.738598) (xy 184.551339 -41.818655) (xy 184.56739 -41.900643)
			(xy 184.575453 -41.983798) (xy 184.575958 -42.02557) (xy 184.575453 -42.067342) (xy 184.56739 -42.150497)
			(xy 184.551339 -42.232485) (xy 184.52745 -42.312542) (xy 184.495945 -42.389919) (xy 184.45712 -42.463894)
			(xy 184.411337 -42.533777) (xy 184.359022 -42.598914) (xy 184.300665 -42.658699) (xy 184.236811 -42.712572)
			(xy 184.168055 -42.760031) (xy 184.095039 -42.800632) (xy 184.018446 -42.833997) (xy 183.93899 -42.859814)
			(xy 183.857414 -42.877842) (xy 183.774478 -42.887912) (xy 183.690958 -42.889931) (xy 183.607632 -42.883879)
			(xy 183.52528 -42.869814) (xy 183.44467 -42.847866) (xy 183.366554 -42.81824) (xy 183.291662 -42.781214)
			(xy 183.220694 -42.737133) (xy 183.154311 -42.686407) (xy 183.093134 -42.629512) (xy 183.037733 -42.566978)
			(xy 182.988627 -42.499389) (xy 182.946273 -42.427376) (xy 182.911067 -42.351611) (xy 182.883338 -42.272802)
			(xy 182.863345 -42.191685) (xy 182.851273 -42.109017) (xy 182.847237 -42.02557) (xy 181.959758 -42.02557)
			(xy 181.959253 -42.067342) (xy 181.95119 -42.150497) (xy 181.935139 -42.232485) (xy 181.91125 -42.312542)
			(xy 181.879745 -42.389919) (xy 181.84092 -42.463894) (xy 181.795137 -42.533777) (xy 181.742822 -42.598914)
			(xy 181.684465 -42.658699) (xy 181.620611 -42.712572) (xy 181.551855 -42.760031) (xy 181.478839 -42.800632)
			(xy 181.402246 -42.833997) (xy 181.32279 -42.859814) (xy 181.241214 -42.877842) (xy 181.158278 -42.887912)
			(xy 181.074758 -42.889931) (xy 180.991432 -42.883879) (xy 180.90908 -42.869814) (xy 180.82847 -42.847866)
			(xy 180.750354 -42.81824) (xy 180.675462 -42.781214) (xy 180.604494 -42.737133) (xy 180.538111 -42.686407)
			(xy 180.476934 -42.629512) (xy 180.421533 -42.566978) (xy 180.372427 -42.499389) (xy 180.330073 -42.427376)
			(xy 180.294867 -42.351611) (xy 180.267138 -42.272802) (xy 180.247145 -42.191685) (xy 180.235073 -42.109017)
			(xy 180.231037 -42.02557) (xy 167.754255 -42.02557) (xy 167.757202 -42.049417) (xy 167.755954 -42.104912)
			(xy 167.746679 -42.15964) (xy 167.729572 -42.212446) (xy 167.704994 -42.262217) (xy 167.673463 -42.307901)
			(xy 167.635647 -42.348535) (xy 167.592341 -42.38326) (xy 167.544462 -42.411344) (xy 167.493018 -42.432194)
			(xy 167.439096 -42.44537) (xy 167.383834 -42.450595) (xy 167.328398 -42.447757) (xy 167.273958 -42.436916)
			(xy 167.221664 -42.418302) (xy 167.172619 -42.392307) (xy 167.127857 -42.35948) (xy 167.088325 -42.320514)
			(xy 167.054855 -42.276231) (xy 167.041068 -42.252138) (xy 167.030472 -42.233627) (xy 167.003972 -42.200204)
			(xy 166.97226 -42.17168) (xy 166.936228 -42.148855) (xy 166.896888 -42.132372) (xy 166.855348 -42.122693)
			(xy 166.812774 -42.120092) (xy 166.770364 -42.12464) (xy 166.729311 -42.136211) (xy 166.709852 -42.14495)
			(xy 166.684544 -42.156354) (xy 166.631466 -42.172597) (xy 166.576595 -42.180978) (xy 166.521089 -42.181319)
			(xy 166.466119 -42.173613) (xy 166.412846 -42.158024) (xy 166.362393 -42.134881) (xy 166.315827 -42.104671)
			(xy 166.274129 -42.068032) (xy 166.238181 -42.025738) (xy 166.20874 -41.978682) (xy 166.186428 -41.927856)
			(xy 166.171716 -41.874334) (xy 166.164915 -41.819245) (xy 154.957107 -41.819245) (xy 154.964386 -41.903607)
			(xy 154.964892 -41.95064) (xy 154.964386 -41.997673) (xy 154.9563 -42.091389) (xy 154.940187 -42.184064)
			(xy 154.916168 -42.275011) (xy 154.884418 -42.363556) (xy 154.845175 -42.449044) (xy 154.798728 -42.530842)
			(xy 154.745421 -42.608344) (xy 154.685649 -42.680977) (xy 154.619855 -42.748203) (xy 154.548525 -42.809524)
			(xy 154.472187 -42.864486) (xy 154.391407 -42.912682) (xy 154.306784 -42.953756) (xy 154.218942 -42.987403)
			(xy 154.128533 -43.013374) (xy 154.036227 -43.031477) (xy 153.942706 -43.041578) (xy 153.848662 -43.043601)
			(xy 153.754793 -43.037533) (xy 153.661793 -43.023418) (xy 153.570351 -43.001361) (xy 153.481143 -42.971524)
			(xy 153.394831 -42.93413) (xy 153.312052 -42.889453) (xy 153.233421 -42.837826) (xy 153.159519 -42.779631)
			(xy 153.090893 -42.715298) (xy 153.028051 -42.645304) (xy 152.971459 -42.570167) (xy 152.921536 -42.490443)
			(xy 152.878651 -42.406722) (xy 152.843122 -42.319625) (xy 152.815212 -42.229796) (xy 152.795127 -42.1379)
			(xy 152.783016 -42.044618) (xy 152.77897 -41.95064) (xy 146.3421 -41.95064) (xy 146.3421 -42.578528)
			(xy 147.64715 -42.578528) (xy 147.651221 -42.522906) (xy 147.663347 -42.468469) (xy 147.68327 -42.416378)
			(xy 147.710566 -42.367743) (xy 147.744652 -42.3236) (xy 147.784801 -42.284891) (xy 147.830159 -42.25244)
			(xy 147.879759 -42.226939) (xy 147.932543 -42.208932) (xy 147.987386 -42.198802) (xy 148.04312 -42.196765)
			(xy 148.098557 -42.202865) (xy 148.152514 -42.216971) (xy 148.203843 -42.238783) (xy 148.251449 -42.267837)
			(xy 148.294317 -42.303512) (xy 148.331534 -42.345049) (xy 148.362307 -42.391562) (xy 148.385979 -42.442059)
			(xy 148.402047 -42.495466) (xy 148.410167 -42.550642) (xy 148.410676 -42.578528) (xy 148.410167 -42.606414)
			(xy 148.402047 -42.66159) (xy 148.385979 -42.714997) (xy 148.362307 -42.765494) (xy 148.331534 -42.812007)
			(xy 148.294317 -42.853544) (xy 148.251449 -42.889219) (xy 148.203843 -42.918273) (xy 148.152514 -42.940085)
			(xy 148.098557 -42.954191) (xy 148.04312 -42.960291) (xy 147.987386 -42.958254) (xy 147.932543 -42.948124)
			(xy 147.879759 -42.930117) (xy 147.830159 -42.904616) (xy 147.784801 -42.872165) (xy 147.744652 -42.833456)
			(xy 147.710566 -42.789313) (xy 147.68327 -42.740678) (xy 147.663347 -42.688587) (xy 147.651221 -42.63415)
			(xy 147.64715 -42.578528) (xy 146.3421 -42.578528) (xy 146.3421 -43.2054) (xy 161.974782 -43.2054)
			(xy 161.978853 -43.149778) (xy 161.990979 -43.095341) (xy 162.010902 -43.04325) (xy 162.038198 -42.994615)
			(xy 162.072284 -42.950472) (xy 162.112433 -42.911763) (xy 162.157791 -42.879312) (xy 162.207391 -42.853811)
			(xy 162.260175 -42.835804) (xy 162.315018 -42.825674) (xy 162.370752 -42.823637) (xy 162.426189 -42.829737)
			(xy 162.480146 -42.843843) (xy 162.531475 -42.865655) (xy 162.579081 -42.894709) (xy 162.621949 -42.930384)
			(xy 162.659166 -42.971921) (xy 162.689939 -43.018434) (xy 162.713611 -43.068931) (xy 162.729679 -43.122338)
			(xy 162.737799 -43.177514) (xy 162.738308 -43.2054) (xy 162.737799 -43.233286) (xy 162.729679 -43.288462)
			(xy 162.713611 -43.341869) (xy 162.689939 -43.392366) (xy 162.659166 -43.438879) (xy 162.621949 -43.480416)
			(xy 162.579081 -43.516091) (xy 162.531475 -43.545145) (xy 162.480146 -43.566957) (xy 162.426189 -43.581063)
			(xy 162.370752 -43.587163) (xy 162.315018 -43.585126) (xy 162.260175 -43.574996) (xy 162.207391 -43.556989)
			(xy 162.157791 -43.531488) (xy 162.112433 -43.499037) (xy 162.072284 -43.460328) (xy 162.038198 -43.416185)
			(xy 162.010902 -43.36755) (xy 161.990979 -43.315459) (xy 161.978853 -43.261022) (xy 161.974782 -43.2054)
			(xy 146.3421 -43.2054) (xy 146.3421 -44.680124) (xy 150.110696 -44.680124) (xy 150.114767 -44.624502)
			(xy 150.126893 -44.570065) (xy 150.146816 -44.517974) (xy 150.174112 -44.469339) (xy 150.208198 -44.425196)
			(xy 150.248347 -44.386487) (xy 150.293705 -44.354036) (xy 150.343305 -44.328535) (xy 150.396089 -44.310528)
			(xy 150.450932 -44.300398) (xy 150.506666 -44.298361) (xy 150.562103 -44.304461) (xy 150.61606 -44.318567)
			(xy 150.667389 -44.340379) (xy 150.714995 -44.369433) (xy 150.757863 -44.405108) (xy 150.762811 -44.41063)
			(xy 153.210774 -44.41063) (xy 153.214788 -44.337869) (xy 153.226782 -44.265992) (xy 153.246611 -44.19587)
			(xy 153.274033 -44.128356) (xy 153.308716 -44.064267) (xy 153.350238 -44.004383) (xy 153.398097 -43.949431)
			(xy 153.45171 -43.900076) (xy 153.510427 -43.856919) (xy 153.573535 -43.820484) (xy 153.640269 -43.791212)
			(xy 153.709817 -43.769458) (xy 153.781337 -43.755488) (xy 153.853959 -43.749471) (xy 153.926803 -43.751479)
			(xy 153.998983 -43.761488) (xy 154.001668 -43.762168) (xy 174.261016 -43.762168) (xy 174.265087 -43.706546)
			(xy 174.277213 -43.652109) (xy 174.297136 -43.600018) (xy 174.324432 -43.551383) (xy 174.358518 -43.50724)
			(xy 174.398667 -43.468531) (xy 174.444025 -43.43608) (xy 174.493625 -43.410579) (xy 174.546409 -43.392572)
			(xy 174.601252 -43.382442) (xy 174.656986 -43.380405) (xy 174.712423 -43.386505) (xy 174.76638 -43.400611)
			(xy 174.817709 -43.422423) (xy 174.865315 -43.451477) (xy 174.908183 -43.487152) (xy 174.9454 -43.528689)
			(xy 174.976173 -43.575202) (xy 174.999845 -43.625699) (xy 175.015913 -43.679106) (xy 175.024033 -43.734282)
			(xy 175.024542 -43.762168) (xy 175.024033 -43.790054) (xy 175.015913 -43.84523) (xy 174.999845 -43.898637)
			(xy 174.976173 -43.949134) (xy 174.9454 -43.995647) (xy 174.908183 -44.037184) (xy 174.883687 -44.05757)
			(xy 180.231037 -44.05757) (xy 180.235073 -43.974123) (xy 180.247145 -43.891455) (xy 180.267138 -43.810338)
			(xy 180.294867 -43.731529) (xy 180.330073 -43.655764) (xy 180.372427 -43.583751) (xy 180.421533 -43.516162)
			(xy 180.476934 -43.453628) (xy 180.538111 -43.396733) (xy 180.604494 -43.346007) (xy 180.675462 -43.301926)
			(xy 180.750354 -43.2649) (xy 180.82847 -43.235274) (xy 180.90908 -43.213326) (xy 180.991432 -43.199261)
			(xy 181.074758 -43.193209) (xy 181.158278 -43.195228) (xy 181.241214 -43.205298) (xy 181.32279 -43.223326)
			(xy 181.402246 -43.249143) (xy 181.478839 -43.282508) (xy 181.551855 -43.323109) (xy 181.620611 -43.370568)
			(xy 181.684465 -43.424441) (xy 181.742822 -43.484226) (xy 181.795137 -43.549363) (xy 181.84092 -43.619246)
			(xy 181.879745 -43.693221) (xy 181.91125 -43.770598) (xy 181.935139 -43.850655) (xy 181.95119 -43.932643)
			(xy 181.959253 -44.015798) (xy 181.959758 -44.05757) (xy 182.847237 -44.05757) (xy 182.851273 -43.974123)
			(xy 182.863345 -43.891455) (xy 182.883338 -43.810338) (xy 182.911067 -43.731529) (xy 182.946273 -43.655764)
			(xy 182.988627 -43.583751) (xy 183.037733 -43.516162) (xy 183.093134 -43.453628) (xy 183.154311 -43.396733)
			(xy 183.220694 -43.346007) (xy 183.291662 -43.301926) (xy 183.366554 -43.2649) (xy 183.44467 -43.235274)
			(xy 183.52528 -43.213326) (xy 183.607632 -43.199261) (xy 183.690958 -43.193209) (xy 183.774478 -43.195228)
			(xy 183.857414 -43.205298) (xy 183.93899 -43.223326) (xy 184.018446 -43.249143) (xy 184.095039 -43.282508)
			(xy 184.168055 -43.323109) (xy 184.236811 -43.370568) (xy 184.300665 -43.424441) (xy 184.359022 -43.484226)
			(xy 184.411337 -43.549363) (xy 184.45712 -43.619246) (xy 184.495945 -43.693221) (xy 184.52745 -43.770598)
			(xy 184.551339 -43.850655) (xy 184.56739 -43.932643) (xy 184.575453 -44.015798) (xy 184.575958 -44.05757)
			(xy 184.575453 -44.099342) (xy 184.56739 -44.182497) (xy 184.551339 -44.264485) (xy 184.52745 -44.344542)
			(xy 184.495945 -44.421919) (xy 184.45712 -44.495894) (xy 184.411337 -44.565777) (xy 184.359022 -44.630914)
			(xy 184.300665 -44.690699) (xy 184.236811 -44.744572) (xy 184.168055 -44.792031) (xy 184.095039 -44.832632)
			(xy 184.018446 -44.865997) (xy 183.93899 -44.891814) (xy 183.857414 -44.909842) (xy 183.774478 -44.919912)
			(xy 183.690958 -44.921931) (xy 183.607632 -44.915879) (xy 183.52528 -44.901814) (xy 183.44467 -44.879866)
			(xy 183.366554 -44.85024) (xy 183.291662 -44.813214) (xy 183.220694 -44.769133) (xy 183.154311 -44.718407)
			(xy 183.093134 -44.661512) (xy 183.037733 -44.598978) (xy 182.988627 -44.531389) (xy 182.946273 -44.459376)
			(xy 182.911067 -44.383611) (xy 182.883338 -44.304802) (xy 182.863345 -44.223685) (xy 182.851273 -44.141017)
			(xy 182.847237 -44.05757) (xy 181.959758 -44.05757) (xy 181.959253 -44.099342) (xy 181.95119 -44.182497)
			(xy 181.935139 -44.264485) (xy 181.91125 -44.344542) (xy 181.879745 -44.421919) (xy 181.84092 -44.495894)
			(xy 181.795137 -44.565777) (xy 181.742822 -44.630914) (xy 181.684465 -44.690699) (xy 181.620611 -44.744572)
			(xy 181.551855 -44.792031) (xy 181.478839 -44.832632) (xy 181.402246 -44.865997) (xy 181.32279 -44.891814)
			(xy 181.241214 -44.909842) (xy 181.158278 -44.919912) (xy 181.074758 -44.921931) (xy 180.991432 -44.915879)
			(xy 180.90908 -44.901814) (xy 180.82847 -44.879866) (xy 180.750354 -44.85024) (xy 180.675462 -44.813214)
			(xy 180.604494 -44.769133) (xy 180.538111 -44.718407) (xy 180.476934 -44.661512) (xy 180.421533 -44.598978)
			(xy 180.372427 -44.531389) (xy 180.330073 -44.459376) (xy 180.294867 -44.383611) (xy 180.267138 -44.304802)
			(xy 180.247145 -44.223685) (xy 180.235073 -44.141017) (xy 180.231037 -44.05757) (xy 174.883687 -44.05757)
			(xy 174.865315 -44.072859) (xy 174.817709 -44.101913) (xy 174.76638 -44.123725) (xy 174.712423 -44.137831)
			(xy 174.656986 -44.143931) (xy 174.601252 -44.141894) (xy 174.546409 -44.131764) (xy 174.493625 -44.113757)
			(xy 174.444025 -44.088256) (xy 174.398667 -44.055805) (xy 174.358518 -44.017096) (xy 174.324432 -43.972953)
			(xy 174.297136 -43.924318) (xy 174.277213 -43.872227) (xy 174.265087 -43.81779) (xy 174.261016 -43.762168)
			(xy 154.001668 -43.762168) (xy 154.069625 -43.779377) (xy 154.13787 -43.804928) (xy 154.202889 -43.837832)
			(xy 154.263895 -43.877688) (xy 154.320145 -43.924014) (xy 154.370958 -43.976247) (xy 154.415716 -44.033753)
			(xy 154.453877 -44.095833) (xy 154.484977 -44.161735) (xy 154.508638 -44.230658) (xy 154.524574 -44.301765)
			(xy 154.53259 -44.374194) (xy 154.533092 -44.41063) (xy 154.53259 -44.447066) (xy 154.524574 -44.519495)
			(xy 154.508638 -44.590602) (xy 154.484977 -44.659525) (xy 154.453877 -44.725427) (xy 154.415716 -44.787507)
			(xy 154.370958 -44.845013) (xy 154.320145 -44.897246) (xy 154.263895 -44.943572) (xy 154.202889 -44.983428)
			(xy 154.13787 -45.016332) (xy 154.069625 -45.041883) (xy 153.998983 -45.059772) (xy 153.926803 -45.069781)
			(xy 153.853959 -45.071789) (xy 153.781337 -45.065772) (xy 153.709817 -45.051802) (xy 153.640269 -45.030048)
			(xy 153.573535 -45.000776) (xy 153.510427 -44.964341) (xy 153.45171 -44.921184) (xy 153.398097 -44.871829)
			(xy 153.350238 -44.816877) (xy 153.308716 -44.756993) (xy 153.274033 -44.692904) (xy 153.246611 -44.62539)
			(xy 153.226782 -44.555268) (xy 153.214788 -44.483391) (xy 153.210774 -44.41063) (xy 150.762811 -44.41063)
			(xy 150.79508 -44.446645) (xy 150.825853 -44.493158) (xy 150.849525 -44.543655) (xy 150.865593 -44.597062)
			(xy 150.873713 -44.652238) (xy 150.874222 -44.680124) (xy 150.873713 -44.70801) (xy 150.865593 -44.763186)
			(xy 150.849525 -44.816593) (xy 150.825853 -44.86709) (xy 150.79508 -44.913603) (xy 150.757863 -44.95514)
			(xy 150.714995 -44.990815) (xy 150.667389 -45.019869) (xy 150.61606 -45.041681) (xy 150.562103 -45.055787)
			(xy 150.506666 -45.061887) (xy 150.450932 -45.05985) (xy 150.396089 -45.04972) (xy 150.343305 -45.031713)
			(xy 150.293705 -45.006212) (xy 150.248347 -44.973761) (xy 150.208198 -44.935052) (xy 150.174112 -44.890909)
			(xy 150.146816 -44.842274) (xy 150.126893 -44.790183) (xy 150.114767 -44.735746) (xy 150.110696 -44.680124)
			(xy 146.3421 -44.680124) (xy 146.3421 -45.70857) (xy 147.424392 -45.70857) (xy 147.428463 -45.652948)
			(xy 147.440589 -45.598511) (xy 147.460512 -45.54642) (xy 147.487808 -45.497785) (xy 147.521894 -45.453642)
			(xy 147.562043 -45.414933) (xy 147.607401 -45.382482) (xy 147.657001 -45.356981) (xy 147.709785 -45.338974)
			(xy 147.764628 -45.328844) (xy 147.820362 -45.326807) (xy 147.875799 -45.332907) (xy 147.929756 -45.347013)
			(xy 147.981085 -45.368825) (xy 148.028691 -45.397879) (xy 148.071559 -45.433554) (xy 148.108776 -45.475091)
			(xy 148.139549 -45.521604) (xy 148.163221 -45.572101) (xy 148.179289 -45.625508) (xy 148.187409 -45.680684)
			(xy 148.187918 -45.70857) (xy 150.31034 -45.70857) (xy 150.314411 -45.652948) (xy 150.326537 -45.598511)
			(xy 150.34646 -45.54642) (xy 150.373756 -45.497785) (xy 150.407842 -45.453642) (xy 150.447991 -45.414933)
			(xy 150.493349 -45.382482) (xy 150.542949 -45.356981) (xy 150.595733 -45.338974) (xy 150.650576 -45.328844)
			(xy 150.70631 -45.326807) (xy 150.761747 -45.332907) (xy 150.815704 -45.347013) (xy 150.867033 -45.368825)
			(xy 150.914639 -45.397879) (xy 150.957507 -45.433554) (xy 150.994724 -45.475091) (xy 151.025497 -45.521604)
			(xy 151.049169 -45.572101) (xy 151.065237 -45.625508) (xy 151.073357 -45.680684) (xy 151.073866 -45.70857)
			(xy 151.073357 -45.736456) (xy 151.065237 -45.791632) (xy 151.049169 -45.845039) (xy 151.025497 -45.895536)
			(xy 150.994724 -45.942049) (xy 150.957507 -45.983586) (xy 150.914639 -46.019261) (xy 150.867033 -46.048315)
			(xy 150.815704 -46.070127) (xy 150.761747 -46.084233) (xy 150.70631 -46.090333) (xy 150.650576 -46.088296)
			(xy 150.595733 -46.078166) (xy 150.542949 -46.060159) (xy 150.493349 -46.034658) (xy 150.447991 -46.002207)
			(xy 150.407842 -45.963498) (xy 150.373756 -45.919355) (xy 150.34646 -45.87072) (xy 150.326537 -45.818629)
			(xy 150.314411 -45.764192) (xy 150.31034 -45.70857) (xy 148.187918 -45.70857) (xy 148.187409 -45.736456)
			(xy 148.179289 -45.791632) (xy 148.163221 -45.845039) (xy 148.139549 -45.895536) (xy 148.108776 -45.942049)
			(xy 148.071559 -45.983586) (xy 148.028691 -46.019261) (xy 147.981085 -46.048315) (xy 147.929756 -46.070127)
			(xy 147.875799 -46.084233) (xy 147.820362 -46.090333) (xy 147.764628 -46.088296) (xy 147.709785 -46.078166)
			(xy 147.657001 -46.060159) (xy 147.607401 -46.034658) (xy 147.562043 -46.002207) (xy 147.521894 -45.963498)
			(xy 147.487808 -45.919355) (xy 147.460512 -45.87072) (xy 147.440589 -45.818629) (xy 147.428463 -45.764192)
			(xy 147.424392 -45.70857) (xy 146.3421 -45.70857) (xy 146.3421 -47.226728) (xy 154.5209 -47.226728)
			(xy 154.5209 -45.410628) (xy 154.52852 -45.35297) (xy 154.534392 -45.312071) (xy 154.553142 -45.231595)
			(xy 154.579602 -45.153314) (xy 154.613522 -45.077965) (xy 154.654582 -45.006258) (xy 154.702398 -44.938866)
			(xy 154.756518 -44.876424) (xy 154.816434 -44.819519) (xy 154.881581 -44.768688) (xy 154.951347 -44.724408)
			(xy 155.025075 -44.687095) (xy 155.102071 -44.657102) (xy 155.181611 -44.634711) (xy 155.262946 -44.620131)
			(xy 155.345311 -44.6135) (xy 155.427932 -44.614882) (xy 155.510029 -44.624261) (xy 155.590832 -44.641552)
			(xy 155.669579 -44.66659) (xy 155.74553 -44.699139) (xy 155.802984 -44.730671) (xy 158.204786 -44.730671)
			(xy 158.208335 -44.67481) (xy 158.220009 -44.620067) (xy 158.239556 -44.567617) (xy 158.266558 -44.518587)
			(xy 158.300435 -44.474028) (xy 158.340458 -44.434898) (xy 158.38577 -44.402036) (xy 158.435398 -44.376149)
			(xy 158.488275 -44.35779) (xy 158.543268 -44.347355) (xy 158.599195 -44.345068) (xy 158.654856 -44.350978)
			(xy 158.709056 -44.364957) (xy 158.760632 -44.386706) (xy 158.808476 -44.415758) (xy 158.851561 -44.45149)
			(xy 158.888963 -44.493133) (xy 158.919878 -44.539795) (xy 158.943643 -44.590473) (xy 158.959748 -44.64408)
			(xy 158.967847 -44.699465) (xy 158.967766 -44.755439) (xy 158.959506 -44.8108) (xy 158.943246 -44.86436)
			(xy 158.919335 -44.914969) (xy 158.888284 -44.961541) (xy 158.869888 -44.982638) (xy 158.855605 -44.999185)
			(xy 158.832268 -45.03614) (xy 158.815595 -45.076541) (xy 158.806079 -45.119198) (xy 158.803998 -45.162855)
			(xy 158.809416 -45.206224) (xy 158.822171 -45.248028) (xy 158.841889 -45.287034) (xy 158.867987 -45.322092)
			(xy 158.899698 -45.35217) (xy 158.91764 -45.364654) (xy 158.940108 -45.379413) (xy 158.981256 -45.414006)
			(xy 159.017496 -45.453713) (xy 159.048196 -45.497842) (xy 159.072824 -45.545627) (xy 159.09095 -45.596237)
			(xy 159.102259 -45.648792) (xy 159.104838 -45.67555) (xy 159.106616 -45.692314) (xy 159.106616 -46.54677)
			(xy 180.231037 -46.54677) (xy 180.235073 -46.463323) (xy 180.247145 -46.380655) (xy 180.267138 -46.299538)
			(xy 180.294867 -46.220729) (xy 180.330073 -46.144964) (xy 180.372427 -46.072951) (xy 180.421533 -46.005362)
			(xy 180.476934 -45.942828) (xy 180.538111 -45.885933) (xy 180.604494 -45.835207) (xy 180.675462 -45.791126)
			(xy 180.750354 -45.7541) (xy 180.82847 -45.724474) (xy 180.90908 -45.702526) (xy 180.991432 -45.688461)
			(xy 181.074758 -45.682409) (xy 181.158278 -45.684428) (xy 181.241214 -45.694498) (xy 181.32279 -45.712526)
			(xy 181.402246 -45.738343) (xy 181.478839 -45.771708) (xy 181.551855 -45.812309) (xy 181.620611 -45.859768)
			(xy 181.684465 -45.913641) (xy 181.742822 -45.973426) (xy 181.795137 -46.038563) (xy 181.84092 -46.108446)
			(xy 181.879745 -46.182421) (xy 181.91125 -46.259798) (xy 181.935139 -46.339855) (xy 181.95119 -46.421843)
			(xy 181.959253 -46.504998) (xy 181.959758 -46.54677) (xy 182.847237 -46.54677) (xy 182.851273 -46.463323)
			(xy 182.863345 -46.380655) (xy 182.883338 -46.299538) (xy 182.911067 -46.220729) (xy 182.946273 -46.144964)
			(xy 182.988627 -46.072951) (xy 183.037733 -46.005362) (xy 183.093134 -45.942828) (xy 183.154311 -45.885933)
			(xy 183.220694 -45.835207) (xy 183.291662 -45.791126) (xy 183.366554 -45.7541) (xy 183.44467 -45.724474)
			(xy 183.52528 -45.702526) (xy 183.607632 -45.688461) (xy 183.690958 -45.682409) (xy 183.774478 -45.684428)
			(xy 183.857414 -45.694498) (xy 183.93899 -45.712526) (xy 184.018446 -45.738343) (xy 184.095039 -45.771708)
			(xy 184.168055 -45.812309) (xy 184.236811 -45.859768) (xy 184.300665 -45.913641) (xy 184.359022 -45.973426)
			(xy 184.411337 -46.038563) (xy 184.45712 -46.108446) (xy 184.495945 -46.182421) (xy 184.52745 -46.259798)
			(xy 184.551339 -46.339855) (xy 184.56739 -46.421843) (xy 184.575453 -46.504998) (xy 184.575958 -46.54677)
			(xy 184.575453 -46.588542) (xy 184.56739 -46.671697) (xy 184.551339 -46.753685) (xy 184.52745 -46.833742)
			(xy 184.495945 -46.911119) (xy 184.45712 -46.985094) (xy 184.411337 -47.054977) (xy 184.359022 -47.120114)
			(xy 184.300665 -47.179899) (xy 184.236811 -47.233772) (xy 184.168055 -47.281231) (xy 184.095039 -47.321832)
			(xy 184.018446 -47.355197) (xy 183.93899 -47.381014) (xy 183.857414 -47.399042) (xy 183.774478 -47.409112)
			(xy 183.690958 -47.411131) (xy 183.607632 -47.405079) (xy 183.52528 -47.391014) (xy 183.44467 -47.369066)
			(xy 183.366554 -47.33944) (xy 183.291662 -47.302414) (xy 183.220694 -47.258333) (xy 183.154311 -47.207607)
			(xy 183.093134 -47.150712) (xy 183.037733 -47.088178) (xy 182.988627 -47.020589) (xy 182.946273 -46.948576)
			(xy 182.911067 -46.872811) (xy 182.883338 -46.794002) (xy 182.863345 -46.712885) (xy 182.851273 -46.630217)
			(xy 182.847237 -46.54677) (xy 181.959758 -46.54677) (xy 181.959253 -46.588542) (xy 181.95119 -46.671697)
			(xy 181.935139 -46.753685) (xy 181.91125 -46.833742) (xy 181.879745 -46.911119) (xy 181.84092 -46.985094)
			(xy 181.795137 -47.054977) (xy 181.742822 -47.120114) (xy 181.684465 -47.179899) (xy 181.620611 -47.233772)
			(xy 181.551855 -47.281231) (xy 181.478839 -47.321832) (xy 181.402246 -47.355197) (xy 181.32279 -47.381014)
			(xy 181.241214 -47.399042) (xy 181.158278 -47.409112) (xy 181.074758 -47.411131) (xy 180.991432 -47.405079)
			(xy 180.90908 -47.391014) (xy 180.82847 -47.369066) (xy 180.750354 -47.33944) (xy 180.675462 -47.302414)
			(xy 180.604494 -47.258333) (xy 180.538111 -47.207607) (xy 180.476934 -47.150712) (xy 180.421533 -47.088178)
			(xy 180.372427 -47.020589) (xy 180.330073 -46.948576) (xy 180.294867 -46.872811) (xy 180.267138 -46.794002)
			(xy 180.247145 -46.712885) (xy 180.235073 -46.630217) (xy 180.231037 -46.54677) (xy 159.106616 -46.54677)
			(xy 159.106616 -46.966124) (xy 159.106108 -46.966886) (xy 159.106108 -46.978062) (xy 159.105861 -47.006559)
			(xy 159.098401 -47.063055) (xy 159.083131 -47.117957) (xy 159.06035 -47.170192) (xy 159.030503 -47.218738)
			(xy 158.994175 -47.262644) (xy 158.952077 -47.301052) (xy 158.905031 -47.33321) (xy 158.853958 -47.35849)
			(xy 158.799858 -47.376396) (xy 158.743789 -47.386579) (xy 158.686847 -47.388839) (xy 158.630147 -47.383132)
			(xy 158.574798 -47.369569) (xy 158.521882 -47.348417) (xy 158.472436 -47.320088) (xy 158.427426 -47.285137)
			(xy 158.387732 -47.244248) (xy 158.354132 -47.198221) (xy 158.327283 -47.147955) (xy 158.30771 -47.094436)
			(xy 158.295796 -47.038708) (xy 158.293308 -47.01032) (xy 158.292292 -46.997366) (xy 158.292292 -45.707554)
			(xy 158.292831 -45.677872) (xy 158.301504 -45.619145) (xy 158.318617 -45.5623) (xy 158.343806 -45.508544)
			(xy 158.376536 -45.459018) (xy 158.395924 -45.436536) (xy 158.406592 -45.425106) (xy 158.42159 -45.408994)
			(xy 158.446272 -45.372549) (xy 158.464305 -45.332396) (xy 158.475149 -45.289736) (xy 158.478481 -45.245846)
			(xy 158.4742 -45.202038) (xy 158.462435 -45.159623) (xy 158.443537 -45.11987) (xy 158.418073 -45.083968)
			(xy 158.386803 -45.05299) (xy 158.369 -45.040042) (xy 158.34627 -45.023708) (xy 158.305482 -44.985375)
			(xy 158.270733 -44.941494) (xy 158.242768 -44.893006) (xy 158.222189 -44.840953) (xy 158.209437 -44.786451)
			(xy 158.204786 -44.730671) (xy 155.802984 -44.730671) (xy 155.817969 -44.738895) (xy 155.886216 -44.785482)
			(xy 155.949628 -44.838463) (xy 156.007608 -44.897338) (xy 156.05961 -44.961555) (xy 156.105147 -45.030507)
			(xy 156.143788 -45.103547) (xy 156.17517 -45.179988) (xy 156.198998 -45.259109) (xy 156.215049 -45.340167)
			(xy 156.223169 -45.422399) (xy 156.223716 -45.463714) (xy 156.223716 -47.156624) (xy 156.223462 -47.16526)
			(xy 156.222843 -47.20614) (xy 156.214577 -47.287488) (xy 156.198548 -47.367667) (xy 156.174905 -47.44594)
			(xy 156.143865 -47.521586) (xy 156.105716 -47.593907) (xy 156.060807 -47.662236) (xy 156.009553 -47.725944)
			(xy 155.952427 -47.784445) (xy 155.92398 -47.808466) (xy 169.113221 -47.808466) (xy 169.113225 -47.752277)
			(xy 169.121472 -47.696696) (xy 169.137782 -47.642927) (xy 169.161804 -47.592131) (xy 169.193016 -47.545409)
			(xy 169.230745 -47.50377) (xy 169.274173 -47.468117) (xy 169.322362 -47.439219) (xy 169.374268 -47.417703)
			(xy 169.428769 -47.404034) (xy 169.484686 -47.398507) (xy 169.540808 -47.401243) (xy 169.595923 -47.412181)
			(xy 169.648836 -47.431086) (xy 169.698404 -47.457548) (xy 169.721276 -47.47387) (xy 169.740201 -47.487276)
			(xy 169.781833 -47.507699) (xy 169.82648 -47.520231) (xy 169.87266 -47.524455) (xy 169.91884 -47.520231)
			(xy 169.963487 -47.507699) (xy 170.005119 -47.487276) (xy 170.024044 -47.47387) (xy 170.046875 -47.457484)
			(xy 170.096451 -47.43102) (xy 170.149373 -47.412115) (xy 170.204496 -47.401176) (xy 170.260627 -47.398442)
			(xy 170.316552 -47.403971) (xy 170.371061 -47.417644) (xy 170.422975 -47.439165) (xy 170.47117 -47.468067)
			(xy 170.514604 -47.503727) (xy 170.552338 -47.545372) (xy 170.583555 -47.592102) (xy 170.60758 -47.642906)
			(xy 170.623892 -47.696684) (xy 170.63214 -47.752273) (xy 170.632144 -47.80847) (xy 170.623905 -47.864061)
			(xy 170.6076 -47.917841) (xy 170.583583 -47.968648) (xy 170.552373 -48.015383) (xy 170.514646 -48.057033)
			(xy 170.471217 -48.0927) (xy 170.423026 -48.12161) (xy 170.371115 -48.143138) (xy 170.316608 -48.156819)
			(xy 170.260684 -48.162356) (xy 170.204553 -48.159631) (xy 170.149428 -48.148701) (xy 170.096503 -48.129803)
			(xy 170.046923 -48.103346) (xy 170.024044 -48.087026) (xy 170.005119 -48.07362) (xy 169.963487 -48.053197)
			(xy 169.91884 -48.040665) (xy 169.87266 -48.036441) (xy 169.82648 -48.040665) (xy 169.781833 -48.053197)
			(xy 169.740201 -48.07362) (xy 169.721276 -48.087026) (xy 169.698355 -48.103283) (xy 169.648784 -48.129737)
			(xy 169.595867 -48.148634) (xy 169.540752 -48.159564) (xy 169.484629 -48.162291) (xy 169.428713 -48.156756)
			(xy 169.374214 -48.143079) (xy 169.322311 -48.121555) (xy 169.274127 -48.09265) (xy 169.230703 -48.05699)
			(xy 169.192981 -48.015346) (xy 169.161775 -47.968619) (xy 169.137762 -47.91782) (xy 169.121459 -47.864048)
			(xy 169.113221 -47.808466) (xy 155.92398 -47.808466) (xy 155.889954 -47.837198) (xy 155.822711 -47.883717)
			(xy 155.751318 -47.923575) (xy 155.676431 -47.956403) (xy 155.598741 -47.981899) (xy 155.518965 -47.999829)
			(xy 155.437838 -48.010026) (xy 155.356106 -48.012397) (xy 155.274523 -48.00692) (xy 155.193842 -47.993646)
			(xy 155.114805 -47.972697) (xy 155.038141 -47.944265) (xy 154.964557 -47.908614) (xy 154.89473 -47.866071)
			(xy 154.829304 -47.817028) (xy 154.768882 -47.761938) (xy 154.714021 -47.701308) (xy 154.665227 -47.635697)
			(xy 154.622948 -47.56571) (xy 154.587576 -47.491991) (xy 154.559435 -47.41522) (xy 154.538785 -47.336105)
			(xy 154.531822 -47.295816) (xy 154.5209 -47.226728) (xy 146.3421 -47.226728) (xy 146.3421 -48.22063)
			(xy 153.210774 -48.22063) (xy 153.214788 -48.147869) (xy 153.226782 -48.075992) (xy 153.246611 -48.00587)
			(xy 153.274033 -47.938356) (xy 153.308716 -47.874267) (xy 153.350238 -47.814383) (xy 153.398097 -47.759431)
			(xy 153.45171 -47.710076) (xy 153.510427 -47.666919) (xy 153.573535 -47.630484) (xy 153.640269 -47.601212)
			(xy 153.709817 -47.579458) (xy 153.781337 -47.565488) (xy 153.853959 -47.559471) (xy 153.926803 -47.561479)
			(xy 153.998983 -47.571488) (xy 154.069625 -47.589377) (xy 154.13787 -47.614928) (xy 154.202889 -47.647832)
			(xy 154.263895 -47.687688) (xy 154.320145 -47.734014) (xy 154.370958 -47.786247) (xy 154.415716 -47.843753)
			(xy 154.453877 -47.905833) (xy 154.484977 -47.971735) (xy 154.508638 -48.040658) (xy 154.524574 -48.111765)
			(xy 154.53259 -48.184194) (xy 154.532938 -48.209454) (xy 158.355282 -48.209454) (xy 158.359353 -48.153832)
			(xy 158.371479 -48.099395) (xy 158.391402 -48.047304) (xy 158.418698 -47.998669) (xy 158.452784 -47.954526)
			(xy 158.492933 -47.915817) (xy 158.538291 -47.883366) (xy 158.587891 -47.857865) (xy 158.640675 -47.839858)
			(xy 158.695518 -47.829728) (xy 158.751252 -47.827691) (xy 158.806689 -47.833791) (xy 158.860646 -47.847897)
			(xy 158.911975 -47.869709) (xy 158.959581 -47.898763) (xy 159.002449 -47.934438) (xy 159.039666 -47.975975)
			(xy 159.070439 -48.022488) (xy 159.094111 -48.072985) (xy 159.110179 -48.126392) (xy 159.118299 -48.181568)
			(xy 159.118808 -48.209454) (xy 159.118299 -48.23734) (xy 159.110179 -48.292516) (xy 159.094111 -48.345923)
			(xy 159.070439 -48.39642) (xy 159.039666 -48.442933) (xy 159.002449 -48.48447) (xy 158.959581 -48.520145)
			(xy 158.911975 -48.549199) (xy 158.860646 -48.571011) (xy 158.806689 -48.585117) (xy 158.751252 -48.591217)
			(xy 158.695518 -48.58918) (xy 158.640675 -48.57905) (xy 158.587891 -48.561043) (xy 158.538291 -48.535542)
			(xy 158.492933 -48.503091) (xy 158.452784 -48.464382) (xy 158.418698 -48.420239) (xy 158.391402 -48.371604)
			(xy 158.371479 -48.319513) (xy 158.359353 -48.265076) (xy 158.355282 -48.209454) (xy 154.532938 -48.209454)
			(xy 154.533092 -48.22063) (xy 154.53259 -48.257066) (xy 154.524574 -48.329495) (xy 154.508638 -48.400602)
			(xy 154.484977 -48.469525) (xy 154.453877 -48.535427) (xy 154.415716 -48.597507) (xy 154.370958 -48.655013)
			(xy 154.320145 -48.707246) (xy 154.263895 -48.753572) (xy 154.202889 -48.793428) (xy 154.13787 -48.826332)
			(xy 154.069625 -48.851883) (xy 153.998983 -48.869772) (xy 153.926803 -48.879781) (xy 153.853959 -48.881789)
			(xy 153.781337 -48.875772) (xy 153.709817 -48.861802) (xy 153.640269 -48.840048) (xy 153.573535 -48.810776)
			(xy 153.510427 -48.774341) (xy 153.45171 -48.731184) (xy 153.398097 -48.681829) (xy 153.350238 -48.626877)
			(xy 153.308716 -48.566993) (xy 153.274033 -48.502904) (xy 153.246611 -48.43539) (xy 153.226782 -48.365268)
			(xy 153.214788 -48.293391) (xy 153.210774 -48.22063) (xy 146.3421 -48.22063) (xy 146.3421 -48.485044)
			(xy 145.495264 -49.33188) (xy 147.679662 -49.33188) (xy 147.683733 -49.276258) (xy 147.695859 -49.221821)
			(xy 147.715782 -49.16973) (xy 147.743078 -49.121095) (xy 147.777164 -49.076952) (xy 147.817313 -49.038243)
			(xy 147.862671 -49.005792) (xy 147.912271 -48.980291) (xy 147.965055 -48.962284) (xy 148.019898 -48.952154)
			(xy 148.075632 -48.950117) (xy 148.131069 -48.956217) (xy 148.185026 -48.970323) (xy 148.192469 -48.973486)
			(xy 149.14575 -48.973486) (xy 149.149821 -48.917864) (xy 149.161947 -48.863427) (xy 149.18187 -48.811336)
			(xy 149.209166 -48.762701) (xy 149.243252 -48.718558) (xy 149.283401 -48.679849) (xy 149.328759 -48.647398)
			(xy 149.378359 -48.621897) (xy 149.431143 -48.60389) (xy 149.485986 -48.59376) (xy 149.54172 -48.591723)
			(xy 149.597157 -48.597823) (xy 149.651114 -48.611929) (xy 149.702443 -48.633741) (xy 149.750049 -48.662795)
			(xy 149.792917 -48.69847) (xy 149.830134 -48.740007) (xy 149.860907 -48.78652) (xy 149.884579 -48.837017)
			(xy 149.900647 -48.890424) (xy 149.908767 -48.9456) (xy 149.909276 -48.973486) (xy 149.908767 -49.001372)
			(xy 149.900647 -49.056548) (xy 149.884579 -49.109955) (xy 149.860907 -49.160452) (xy 149.830134 -49.206965)
			(xy 149.792917 -49.248502) (xy 149.750049 -49.284177) (xy 149.702443 -49.313231) (xy 149.651114 -49.335043)
			(xy 149.597157 -49.349149) (xy 149.54172 -49.355249) (xy 149.485986 -49.353212) (xy 149.431143 -49.343082)
			(xy 149.378359 -49.325075) (xy 149.328759 -49.299574) (xy 149.283401 -49.267123) (xy 149.243252 -49.228414)
			(xy 149.209166 -49.184271) (xy 149.18187 -49.135636) (xy 149.161947 -49.083545) (xy 149.149821 -49.029108)
			(xy 149.14575 -48.973486) (xy 148.192469 -48.973486) (xy 148.236355 -48.992135) (xy 148.283961 -49.021189)
			(xy 148.326829 -49.056864) (xy 148.364046 -49.098401) (xy 148.394819 -49.144914) (xy 148.418491 -49.195411)
			(xy 148.434559 -49.248818) (xy 148.442679 -49.303994) (xy 148.443188 -49.33188) (xy 148.442679 -49.359766)
			(xy 148.434559 -49.414942) (xy 148.418491 -49.468349) (xy 148.394819 -49.518846) (xy 148.364046 -49.565359)
			(xy 148.326829 -49.606896) (xy 148.283961 -49.642571) (xy 148.236355 -49.671625) (xy 148.185026 -49.693437)
			(xy 148.131069 -49.707543) (xy 148.075632 -49.713643) (xy 148.019898 -49.711606) (xy 147.965055 -49.701476)
			(xy 147.912271 -49.683469) (xy 147.862671 -49.657968) (xy 147.817313 -49.625517) (xy 147.777164 -49.586808)
			(xy 147.743078 -49.542665) (xy 147.715782 -49.49403) (xy 147.695859 -49.441939) (xy 147.683733 -49.387502)
			(xy 147.679662 -49.33188) (xy 145.495264 -49.33188) (xy 144.657572 -50.169572) (xy 138.684762 -50.169572)
			(xy 138.683966 -50.196628) (xy 138.67568 -50.250118) (xy 138.659923 -50.301901) (xy 138.637009 -50.350939)
			(xy 138.6074 -50.39625) (xy 138.571687 -50.436924) (xy 138.530588 -50.472147) (xy 138.484926 -50.501212)
			(xy 138.435617 -50.523536) (xy 138.383649 -50.538673) (xy 138.330064 -50.546318) (xy 138.275936 -50.546318)
			(xy 138.222351 -50.538673) (xy 138.170383 -50.523536) (xy 138.121074 -50.501212) (xy 138.075412 -50.472147)
			(xy 138.034313 -50.436924) (xy 137.9986 -50.39625) (xy 137.968991 -50.350939) (xy 137.946077 -50.301901)
			(xy 137.93032 -50.250118) (xy 137.922034 -50.196628) (xy 137.921238 -50.169572) (xy 137.313924 -50.169572)
			(xy 137.294098 -50.190348) (xy 137.249317 -50.2263) (xy 137.199657 -50.255141) (xy 137.146238 -50.276219)
			(xy 137.090265 -50.289058) (xy 137.033 -50.293371) (xy 136.975735 -50.289058) (xy 136.919762 -50.276219)
			(xy 136.866343 -50.255141) (xy 136.816683 -50.2263) (xy 136.771902 -50.190348) (xy 136.752076 -50.169572)
			(xy 135.78332 -50.169572) (xy 135.763494 -50.190348) (xy 135.718713 -50.2263) (xy 135.669053 -50.255141)
			(xy 135.615634 -50.276219) (xy 135.559661 -50.289058) (xy 135.502396 -50.293371) (xy 135.445131 -50.289058)
			(xy 135.389158 -50.276219) (xy 135.335739 -50.255141) (xy 135.286079 -50.2263) (xy 135.241298 -50.190348)
			(xy 135.221472 -50.169572) (xy 133.622034 -50.169572) (xy 133.599677 -50.170047) (xy 133.555654 -50.177876)
			(xy 133.513678 -50.193283) (xy 133.475042 -50.215792) (xy 133.440937 -50.244709) (xy 133.412414 -50.279144)
			(xy 133.390351 -50.318036) (xy 133.375429 -50.360186) (xy 133.371336 -50.38217) (xy 133.367464 -50.409542)
			(xy 133.352848 -50.462854) (xy 133.330692 -50.5135) (xy 133.30146 -50.560418) (xy 133.265763 -50.602627)
			(xy 133.22435 -50.639244) (xy 133.178086 -50.669502) (xy 133.127941 -50.692767) (xy 133.074963 -50.708554)
			(xy 133.020262 -50.71653) (xy 132.964982 -50.71653) (xy 132.910281 -50.708554) (xy 132.857303 -50.692767)
			(xy 132.807158 -50.669502) (xy 132.760894 -50.639244) (xy 132.719481 -50.602627) (xy 132.683784 -50.560418)
			(xy 132.654552 -50.5135) (xy 132.632396 -50.462854) (xy 132.61778 -50.409542) (xy 132.613908 -50.38217)
			(xy 132.609803 -50.360185) (xy 132.59491 -50.318019) (xy 132.572864 -50.279112) (xy 132.544347 -50.244666)
			(xy 132.510238 -50.215746) (xy 132.471592 -50.193244) (xy 132.429604 -50.177858) (xy 132.38557 -50.17006)
			(xy 132.36321 -50.169572) (xy 128.69672 -50.169572) (xy 127.73914 -49.211992) (xy 127.73914 -47.20463)
			(xy 129.013712 -45.930312) (xy 133.560566 -45.930312) (xy 133.768592 -46.138338) (xy 134.949692 -46.138338)
			(xy 134.973382 -46.137813) (xy 135.019941 -46.12904) (xy 135.064071 -46.111795) (xy 135.104243 -46.086676)
			(xy 135.139069 -46.054552) (xy 135.167342 -46.016534) (xy 135.188085 -45.973937) (xy 135.200581 -45.928235)
			(xy 135.20293 -45.904658) (xy 135.2042 -45.881544) (xy 135.205216 -45.871638) (xy 135.20928 -45.844206)
			(xy 135.211689 -45.831845) (xy 135.21792 -45.807442) (xy 135.221726 -45.795438) (xy 135.222234 -45.794168)
			(xy 135.232756 -45.764451) (xy 135.262116 -45.708669) (xy 135.280654 -45.68317) (xy 135.293247 -45.664226)
			(xy 135.312204 -45.622882) (xy 135.3235 -45.578823) (xy 135.326772 -45.533457) (xy 135.321918 -45.488234)
			(xy 135.309092 -45.444596) (xy 135.288703 -45.403938) (xy 135.261403 -45.367559) (xy 135.245094 -45.3517)
			(xy 135.225369 -45.332765) (xy 135.190998 -45.290242) (xy 135.163051 -45.243247) (xy 135.1421 -45.192743)
			(xy 135.128573 -45.139765) (xy 135.12275 -45.085399) (xy 135.124747 -45.030759) (xy 135.134526 -44.976963)
			(xy 135.151884 -44.925115) (xy 135.176468 -44.876276) (xy 135.191754 -44.853606) (xy 135.208758 -44.830174)
			(xy 135.248681 -44.788247) (xy 135.29448 -44.752834) (xy 135.345104 -44.724748) (xy 135.399391 -44.704633)
			(xy 135.456095 -44.692953) (xy 135.513911 -44.689975) (xy 135.571515 -44.695767) (xy 135.599678 -44.702476)
			(xy 135.627364 -44.710858) (xy 135.65216 -44.719763) (xy 135.699232 -44.743429) (xy 135.742604 -44.773339)
			(xy 135.781455 -44.808925) (xy 135.815046 -44.849513) (xy 135.842742 -44.894333) (xy 135.864015 -44.942533)
			(xy 135.878463 -44.993199) (xy 135.882634 -45.019214) (xy 135.885612 -45.043528) (xy 135.886097 -45.092511)
			(xy 135.880329 -45.141155) (xy 135.87476 -45.16501) (xy 135.869172 -45.184822) (xy 135.858602 -45.216503)
			(xy 135.828077 -45.275898) (xy 135.808466 -45.302932) (xy 135.795872 -45.321875) (xy 135.776914 -45.363219)
			(xy 135.765618 -45.407278) (xy 135.762345 -45.452644) (xy 135.7672 -45.497868) (xy 135.780028 -45.541505)
			(xy 135.800418 -45.582162) (xy 135.82772 -45.61854) (xy 135.844026 -45.634402) (xy 135.851617 -45.641547)
			(xy 135.866102 -45.656542) (xy 135.872982 -45.664374) (xy 135.890665 -45.685579) (xy 135.920374 -45.732117)
			(xy 135.932164 -45.757084) (xy 135.942251 -45.78041) (xy 135.95686 -45.829085) (xy 135.964883 -45.879267)
			(xy 135.965946 -45.904658) (xy 135.968361 -45.928231) (xy 135.980828 -45.973941) (xy 136.001551 -46.016549)
			(xy 136.029811 -46.054578) (xy 136.06463 -46.086712) (xy 136.104801 -46.111835) (xy 136.148932 -46.129078)
			(xy 136.195494 -46.137844) (xy 136.219184 -46.138338) (xy 137.764012 -46.138338) (xy 138.250422 -45.651928)
			(xy 138.261825 -45.639801) (xy 138.278522 -45.61102) (xy 138.287214 -45.578901) (xy 138.28776 -45.562266)
			(xy 138.28776 -44.19727) (xy 135.9789 -41.88841) (xy 129.4511 -41.88841) (xy 128.179322 -40.616632)
			(xy 127.779272 -40.616632) (xy 127.756833 -40.617086) (xy 127.712644 -40.624922) (xy 127.670519 -40.640398)
			(xy 127.631768 -40.663034) (xy 127.597596 -40.692124) (xy 127.569065 -40.726766) (xy 127.547063 -40.76588)
			(xy 127.532274 -40.808251) (xy 127.525159 -40.852561) (xy 127.525937 -40.897432) (xy 127.534585 -40.941469)
			(xy 127.550835 -40.983301) (xy 127.562102 -41.002712) (xy 127.576936 -41.025833) (xy 127.600528 -41.075442)
			(xy 127.616761 -41.127921) (xy 127.625301 -41.182186) (xy 127.625971 -41.237114) (xy 127.618756 -41.291571)
			(xy 127.603806 -41.34443) (xy 127.58143 -41.394599) (xy 127.552091 -41.44104) (xy 127.516394 -41.482794)
			(xy 127.475079 -41.518996) (xy 127.428999 -41.5489) (xy 127.379106 -41.571885) (xy 127.326433 -41.587479)
			(xy 127.272068 -41.595356) (xy 127.217136 -41.595356) (xy 127.162771 -41.587479) (xy 127.110098 -41.571885)
			(xy 127.060205 -41.5489) (xy 127.014125 -41.518996) (xy 126.97281 -41.482794) (xy 126.937113 -41.44104)
			(xy 126.907774 -41.394599) (xy 126.885398 -41.34443) (xy 126.870448 -41.291571) (xy 126.863233 -41.237114)
			(xy 126.863903 -41.182186) (xy 126.872443 -41.127921) (xy 126.888676 -41.075442) (xy 126.912268 -41.025833)
			(xy 126.927102 -41.002712) (xy 126.938363 -40.983297) (xy 126.954607 -40.941459) (xy 126.963251 -40.89742)
			(xy 126.964027 -40.852547) (xy 126.95691 -40.808235) (xy 126.942122 -40.765861) (xy 126.920123 -40.726743)
			(xy 126.891597 -40.692096) (xy 126.857429 -40.662997) (xy 126.818682 -40.640351) (xy 126.77656 -40.624861)
			(xy 126.732372 -40.617009) (xy 126.709932 -40.616632) (xy 124.516134 -40.616632) (xy 124.492882 -40.617158)
			(xy 124.447156 -40.625628) (xy 124.403733 -40.642274) (xy 124.364062 -40.66654) (xy 124.329467 -40.697616)
			(xy 124.3011 -40.734467) (xy 124.27991 -40.775862) (xy 124.266602 -40.820421) (xy 124.26162 -40.866658)
			(xy 124.265131 -40.913029) (xy 124.270516 -40.935656) (xy 124.34951 -41.010586) (xy 124.362676 -41.022222)
			(xy 124.39383 -41.038444) (xy 124.42822 -41.045586) (xy 124.445776 -41.044876) (xy 124.45111 -41.044622)
			(xy 124.453396 -41.044368) (xy 124.48254 -41.041858) (xy 124.540964 -41.044742) (xy 124.59826 -41.056524)
			(xy 124.625862 -41.066212) (xy 124.652 -41.076459) (xy 124.70119 -41.10352) (xy 124.745883 -41.137495)
			(xy 124.785117 -41.177653) (xy 124.818043 -41.223126) (xy 124.843951 -41.272932) (xy 124.862282 -41.325996)
			(xy 124.87264 -41.381174) (xy 124.874802 -41.437274) (xy 124.868721 -41.493085) (xy 124.854529 -41.547403)
			(xy 124.844048 -41.57345) (xy 124.832638 -41.59897) (xy 124.803448 -41.646646) (xy 124.767616 -41.689553)
			(xy 124.725908 -41.726773) (xy 124.679215 -41.75751) (xy 124.628538 -41.781106) (xy 124.574961 -41.797057)
			(xy 124.51963 -41.805021) (xy 124.463729 -41.804827) (xy 124.408454 -41.79648) (xy 124.354988 -41.780158)
			(xy 124.304476 -41.756211) (xy 124.257998 -41.725151) (xy 124.216548 -41.687643) (xy 124.181014 -41.644488)
			(xy 124.152156 -41.596612) (xy 124.130591 -41.545037) (xy 124.123196 -41.518078) (xy 124.116211 -41.495961)
			(xy 124.095368 -41.454533) (xy 124.067355 -41.417574) (xy 124.033103 -41.386309) (xy 123.993748 -41.361775)
			(xy 123.950596 -41.344788) (xy 123.905078 -41.33591) (xy 123.881896 -41.335198) (xy 123.877578 -41.335198)
			(xy 123.850165 -41.334107) (xy 123.796061 -41.325026) (xy 123.743819 -41.308278) (xy 123.69452 -41.284211)
			(xy 123.671584 -41.269158) (xy 123.67133 -41.268904) (xy 123.656458 -41.259527) (xy 123.62308 -41.248527)
			(xy 123.587966 -41.247048) (xy 123.553781 -41.2552) (xy 123.523114 -41.272366) (xy 123.510294 -41.284398)
			(xy 122.950732 -41.84396) (xy 122.950732 -42.474134) (xy 125.693422 -42.474134) (xy 125.697493 -42.418512)
			(xy 125.709619 -42.364075) (xy 125.729542 -42.311984) (xy 125.756838 -42.263349) (xy 125.790924 -42.219206)
			(xy 125.831073 -42.180497) (xy 125.876431 -42.148046) (xy 125.926031 -42.122545) (xy 125.978815 -42.104538)
			(xy 126.033658 -42.094408) (xy 126.089392 -42.092371) (xy 126.144829 -42.098471) (xy 126.198786 -42.112577)
			(xy 126.250115 -42.134389) (xy 126.297721 -42.163443) (xy 126.340589 -42.199118) (xy 126.377806 -42.240655)
			(xy 126.408579 -42.287168) (xy 126.432251 -42.337665) (xy 126.448319 -42.391072) (xy 126.456439 -42.446248)
			(xy 126.456948 -42.474134) (xy 126.456439 -42.50202) (xy 126.448319 -42.557196) (xy 126.432251 -42.610603)
			(xy 126.408579 -42.6611) (xy 126.377806 -42.707613) (xy 126.340589 -42.74915) (xy 126.297721 -42.784825)
			(xy 126.250115 -42.813879) (xy 126.198786 -42.835691) (xy 126.144829 -42.849797) (xy 126.089392 -42.855897)
			(xy 126.033658 -42.85386) (xy 125.978815 -42.84373) (xy 125.926031 -42.825723) (xy 125.876431 -42.800222)
			(xy 125.831073 -42.767771) (xy 125.790924 -42.729062) (xy 125.756838 -42.684919) (xy 125.729542 -42.636284)
			(xy 125.709619 -42.584193) (xy 125.697493 -42.529756) (xy 125.693422 -42.474134) (xy 122.950732 -42.474134)
			(xy 122.950732 -43.048682) (xy 123.834142 -43.048682) (xy 123.838213 -42.99306) (xy 123.850339 -42.938623)
			(xy 123.870262 -42.886532) (xy 123.897558 -42.837897) (xy 123.931644 -42.793754) (xy 123.971793 -42.755045)
			(xy 124.017151 -42.722594) (xy 124.066751 -42.697093) (xy 124.119535 -42.679086) (xy 124.174378 -42.668956)
			(xy 124.230112 -42.666919) (xy 124.285549 -42.673019) (xy 124.339506 -42.687125) (xy 124.390835 -42.708937)
			(xy 124.438441 -42.737991) (xy 124.481309 -42.773666) (xy 124.518526 -42.815203) (xy 124.549299 -42.861716)
			(xy 124.572971 -42.912213) (xy 124.589039 -42.96562) (xy 124.597159 -43.020796) (xy 124.597668 -43.048682)
			(xy 124.597159 -43.076568) (xy 124.589039 -43.131744) (xy 124.572971 -43.185151) (xy 124.549299 -43.235648)
			(xy 124.518526 -43.282161) (xy 124.481309 -43.323698) (xy 124.438441 -43.359373) (xy 124.390835 -43.388427)
			(xy 124.339506 -43.410239) (xy 124.285549 -43.424345) (xy 124.230112 -43.430445) (xy 124.174378 -43.428408)
			(xy 124.119535 -43.418278) (xy 124.066751 -43.400271) (xy 124.017151 -43.37477) (xy 123.971793 -43.342319)
			(xy 123.931644 -43.30361) (xy 123.897558 -43.259467) (xy 123.870262 -43.210832) (xy 123.850339 -43.158741)
			(xy 123.838213 -43.104304) (xy 123.834142 -43.048682) (xy 122.950732 -43.048682) (xy 122.950732 -43.678621)
			(xy 125.010705 -43.678621) (xy 125.011379 -43.622785) (xy 125.020183 -43.567643) (xy 125.03693 -43.514374)
			(xy 125.061262 -43.464114) (xy 125.092659 -43.417937) (xy 125.130451 -43.376829) (xy 125.173831 -43.341668)
			(xy 125.221872 -43.313206) (xy 125.273549 -43.292048) (xy 125.327757 -43.278649) (xy 125.38334 -43.273293)
			(xy 125.439109 -43.276095) (xy 125.493875 -43.286996) (xy 125.546467 -43.305762) (xy 125.560727 -43.31335)
			(xy 131.373878 -43.31335) (xy 131.377951 -43.257691) (xy 131.390086 -43.203218) (xy 131.410022 -43.151092)
			(xy 131.437336 -43.102424) (xy 131.471444 -43.058252) (xy 131.511621 -43.019517) (xy 131.557009 -42.987045)
			(xy 131.606641 -42.961527) (xy 131.659461 -42.943508) (xy 131.71434 -42.933371) (xy 131.770111 -42.931333)
			(xy 131.825585 -42.937436) (xy 131.879578 -42.951552) (xy 131.930941 -42.973379) (xy 131.978579 -43.002452)
			(xy 132.021475 -43.038151) (xy 132.058717 -43.079715) (xy 132.089511 -43.126259) (xy 132.113199 -43.17679)
			(xy 132.129277 -43.230232) (xy 132.137403 -43.285446) (xy 132.137912 -43.31335) (xy 132.137403 -43.341254)
			(xy 132.129277 -43.396468) (xy 132.113199 -43.44991) (xy 132.089511 -43.500441) (xy 132.058717 -43.546985)
			(xy 132.021475 -43.588549) (xy 131.978579 -43.624248) (xy 131.930941 -43.653321) (xy 131.879578 -43.675148)
			(xy 131.825585 -43.689264) (xy 131.770111 -43.695367) (xy 131.71434 -43.693329) (xy 131.659461 -43.683192)
			(xy 131.606641 -43.665173) (xy 131.557009 -43.639655) (xy 131.511621 -43.607183) (xy 131.471444 -43.568448)
			(xy 131.437336 -43.524276) (xy 131.410022 -43.475608) (xy 131.390086 -43.423482) (xy 131.377951 -43.369009)
			(xy 131.373878 -43.31335) (xy 125.560727 -43.31335) (xy 125.595763 -43.331993) (xy 125.640709 -43.365128)
			(xy 125.680345 -43.40446) (xy 125.713827 -43.449149) (xy 125.740437 -43.498241) (xy 125.759608 -43.550687)
			(xy 125.770931 -43.605367) (xy 125.774163 -43.661113) (xy 125.769236 -43.716735) (xy 125.756255 -43.771045)
			(xy 125.735497 -43.822884) (xy 125.721872 -43.847258) (xy 125.711209 -43.866635) (xy 125.695922 -43.908131)
			(xy 125.688051 -43.951647) (xy 125.687834 -43.995868) (xy 125.695278 -44.039459) (xy 125.700845 -44.055039)
			(xy 129.157983 -44.055039) (xy 129.164086 -43.999565) (xy 129.178202 -43.945572) (xy 129.200029 -43.894209)
			(xy 129.229102 -43.846571) (xy 129.264801 -43.803675) (xy 129.306365 -43.766433) (xy 129.352909 -43.735639)
			(xy 129.40344 -43.711951) (xy 129.456882 -43.695873) (xy 129.512096 -43.687747) (xy 129.54 -43.687238)
			(xy 129.567904 -43.687747) (xy 129.623118 -43.695873) (xy 129.67656 -43.711951) (xy 129.727091 -43.735639)
			(xy 129.773635 -43.766433) (xy 129.815199 -43.803675) (xy 129.850898 -43.846571) (xy 129.869614 -43.877239)
			(xy 130.580383 -43.877239) (xy 130.586486 -43.821765) (xy 130.600602 -43.767772) (xy 130.622429 -43.716409)
			(xy 130.651502 -43.668771) (xy 130.687201 -43.625875) (xy 130.728765 -43.588633) (xy 130.775309 -43.557839)
			(xy 130.82584 -43.534151) (xy 130.879282 -43.518073) (xy 130.934496 -43.509947) (xy 130.9624 -43.509438)
			(xy 130.990304 -43.509947) (xy 131.045518 -43.518073) (xy 131.09896 -43.534151) (xy 131.149491 -43.557839)
			(xy 131.196035 -43.588633) (xy 131.237599 -43.625875) (xy 131.273298 -43.668771) (xy 131.302371 -43.716409)
			(xy 131.324198 -43.767772) (xy 131.338314 -43.821765) (xy 131.344417 -43.877239) (xy 131.342379 -43.93301)
			(xy 131.332242 -43.987889) (xy 131.314223 -44.040709) (xy 131.288705 -44.090341) (xy 131.256233 -44.135729)
			(xy 131.217498 -44.175906) (xy 131.173326 -44.210014) (xy 131.124658 -44.237328) (xy 131.072532 -44.257264)
			(xy 131.018059 -44.269399) (xy 130.9624 -44.273473) (xy 130.906741 -44.269399) (xy 130.852268 -44.257264)
			(xy 130.800142 -44.237328) (xy 130.751474 -44.210014) (xy 130.707302 -44.175906) (xy 130.668567 -44.135729)
			(xy 130.636095 -44.090341) (xy 130.610577 -44.040709) (xy 130.592558 -43.987889) (xy 130.582421 -43.93301)
			(xy 130.580383 -43.877239) (xy 129.869614 -43.877239) (xy 129.879971 -43.894209) (xy 129.901798 -43.945572)
			(xy 129.915914 -43.999565) (xy 129.922017 -44.055039) (xy 129.919979 -44.11081) (xy 129.909842 -44.165689)
			(xy 129.891823 -44.218509) (xy 129.866305 -44.268141) (xy 129.833833 -44.313529) (xy 129.795098 -44.353706)
			(xy 129.750926 -44.387814) (xy 129.702258 -44.415128) (xy 129.650132 -44.435064) (xy 129.595659 -44.447199)
			(xy 129.54 -44.451273) (xy 129.484341 -44.447199) (xy 129.429868 -44.435064) (xy 129.377742 -44.415128)
			(xy 129.329074 -44.387814) (xy 129.284902 -44.353706) (xy 129.246167 -44.313529) (xy 129.213695 -44.268141)
			(xy 129.188177 -44.218509) (xy 129.170158 -44.165689) (xy 129.160021 -44.11081) (xy 129.157983 -44.055039)
			(xy 125.700845 -44.055039) (xy 125.710157 -44.081103) (xy 125.732023 -44.119541) (xy 125.760213 -44.153613)
			(xy 125.776736 -44.168314) (xy 125.797683 -44.186785) (xy 125.83448 -44.228795) (xy 125.864761 -44.275719)
			(xy 125.887879 -44.326556) (xy 125.90334 -44.38022) (xy 125.910815 -44.435564) (xy 125.910143 -44.491406)
			(xy 125.901339 -44.546554) (xy 125.884591 -44.59983) (xy 125.860257 -44.650096) (xy 125.828855 -44.696278)
			(xy 125.791058 -44.737391) (xy 125.747672 -44.772555) (xy 125.699625 -44.801019) (xy 125.647941 -44.822177)
			(xy 125.593726 -44.835575) (xy 125.538136 -44.840928) (xy 125.48236 -44.838122) (xy 125.427589 -44.827216)
			(xy 125.374992 -44.808443) (xy 125.325694 -44.782204) (xy 125.280746 -44.74906) (xy 125.241109 -44.709719)
			(xy 125.207629 -44.66502) (xy 125.181022 -44.615919) (xy 125.161856 -44.563465) (xy 125.150541 -44.508777)
			(xy 125.147317 -44.453023) (xy 125.152254 -44.397395) (xy 125.165246 -44.343081) (xy 125.186016 -44.291241)
			(xy 125.199648 -44.266866) (xy 125.210387 -44.247529) (xy 125.225665 -44.206022) (xy 125.233525 -44.162497)
			(xy 125.233732 -44.118268) (xy 125.226277 -44.074672) (xy 125.211388 -44.033025) (xy 125.189512 -43.994584)
			(xy 125.161311 -43.960511) (xy 125.144784 -43.94581) (xy 125.123809 -43.927377) (xy 125.08702 -43.88537)
			(xy 125.056746 -43.838449) (xy 125.033633 -43.787616) (xy 125.018176 -43.733958) (xy 125.010705 -43.678621)
			(xy 122.950732 -43.678621) (xy 122.950732 -44.556426) (xy 123.785882 -44.556426) (xy 123.789953 -44.500804)
			(xy 123.802079 -44.446367) (xy 123.822002 -44.394276) (xy 123.849298 -44.345641) (xy 123.883384 -44.301498)
			(xy 123.923533 -44.262789) (xy 123.968891 -44.230338) (xy 124.018491 -44.204837) (xy 124.071275 -44.18683)
			(xy 124.126118 -44.1767) (xy 124.181852 -44.174663) (xy 124.237289 -44.180763) (xy 124.291246 -44.194869)
			(xy 124.342575 -44.216681) (xy 124.390181 -44.245735) (xy 124.433049 -44.28141) (xy 124.470266 -44.322947)
			(xy 124.501039 -44.36946) (xy 124.524711 -44.419957) (xy 124.540779 -44.473364) (xy 124.548899 -44.52854)
			(xy 124.549408 -44.556426) (xy 124.548899 -44.584312) (xy 124.540779 -44.639488) (xy 124.524711 -44.692895)
			(xy 124.501039 -44.743392) (xy 124.470266 -44.789905) (xy 124.433049 -44.831442) (xy 124.390181 -44.867117)
			(xy 124.342575 -44.896171) (xy 124.291246 -44.917983) (xy 124.237289 -44.932089) (xy 124.181852 -44.938189)
			(xy 124.126118 -44.936152) (xy 124.071275 -44.926022) (xy 124.018491 -44.908015) (xy 123.968891 -44.882514)
			(xy 123.923533 -44.850063) (xy 123.883384 -44.811354) (xy 123.849298 -44.767211) (xy 123.822002 -44.718576)
			(xy 123.802079 -44.666485) (xy 123.789953 -44.612048) (xy 123.785882 -44.556426) (xy 122.950732 -44.556426)
			(xy 122.950732 -45.722794) (xy 122.977656 -45.757338) (xy 122.994548 -45.7798) (xy 123.022245 -45.828703)
			(xy 123.042467 -45.881141) (xy 123.054776 -45.935977) (xy 123.056043 -45.953172) (xy 123.336302 -45.953172)
			(xy 123.340373 -45.89755) (xy 123.352499 -45.843113) (xy 123.372422 -45.791022) (xy 123.399718 -45.742387)
			(xy 123.433804 -45.698244) (xy 123.473953 -45.659535) (xy 123.519311 -45.627084) (xy 123.568911 -45.601583)
			(xy 123.621695 -45.583576) (xy 123.676538 -45.573446) (xy 123.732272 -45.571409) (xy 123.787709 -45.577509)
			(xy 123.841666 -45.591615) (xy 123.892995 -45.613427) (xy 123.940601 -45.642481) (xy 123.947628 -45.648329)
			(xy 126.349004 -45.648329) (xy 126.354069 -45.592652) (xy 126.367207 -45.53831) (xy 126.388137 -45.486469)
			(xy 126.416411 -45.438238) (xy 126.451423 -45.394652) (xy 126.492422 -45.356643) (xy 126.53853 -45.325026)
			(xy 126.58876 -45.300479) (xy 126.642035 -45.283527) (xy 126.669546 -45.278548) (xy 126.691438 -45.274497)
			(xy 126.733451 -45.259779) (xy 126.772258 -45.237967) (xy 126.806673 -45.209729) (xy 126.835642 -45.175927)
			(xy 126.85828 -45.137596) (xy 126.873894 -45.095907) (xy 126.882008 -45.052136) (xy 126.882652 -45.029882)
			(xy 126.883472 -45.002479) (xy 126.891861 -44.948306) (xy 126.907917 -44.895891) (xy 126.931311 -44.846314)
			(xy 126.96156 -44.800596) (xy 126.998041 -44.759679) (xy 127.040003 -44.724404) (xy 127.086582 -44.695499)
			(xy 127.136818 -44.673558) (xy 127.189678 -44.659033) (xy 127.244073 -44.652225) (xy 127.298882 -44.653272)
			(xy 127.352977 -44.662153) (xy 127.405243 -44.678685) (xy 127.454605 -44.702529) (xy 127.500046 -44.733192)
			(xy 127.54063 -44.770044) (xy 127.575522 -44.812325) (xy 127.604003 -44.859165) (xy 127.625486 -44.909599)
			(xy 127.639529 -44.962589) (xy 127.645843 -45.017043) (xy 127.644297 -45.07184) (xy 127.634924 -45.125852)
			(xy 127.626872 -45.152056) (xy 127.620453 -45.172934) (xy 127.614168 -45.216158) (xy 127.614369 -45.223439)
			(xy 130.707383 -45.223439) (xy 130.713486 -45.167965) (xy 130.727602 -45.113972) (xy 130.749429 -45.062609)
			(xy 130.778502 -45.014971) (xy 130.814201 -44.972075) (xy 130.855765 -44.934833) (xy 130.902309 -44.904039)
			(xy 130.95284 -44.880351) (xy 131.006282 -44.864273) (xy 131.061496 -44.856147) (xy 131.0894 -44.855638)
			(xy 131.117304 -44.856147) (xy 131.172518 -44.864273) (xy 131.22596 -44.880351) (xy 131.276491 -44.904039)
			(xy 131.323035 -44.934833) (xy 131.364599 -44.972075) (xy 131.400298 -45.014971) (xy 131.429371 -45.062609)
			(xy 131.451198 -45.113972) (xy 131.465314 -45.167965) (xy 131.471417 -45.223439) (xy 131.470637 -45.244775)
			(xy 132.033263 -45.244775) (xy 132.039366 -45.189301) (xy 132.053482 -45.135308) (xy 132.075309 -45.083945)
			(xy 132.104382 -45.036307) (xy 132.140081 -44.993411) (xy 132.181645 -44.956169) (xy 132.228189 -44.925375)
			(xy 132.27872 -44.901687) (xy 132.332162 -44.885609) (xy 132.387376 -44.877483) (xy 132.41528 -44.876974)
			(xy 132.443184 -44.877483) (xy 132.498398 -44.885609) (xy 132.55184 -44.901687) (xy 132.602371 -44.925375)
			(xy 132.648915 -44.956169) (xy 132.657772 -44.964105) (xy 133.379717 -44.964105) (xy 133.38582 -44.908631)
			(xy 133.399936 -44.854638) (xy 133.421763 -44.803275) (xy 133.450836 -44.755637) (xy 133.486535 -44.712741)
			(xy 133.528099 -44.675499) (xy 133.574643 -44.644705) (xy 133.625174 -44.621017) (xy 133.678616 -44.604939)
			(xy 133.73383 -44.596813) (xy 133.761734 -44.596304) (xy 133.789638 -44.596813) (xy 133.844852 -44.604939)
			(xy 133.898294 -44.621017) (xy 133.948825 -44.644705) (xy 133.995369 -44.675499) (xy 134.036933 -44.712741)
			(xy 134.072632 -44.755637) (xy 134.101705 -44.803275) (xy 134.123532 -44.854638) (xy 134.137648 -44.908631)
			(xy 134.143751 -44.964105) (xy 134.141713 -45.019876) (xy 134.131576 -45.074755) (xy 134.113557 -45.127575)
			(xy 134.088039 -45.177207) (xy 134.055567 -45.222595) (xy 134.016832 -45.262772) (xy 133.97266 -45.29688)
			(xy 133.923992 -45.324194) (xy 133.871866 -45.34413) (xy 133.817393 -45.356265) (xy 133.761734 -45.360339)
			(xy 133.706075 -45.356265) (xy 133.651602 -45.34413) (xy 133.599476 -45.324194) (xy 133.550808 -45.29688)
			(xy 133.506636 -45.262772) (xy 133.467901 -45.222595) (xy 133.435429 -45.177207) (xy 133.409911 -45.127575)
			(xy 133.391892 -45.074755) (xy 133.381755 -45.019876) (xy 133.379717 -44.964105) (xy 132.657772 -44.964105)
			(xy 132.690479 -44.993411) (xy 132.726178 -45.036307) (xy 132.755251 -45.083945) (xy 132.777078 -45.135308)
			(xy 132.791194 -45.189301) (xy 132.797297 -45.244775) (xy 132.795259 -45.300546) (xy 132.785122 -45.355425)
			(xy 132.767103 -45.408245) (xy 132.741585 -45.457877) (xy 132.709113 -45.503265) (xy 132.670378 -45.543442)
			(xy 132.626206 -45.57755) (xy 132.577538 -45.604864) (xy 132.525412 -45.6248) (xy 132.470939 -45.636935)
			(xy 132.41528 -45.641009) (xy 132.359621 -45.636935) (xy 132.305148 -45.6248) (xy 132.253022 -45.604864)
			(xy 132.204354 -45.57755) (xy 132.160182 -45.543442) (xy 132.121447 -45.503265) (xy 132.088975 -45.457877)
			(xy 132.063457 -45.408245) (xy 132.045438 -45.355425) (xy 132.035301 -45.300546) (xy 132.033263 -45.244775)
			(xy 131.470637 -45.244775) (xy 131.469379 -45.27921) (xy 131.459242 -45.334089) (xy 131.441223 -45.386909)
			(xy 131.415705 -45.436541) (xy 131.383233 -45.481929) (xy 131.344498 -45.522106) (xy 131.300326 -45.556214)
			(xy 131.251658 -45.583528) (xy 131.199532 -45.603464) (xy 131.145059 -45.615599) (xy 131.0894 -45.619673)
			(xy 131.033741 -45.615599) (xy 130.979268 -45.603464) (xy 130.927142 -45.583528) (xy 130.878474 -45.556214)
			(xy 130.834302 -45.522106) (xy 130.795567 -45.481929) (xy 130.763095 -45.436541) (xy 130.737577 -45.386909)
			(xy 130.719558 -45.334089) (xy 130.709421 -45.27921) (xy 130.707383 -45.223439) (xy 127.614369 -45.223439)
			(xy 127.615373 -45.25982) (xy 127.624033 -45.302631) (xy 127.639892 -45.343329) (xy 127.662483 -45.380712)
			(xy 127.691138 -45.413677) (xy 127.725012 -45.441251) (xy 127.763106 -45.462621) (xy 127.804295 -45.477156)
			(xy 127.825754 -45.48124) (xy 127.85306 -45.48644) (xy 127.905925 -45.503609) (xy 127.955738 -45.528268)
			(xy 128.001446 -45.559894) (xy 128.042081 -45.597819) (xy 128.076783 -45.641239) (xy 128.104816 -45.689234)
			(xy 128.125588 -45.74079) (xy 128.138659 -45.794814) (xy 128.143752 -45.850163) (xy 128.14076 -45.905665)
			(xy 128.129745 -45.960146) (xy 128.110941 -46.012451) (xy 128.084745 -46.061474) (xy 128.051714 -46.106177)
			(xy 128.012544 -46.145614) (xy 127.968067 -46.178949) (xy 127.919224 -46.205477) (xy 127.867047 -46.224637)
			(xy 127.812643 -46.236022) (xy 127.757162 -46.239393) (xy 127.70178 -46.234677) (xy 127.647668 -46.221974)
			(xy 127.595972 -46.201553) (xy 127.547787 -46.173847) (xy 127.504132 -46.139441) (xy 127.465932 -46.099066)
			(xy 127.433995 -46.053574) (xy 127.408998 -46.003929) (xy 127.391469 -45.951183) (xy 127.38178 -45.896451)
			(xy 127.380136 -45.840892) (xy 127.386571 -45.785683) (xy 127.40095 -45.731992) (xy 127.422967 -45.680956)
			(xy 127.452158 -45.633655) (xy 127.469646 -45.61205) (xy 127.479472 -45.59969) (xy 127.493182 -45.571252)
			(xy 127.499488 -45.540319) (xy 127.498005 -45.508784) (xy 127.488822 -45.478579) (xy 127.472504 -45.451554)
			(xy 127.450048 -45.429364) (xy 127.422831 -45.413368) (xy 127.392519 -45.404546) (xy 127.360969 -45.403438)
			(xy 127.34544 -45.40631) (xy 127.325374 -45.409866) (xy 127.303482 -45.413919) (xy 127.261468 -45.428635)
			(xy 127.222659 -45.450445) (xy 127.188244 -45.478683) (xy 127.159274 -45.512485) (xy 127.136637 -45.550817)
			(xy 127.121023 -45.592506) (xy 127.112911 -45.636278) (xy 127.112268 -45.658532) (xy 127.111554 -45.68648)
			(xy 127.102881 -45.74171) (xy 127.086239 -45.795083) (xy 127.061983 -45.845454) (xy 127.030634 -45.891745)
			(xy 126.992864 -45.932964) (xy 126.949481 -45.968227) (xy 126.901415 -45.99678) (xy 126.849695 -46.01801)
			(xy 126.795431 -46.031463) (xy 126.739784 -46.036851) (xy 126.683947 -46.034057) (xy 126.629116 -46.023142)
			(xy 126.576465 -46.00434) (xy 126.527123 -45.978054) (xy 126.482147 -45.944846) (xy 126.4425 -45.905429)
			(xy 126.409033 -45.860646) (xy 126.382461 -45.811457) (xy 126.363354 -45.758916) (xy 126.352121 -45.704149)
			(xy 126.349004 -45.648329) (xy 123.947628 -45.648329) (xy 123.983469 -45.678156) (xy 124.020686 -45.719693)
			(xy 124.051459 -45.766206) (xy 124.075131 -45.816703) (xy 124.091199 -45.87011) (xy 124.099319 -45.925286)
			(xy 124.099828 -45.953172) (xy 124.099319 -45.981058) (xy 124.091199 -46.036234) (xy 124.075131 -46.089641)
			(xy 124.051459 -46.140138) (xy 124.020686 -46.186651) (xy 123.983469 -46.228188) (xy 123.940601 -46.263863)
			(xy 123.892995 -46.292917) (xy 123.841666 -46.314729) (xy 123.787709 -46.328835) (xy 123.732272 -46.334935)
			(xy 123.676538 -46.332898) (xy 123.621695 -46.322768) (xy 123.568911 -46.304761) (xy 123.519311 -46.27926)
			(xy 123.473953 -46.246809) (xy 123.433804 -46.2081) (xy 123.399718 -46.163957) (xy 123.372422 -46.115322)
			(xy 123.352499 -46.063231) (xy 123.340373 -46.008794) (xy 123.336302 -45.953172) (xy 123.056043 -45.953172)
			(xy 123.058906 -45.992027) (xy 123.054768 -46.048076) (xy 123.042451 -46.102911) (xy 123.022222 -46.155345)
			(xy 122.994518 -46.204244) (xy 122.977656 -46.22673) (xy 122.950732 -46.261274) (xy 122.950732 -47.535846)
			(xy 122.951234 -47.558315) (xy 122.959178 -47.602546) (xy 122.974776 -47.644691) (xy 122.997542 -47.683437)
			(xy 123.026765 -47.717576) (xy 123.061536 -47.746046) (xy 123.100771 -47.767957) (xy 123.143248 -47.782629)
			(xy 123.187642 -47.789603) (xy 123.232572 -47.788662) (xy 123.276635 -47.779837) (xy 123.318461 -47.7634)
			(xy 123.337828 -47.752) (xy 123.361881 -47.737754) (xy 123.413245 -47.715689) (xy 123.467278 -47.701353)
			(xy 123.522824 -47.695053) (xy 123.578695 -47.696924) (xy 123.633695 -47.706927) (xy 123.686647 -47.724847)
			(xy 123.736419 -47.7503) (xy 123.781944 -47.782743) (xy 123.82225 -47.82148) (xy 123.856472 -47.865682)
			(xy 123.88388 -47.914405) (xy 123.903886 -47.966605) (xy 123.916062 -48.021165) (xy 123.920148 -48.076918)
			(xy 123.916057 -48.13267) (xy 123.903876 -48.187229) (xy 123.883865 -48.239427) (xy 123.856452 -48.288147)
			(xy 123.822226 -48.332347) (xy 123.781917 -48.37108) (xy 123.736388 -48.403518) (xy 123.686614 -48.428967)
			(xy 123.63366 -48.446882) (xy 123.578659 -48.456879) (xy 123.522788 -48.458746) (xy 123.467242 -48.452441)
			(xy 123.413211 -48.4381) (xy 123.36185 -48.416029) (xy 123.337828 -48.401732) (xy 123.318436 -48.390365)
			(xy 123.27661 -48.373911) (xy 123.232543 -48.36507) (xy 123.187607 -48.364117) (xy 123.143204 -48.371083)
			(xy 123.100719 -48.385749) (xy 123.061474 -48.407658) (xy 123.026696 -48.436128) (xy 122.997466 -48.470271)
			(xy 122.974697 -48.509023) (xy 122.959098 -48.551175) (xy 122.951156 -48.595413) (xy 122.950732 -48.617886)
			(xy 122.950732 -49.298116) (xy 123.529343 -49.298116) (xy 123.535443 -49.242679) (xy 123.549549 -49.188722)
			(xy 123.571361 -49.137393) (xy 123.600415 -49.089787) (xy 123.63609 -49.046919) (xy 123.677627 -49.009702)
			(xy 123.72414 -48.978929) (xy 123.774637 -48.955257) (xy 123.828044 -48.939189) (xy 123.88322 -48.931069)
			(xy 123.911106 -48.93056) (xy 123.938992 -48.931069) (xy 123.994168 -48.939189) (xy 124.047575 -48.955257)
			(xy 124.098072 -48.978929) (xy 124.144585 -49.009702) (xy 124.186122 -49.046919) (xy 124.221797 -49.089787)
			(xy 124.250851 -49.137393) (xy 124.272663 -49.188722) (xy 124.286769 -49.242679) (xy 124.292869 -49.298116)
			(xy 124.290832 -49.35385) (xy 124.280702 -49.408693) (xy 124.262695 -49.461477) (xy 124.237194 -49.511077)
			(xy 124.204743 -49.556435) (xy 124.166034 -49.596584) (xy 124.121891 -49.63067) (xy 124.073256 -49.657966)
			(xy 124.021165 -49.677889) (xy 123.966728 -49.690015) (xy 123.911106 -49.694086) (xy 123.855484 -49.690015)
			(xy 123.801047 -49.677889) (xy 123.748956 -49.657966) (xy 123.700321 -49.63067) (xy 123.656178 -49.596584)
			(xy 123.617469 -49.556435) (xy 123.585018 -49.511077) (xy 123.559517 -49.461477) (xy 123.54151 -49.408693)
			(xy 123.53138 -49.35385) (xy 123.529343 -49.298116) (xy 122.950732 -49.298116) (xy 122.950732 -50.421812)
			(xy 123.434093 -50.421812) (xy 123.440193 -50.366375) (xy 123.454299 -50.312418) (xy 123.476111 -50.261089)
			(xy 123.505165 -50.213483) (xy 123.54084 -50.170615) (xy 123.582377 -50.133398) (xy 123.62889 -50.102625)
			(xy 123.679387 -50.078953) (xy 123.732794 -50.062885) (xy 123.78797 -50.054765) (xy 123.815856 -50.054256)
			(xy 123.843742 -50.054765) (xy 123.898918 -50.062885) (xy 123.952325 -50.078953) (xy 124.002822 -50.102625)
			(xy 124.049335 -50.133398) (xy 124.090872 -50.170615) (xy 124.126547 -50.213483) (xy 124.155601 -50.261089)
			(xy 124.177413 -50.312418) (xy 124.191519 -50.366375) (xy 124.197619 -50.421812) (xy 124.195582 -50.477546)
			(xy 124.185452 -50.532389) (xy 124.167445 -50.585173) (xy 124.141944 -50.634773) (xy 124.109493 -50.680131)
			(xy 124.070784 -50.72028) (xy 124.026641 -50.754366) (xy 123.978006 -50.781662) (xy 123.925915 -50.801585)
			(xy 123.871478 -50.813711) (xy 123.815856 -50.817782) (xy 123.760234 -50.813711) (xy 123.705797 -50.801585)
			(xy 123.653706 -50.781662) (xy 123.605071 -50.754366) (xy 123.560928 -50.72028) (xy 123.522219 -50.680131)
			(xy 123.489768 -50.634773) (xy 123.464267 -50.585173) (xy 123.44626 -50.532389) (xy 123.43613 -50.477546)
			(xy 123.434093 -50.421812) (xy 122.950732 -50.421812) (xy 122.950732 -51.2064) (xy 125.423928 -51.2064)
			(xy 125.428001 -51.150741) (xy 125.440136 -51.096268) (xy 125.460072 -51.044142) (xy 125.487386 -50.995474)
			(xy 125.521494 -50.951302) (xy 125.561671 -50.912567) (xy 125.607059 -50.880095) (xy 125.656691 -50.854577)
			(xy 125.709511 -50.836558) (xy 125.76439 -50.826421) (xy 125.820161 -50.824383) (xy 125.875635 -50.830486)
			(xy 125.929628 -50.844602) (xy 125.980991 -50.866429) (xy 126.028629 -50.895502) (xy 126.071525 -50.931201)
			(xy 126.108767 -50.972765) (xy 126.139561 -51.019309) (xy 126.147727 -51.036728) (xy 154.5209 -51.036728)
			(xy 154.5209 -49.220628) (xy 154.52852 -49.16297) (xy 154.534392 -49.122071) (xy 154.553142 -49.041595)
			(xy 154.579602 -48.963314) (xy 154.613522 -48.887965) (xy 154.654582 -48.816258) (xy 154.702398 -48.748866)
			(xy 154.756518 -48.686424) (xy 154.816434 -48.629519) (xy 154.881581 -48.578688) (xy 154.951347 -48.534408)
			(xy 155.025075 -48.497095) (xy 155.102071 -48.467102) (xy 155.181611 -48.444711) (xy 155.262946 -48.430131)
			(xy 155.345311 -48.4235) (xy 155.427932 -48.424882) (xy 155.510029 -48.434261) (xy 155.590832 -48.451552)
			(xy 155.669579 -48.47659) (xy 155.74553 -48.509139) (xy 155.817969 -48.548895) (xy 155.886216 -48.595482)
			(xy 155.949628 -48.648463) (xy 156.007608 -48.707338) (xy 156.05961 -48.771555) (xy 156.105147 -48.840507)
			(xy 156.143788 -48.913547) (xy 156.158278 -48.948843) (xy 160.269022 -48.948843) (xy 160.275614 -48.893543)
			(xy 160.290175 -48.83979) (xy 160.312396 -48.788723) (xy 160.341805 -48.74143) (xy 160.377776 -48.698914)
			(xy 160.419545 -48.662079) (xy 160.466225 -48.631708) (xy 160.516825 -48.608445) (xy 160.570269 -48.592785)
			(xy 160.625422 -48.58506) (xy 160.681112 -48.585435) (xy 160.736156 -48.593902) (xy 160.789384 -48.610281)
			(xy 160.839666 -48.634223) (xy 160.885933 -48.665221) (xy 160.927202 -48.702616) (xy 160.962597 -48.745612)
			(xy 160.991365 -48.793297) (xy 161.012896 -48.844658) (xy 161.026732 -48.898603) (xy 161.030158 -48.926242)
			(xy 161.033004 -48.94892) (xy 161.045807 -48.992791) (xy 161.066244 -49.033668) (xy 161.093658 -49.070235)
			(xy 161.127166 -49.101313) (xy 161.165688 -49.125902) (xy 161.207985 -49.14321) (xy 161.252695 -49.15268)
			(xy 161.275522 -49.153826) (xy 161.303333 -49.153965) (xy 161.358517 -49.160879) (xy 161.412245 -49.175244)
			(xy 161.463516 -49.196793) (xy 161.511374 -49.225125) (xy 161.554927 -49.259711) (xy 161.593364 -49.299907)
			(xy 161.625968 -49.344963) (xy 161.652131 -49.39404) (xy 161.671366 -49.446223) (xy 161.683315 -49.500539)
			(xy 161.685986 -49.528222) (xy 161.68638 -49.531934) (xy 168.416237 -49.531934) (xy 168.420537 -49.477359)
			(xy 168.432593 -49.423959) (xy 168.452158 -49.372831) (xy 168.47883 -49.325024) (xy 168.512062 -49.281521)
			(xy 168.531286 -49.26203) (xy 168.546975 -49.245922) (xy 168.573085 -49.209322) (xy 168.592342 -49.168697)
			(xy 168.604145 -49.125315) (xy 168.608125 -49.080533) (xy 168.604157 -49.03575) (xy 168.592365 -48.992365)
			(xy 168.573118 -48.951735) (xy 168.547018 -48.915128) (xy 168.531286 -48.899064) (xy 168.512062 -48.879573)
			(xy 168.47883 -48.83607) (xy 168.452158 -48.788263) (xy 168.432593 -48.737135) (xy 168.420537 -48.683735)
			(xy 168.416237 -48.62916) (xy 168.419783 -48.574531) (xy 168.4311 -48.520969) (xy 168.449957 -48.469576)
			(xy 168.475967 -48.421405) (xy 168.508595 -48.377447) (xy 168.547171 -48.338603) (xy 168.590903 -48.305673)
			(xy 168.638892 -48.279331) (xy 168.690155 -48.26012) (xy 168.743637 -48.248433) (xy 168.79824 -48.24451)
			(xy 168.852843 -48.248433) (xy 168.906325 -48.26012) (xy 168.957588 -48.279331) (xy 169.005577 -48.305673)
			(xy 169.049309 -48.338603) (xy 169.087885 -48.377447) (xy 169.120513 -48.421405) (xy 169.146523 -48.469576)
			(xy 169.16538 -48.520969) (xy 169.176697 -48.574531) (xy 169.180243 -48.62916) (xy 169.175943 -48.683735)
			(xy 169.163887 -48.737135) (xy 169.144322 -48.788263) (xy 169.11765 -48.83607) (xy 169.084418 -48.879573)
			(xy 169.065194 -48.899064) (xy 169.049444 -48.915102) (xy 169.023399 -48.951736) (xy 169.004196 -48.992376)
			(xy 168.992432 -49.035759) (xy 168.988473 -49.080533) (xy 168.992443 -49.125306) (xy 169.004219 -49.168685)
			(xy 169.023432 -49.209321) (xy 169.049487 -49.245948) (xy 169.065194 -49.26203) (xy 169.084418 -49.281521)
			(xy 169.11765 -49.325024) (xy 169.144322 -49.372831) (xy 169.163887 -49.423959) (xy 169.175943 -49.477359)
			(xy 169.180243 -49.531934) (xy 169.176697 -49.586563) (xy 169.16538 -49.640125) (xy 169.146523 -49.691518)
			(xy 169.120513 -49.739689) (xy 169.087885 -49.783647) (xy 169.049309 -49.822491) (xy 169.005577 -49.855421)
			(xy 168.957588 -49.881763) (xy 168.906325 -49.900974) (xy 168.852843 -49.912661) (xy 168.79824 -49.916584)
			(xy 168.743637 -49.912661) (xy 168.690155 -49.900974) (xy 168.638892 -49.881763) (xy 168.590903 -49.855421)
			(xy 168.547171 -49.822491) (xy 168.508595 -49.783647) (xy 168.475967 -49.739689) (xy 168.449957 -49.691518)
			(xy 168.4311 -49.640125) (xy 168.419783 -49.586563) (xy 168.416237 -49.531934) (xy 161.68638 -49.531934)
			(xy 161.687764 -49.544986) (xy 161.687764 -50.818796) (xy 161.687256 -50.819558) (xy 161.687256 -50.830734)
			(xy 161.687075 -50.858712) (xy 161.679895 -50.914201) (xy 161.66518 -50.968183) (xy 161.643208 -51.019639)
			(xy 161.614393 -51.0676) (xy 161.579279 -51.11116) (xy 161.538527 -51.149499) (xy 161.492907 -51.181893)
			(xy 161.468308 -51.195224) (xy 161.445353 -51.206724) (xy 161.397199 -51.224536) (xy 161.347189 -51.23616)
			(xy 161.296115 -51.241411) (xy 161.270442 -51.241198) (xy 161.246315 -51.241111) (xy 161.198732 -51.249062)
			(xy 161.153502 -51.265845) (xy 161.11225 -51.290859) (xy 161.076456 -51.323203) (xy 161.047405 -51.361719)
			(xy 161.026141 -51.405023) (xy 161.019236 -51.428142) (xy 161.01139 -51.454988) (xy 160.988932 -51.506211)
			(xy 160.959235 -51.553607) (xy 160.922938 -51.596158) (xy 160.880816 -51.632954) (xy 160.879768 -51.633628)
			(xy 167.435782 -51.633628) (xy 167.439853 -51.578006) (xy 167.451979 -51.523569) (xy 167.471902 -51.471478)
			(xy 167.499198 -51.422843) (xy 167.533284 -51.3787) (xy 167.573433 -51.339991) (xy 167.618791 -51.30754)
			(xy 167.668391 -51.282039) (xy 167.721175 -51.264032) (xy 167.776018 -51.253902) (xy 167.831752 -51.251865)
			(xy 167.887189 -51.257965) (xy 167.941146 -51.272071) (xy 167.992475 -51.293883) (xy 168.040081 -51.322937)
			(xy 168.082949 -51.358612) (xy 168.120166 -51.400149) (xy 168.150939 -51.446662) (xy 168.174611 -51.497159)
			(xy 168.190679 -51.550566) (xy 168.198799 -51.605742) (xy 168.199308 -51.633628) (xy 168.199085 -51.645841)
			(xy 168.609936 -51.645841) (xy 168.610916 -51.590306) (xy 168.619942 -51.535499) (xy 168.636821 -51.482582)
			(xy 168.661196 -51.432672) (xy 168.692553 -51.386825) (xy 168.730228 -51.346011) (xy 168.773424 -51.311093)
			(xy 168.821228 -51.28281) (xy 168.872629 -51.261759) (xy 168.926539 -51.248386) (xy 168.981819 -51.242973)
			(xy 169.0373 -51.245636) (xy 169.091807 -51.256317) (xy 169.14419 -51.274791) (xy 169.193338 -51.300667)
			(xy 169.238214 -51.333398) (xy 169.277868 -51.372292) (xy 169.295064 -51.394106) (xy 169.309374 -51.412073)
			(xy 169.34329 -51.44304) (xy 169.382216 -51.467415) (xy 169.424885 -51.484404) (xy 169.469911 -51.493456)
			(xy 169.515831 -51.494275) (xy 169.561152 -51.486837) (xy 169.6044 -51.471382) (xy 169.644171 -51.448412)
			(xy 169.679171 -51.418675) (xy 169.694098 -51.401218) (xy 169.712049 -51.380022) (xy 169.753054 -51.342556)
			(xy 169.799059 -51.311433) (xy 169.849091 -51.287312) (xy 169.902093 -51.270702) (xy 169.956944 -51.261956)
			(xy 170.012483 -51.261258) (xy 170.067536 -51.268623) (xy 170.120939 -51.283895) (xy 170.171562 -51.306752)
			(xy 170.218334 -51.336709) (xy 170.260267 -51.373133) (xy 170.296473 -51.415254) (xy 170.326187 -51.462181)
			(xy 170.348781 -51.512921) (xy 170.363776 -51.566403) (xy 170.370856 -51.621493) (xy 170.36987 -51.677028)
			(xy 170.36084 -51.731832) (xy 170.343956 -51.784748) (xy 170.319576 -51.834655) (xy 170.288215 -51.880498)
			(xy 170.250536 -51.921307) (xy 170.207337 -51.95622) (xy 170.159531 -51.984498) (xy 170.108129 -52.005544)
			(xy 170.054218 -52.018911) (xy 169.998938 -52.024317) (xy 169.943459 -52.021649) (xy 169.888953 -52.010961)
			(xy 169.836574 -51.992482) (xy 169.787429 -51.9666) (xy 169.742558 -51.933864) (xy 169.702909 -51.894966)
			(xy 169.685716 -51.87315) (xy 169.671428 -51.855166) (xy 169.637506 -51.824203) (xy 169.598577 -51.799833)
			(xy 169.555905 -51.782848) (xy 169.510877 -51.7738) (xy 169.464956 -51.772982) (xy 169.419635 -51.780422)
			(xy 169.376385 -51.795877) (xy 169.336613 -51.818846) (xy 169.301611 -51.848582) (xy 169.286682 -51.866038)
			(xy 169.268773 -51.887269) (xy 169.227771 -51.924739) (xy 169.181767 -51.955865) (xy 169.131735 -51.979989)
			(xy 169.078734 -51.996602) (xy 169.023883 -52.005352) (xy 168.968343 -52.006054) (xy 168.913288 -51.998693)
			(xy 168.859884 -51.983424) (xy 168.809259 -51.960572) (xy 168.762483 -51.930618) (xy 168.720547 -51.894196)
			(xy 168.684337 -51.852077) (xy 168.654618 -51.805152) (xy 168.63202 -51.754413) (xy 168.61702 -51.700932)
			(xy 168.609936 -51.645841) (xy 168.199085 -51.645841) (xy 168.198799 -51.661514) (xy 168.190679 -51.71669)
			(xy 168.174611 -51.770097) (xy 168.150939 -51.820594) (xy 168.120166 -51.867107) (xy 168.082949 -51.908644)
			(xy 168.040081 -51.944319) (xy 167.992475 -51.973373) (xy 167.941146 -51.995185) (xy 167.887189 -52.009291)
			(xy 167.831752 -52.015391) (xy 167.776018 -52.013354) (xy 167.721175 -52.003224) (xy 167.668391 -51.985217)
			(xy 167.618791 -51.959716) (xy 167.573433 -51.927265) (xy 167.533284 -51.888556) (xy 167.499198 -51.844413)
			(xy 167.471902 -51.795778) (xy 167.451979 -51.743687) (xy 167.439853 -51.68925) (xy 167.435782 -51.633628)
			(xy 160.879768 -51.633628) (xy 160.833774 -51.663206) (xy 160.782819 -51.686266) (xy 160.729043 -51.701639)
			(xy 160.673599 -51.708996) (xy 160.617675 -51.70818) (xy 160.562469 -51.699207) (xy 160.509165 -51.68227)
			(xy 160.458905 -51.657732) (xy 160.412766 -51.62612) (xy 160.371737 -51.588109) (xy 160.336697 -51.544516)
			(xy 160.308397 -51.496274) (xy 160.287444 -51.444417) (xy 160.274286 -51.390057) (xy 160.269206 -51.334358)
			(xy 160.272313 -51.278514) (xy 160.28354 -51.223722) (xy 160.302645 -51.171157) (xy 160.329221 -51.121944)
			(xy 160.362697 -51.077138) (xy 160.402356 -51.037701) (xy 160.447348 -51.004476) (xy 160.496709 -50.978176)
			(xy 160.549381 -50.959364) (xy 160.604234 -50.948444) (xy 160.63214 -50.946558) (xy 160.655751 -50.944865)
			(xy 160.701776 -50.933815) (xy 160.744959 -50.914436) (xy 160.783807 -50.887397) (xy 160.816978 -50.853633)
			(xy 160.843324 -50.814311) (xy 160.861935 -50.770791) (xy 160.872166 -50.724578) (xy 160.87344 -50.70094)
			(xy 160.87344 -49.560226) (xy 160.873631 -49.541448) (xy 160.877068 -49.504049) (xy 160.880298 -49.48555)
			(xy 160.882461 -49.470228) (xy 160.880166 -49.439378) (xy 160.870515 -49.409987) (xy 160.854074 -49.383782)
			(xy 160.83181 -49.362304) (xy 160.805032 -49.346814) (xy 160.775314 -49.338224) (xy 160.744401 -49.337037)
			(xy 160.729168 -49.339754) (xy 160.701805 -49.344944) (xy 160.646218 -49.348351) (xy 160.590726 -49.343641)
			(xy 160.536509 -49.330914) (xy 160.484718 -49.310441) (xy 160.436453 -49.282656) (xy 160.392739 -49.24815)
			(xy 160.354507 -49.207656) (xy 160.322567 -49.162034) (xy 160.297599 -49.112253) (xy 160.280132 -49.059372)
			(xy 160.270539 -49.004513) (xy 160.269022 -48.948843) (xy 156.158278 -48.948843) (xy 156.17517 -48.989988)
			(xy 156.198998 -49.069109) (xy 156.215049 -49.150167) (xy 156.223169 -49.232399) (xy 156.223716 -49.273714)
			(xy 156.223716 -50.966624) (xy 156.223462 -50.97526) (xy 156.222843 -51.01614) (xy 156.214577 -51.097488)
			(xy 156.198548 -51.177667) (xy 156.174905 -51.25594) (xy 156.143865 -51.331586) (xy 156.105716 -51.403907)
			(xy 156.060807 -51.472236) (xy 156.009553 -51.535944) (xy 155.952427 -51.594445) (xy 155.889954 -51.647198)
			(xy 155.822711 -51.693717) (xy 155.751318 -51.733575) (xy 155.676431 -51.766403) (xy 155.598741 -51.791899)
			(xy 155.518965 -51.809829) (xy 155.437838 -51.820026) (xy 155.356106 -51.822397) (xy 155.274523 -51.81692)
			(xy 155.193842 -51.803646) (xy 155.114805 -51.782697) (xy 155.038141 -51.754265) (xy 154.964557 -51.718614)
			(xy 154.89473 -51.676071) (xy 154.829304 -51.627028) (xy 154.768882 -51.571938) (xy 154.714021 -51.511308)
			(xy 154.665227 -51.445697) (xy 154.622948 -51.37571) (xy 154.587576 -51.301991) (xy 154.559435 -51.22522)
			(xy 154.538785 -51.146105) (xy 154.531822 -51.105816) (xy 154.5209 -51.036728) (xy 126.147727 -51.036728)
			(xy 126.163249 -51.06984) (xy 126.179327 -51.123282) (xy 126.187453 -51.178496) (xy 126.187962 -51.2064)
			(xy 126.187453 -51.234304) (xy 126.179327 -51.289518) (xy 126.163249 -51.34296) (xy 126.139561 -51.393491)
			(xy 126.108767 -51.440035) (xy 126.071525 -51.481599) (xy 126.028629 -51.517298) (xy 125.980991 -51.546371)
			(xy 125.929628 -51.568198) (xy 125.875635 -51.582314) (xy 125.820161 -51.588417) (xy 125.76439 -51.586379)
			(xy 125.709511 -51.576242) (xy 125.656691 -51.558223) (xy 125.607059 -51.532705) (xy 125.561671 -51.500233)
			(xy 125.521494 -51.461498) (xy 125.487386 -51.417326) (xy 125.460072 -51.368658) (xy 125.440136 -51.316532)
			(xy 125.428001 -51.262059) (xy 125.423928 -51.2064) (xy 122.950732 -51.2064) (xy 122.950732 -51.695604)
			(xy 122.951233 -51.718638) (xy 122.959538 -51.76395) (xy 122.975874 -51.807023) (xy 122.999708 -51.846446)
			(xy 123.030257 -51.880927) (xy 123.066522 -51.909336) (xy 123.107313 -51.930743) (xy 123.151296 -51.944446)
			(xy 123.197027 -51.949996) (xy 123.24301 -51.947212) (xy 123.287738 -51.936185) (xy 123.329746 -51.917275)
			(xy 123.367657 -51.891103) (xy 123.38431 -51.875182) (xy 123.578366 -51.681126) (xy 123.587002 -51.647852)
			(xy 123.594443 -51.621199) (xy 123.615961 -51.570218) (xy 123.644617 -51.52288) (xy 123.67981 -51.480178)
			(xy 123.720802 -51.443006) (xy 123.766734 -51.412146) (xy 123.816641 -51.388244) (xy 123.869477 -51.371801)
			(xy 123.924135 -51.363162) (xy 123.979467 -51.362509) (xy 124.034313 -51.369854) (xy 124.087523 -51.385045)
			(xy 124.13798 -51.407763) (xy 124.184628 -51.43753) (xy 124.226486 -51.473723) (xy 124.262678 -51.515583)
			(xy 124.292443 -51.562231) (xy 124.315159 -51.612689) (xy 124.330348 -51.6659) (xy 124.337692 -51.720746)
			(xy 124.337037 -51.776078) (xy 124.328396 -51.830735) (xy 124.311952 -51.883571) (xy 124.288048 -51.933478)
			(xy 124.257186 -51.979408) (xy 124.220013 -52.020399) (xy 124.177309 -52.05559) (xy 124.12997 -52.084245)
			(xy 124.078989 -52.105761) (xy 124.05233 -52.11318) (xy 124.019056 -52.121816) (xy 124.009649 -52.131223)
			(xy 126.421133 -52.131223) (xy 126.427236 -52.075749) (xy 126.441352 -52.021756) (xy 126.463179 -51.970393)
			(xy 126.492252 -51.922755) (xy 126.527951 -51.879859) (xy 126.569515 -51.842617) (xy 126.616059 -51.811823)
			(xy 126.66659 -51.788135) (xy 126.720032 -51.772057) (xy 126.775246 -51.763931) (xy 126.80315 -51.763422)
			(xy 126.831054 -51.763931) (xy 126.886268 -51.772057) (xy 126.93971 -51.788135) (xy 126.990241 -51.811823)
			(xy 127.036785 -51.842617) (xy 127.078349 -51.879859) (xy 127.114048 -51.922755) (xy 127.143121 -51.970393)
			(xy 127.164948 -52.021756) (xy 127.167268 -52.03063) (xy 153.210774 -52.03063) (xy 153.214788 -51.957869)
			(xy 153.226782 -51.885992) (xy 153.246611 -51.81587) (xy 153.274033 -51.748356) (xy 153.308716 -51.684267)
			(xy 153.350238 -51.624383) (xy 153.398097 -51.569431) (xy 153.45171 -51.520076) (xy 153.510427 -51.476919)
			(xy 153.573535 -51.440484) (xy 153.640269 -51.411212) (xy 153.709817 -51.389458) (xy 153.781337 -51.375488)
			(xy 153.853959 -51.369471) (xy 153.926803 -51.371479) (xy 153.998983 -51.381488) (xy 154.069625 -51.399377)
			(xy 154.13787 -51.424928) (xy 154.202889 -51.457832) (xy 154.263895 -51.497688) (xy 154.320145 -51.544014)
			(xy 154.370958 -51.596247) (xy 154.415716 -51.653753) (xy 154.453877 -51.715833) (xy 154.484977 -51.781735)
			(xy 154.508638 -51.850658) (xy 154.524574 -51.921765) (xy 154.53259 -51.994194) (xy 154.533092 -52.03063)
			(xy 154.53259 -52.067066) (xy 154.524574 -52.139495) (xy 154.508638 -52.210602) (xy 154.484977 -52.279525)
			(xy 154.453877 -52.345427) (xy 154.415716 -52.407507) (xy 154.370958 -52.465013) (xy 154.320145 -52.517246)
			(xy 154.263895 -52.563572) (xy 154.202889 -52.603428) (xy 154.13787 -52.636332) (xy 154.069625 -52.661883)
			(xy 153.998983 -52.679772) (xy 153.926803 -52.689781) (xy 153.853959 -52.691789) (xy 153.781337 -52.685772)
			(xy 153.709817 -52.671802) (xy 153.640269 -52.650048) (xy 153.573535 -52.620776) (xy 153.510427 -52.584341)
			(xy 153.45171 -52.541184) (xy 153.398097 -52.491829) (xy 153.350238 -52.436877) (xy 153.308716 -52.376993)
			(xy 153.274033 -52.312904) (xy 153.246611 -52.24539) (xy 153.226782 -52.175268) (xy 153.214788 -52.103391)
			(xy 153.210774 -52.03063) (xy 127.167268 -52.03063) (xy 127.179064 -52.075749) (xy 127.185167 -52.131223)
			(xy 127.183129 -52.186994) (xy 127.172992 -52.241873) (xy 127.154973 -52.294693) (xy 127.129455 -52.344325)
			(xy 127.096983 -52.389713) (xy 127.058248 -52.42989) (xy 127.014076 -52.463998) (xy 126.965408 -52.491312)
			(xy 126.913282 -52.511248) (xy 126.858809 -52.523383) (xy 126.80315 -52.527457) (xy 126.747491 -52.523383)
			(xy 126.693018 -52.511248) (xy 126.640892 -52.491312) (xy 126.592224 -52.463998) (xy 126.548052 -52.42989)
			(xy 126.509317 -52.389713) (xy 126.476845 -52.344325) (xy 126.451327 -52.294693) (xy 126.433308 -52.241873)
			(xy 126.423171 -52.186994) (xy 126.421133 -52.131223) (xy 124.009649 -52.131223) (xy 123.4483 -52.692572)
			(xy 124.343921 -52.692572) (xy 124.350021 -52.637135) (xy 124.364127 -52.583178) (xy 124.385939 -52.531849)
			(xy 124.414993 -52.484243) (xy 124.450668 -52.441375) (xy 124.492205 -52.404158) (xy 124.538718 -52.373385)
			(xy 124.589215 -52.349713) (xy 124.642622 -52.333645) (xy 124.697798 -52.325525) (xy 124.725684 -52.325016)
			(xy 124.75357 -52.325525) (xy 124.808746 -52.333645) (xy 124.862153 -52.349713) (xy 124.91265 -52.373385)
			(xy 124.959163 -52.404158) (xy 125.0007 -52.441375) (xy 125.036375 -52.484243) (xy 125.065429 -52.531849)
			(xy 125.087241 -52.583178) (xy 125.101347 -52.637135) (xy 125.10359 -52.65752) (xy 128.201673 -52.65752)
			(xy 128.207773 -52.602083) (xy 128.221879 -52.548126) (xy 128.243691 -52.496797) (xy 128.272745 -52.449191)
			(xy 128.30842 -52.406323) (xy 128.349957 -52.369106) (xy 128.39647 -52.338333) (xy 128.446967 -52.314661)
			(xy 128.500374 -52.298593) (xy 128.55555 -52.290473) (xy 128.583436 -52.289964) (xy 128.611322 -52.290473)
			(xy 128.666498 -52.298593) (xy 128.719905 -52.314661) (xy 128.770402 -52.338333) (xy 128.816915 -52.369106)
			(xy 128.858452 -52.406323) (xy 128.894127 -52.449191) (xy 128.923181 -52.496797) (xy 128.944993 -52.548126)
			(xy 128.959099 -52.602083) (xy 128.965199 -52.65752) (xy 128.963162 -52.713254) (xy 128.953032 -52.768097)
			(xy 128.948838 -52.78039) (xy 129.665474 -52.78039) (xy 129.667097 -52.724347) (xy 129.676903 -52.669145)
			(xy 129.694682 -52.615972) (xy 129.720051 -52.565973) (xy 129.752463 -52.520225) (xy 129.791221 -52.479712)
			(xy 129.835491 -52.445307) (xy 129.884318 -52.417751) (xy 129.936652 -52.397636) (xy 129.991366 -52.385397)
			(xy 130.047283 -52.381296) (xy 130.103197 -52.385421) (xy 130.157906 -52.397684) (xy 130.210232 -52.417822)
			(xy 130.259047 -52.445399) (xy 130.303301 -52.479823) (xy 130.342042 -52.520353) (xy 130.358642 -52.542948)
			(xy 130.368653 -52.556062) (xy 130.39398 -52.577181) (xy 130.423875 -52.591099) (xy 130.456339 -52.596886)
			(xy 130.489202 -52.594156) (xy 130.520266 -52.58309) (xy 130.534156 -52.57419) (xy 130.557507 -52.558671)
			(xy 130.607836 -52.533964) (xy 130.66124 -52.516889) (xy 130.716567 -52.507811) (xy 130.772627 -52.506928)
			(xy 130.828212 -52.514258) (xy 130.882127 -52.529643) (xy 130.93321 -52.552752) (xy 130.980361 -52.583087)
			(xy 131.015787 -52.614068) (xy 131.715254 -52.614068) (xy 131.719325 -52.558446) (xy 131.731451 -52.504009)
			(xy 131.751374 -52.451918) (xy 131.77867 -52.403283) (xy 131.812756 -52.35914) (xy 131.852905 -52.320431)
			(xy 131.898263 -52.28798) (xy 131.947863 -52.262479) (xy 132.000647 -52.244472) (xy 132.05549 -52.234342)
			(xy 132.111224 -52.232305) (xy 132.166661 -52.238405) (xy 132.220618 -52.252511) (xy 132.271947 -52.274323)
			(xy 132.319553 -52.303377) (xy 132.362421 -52.339052) (xy 132.399638 -52.380589) (xy 132.430411 -52.427102)
			(xy 132.454083 -52.477599) (xy 132.470151 -52.531006) (xy 132.478271 -52.586182) (xy 132.47878 -52.614068)
			(xy 132.478271 -52.641954) (xy 132.470151 -52.69713) (xy 132.456703 -52.74183) (xy 137.19886 -52.74183)
			(xy 137.202931 -52.686208) (xy 137.215057 -52.631771) (xy 137.23498 -52.57968) (xy 137.262276 -52.531045)
			(xy 137.296362 -52.486902) (xy 137.336511 -52.448193) (xy 137.381869 -52.415742) (xy 137.431469 -52.390241)
			(xy 137.484253 -52.372234) (xy 137.539096 -52.362104) (xy 137.59483 -52.360067) (xy 137.650267 -52.366167)
			(xy 137.704224 -52.380273) (xy 137.755553 -52.402085) (xy 137.803159 -52.431139) (xy 137.846027 -52.466814)
			(xy 137.883244 -52.508351) (xy 137.914017 -52.554864) (xy 137.937689 -52.605361) (xy 137.953757 -52.658768)
			(xy 137.95686 -52.679854) (xy 140.310868 -52.679854) (xy 140.314939 -52.624232) (xy 140.327065 -52.569795)
			(xy 140.346988 -52.517704) (xy 140.374284 -52.469069) (xy 140.40837 -52.424926) (xy 140.448519 -52.386217)
			(xy 140.493877 -52.353766) (xy 140.543477 -52.328265) (xy 140.596261 -52.310258) (xy 140.651104 -52.300128)
			(xy 140.706838 -52.298091) (xy 140.762275 -52.304191) (xy 140.816232 -52.318297) (xy 140.867561 -52.340109)
			(xy 140.915167 -52.369163) (xy 140.958035 -52.404838) (xy 140.995252 -52.446375) (xy 141.026025 -52.492888)
			(xy 141.049697 -52.543385) (xy 141.065765 -52.596792) (xy 141.073885 -52.651968) (xy 141.074357 -52.677822)
			(xy 142.342868 -52.677822) (xy 142.346939 -52.6222) (xy 142.359065 -52.567763) (xy 142.378988 -52.515672)
			(xy 142.406284 -52.467037) (xy 142.44037 -52.422894) (xy 142.480519 -52.384185) (xy 142.525877 -52.351734)
			(xy 142.575477 -52.326233) (xy 142.628261 -52.308226) (xy 142.683104 -52.298096) (xy 142.738838 -52.296059)
			(xy 142.794275 -52.302159) (xy 142.848232 -52.316265) (xy 142.899561 -52.338077) (xy 142.947167 -52.367131)
			(xy 142.990035 -52.402806) (xy 143.027252 -52.444343) (xy 143.058025 -52.490856) (xy 143.081697 -52.541353)
			(xy 143.097765 -52.59476) (xy 143.105885 -52.649936) (xy 143.106394 -52.677822) (xy 143.105885 -52.705708)
			(xy 143.097765 -52.760884) (xy 143.081697 -52.814291) (xy 143.058025 -52.864788) (xy 143.027252 -52.911301)
			(xy 142.990035 -52.952838) (xy 142.947167 -52.988513) (xy 142.899561 -53.017567) (xy 142.848232 -53.039379)
			(xy 142.794275 -53.053485) (xy 142.738838 -53.059585) (xy 142.683104 -53.057548) (xy 142.628261 -53.047418)
			(xy 142.575477 -53.029411) (xy 142.525877 -53.00391) (xy 142.480519 -52.971459) (xy 142.44037 -52.93275)
			(xy 142.406284 -52.888607) (xy 142.378988 -52.839972) (xy 142.359065 -52.787881) (xy 142.346939 -52.733444)
			(xy 142.342868 -52.677822) (xy 141.074357 -52.677822) (xy 141.074394 -52.679854) (xy 141.073885 -52.70774)
			(xy 141.065765 -52.762916) (xy 141.049697 -52.816323) (xy 141.026025 -52.86682) (xy 140.995252 -52.913333)
			(xy 140.958035 -52.95487) (xy 140.915167 -52.990545) (xy 140.867561 -53.019599) (xy 140.816232 -53.041411)
			(xy 140.762275 -53.055517) (xy 140.706838 -53.061617) (xy 140.651104 -53.05958) (xy 140.596261 -53.04945)
			(xy 140.543477 -53.031443) (xy 140.493877 -53.005942) (xy 140.448519 -52.973491) (xy 140.40837 -52.934782)
			(xy 140.374284 -52.890639) (xy 140.346988 -52.842004) (xy 140.327065 -52.789913) (xy 140.314939 -52.735476)
			(xy 140.310868 -52.679854) (xy 137.95686 -52.679854) (xy 137.961877 -52.713944) (xy 137.962386 -52.74183)
			(xy 137.961877 -52.769716) (xy 137.953757 -52.824892) (xy 137.937689 -52.878299) (xy 137.914017 -52.928796)
			(xy 137.883244 -52.975309) (xy 137.846027 -53.016846) (xy 137.803159 -53.052521) (xy 137.755553 -53.081575)
			(xy 137.704224 -53.103387) (xy 137.650267 -53.117493) (xy 137.59483 -53.123593) (xy 137.539096 -53.121556)
			(xy 137.484253 -53.111426) (xy 137.431469 -53.093419) (xy 137.381869 -53.067918) (xy 137.336511 -53.035467)
			(xy 137.296362 -52.996758) (xy 137.262276 -52.952615) (xy 137.23498 -52.90398) (xy 137.215057 -52.851889)
			(xy 137.202931 -52.797452) (xy 137.19886 -52.74183) (xy 132.456703 -52.74183) (xy 132.454083 -52.750537)
			(xy 132.430411 -52.801034) (xy 132.399638 -52.847547) (xy 132.362421 -52.889084) (xy 132.319553 -52.924759)
			(xy 132.271947 -52.953813) (xy 132.220618 -52.975625) (xy 132.166661 -52.989731) (xy 132.111224 -52.995831)
			(xy 132.05549 -52.993794) (xy 132.000647 -52.983664) (xy 131.947863 -52.965657) (xy 131.898263 -52.940156)
			(xy 131.852905 -52.907705) (xy 131.812756 -52.868996) (xy 131.77867 -52.824853) (xy 131.751374 -52.776218)
			(xy 131.731451 -52.724127) (xy 131.719325 -52.66969) (xy 131.715254 -52.614068) (xy 131.015787 -52.614068)
			(xy 131.022566 -52.619996) (xy 131.058915 -52.662684) (xy 131.088626 -52.710231) (xy 131.11106 -52.761614)
			(xy 131.125733 -52.815727) (xy 131.132329 -52.871404) (xy 131.130707 -52.927448) (xy 131.120901 -52.982651)
			(xy 131.103123 -53.035824) (xy 131.077754 -53.085823) (xy 131.045343 -53.131572) (xy 131.006585 -53.172086)
			(xy 130.981698 -53.191428) (xy 134.827517 -53.191428) (xy 134.833617 -53.135991) (xy 134.847723 -53.082034)
			(xy 134.869535 -53.030705) (xy 134.898589 -52.983099) (xy 134.934264 -52.940231) (xy 134.975801 -52.903014)
			(xy 135.022314 -52.872241) (xy 135.072811 -52.848569) (xy 135.126218 -52.832501) (xy 135.181394 -52.824381)
			(xy 135.20928 -52.823872) (xy 135.237166 -52.824381) (xy 135.292342 -52.832501) (xy 135.345749 -52.848569)
			(xy 135.396246 -52.872241) (xy 135.442759 -52.903014) (xy 135.484296 -52.940231) (xy 135.519971 -52.983099)
			(xy 135.549025 -53.030705) (xy 135.570837 -53.082034) (xy 135.584943 -53.135991) (xy 135.591043 -53.191428)
			(xy 135.589006 -53.247162) (xy 135.578876 -53.302005) (xy 135.560869 -53.354789) (xy 135.535368 -53.404389)
			(xy 135.502917 -53.449747) (xy 135.464208 -53.489896) (xy 135.433992 -53.513228) (xy 141.455646 -53.513228)
			(xy 141.459717 -53.457606) (xy 141.471843 -53.403169) (xy 141.491766 -53.351078) (xy 141.519062 -53.302443)
			(xy 141.553148 -53.2583) (xy 141.593297 -53.219591) (xy 141.638655 -53.18714) (xy 141.688255 -53.161639)
			(xy 141.741039 -53.143632) (xy 141.795882 -53.133502) (xy 141.851616 -53.131465) (xy 141.907053 -53.137565)
			(xy 141.96101 -53.151671) (xy 142.012339 -53.173483) (xy 142.059945 -53.202537) (xy 142.102813 -53.238212)
			(xy 142.14003 -53.279749) (xy 142.170803 -53.326262) (xy 142.194475 -53.376759) (xy 142.210543 -53.430166)
			(xy 142.216562 -53.471064) (xy 148.355302 -53.471064) (xy 148.359373 -53.415442) (xy 148.371499 -53.361005)
			(xy 148.391422 -53.308914) (xy 148.418718 -53.260279) (xy 148.452804 -53.216136) (xy 148.492953 -53.177427)
			(xy 148.538311 -53.144976) (xy 148.587911 -53.119475) (xy 148.640695 -53.101468) (xy 148.695538 -53.091338)
			(xy 148.751272 -53.089301) (xy 148.806709 -53.095401) (xy 148.860666 -53.109507) (xy 148.911995 -53.131319)
			(xy 148.959601 -53.160373) (xy 149.002469 -53.196048) (xy 149.039686 -53.237585) (xy 149.070459 -53.284098)
			(xy 149.094131 -53.334595) (xy 149.110199 -53.388002) (xy 149.118319 -53.443178) (xy 149.118828 -53.471064)
			(xy 149.118319 -53.49895) (xy 149.110199 -53.554126) (xy 149.094131 -53.607533) (xy 149.070459 -53.65803)
			(xy 149.039686 -53.704543) (xy 149.002469 -53.74608) (xy 148.959601 -53.781755) (xy 148.911995 -53.810809)
			(xy 148.860666 -53.832621) (xy 148.806709 -53.846727) (xy 148.751272 -53.852827) (xy 148.695538 -53.85079)
			(xy 148.640695 -53.84066) (xy 148.587911 -53.822653) (xy 148.538311 -53.797152) (xy 148.492953 -53.764701)
			(xy 148.452804 -53.725992) (xy 148.418718 -53.681849) (xy 148.391422 -53.633214) (xy 148.371499 -53.581123)
			(xy 148.359373 -53.526686) (xy 148.355302 -53.471064) (xy 142.216562 -53.471064) (xy 142.218663 -53.485342)
			(xy 142.219172 -53.513228) (xy 142.218663 -53.541114) (xy 142.210543 -53.59629) (xy 142.194475 -53.649697)
			(xy 142.170803 -53.700194) (xy 142.14003 -53.746707) (xy 142.102813 -53.788244) (xy 142.059945 -53.823919)
			(xy 142.012339 -53.852973) (xy 141.96101 -53.874785) (xy 141.907053 -53.888891) (xy 141.851616 -53.894991)
			(xy 141.795882 -53.892954) (xy 141.741039 -53.882824) (xy 141.688255 -53.864817) (xy 141.638655 -53.839316)
			(xy 141.593297 -53.806865) (xy 141.553148 -53.768156) (xy 141.519062 -53.724013) (xy 141.491766 -53.675378)
			(xy 141.471843 -53.623287) (xy 141.459717 -53.56885) (xy 141.455646 -53.513228) (xy 135.433992 -53.513228)
			(xy 135.420065 -53.523982) (xy 135.37143 -53.551278) (xy 135.319339 -53.571201) (xy 135.264902 -53.583327)
			(xy 135.20928 -53.587398) (xy 135.153658 -53.583327) (xy 135.099221 -53.571201) (xy 135.04713 -53.551278)
			(xy 134.998495 -53.523982) (xy 134.954352 -53.489896) (xy 134.915643 -53.449747) (xy 134.883192 -53.404389)
			(xy 134.857691 -53.354789) (xy 134.839684 -53.302005) (xy 134.829554 -53.247162) (xy 134.827517 -53.191428)
			(xy 130.981698 -53.191428) (xy 130.962316 -53.206492) (xy 130.913489 -53.234049) (xy 130.861155 -53.254165)
			(xy 130.806441 -53.266405) (xy 130.750524 -53.270507) (xy 130.694609 -53.266383) (xy 130.6399 -53.25412)
			(xy 130.587573 -53.233984) (xy 130.538757 -53.206407) (xy 130.494502 -53.171984) (xy 130.455761 -53.131455)
			(xy 130.43916 -53.10886) (xy 130.429146 -53.095748) (xy 130.40382 -53.074629) (xy 130.373926 -53.06071)
			(xy 130.341462 -53.054922) (xy 130.308599 -53.057652) (xy 130.277535 -53.068718) (xy 130.263646 -53.077618)
			(xy 130.240289 -53.093128) (xy 130.18996 -53.117834) (xy 130.136557 -53.134909) (xy 130.08123 -53.143986)
			(xy 130.02517 -53.144869) (xy 129.969585 -53.137539) (xy 129.91567 -53.122153) (xy 129.864588 -53.099044)
			(xy 129.817437 -53.068708) (xy 129.775233 -53.031799) (xy 129.738885 -52.989111) (xy 129.709174 -52.941564)
			(xy 129.686741 -52.89018) (xy 129.672069 -52.836068) (xy 129.665474 -52.78039) (xy 128.948838 -52.78039)
			(xy 128.935025 -52.820881) (xy 128.909524 -52.870481) (xy 128.877073 -52.915839) (xy 128.838364 -52.955988)
			(xy 128.794221 -52.990074) (xy 128.745586 -53.01737) (xy 128.693495 -53.037293) (xy 128.639058 -53.049419)
			(xy 128.583436 -53.05349) (xy 128.527814 -53.049419) (xy 128.473377 -53.037293) (xy 128.421286 -53.01737)
			(xy 128.372651 -52.990074) (xy 128.328508 -52.955988) (xy 128.289799 -52.915839) (xy 128.257348 -52.870481)
			(xy 128.231847 -52.820881) (xy 128.21384 -52.768097) (xy 128.20371 -52.713254) (xy 128.201673 -52.65752)
			(xy 125.10359 -52.65752) (xy 125.107447 -52.692572) (xy 125.10541 -52.748306) (xy 125.09528 -52.803149)
			(xy 125.077273 -52.855933) (xy 125.051772 -52.905533) (xy 125.019321 -52.950891) (xy 124.980612 -52.99104)
			(xy 124.936469 -53.025126) (xy 124.887834 -53.052422) (xy 124.835743 -53.072345) (xy 124.781306 -53.084471)
			(xy 124.725684 -53.088542) (xy 124.670062 -53.084471) (xy 124.615625 -53.072345) (xy 124.563534 -53.052422)
			(xy 124.514899 -53.025126) (xy 124.470756 -52.99104) (xy 124.432047 -52.950891) (xy 124.399596 -52.905533)
			(xy 124.374095 -52.855933) (xy 124.356088 -52.803149) (xy 124.345958 -52.748306) (xy 124.343921 -52.692572)
			(xy 123.4483 -52.692572) (xy 122.950732 -53.19014) (xy 122.950732 -53.450236) (xy 123.249434 -53.450236)
			(xy 123.253505 -53.394614) (xy 123.265631 -53.340177) (xy 123.285554 -53.288086) (xy 123.31285 -53.239451)
			(xy 123.346936 -53.195308) (xy 123.387085 -53.156599) (xy 123.432443 -53.124148) (xy 123.482043 -53.098647)
			(xy 123.534827 -53.08064) (xy 123.58967 -53.07051) (xy 123.645404 -53.068473) (xy 123.700841 -53.074573)
			(xy 123.754798 -53.088679) (xy 123.806127 -53.110491) (xy 123.853733 -53.139545) (xy 123.896601 -53.17522)
			(xy 123.933818 -53.216757) (xy 123.964591 -53.26327) (xy 123.988263 -53.313767) (xy 124.004331 -53.367174)
			(xy 124.012451 -53.42235) (xy 124.01296 -53.450236) (xy 124.012451 -53.478122) (xy 124.004331 -53.533298)
			(xy 123.988263 -53.586705) (xy 123.964591 -53.637202) (xy 123.933818 -53.683715) (xy 123.896601 -53.725252)
			(xy 123.853733 -53.760927) (xy 123.806127 -53.789981) (xy 123.754798 -53.811793) (xy 123.700841 -53.825899)
			(xy 123.645404 -53.831999) (xy 123.58967 -53.829962) (xy 123.534827 -53.819832) (xy 123.482043 -53.801825)
			(xy 123.432443 -53.776324) (xy 123.387085 -53.743873) (xy 123.346936 -53.705164) (xy 123.31285 -53.661021)
			(xy 123.285554 -53.612386) (xy 123.265631 -53.560295) (xy 123.253505 -53.505858) (xy 123.249434 -53.450236)
			(xy 122.950732 -53.450236) (xy 122.950732 -53.749194) (xy 123.17046 -53.968922) (xy 132.817107 -53.968922)
			(xy 132.823207 -53.913485) (xy 132.837313 -53.859528) (xy 132.859125 -53.808199) (xy 132.888179 -53.760593)
			(xy 132.923854 -53.717725) (xy 132.965391 -53.680508) (xy 133.011904 -53.649735) (xy 133.062401 -53.626063)
			(xy 133.115808 -53.609995) (xy 133.170984 -53.601875) (xy 133.19887 -53.601366) (xy 133.226756 -53.601875)
			(xy 133.281932 -53.609995) (xy 133.335339 -53.626063) (xy 133.385836 -53.649735) (xy 133.432349 -53.680508)
			(xy 133.473886 -53.717725) (xy 133.509561 -53.760593) (xy 133.538615 -53.808199) (xy 133.560427 -53.859528)
			(xy 133.574533 -53.913485) (xy 133.580633 -53.968922) (xy 133.578596 -54.024656) (xy 133.568466 -54.079499)
			(xy 133.550459 -54.132283) (xy 133.524958 -54.181883) (xy 133.51486 -54.195998) (xy 136.403587 -54.195998)
			(xy 136.409687 -54.140561) (xy 136.423793 -54.086604) (xy 136.445605 -54.035275) (xy 136.474659 -53.987669)
			(xy 136.510334 -53.944801) (xy 136.551871 -53.907584) (xy 136.598384 -53.876811) (xy 136.648881 -53.853139)
			(xy 136.702288 -53.837071) (xy 136.757464 -53.828951) (xy 136.78535 -53.828442) (xy 136.813236 -53.828951)
			(xy 136.868412 -53.837071) (xy 136.921819 -53.853139) (xy 136.972316 -53.876811) (xy 137.001713 -53.89626)
			(xy 138.79144 -53.89626) (xy 138.795511 -53.840638) (xy 138.807637 -53.786201) (xy 138.82756 -53.73411)
			(xy 138.854856 -53.685475) (xy 138.888942 -53.641332) (xy 138.929091 -53.602623) (xy 138.974449 -53.570172)
			(xy 139.024049 -53.544671) (xy 139.076833 -53.526664) (xy 139.131676 -53.516534) (xy 139.18741 -53.514497)
			(xy 139.242847 -53.520597) (xy 139.296804 -53.534703) (xy 139.348133 -53.556515) (xy 139.395739 -53.585569)
			(xy 139.438607 -53.621244) (xy 139.475824 -53.662781) (xy 139.506597 -53.709294) (xy 139.530269 -53.759791)
			(xy 139.546337 -53.813198) (xy 139.554457 -53.868374) (xy 139.554966 -53.89626) (xy 139.554457 -53.924146)
			(xy 139.546337 -53.979322) (xy 139.530269 -54.032729) (xy 139.506597 -54.083226) (xy 139.475824 -54.129739)
			(xy 139.438607 -54.171276) (xy 139.395739 -54.206951) (xy 139.348133 -54.236005) (xy 139.296804 -54.257817)
			(xy 139.242847 -54.271923) (xy 139.18741 -54.278023) (xy 139.131676 -54.275986) (xy 139.076833 -54.265856)
			(xy 139.024049 -54.247849) (xy 138.974449 -54.222348) (xy 138.929091 -54.189897) (xy 138.888942 -54.151188)
			(xy 138.854856 -54.107045) (xy 138.82756 -54.05841) (xy 138.807637 -54.006319) (xy 138.795511 -53.951882)
			(xy 138.79144 -53.89626) (xy 137.001713 -53.89626) (xy 137.018829 -53.907584) (xy 137.060366 -53.944801)
			(xy 137.096041 -53.987669) (xy 137.125095 -54.035275) (xy 137.146907 -54.086604) (xy 137.161013 -54.140561)
			(xy 137.167113 -54.195998) (xy 137.165076 -54.251732) (xy 137.154946 -54.306575) (xy 137.136939 -54.359359)
			(xy 137.111438 -54.408959) (xy 137.078987 -54.454317) (xy 137.040278 -54.494466) (xy 136.996135 -54.528552)
			(xy 136.9475 -54.555848) (xy 136.895409 -54.575771) (xy 136.840972 -54.587897) (xy 136.78535 -54.591968)
			(xy 136.729728 -54.587897) (xy 136.675291 -54.575771) (xy 136.6232 -54.555848) (xy 136.574565 -54.528552)
			(xy 136.530422 -54.494466) (xy 136.491713 -54.454317) (xy 136.459262 -54.408959) (xy 136.433761 -54.359359)
			(xy 136.415754 -54.306575) (xy 136.405624 -54.251732) (xy 136.403587 -54.195998) (xy 133.51486 -54.195998)
			(xy 133.492507 -54.227241) (xy 133.453798 -54.26739) (xy 133.409655 -54.301476) (xy 133.36102 -54.328772)
			(xy 133.308929 -54.348695) (xy 133.254492 -54.360821) (xy 133.19887 -54.364892) (xy 133.143248 -54.360821)
			(xy 133.088811 -54.348695) (xy 133.03672 -54.328772) (xy 132.988085 -54.301476) (xy 132.943942 -54.26739)
			(xy 132.905233 -54.227241) (xy 132.872782 -54.181883) (xy 132.847281 -54.132283) (xy 132.829274 -54.079499)
			(xy 132.819144 -54.024656) (xy 132.817107 -53.968922) (xy 123.17046 -53.968922) (xy 123.368562 -54.167024)
			(xy 123.381297 -54.17901) (xy 123.411779 -54.196126) (xy 123.445763 -54.204324) (xy 123.480697 -54.202987)
			(xy 123.513955 -54.192217) (xy 123.528836 -54.183026) (xy 123.551759 -54.168255) (xy 123.600944 -54.14471)
			(xy 123.652984 -54.128415) (xy 123.706815 -54.119705) (xy 123.734068 -54.118764) (xy 123.76078 -54.118754)
			(xy 123.813796 -54.125295) (xy 123.865381 -54.139165) (xy 123.914528 -54.160091) (xy 123.960278 -54.187666)
			(xy 124.001736 -54.22135) (xy 124.038093 -54.260486) (xy 124.068638 -54.304308) (xy 124.092775 -54.351961)
			(xy 124.10186 -54.377082) (xy 124.331476 -54.606698) (xy 130.821936 -54.606698) (xy 130.826007 -54.551076)
			(xy 130.838133 -54.496639) (xy 130.858056 -54.444548) (xy 130.885352 -54.395913) (xy 130.919438 -54.35177)
			(xy 130.959587 -54.313061) (xy 131.004945 -54.28061) (xy 131.054545 -54.255109) (xy 131.107329 -54.237102)
			(xy 131.162172 -54.226972) (xy 131.217906 -54.224935) (xy 131.273343 -54.231035) (xy 131.3273 -54.245141)
			(xy 131.378629 -54.266953) (xy 131.426235 -54.296007) (xy 131.469103 -54.331682) (xy 131.50632 -54.373219)
			(xy 131.537093 -54.419732) (xy 131.560765 -54.470229) (xy 131.576833 -54.523636) (xy 131.584953 -54.578812)
			(xy 131.585462 -54.606698) (xy 131.584953 -54.634584) (xy 131.576833 -54.68976) (xy 131.560765 -54.743167)
			(xy 131.537093 -54.793664) (xy 131.50632 -54.840177) (xy 131.469103 -54.881714) (xy 131.459867 -54.8894)
			(xy 137.971782 -54.8894) (xy 137.975853 -54.833778) (xy 137.987979 -54.779341) (xy 138.007902 -54.72725)
			(xy 138.035198 -54.678615) (xy 138.069284 -54.634472) (xy 138.109433 -54.595763) (xy 138.154791 -54.563312)
			(xy 138.204391 -54.537811) (xy 138.257175 -54.519804) (xy 138.312018 -54.509674) (xy 138.367752 -54.507637)
			(xy 138.423189 -54.513737) (xy 138.477146 -54.527843) (xy 138.528475 -54.549655) (xy 138.576081 -54.578709)
			(xy 138.618949 -54.614384) (xy 138.656166 -54.655921) (xy 138.686939 -54.702434) (xy 138.710611 -54.752931)
			(xy 138.718962 -54.780688) (xy 153.778968 -54.780688) (xy 153.783014 -54.68671) (xy 153.795125 -54.593428)
			(xy 153.81521 -54.501532) (xy 153.84312 -54.411703) (xy 153.878649 -54.324606) (xy 153.921534 -54.240885)
			(xy 153.971457 -54.161161) (xy 154.028049 -54.086024) (xy 154.090891 -54.01603) (xy 154.159517 -53.951697)
			(xy 154.233419 -53.893502) (xy 154.31205 -53.841875) (xy 154.394829 -53.797198) (xy 154.481141 -53.759804)
			(xy 154.570349 -53.729967) (xy 154.661791 -53.70791) (xy 154.754791 -53.693795) (xy 154.84866 -53.687727)
			(xy 154.942704 -53.68975) (xy 155.036225 -53.699851) (xy 155.128531 -53.717954) (xy 155.21894 -53.743925)
			(xy 155.306782 -53.777572) (xy 155.391405 -53.818646) (xy 155.472185 -53.866842) (xy 155.548523 -53.921804)
			(xy 155.619853 -53.983125) (xy 155.685647 -54.050351) (xy 155.745419 -54.122984) (xy 155.798726 -54.200486)
			(xy 155.845173 -54.282284) (xy 155.884416 -54.367772) (xy 155.916166 -54.456317) (xy 155.940185 -54.547264)
			(xy 155.948929 -54.597554) (xy 167.453562 -54.597554) (xy 167.457633 -54.541932) (xy 167.469759 -54.487495)
			(xy 167.489682 -54.435404) (xy 167.516978 -54.386769) (xy 167.551064 -54.342626) (xy 167.591213 -54.303917)
			(xy 167.636571 -54.271466) (xy 167.686171 -54.245965) (xy 167.738955 -54.227958) (xy 167.793798 -54.217828)
			(xy 167.849532 -54.215791) (xy 167.904969 -54.221891) (xy 167.958926 -54.235997) (xy 168.010255 -54.257809)
			(xy 168.057861 -54.286863) (xy 168.100729 -54.322538) (xy 168.137946 -54.364075) (xy 168.168719 -54.410588)
			(xy 168.192391 -54.461085) (xy 168.208459 -54.514492) (xy 168.216579 -54.569668) (xy 168.217088 -54.597554)
			(xy 168.216866 -54.609719) (xy 168.627766 -54.609719) (xy 168.62875 -54.554188) (xy 168.637777 -54.499388)
			(xy 168.654657 -54.446476) (xy 168.679033 -54.396572) (xy 168.710389 -54.350731) (xy 168.748062 -54.309923)
			(xy 168.791256 -54.27501) (xy 168.839056 -54.246731) (xy 168.890453 -54.225684) (xy 168.944358 -54.212315)
			(xy 168.999633 -54.206904) (xy 169.055108 -54.209569) (xy 169.109611 -54.22025) (xy 169.161987 -54.238724)
			(xy 169.21113 -54.264599) (xy 169.256001 -54.297329) (xy 169.29565 -54.33622) (xy 169.312844 -54.358032)
			(xy 169.327178 -54.375978) (xy 169.361092 -54.406943) (xy 169.400014 -54.431315) (xy 169.442679 -54.448303)
			(xy 169.487701 -54.457355) (xy 169.533617 -54.458177) (xy 169.578934 -54.450742) (xy 169.62218 -54.435292)
			(xy 169.66195 -54.412328) (xy 169.69695 -54.382598) (xy 169.711878 -54.365144) (xy 169.729804 -54.343924)
			(xy 169.770809 -54.306451) (xy 169.816816 -54.275321) (xy 169.866851 -54.251193) (xy 169.919857 -54.234578)
			(xy 169.974712 -54.225827) (xy 170.030257 -54.225125) (xy 170.085316 -54.232487) (xy 170.138724 -54.247756)
			(xy 170.189354 -54.270611) (xy 170.236133 -54.300568) (xy 170.278072 -54.336993) (xy 170.314284 -54.379116)
			(xy 170.344004 -54.426045) (xy 170.366603 -54.47679) (xy 170.381603 -54.530275) (xy 170.388686 -54.58537)
			(xy 170.387703 -54.64091) (xy 170.378675 -54.695721) (xy 170.361792 -54.748642) (xy 170.337412 -54.798555)
			(xy 170.306051 -54.844404) (xy 170.26837 -54.885219) (xy 170.225169 -54.920137) (xy 170.177359 -54.94842)
			(xy 170.125953 -54.969469) (xy 170.072037 -54.98284) (xy 170.016752 -54.988249) (xy 169.961267 -54.985582)
			(xy 169.906756 -54.974895) (xy 169.854371 -54.956415) (xy 169.805221 -54.930532) (xy 169.760345 -54.897794)
			(xy 169.720691 -54.858893) (xy 169.703496 -54.837076) (xy 169.689232 -54.819071) (xy 169.655308 -54.788105)
			(xy 169.616375 -54.763733) (xy 169.573699 -54.746747) (xy 169.528667 -54.737699) (xy 169.482742 -54.736884)
			(xy 169.437417 -54.744327) (xy 169.394165 -54.759788) (xy 169.354392 -54.782762) (xy 169.31939 -54.812504)
			(xy 169.304462 -54.829964) (xy 169.286528 -54.851171) (xy 169.245526 -54.888634) (xy 169.199524 -54.919753)
			(xy 169.149495 -54.943871) (xy 169.096497 -54.960478) (xy 169.041651 -54.969223) (xy 168.986117 -54.969921)
			(xy 168.931068 -54.962556) (xy 168.87767 -54.947285) (xy 168.827051 -54.924431) (xy 168.780282 -54.894477)
			(xy 168.738352 -54.858056) (xy 168.702148 -54.815939) (xy 168.672435 -54.769017) (xy 168.649842 -54.718281)
			(xy 168.634847 -54.664804) (xy 168.627766 -54.609719) (xy 168.216866 -54.609719) (xy 168.216579 -54.62544)
			(xy 168.208459 -54.680616) (xy 168.192391 -54.734023) (xy 168.168719 -54.78452) (xy 168.137946 -54.831033)
			(xy 168.100729 -54.87257) (xy 168.057861 -54.908245) (xy 168.010255 -54.937299) (xy 167.958926 -54.959111)
			(xy 167.904969 -54.973217) (xy 167.849532 -54.979317) (xy 167.793798 -54.97728) (xy 167.738955 -54.96715)
			(xy 167.686171 -54.949143) (xy 167.636571 -54.923642) (xy 167.591213 -54.891191) (xy 167.551064 -54.852482)
			(xy 167.516978 -54.808339) (xy 167.489682 -54.759704) (xy 167.469759 -54.707613) (xy 167.457633 -54.653176)
			(xy 167.453562 -54.597554) (xy 155.948929 -54.597554) (xy 155.956298 -54.639939) (xy 155.964384 -54.733655)
			(xy 155.96489 -54.780688) (xy 155.964384 -54.827721) (xy 155.956298 -54.921437) (xy 155.940185 -55.014112)
			(xy 155.916166 -55.105059) (xy 155.884416 -55.193604) (xy 155.845173 -55.279092) (xy 155.798726 -55.36089)
			(xy 155.745419 -55.438392) (xy 155.685647 -55.511025) (xy 155.619853 -55.578251) (xy 155.548523 -55.639572)
			(xy 155.472185 -55.694534) (xy 155.391405 -55.74273) (xy 155.306782 -55.783804) (xy 155.21894 -55.817451)
			(xy 155.128531 -55.843422) (xy 155.036225 -55.861525) (xy 154.942704 -55.871626) (xy 154.84866 -55.873649)
			(xy 154.754791 -55.867581) (xy 154.661791 -55.853466) (xy 154.570349 -55.831409) (xy 154.481141 -55.801572)
			(xy 154.394829 -55.764178) (xy 154.31205 -55.719501) (xy 154.233419 -55.667874) (xy 154.159517 -55.609679)
			(xy 154.090891 -55.545346) (xy 154.028049 -55.475352) (xy 153.971457 -55.400215) (xy 153.921534 -55.320491)
			(xy 153.878649 -55.23677) (xy 153.84312 -55.149673) (xy 153.81521 -55.059844) (xy 153.795125 -54.967948)
			(xy 153.783014 -54.874666) (xy 153.778968 -54.780688) (xy 138.718962 -54.780688) (xy 138.726679 -54.806338)
			(xy 138.734799 -54.861514) (xy 138.735308 -54.8894) (xy 138.734799 -54.917286) (xy 138.726679 -54.972462)
			(xy 138.710611 -55.025869) (xy 138.686939 -55.076366) (xy 138.656166 -55.122879) (xy 138.618949 -55.164416)
			(xy 138.576081 -55.200091) (xy 138.528475 -55.229145) (xy 138.477146 -55.250957) (xy 138.423189 -55.265063)
			(xy 138.367752 -55.271163) (xy 138.312018 -55.269126) (xy 138.257175 -55.258996) (xy 138.204391 -55.240989)
			(xy 138.154791 -55.215488) (xy 138.109433 -55.183037) (xy 138.069284 -55.144328) (xy 138.035198 -55.100185)
			(xy 138.007902 -55.05155) (xy 137.987979 -54.999459) (xy 137.975853 -54.945022) (xy 137.971782 -54.8894)
			(xy 131.459867 -54.8894) (xy 131.426235 -54.917389) (xy 131.378629 -54.946443) (xy 131.3273 -54.968255)
			(xy 131.273343 -54.982361) (xy 131.217906 -54.988461) (xy 131.162172 -54.986424) (xy 131.107329 -54.976294)
			(xy 131.054545 -54.958287) (xy 131.004945 -54.932786) (xy 130.959587 -54.900335) (xy 130.919438 -54.861626)
			(xy 130.885352 -54.817483) (xy 130.858056 -54.768848) (xy 130.838133 -54.716757) (xy 130.826007 -54.66232)
			(xy 130.821936 -54.606698) (xy 124.331476 -54.606698) (xy 125.278896 -55.554118) (xy 126.093982 -55.554118)
			(xy 126.116739 -55.553614) (xy 126.161527 -55.545511) (xy 126.204155 -55.52956) (xy 126.243261 -55.506273)
			(xy 126.277595 -55.476393) (xy 126.306058 -55.440876) (xy 126.32774 -55.400858) (xy 126.341948 -55.357617)
			(xy 126.348227 -55.312538) (xy 126.346378 -55.267061) (xy 126.341886 -55.244746) (xy 126.336393 -55.217966)
			(xy 126.332229 -55.163458) (xy 126.335888 -55.108913) (xy 126.347295 -55.055449) (xy 126.366215 -55.004161)
			(xy 126.392263 -54.956098) (xy 126.424904 -54.912245) (xy 126.46347 -54.8735) (xy 126.507171 -54.840657)
			(xy 126.555112 -54.814387) (xy 126.606312 -54.795229) (xy 126.659723 -54.783575) (xy 126.71425 -54.779663)
			(xy 126.768777 -54.783575) (xy 126.822188 -54.795229) (xy 126.873388 -54.814387) (xy 126.921329 -54.840657)
			(xy 126.96503 -54.8735) (xy 127.003596 -54.912245) (xy 127.036237 -54.956098) (xy 127.062285 -55.004161)
			(xy 127.081205 -55.055449) (xy 127.092612 -55.108913) (xy 127.096271 -55.163458) (xy 127.092107 -55.217966)
			(xy 127.086614 -55.244746) (xy 127.082148 -55.267064) (xy 127.080299 -55.312537) (xy 127.086578 -55.357611)
			(xy 127.100785 -55.400847) (xy 127.122465 -55.440861) (xy 127.150925 -55.476374) (xy 127.185254 -55.506251)
			(xy 127.224356 -55.529536) (xy 127.26698 -55.545485) (xy 127.311763 -55.553587) (xy 127.334518 -55.554118)
			(xy 129.46253 -55.554118) (xy 129.484684 -55.553634) (xy 129.528319 -55.545941) (xy 129.569957 -55.530794)
			(xy 129.608336 -55.508653) (xy 129.642292 -55.480188) (xy 129.670793 -55.446264) (xy 129.692977 -55.407909)
			(xy 129.708169 -55.366288) (xy 129.71591 -55.322661) (xy 129.715963 -55.278353) (xy 129.71272 -55.25643)
			(xy 129.709126 -55.233565) (xy 129.706833 -55.187336) (xy 129.708148 -55.164228) (xy 129.706632 -55.136994)
			(xy 129.710462 -55.082583) (xy 129.722002 -55.029272) (xy 129.741017 -54.978149) (xy 129.767119 -54.930255)
			(xy 129.799776 -54.886566) (xy 129.838323 -54.847974) (xy 129.881973 -54.815265) (xy 129.929836 -54.789107)
			(xy 129.980937 -54.770031) (xy 130.034234 -54.758428) (xy 130.08864 -54.754534) (xy 130.143046 -54.758428)
			(xy 130.196343 -54.770031) (xy 130.247444 -54.789107) (xy 130.295307 -54.815265) (xy 130.338957 -54.847974)
			(xy 130.377504 -54.886566) (xy 130.410161 -54.930255) (xy 130.436263 -54.978149) (xy 130.455278 -55.029272)
			(xy 130.466818 -55.082583) (xy 130.470648 -55.136994) (xy 130.469132 -55.164228) (xy 130.470456 -55.187336)
			(xy 130.468158 -55.233565) (xy 130.46456 -55.25643) (xy 130.461225 -55.27834) (xy 130.461294 -55.322654)
			(xy 130.469049 -55.366284) (xy 130.484254 -55.407907) (xy 130.506449 -55.446262) (xy 130.53496 -55.480187)
			(xy 130.568923 -55.508651) (xy 130.607308 -55.530793) (xy 130.648953 -55.545941) (xy 130.692593 -55.553636)
			(xy 130.71475 -55.554118) (xy 134.925308 -55.554118) (xy 135.307113 -55.93588) (xy 138.593574 -55.93588)
			(xy 138.597645 -55.880258) (xy 138.609771 -55.825821) (xy 138.629694 -55.77373) (xy 138.65699 -55.725095)
			(xy 138.691076 -55.680952) (xy 138.731225 -55.642243) (xy 138.776583 -55.609792) (xy 138.826183 -55.584291)
			(xy 138.878967 -55.566284) (xy 138.93381 -55.556154) (xy 138.989544 -55.554117) (xy 139.044981 -55.560217)
			(xy 139.098938 -55.574323) (xy 139.150267 -55.596135) (xy 139.197873 -55.625189) (xy 139.240741 -55.660864)
			(xy 139.277958 -55.702401) (xy 139.308731 -55.748914) (xy 139.332403 -55.799411) (xy 139.348471 -55.852818)
			(xy 139.356591 -55.907994) (xy 139.3571 -55.93588) (xy 139.356591 -55.963766) (xy 139.348471 -56.018942)
			(xy 139.334086 -56.066756) (xy 146.863986 -56.066756) (xy 146.86538 -56.010701) (xy 146.874964 -55.955453)
			(xy 146.89253 -55.902204) (xy 146.917701 -55.852099) (xy 146.949935 -55.806217) (xy 146.988537 -55.765548)
			(xy 147.032676 -55.730967) (xy 147.081401 -55.703219) (xy 147.133663 -55.682901) (xy 147.188336 -55.670451)
			(xy 147.244242 -55.666138) (xy 147.300178 -55.670054) (xy 147.354937 -55.682114) (xy 147.407342 -55.70206)
			(xy 147.456263 -55.729462) (xy 147.500647 -55.763728) (xy 147.539537 -55.804122) (xy 147.55622 -55.82666)
			(xy 147.570304 -55.845552) (xy 147.604261 -55.878215) (xy 147.643654 -55.904065) (xy 147.687134 -55.922217)
			(xy 147.733213 -55.932049) (xy 147.780316 -55.933226) (xy 147.826829 -55.925708) (xy 147.871161 -55.90975)
			(xy 147.911796 -55.8859) (xy 147.947342 -55.854973) (xy 147.962366 -55.83682) (xy 147.979278 -55.816144)
			(xy 148.017936 -55.77928) (xy 148.061357 -55.748169) (xy 148.108693 -55.723419) (xy 148.159019 -55.705513)
			(xy 148.211351 -55.694802) (xy 148.264665 -55.691495) (xy 148.317919 -55.695657) (xy 148.370072 -55.707206)
			(xy 148.420104 -55.725917) (xy 148.467037 -55.751424) (xy 148.509954 -55.783228) (xy 148.548014 -55.820707)
			(xy 148.5646 -55.841646) (xy 148.579276 -55.860072) (xy 148.614293 -55.891577) (xy 148.654514 -55.916095)
			(xy 148.698561 -55.932786) (xy 148.744929 -55.941081) (xy 148.792032 -55.940694) (xy 148.838258 -55.93164)
			(xy 148.882025 -55.914228) (xy 148.921838 -55.889054) (xy 148.956334 -55.856979) (xy 148.970746 -55.838344)
			(xy 148.987755 -55.816064) (xy 149.027305 -55.776341) (xy 149.072243 -55.742834) (xy 149.1216 -55.716264)
			(xy 149.174315 -55.697204) (xy 149.229251 -55.686063) (xy 149.285226 -55.683082) (xy 149.341035 -55.688324)
			(xy 149.395475 -55.701678) (xy 149.447376 -55.722855) (xy 149.495618 -55.751399) (xy 149.539164 -55.786696)
			(xy 149.577075 -55.827985) (xy 149.608536 -55.874379) (xy 149.632868 -55.924876) (xy 149.649549 -55.978391)
			(xy 149.658218 -56.033772) (xy 149.658689 -56.089824) (xy 149.651757 -56.139563) (xy 149.912017 -56.139563)
			(xy 149.91884 -56.083912) (xy 149.933734 -56.029859) (xy 149.95638 -55.978568) (xy 149.986289 -55.931144)
			(xy 150.022817 -55.888608) (xy 150.065178 -55.851877) (xy 150.112458 -55.821742) (xy 150.16364 -55.798851)
			(xy 150.217622 -55.783699) (xy 150.27324 -55.77661) (xy 150.329296 -55.777738) (xy 150.384583 -55.787059)
			(xy 150.437911 -55.804372) (xy 150.488131 -55.829304) (xy 150.53416 -55.861318) (xy 150.575008 -55.899724)
			(xy 150.59279 -55.921402) (xy 150.607844 -55.939544) (xy 150.643361 -55.97053) (xy 150.683985 -55.994432)
			(xy 150.728322 -56.010427) (xy 150.774848 -56.017968) (xy 150.821968 -56.016794) (xy 150.868061 -56.006946)
			(xy 150.911547 -55.988762) (xy 150.95093 -55.962867) (xy 150.984859 -55.93015) (xy 150.998936 -55.911242)
			(xy 151.015573 -55.888667) (xy 151.054459 -55.848258) (xy 151.098841 -55.813977) (xy 151.147762 -55.786561)
			(xy 151.20017 -55.7666) (xy 151.254934 -55.754526) (xy 151.310876 -55.750598) (xy 151.366791 -55.7549)
			(xy 151.421473 -55.76734) (xy 151.473746 -55.787649) (xy 151.522484 -55.815392) (xy 151.566635 -55.849969)
			(xy 151.60525 -55.890636) (xy 151.637497 -55.936518) (xy 151.662681 -55.986625) (xy 151.680259 -56.039879)
			(xy 151.689853 -56.095132) (xy 151.691257 -56.151194) (xy 151.684439 -56.206858) (xy 151.669548 -56.260924)
			(xy 151.646903 -56.312229) (xy 151.616992 -56.359666) (xy 151.580461 -56.402215) (xy 151.538095 -56.438958)
			(xy 151.490807 -56.469105) (xy 151.439616 -56.492005) (xy 151.385624 -56.507165) (xy 151.329995 -56.51426)
			(xy 151.273926 -56.513136) (xy 151.218626 -56.503817) (xy 151.165285 -56.486504) (xy 151.115053 -56.46157)
			(xy 151.069012 -56.429552) (xy 151.028153 -56.39114) (xy 151.010366 -56.369458) (xy 150.995361 -56.351275)
			(xy 150.959835 -56.320293) (xy 150.919202 -56.296396) (xy 150.874859 -56.280406) (xy 150.828327 -56.272871)
			(xy 150.781203 -56.27405) (xy 150.735106 -56.283902) (xy 150.691617 -56.30209) (xy 150.652231 -56.327988)
			(xy 150.618298 -56.360708) (xy 150.60422 -56.379618) (xy 150.587524 -56.402144) (xy 150.548639 -56.442536)
			(xy 150.504261 -56.476802) (xy 150.455345 -56.504203) (xy 150.402946 -56.52415) (xy 150.348191 -56.536212)
			(xy 150.29226 -56.54013) (xy 150.236358 -56.53582) (xy 150.181689 -56.523374) (xy 150.129431 -56.50306)
			(xy 150.080709 -56.475317) (xy 150.036572 -56.44074) (xy 149.997971 -56.400076) (xy 149.965738 -56.3542)
			(xy 149.940566 -56.3041) (xy 149.922999 -56.250856) (xy 149.913413 -56.195614) (xy 149.912017 -56.139563)
			(xy 149.651757 -56.139563) (xy 149.650952 -56.145342) (xy 149.635174 -56.19913) (xy 149.611693 -56.25003)
			(xy 149.581017 -56.296945) (xy 149.543805 -56.338866) (xy 149.500859 -56.37489) (xy 149.453103 -56.404241)
			(xy 149.401566 -56.426288) (xy 149.347358 -56.440554) (xy 149.291645 -56.446734) (xy 149.235628 -56.444695)
			(xy 149.180512 -56.434479) (xy 149.127485 -56.416307) (xy 149.077688 -56.390571) (xy 149.032193 -56.357824)
			(xy 148.991981 -56.318772) (xy 148.974556 -56.296814) (xy 148.959812 -56.278446) (xy 148.924803 -56.246947)
			(xy 148.884593 -56.222432) (xy 148.840557 -56.205741) (xy 148.794199 -56.197443) (xy 148.747107 -56.197823)
			(xy 148.70089 -56.206868) (xy 148.657129 -56.224268) (xy 148.617319 -56.249429) (xy 148.582824 -56.281489)
			(xy 148.56841 -56.300116) (xy 148.551555 -56.322089) (xy 148.512581 -56.361428) (xy 148.468327 -56.394716)
			(xy 148.419724 -56.421254) (xy 148.367794 -56.440484) (xy 148.313629 -56.452001) (xy 148.258367 -56.455563)
			(xy 148.203171 -56.451095) (xy 148.149202 -56.438691) (xy 148.097595 -56.418611) (xy 148.049434 -56.39128)
			(xy 148.005732 -56.357269) (xy 147.967409 -56.317296) (xy 147.950936 -56.295036) (xy 147.936784 -56.276198)
			(xy 147.902837 -56.243536) (xy 147.863455 -56.217686) (xy 147.819985 -56.199532) (xy 147.773915 -56.189696)
			(xy 147.726821 -56.188513) (xy 147.680316 -56.196024) (xy 147.635989 -56.211972) (xy 147.595358 -56.235812)
			(xy 147.559814 -56.266728) (xy 147.54479 -56.284876) (xy 147.527043 -56.306585) (xy 147.486194 -56.344996)
			(xy 147.440162 -56.377015) (xy 147.389939 -56.401951) (xy 147.336608 -56.419267) (xy 147.281316 -56.428591)
			(xy 147.225255 -56.429722) (xy 147.169632 -56.422636) (xy 147.115646 -56.407484) (xy 147.064459 -56.384594)
			(xy 147.017173 -56.354459) (xy 146.974807 -56.317726) (xy 146.938274 -56.275189) (xy 146.90836 -56.227762)
			(xy 146.88571 -56.176468) (xy 146.870812 -56.122411) (xy 146.863986 -56.066756) (xy 139.334086 -56.066756)
			(xy 139.332403 -56.072349) (xy 139.308731 -56.122846) (xy 139.277958 -56.169359) (xy 139.240741 -56.210896)
			(xy 139.197873 -56.246571) (xy 139.150267 -56.275625) (xy 139.098938 -56.297437) (xy 139.044981 -56.311543)
			(xy 138.989544 -56.317643) (xy 138.93381 -56.315606) (xy 138.878967 -56.305476) (xy 138.826183 -56.287469)
			(xy 138.776583 -56.261968) (xy 138.731225 -56.229517) (xy 138.691076 -56.190808) (xy 138.65699 -56.146665)
			(xy 138.629694 -56.09803) (xy 138.609771 -56.045939) (xy 138.597645 -55.991502) (xy 138.593574 -55.93588)
			(xy 135.307113 -55.93588) (xy 135.848956 -56.477662) (xy 143.884902 -56.477662) (xy 143.888973 -56.42204)
			(xy 143.901099 -56.367603) (xy 143.921022 -56.315512) (xy 143.948318 -56.266877) (xy 143.982404 -56.222734)
			(xy 144.022553 -56.184025) (xy 144.067911 -56.151574) (xy 144.117511 -56.126073) (xy 144.170295 -56.108066)
			(xy 144.225138 -56.097936) (xy 144.280872 -56.095899) (xy 144.336309 -56.101999) (xy 144.390266 -56.116105)
			(xy 144.441595 -56.137917) (xy 144.489201 -56.166971) (xy 144.532069 -56.202646) (xy 144.569286 -56.244183)
			(xy 144.600059 -56.290696) (xy 144.623731 -56.341193) (xy 144.639799 -56.3946) (xy 144.647919 -56.449776)
			(xy 144.648428 -56.477662) (xy 144.648243 -56.487822) (xy 144.911062 -56.487822) (xy 144.915133 -56.4322)
			(xy 144.927259 -56.377763) (xy 144.947182 -56.325672) (xy 144.974478 -56.277037) (xy 145.008564 -56.232894)
			(xy 145.048713 -56.194185) (xy 145.094071 -56.161734) (xy 145.143671 -56.136233) (xy 145.196455 -56.118226)
			(xy 145.251298 -56.108096) (xy 145.307032 -56.106059) (xy 145.362469 -56.112159) (xy 145.416426 -56.126265)
			(xy 145.467755 -56.148077) (xy 145.515361 -56.177131) (xy 145.558229 -56.212806) (xy 145.595446 -56.254343)
			(xy 145.626219 -56.300856) (xy 145.649891 -56.351353) (xy 145.665959 -56.40476) (xy 145.674079 -56.459936)
			(xy 145.674588 -56.487822) (xy 145.674079 -56.515708) (xy 145.665959 -56.570884) (xy 145.649891 -56.624291)
			(xy 145.626219 -56.674788) (xy 145.595446 -56.721301) (xy 145.558229 -56.762838) (xy 145.515361 -56.798513)
			(xy 145.467755 -56.827567) (xy 145.445399 -56.837067) (xy 165.995828 -56.837067) (xy 165.999014 -56.781404)
			(xy 166.01027 -56.726797) (xy 166.029357 -56.674411) (xy 166.055867 -56.625363) (xy 166.089237 -56.580697)
			(xy 166.128754 -56.541365) (xy 166.173576 -56.508206) (xy 166.222749 -56.481926) (xy 166.275223 -56.463085)
			(xy 166.329882 -56.452085) (xy 166.38556 -56.449161) (xy 166.44107 -56.454374) (xy 166.49523 -56.467614)
			(xy 166.546885 -56.488598) (xy 166.571168 -56.5023) (xy 166.591875 -56.513924) (xy 166.636562 -56.52998)
			(xy 166.683453 -56.537465) (xy 166.730918 -56.53612) (xy 166.777309 -56.525992) (xy 166.821015 -56.507432)
			(xy 166.860519 -56.481084) (xy 166.894448 -56.447865) (xy 166.921624 -56.408927) (xy 166.931848 -56.387492)
			(xy 166.943745 -56.362268) (xy 166.973772 -56.315273) (xy 167.010322 -56.273152) (xy 167.052615 -56.2368)
			(xy 167.09975 -56.206994) (xy 167.150723 -56.184369) (xy 167.204447 -56.169407) (xy 167.259777 -56.162426)
			(xy 167.315534 -56.163576) (xy 167.370529 -56.172832) (xy 167.42359 -56.189997) (xy 167.473587 -56.214704)
			(xy 167.519453 -56.246428) (xy 167.560212 -56.284492) (xy 167.594994 -56.328085) (xy 167.623058 -56.376278)
			(xy 167.643806 -56.428043) (xy 167.656796 -56.482277) (xy 167.661751 -56.537825) (xy 167.658565 -56.593503)
			(xy 167.647306 -56.648123) (xy 167.628215 -56.700522) (xy 167.601697 -56.749583) (xy 167.568319 -56.79426)
			(xy 167.528792 -56.8336) (xy 167.483957 -56.866767) (xy 167.434772 -56.893052) (xy 167.382283 -56.911895)
			(xy 167.32761 -56.922895) (xy 167.271918 -56.925818) (xy 167.216394 -56.9206) (xy 167.162222 -56.907354)
			(xy 167.110555 -56.886361) (xy 167.08628 -56.872632) (xy 167.065528 -56.861095) (xy 167.020852 -56.845041)
			(xy 166.973974 -56.837553) (xy 166.92652 -56.838891) (xy 166.880138 -56.84901) (xy 166.836439 -56.867557)
			(xy 166.796938 -56.89389) (xy 166.763009 -56.927093) (xy 166.735828 -56.966014) (xy 166.7256 -56.98744)
			(xy 166.713662 -57.012638) (xy 166.683636 -57.059617) (xy 166.647091 -57.101724) (xy 166.604804 -57.138061)
			(xy 166.557677 -57.167855) (xy 166.506715 -57.190469) (xy 166.453003 -57.205423) (xy 166.397686 -57.212397)
			(xy 166.341944 -57.211242) (xy 166.286963 -57.201985) (xy 166.233916 -57.184821) (xy 166.183934 -57.160116)
			(xy 166.13808 -57.128398) (xy 166.097334 -57.090341) (xy 166.062563 -57.046757) (xy 166.034507 -56.998576)
			(xy 166.013766 -56.946823) (xy 166.000781 -56.892601) (xy 165.995828 -56.837067) (xy 145.445399 -56.837067)
			(xy 145.416426 -56.849379) (xy 145.362469 -56.863485) (xy 145.307032 -56.869585) (xy 145.251298 -56.867548)
			(xy 145.196455 -56.857418) (xy 145.143671 -56.839411) (xy 145.094071 -56.81391) (xy 145.048713 -56.781459)
			(xy 145.008564 -56.74275) (xy 144.974478 -56.698607) (xy 144.947182 -56.649972) (xy 144.927259 -56.597881)
			(xy 144.915133 -56.543444) (xy 144.911062 -56.487822) (xy 144.648243 -56.487822) (xy 144.647919 -56.505548)
			(xy 144.639799 -56.560724) (xy 144.623731 -56.614131) (xy 144.600059 -56.664628) (xy 144.569286 -56.711141)
			(xy 144.532069 -56.752678) (xy 144.489201 -56.788353) (xy 144.441595 -56.817407) (xy 144.390266 -56.839219)
			(xy 144.336309 -56.853325) (xy 144.280872 -56.859425) (xy 144.225138 -56.857388) (xy 144.170295 -56.847258)
			(xy 144.117511 -56.829251) (xy 144.067911 -56.80375) (xy 144.022553 -56.771299) (xy 143.982404 -56.73259)
			(xy 143.948318 -56.688447) (xy 143.921022 -56.639812) (xy 143.901099 -56.587721) (xy 143.888973 -56.533284)
			(xy 143.884902 -56.477662) (xy 135.848956 -56.477662) (xy 137.173716 -57.802272) (xy 138.548364 -57.802272)
			(xy 139.100814 -57.250076) (xy 140.545566 -57.250076) (xy 140.863828 -57.568338) (xy 143.994122 -57.568338)
			(xy 143.998193 -57.512716) (xy 144.010319 -57.458279) (xy 144.030242 -57.406188) (xy 144.057538 -57.357553)
			(xy 144.091624 -57.31341) (xy 144.131773 -57.274701) (xy 144.177131 -57.24225) (xy 144.226731 -57.216749)
			(xy 144.279515 -57.198742) (xy 144.334358 -57.188612) (xy 144.390092 -57.186575) (xy 144.445529 -57.192675)
			(xy 144.499486 -57.206781) (xy 144.550815 -57.228593) (xy 144.598421 -57.257647) (xy 144.641289 -57.293322)
			(xy 144.678506 -57.334859) (xy 144.709279 -57.381372) (xy 144.732951 -57.431869) (xy 144.749019 -57.485276)
			(xy 144.757139 -57.540452) (xy 144.757286 -57.548526) (xy 145.081242 -57.548526) (xy 145.085313 -57.492904)
			(xy 145.097439 -57.438467) (xy 145.117362 -57.386376) (xy 145.144658 -57.337741) (xy 145.178744 -57.293598)
			(xy 145.218893 -57.254889) (xy 145.264251 -57.222438) (xy 145.313851 -57.196937) (xy 145.366635 -57.17893)
			(xy 145.421478 -57.1688) (xy 145.477212 -57.166763) (xy 145.532649 -57.172863) (xy 145.586606 -57.186969)
			(xy 145.637935 -57.208781) (xy 145.685541 -57.237835) (xy 145.728409 -57.27351) (xy 145.765626 -57.315047)
			(xy 145.796399 -57.36156) (xy 145.820071 -57.412057) (xy 145.836139 -57.465464) (xy 145.844259 -57.52064)
			(xy 145.844768 -57.548526) (xy 145.844259 -57.576412) (xy 145.836139 -57.631588) (xy 145.820071 -57.684995)
			(xy 145.796399 -57.735492) (xy 145.765626 -57.782005) (xy 145.728409 -57.823542) (xy 145.685541 -57.859217)
			(xy 145.637935 -57.888271) (xy 145.586606 -57.910083) (xy 145.532649 -57.924189) (xy 145.477212 -57.930289)
			(xy 145.421478 -57.928252) (xy 145.366635 -57.918122) (xy 145.313851 -57.900115) (xy 145.264251 -57.874614)
			(xy 145.218893 -57.842163) (xy 145.178744 -57.803454) (xy 145.144658 -57.759311) (xy 145.117362 -57.710676)
			(xy 145.097439 -57.658585) (xy 145.085313 -57.604148) (xy 145.081242 -57.548526) (xy 144.757286 -57.548526)
			(xy 144.757648 -57.568338) (xy 144.757139 -57.596224) (xy 144.749019 -57.6514) (xy 144.732951 -57.704807)
			(xy 144.709279 -57.755304) (xy 144.678506 -57.801817) (xy 144.641289 -57.843354) (xy 144.598421 -57.879029)
			(xy 144.550815 -57.908083) (xy 144.499486 -57.929895) (xy 144.445529 -57.944001) (xy 144.390092 -57.950101)
			(xy 144.334358 -57.948064) (xy 144.279515 -57.937934) (xy 144.226731 -57.919927) (xy 144.177131 -57.894426)
			(xy 144.131773 -57.861975) (xy 144.091624 -57.823266) (xy 144.057538 -57.779123) (xy 144.030242 -57.730488)
			(xy 144.010319 -57.678397) (xy 143.998193 -57.62396) (xy 143.994122 -57.568338) (xy 140.863828 -57.568338)
			(xy 141.94409 -58.6486) (xy 141.956128 -58.659942) (xy 141.984696 -58.676584) (xy 142.016585 -58.685314)
			(xy 142.049646 -58.685546) (xy 142.081653 -58.677263) (xy 142.110452 -58.661023) (xy 142.134103 -58.637921)
			(xy 142.142972 -58.623962) (xy 142.155382 -58.602069) (xy 142.172209 -58.554648) (xy 142.179362 -58.504842)
			(xy 142.178532 -58.47969) (xy 142.177493 -58.451594) (xy 142.182686 -58.395613) (xy 142.196038 -58.341001)
			(xy 142.217259 -58.288939) (xy 142.245891 -58.240554) (xy 142.281314 -58.196896) (xy 142.322759 -58.158908)
			(xy 142.369331 -58.127413) (xy 142.42002 -58.103094) (xy 142.473729 -58.086476) (xy 142.529295 -58.07792)
			(xy 142.585516 -58.077611) (xy 142.641173 -58.085556) (xy 142.695061 -58.101582) (xy 142.746015 -58.125343)
			(xy 142.79293 -58.156323) (xy 142.83479 -58.193853) (xy 142.87069 -58.23712) (xy 142.899853 -58.285186)
			(xy 142.921645 -58.337012) (xy 142.929102 -58.36412) (xy 142.935122 -58.385621) (xy 142.953635 -58.426247)
			(xy 142.978957 -58.463016) (xy 143.010309 -58.494801) (xy 143.046729 -58.520624) (xy 143.087097 -58.539693)
			(xy 143.130175 -58.551421) (xy 143.152368 -58.553858) (xy 143.188182 -58.557668) (xy 143.209999 -58.559906)
			(xy 143.2538 -58.557743) (xy 143.296579 -58.548089) (xy 143.337063 -58.531231) (xy 143.374051 -58.507671)
			(xy 143.406442 -58.478107) (xy 143.433274 -58.44342) (xy 143.45375 -58.404639) (xy 143.460978 -58.383932)
			(xy 143.469299 -58.357447) (xy 143.49254 -58.307033) (xy 143.522849 -58.260524) (xy 143.559584 -58.218904)
			(xy 143.601968 -58.183053) (xy 143.649105 -58.15373) (xy 143.699996 -58.131555) (xy 143.726662 -58.123836)
			(xy 143.753196 -58.117093) (xy 143.80753 -58.110394) (xy 143.862264 -58.111528) (xy 143.916274 -58.120473)
			(xy 143.968452 -58.137044) (xy 144.017726 -58.160902) (xy 144.063084 -58.191556) (xy 144.103597 -58.228378)
			(xy 144.138431 -58.270612) (xy 144.166873 -58.31739) (xy 144.188337 -58.367752) (xy 144.1958 -58.394092)
			(xy 144.202667 -58.415248) (xy 144.222731 -58.454941) (xy 144.249393 -58.490539) (xy 144.281839 -58.520959)
			(xy 144.319081 -58.545272) (xy 144.359983 -58.562738) (xy 144.4033 -58.572825) (xy 144.447711 -58.575225)
			(xy 144.491863 -58.569865) (xy 144.534409 -58.556908) (xy 144.554448 -58.547254) (xy 144.576387 -58.53479)
			(xy 144.622849 -58.515109) (xy 144.671499 -58.501719) (xy 144.721488 -58.494853) (xy 144.771946 -58.494631)
			(xy 144.797018 -58.49747) (xy 144.816238 -58.500218) (xy 144.854031 -58.509127) (xy 144.872456 -58.51525)
			(xy 144.897117 -58.524245) (xy 144.943905 -58.548043) (xy 144.986995 -58.578022) (xy 145.006568 -58.595514)
			(xy 145.021762 -58.609912) (xy 145.049258 -58.641478) (xy 145.061432 -58.658506) (xy 145.06194 -58.659268)
			(xy 145.08099 -58.685938) (xy 145.187924 -58.74766) (xy 145.868644 -58.74766) (xy 145.981928 -58.675016)
			(xy 145.997422 -58.647076) (xy 146.011 -58.623703) (xy 146.043734 -58.580688) (xy 146.08221 -58.542723)
			(xy 146.125659 -58.510567) (xy 146.17321 -58.484863) (xy 146.223913 -58.466128) (xy 146.276752 -58.454734)
			(xy 146.33067 -58.450911) (xy 146.384588 -58.454734) (xy 146.437427 -58.466128) (xy 146.48813 -58.484863)
			(xy 146.535681 -58.510567) (xy 146.57913 -58.542723) (xy 146.617606 -58.580688) (xy 146.65034 -58.623703)
			(xy 146.663918 -58.647076) (xy 146.679412 -58.675016) (xy 146.735038 -58.71083) (xy 146.748618 -58.718954)
			(xy 146.778637 -58.728933) (xy 146.810188 -58.731227) (xy 146.841334 -58.725694) (xy 146.870165 -58.712675)
			(xy 146.894911 -58.692968) (xy 146.914053 -58.667782) (xy 146.920712 -58.653426) (xy 146.957034 -58.567574)
			(xy 146.930364 -58.48223) (xy 146.921728 -58.468514) (xy 146.907083 -58.444084) (xy 146.884414 -58.391834)
			(xy 146.869763 -58.336795) (xy 146.863456 -58.28019) (xy 146.865633 -58.223275) (xy 146.876247 -58.167317)
			(xy 146.89506 -58.113558) (xy 146.921656 -58.063193) (xy 146.955443 -58.017341) (xy 146.99567 -57.97702)
			(xy 147.041444 -57.943127) (xy 147.091747 -57.916415) (xy 147.145462 -57.897477) (xy 147.201396 -57.886734)
			(xy 147.22983 -57.885076) (xy 147.256789 -57.884426) (xy 147.310446 -57.889806) (xy 147.36281 -57.902687)
			(xy 147.41284 -57.922813) (xy 147.459537 -57.949782) (xy 147.501972 -57.983058) (xy 147.539298 -58.021977)
			(xy 147.570773 -58.065763) (xy 147.59577 -58.113546) (xy 147.613789 -58.164372) (xy 147.624473 -58.217228)
			(xy 147.627608 -58.271063) (xy 147.623132 -58.324802) (xy 147.611133 -58.377376) (xy 147.60194 -58.402728)
			(xy 147.594368 -58.423786) (xy 147.585906 -58.467726) (xy 147.58527 -58.512468) (xy 147.59248 -58.55663)
			(xy 147.607312 -58.598848) (xy 147.629308 -58.637815) (xy 147.657788 -58.672328) (xy 147.691873 -58.70132)
			(xy 147.730508 -58.723895) (xy 147.772499 -58.739355) (xy 147.816549 -58.747222) (xy 147.838922 -58.74766)
			(xy 148.10359 -58.74766) (xy 148.126408 -58.74718) (xy 148.171311 -58.739031) (xy 148.214037 -58.722994)
			(xy 148.253212 -58.699585) (xy 148.287577 -58.669555) (xy 148.316025 -58.633871) (xy 148.337644 -58.593679)
			(xy 148.351737 -58.550273) (xy 148.357851 -58.505048) (xy 148.357336 -58.48223) (xy 148.355062 -58.454583)
			(xy 148.357573 -58.399168) (xy 148.368081 -58.3447) (xy 148.386363 -58.292327) (xy 148.412036 -58.243153)
			(xy 148.444557 -58.198214) (xy 148.483241 -58.158457) (xy 148.527274 -58.124719) (xy 148.575727 -58.097711)
			(xy 148.62758 -58.078003) (xy 148.68174 -58.066009) (xy 148.737066 -58.061983) (xy 148.792392 -58.066009)
			(xy 148.846552 -58.078003) (xy 148.898405 -58.097711) (xy 148.946858 -58.124719) (xy 148.990891 -58.158457)
			(xy 149.029575 -58.198214) (xy 149.062096 -58.243153) (xy 149.087769 -58.292327) (xy 149.106051 -58.3447)
			(xy 149.116559 -58.399168) (xy 149.11907 -58.454583) (xy 149.116796 -58.48223) (xy 149.116246 -58.505049)
			(xy 149.122361 -58.550278) (xy 149.136457 -58.593688) (xy 149.158078 -58.633882) (xy 149.186532 -58.669568)
			(xy 149.220901 -58.699598) (xy 149.260082 -58.723007) (xy 149.302813 -58.739041) (xy 149.347722 -58.747186)
			(xy 149.370542 -58.74766) (xy 149.658832 -58.74766) (xy 149.681665 -58.747175) (xy 149.726596 -58.739012)
			(xy 149.769346 -58.722953) (xy 149.80854 -58.699516) (xy 149.842916 -58.669454) (xy 149.871369 -58.633734)
			(xy 149.892983 -58.593507) (xy 149.907064 -58.550065) (xy 149.913157 -58.504807) (xy 149.912578 -58.481976)
			(xy 149.911545 -58.453785) (xy 149.916792 -58.39762) (xy 149.930251 -58.342839) (xy 149.951629 -58.290637)
			(xy 149.980459 -58.242151) (xy 150.016114 -58.198437) (xy 150.057815 -58.16045) (xy 150.104656 -58.129016)
			(xy 150.155613 -58.104821) (xy 150.209578 -58.088392) (xy 150.265373 -58.080087) (xy 150.321783 -58.080087)
			(xy 150.377578 -58.088392) (xy 150.431543 -58.104821) (xy 150.432828 -58.105431) (xy 165.995558 -58.105431)
			(xy 165.998959 -58.049833) (xy 166.010409 -57.99532) (xy 166.029663 -57.943051) (xy 166.056312 -57.894138)
			(xy 166.089791 -57.849619) (xy 166.129387 -57.810441) (xy 166.174258 -57.777436) (xy 166.223452 -57.751307)
			(xy 166.275922 -57.732609) (xy 166.330554 -57.721739) (xy 166.386185 -57.718928) (xy 166.441634 -57.724235)
			(xy 166.495722 -57.737549) (xy 166.547299 -57.758586) (xy 166.595269 -57.786899) (xy 166.638612 -57.821886)
			(xy 166.676408 -57.862803) (xy 166.707853 -57.908781) (xy 166.72052 -57.93359) (xy 166.731399 -57.954579)
			(xy 166.759609 -57.992504) (xy 166.794349 -58.024555) (xy 166.83442 -58.049624) (xy 166.878437 -58.066846)
			(xy 166.924881 -58.075626) (xy 166.972148 -58.075661) (xy 167.018605 -58.066949) (xy 167.062647 -58.049791)
			(xy 167.082978 -58.03773) (xy 167.106862 -58.023389) (xy 167.157929 -58.001125) (xy 167.211691 -57.986523)
			(xy 167.267005 -57.979893) (xy 167.322695 -57.981377) (xy 167.377577 -57.990942) (xy 167.430485 -58.008386)
			(xy 167.480295 -58.033338) (xy 167.525947 -58.065267) (xy 167.566471 -58.103495) (xy 167.601006 -58.147209)
			(xy 167.628818 -58.19548) (xy 167.649315 -58.247281) (xy 167.662063 -58.301513) (xy 167.666789 -58.357022)
			(xy 167.663394 -58.412628) (xy 167.65195 -58.467149) (xy 167.6327 -58.519428) (xy 167.606052 -58.568351)
			(xy 167.572575 -58.61288) (xy 167.532978 -58.652067) (xy 167.488104 -58.685081) (xy 167.438907 -58.711219)
			(xy 167.386432 -58.729926) (xy 167.331794 -58.740804) (xy 167.276156 -58.743621) (xy 167.220699 -58.738319)
			(xy 167.166603 -58.725009) (xy 167.115016 -58.703975) (xy 167.067037 -58.675664) (xy 167.023684 -58.640677)
			(xy 166.985879 -58.599758) (xy 166.954425 -58.553777) (xy 166.941754 -58.528966) (xy 166.93092 -58.507954)
			(xy 166.902701 -58.47003) (xy 166.867953 -58.437982) (xy 166.827876 -58.412916) (xy 166.783853 -58.395697)
			(xy 166.737404 -58.386921) (xy 166.690134 -58.386889) (xy 166.643674 -58.395604) (xy 166.599628 -58.412763)
			(xy 166.579296 -58.424826) (xy 166.55537 -58.439093) (xy 166.504307 -58.461347) (xy 166.45055 -58.47594)
			(xy 166.395243 -58.482561) (xy 166.33956 -58.48107) (xy 166.284686 -58.471499) (xy 166.231787 -58.45405)
			(xy 166.181988 -58.429096) (xy 166.136346 -58.397165) (xy 166.095832 -58.358937) (xy 166.061307 -58.315225)
			(xy 166.033505 -58.266957) (xy 166.013016 -58.21516) (xy 166.000277 -58.160934) (xy 165.995558 -58.105431)
			(xy 150.432828 -58.105431) (xy 150.4825 -58.129016) (xy 150.529341 -58.16045) (xy 150.571042 -58.198437)
			(xy 150.606697 -58.242151) (xy 150.635527 -58.290637) (xy 150.656905 -58.342839) (xy 150.670364 -58.39762)
			(xy 150.675611 -58.453785) (xy 150.674578 -58.481976) (xy 150.674006 -58.50481) (xy 150.680085 -58.550076)
			(xy 150.694156 -58.593526) (xy 150.715765 -58.633763) (xy 150.744217 -58.66949) (xy 150.778595 -58.699558)
			(xy 150.817794 -58.722997) (xy 150.86055 -58.739055) (xy 150.905488 -58.747212) (xy 150.928324 -58.74766)
			(xy 157.61462 -58.74766) (xy 158.68015 -59.81319) (xy 167.552622 -59.81319) (xy 167.556693 -59.757568)
			(xy 167.568819 -59.703131) (xy 167.588742 -59.65104) (xy 167.616038 -59.602405) (xy 167.650124 -59.558262)
			(xy 167.690273 -59.519553) (xy 167.735631 -59.487102) (xy 167.785231 -59.461601) (xy 167.838015 -59.443594)
			(xy 167.892858 -59.433464) (xy 167.948592 -59.431427) (xy 168.004029 -59.437527) (xy 168.057986 -59.451633)
			(xy 168.109315 -59.473445) (xy 168.156921 -59.502499) (xy 168.199789 -59.538174) (xy 168.237006 -59.579711)
			(xy 168.267779 -59.626224) (xy 168.291451 -59.676721) (xy 168.307519 -59.730128) (xy 168.315639 -59.785304)
			(xy 168.316148 -59.81319) (xy 168.315639 -59.841076) (xy 168.307519 -59.896252) (xy 168.291451 -59.949659)
			(xy 168.267779 -60.000156) (xy 168.237006 -60.046669) (xy 168.199789 -60.088206) (xy 168.156921 -60.123881)
			(xy 168.109315 -60.152935) (xy 168.057986 -60.174747) (xy 168.004029 -60.188853) (xy 167.948592 -60.194953)
			(xy 167.892858 -60.192916) (xy 167.838015 -60.182786) (xy 167.785231 -60.164779) (xy 167.735631 -60.139278)
			(xy 167.690273 -60.106827) (xy 167.650124 -60.068118) (xy 167.616038 -60.023975) (xy 167.588742 -59.97534)
			(xy 167.568819 -59.923249) (xy 167.556693 -59.868812) (xy 167.552622 -59.81319) (xy 158.68015 -59.81319)
			(xy 159.422338 -60.555378) (xy 166.708834 -60.555378) (xy 166.712905 -60.499756) (xy 166.725031 -60.445319)
			(xy 166.744954 -60.393228) (xy 166.77225 -60.344593) (xy 166.806336 -60.30045) (xy 166.846485 -60.261741)
			(xy 166.891843 -60.22929) (xy 166.941443 -60.203789) (xy 166.994227 -60.185782) (xy 167.04907 -60.175652)
			(xy 167.104804 -60.173615) (xy 167.160241 -60.179715) (xy 167.214198 -60.193821) (xy 167.265527 -60.215633)
			(xy 167.313133 -60.244687) (xy 167.356001 -60.280362) (xy 167.393218 -60.321899) (xy 167.423991 -60.368412)
			(xy 167.447663 -60.418909) (xy 167.463731 -60.472316) (xy 167.471851 -60.527492) (xy 167.47236 -60.555378)
			(xy 167.471851 -60.583264) (xy 167.463731 -60.63844) (xy 167.452499 -60.675774) (xy 171.490132 -60.675774)
			(xy 171.490132 -50.454052) (xy 171.878244 -50.06594) (xy 178.589178 -50.06594) (xy 178.612601 -50.065401)
			(xy 178.658652 -50.056803) (xy 178.702348 -50.039913) (xy 178.742209 -50.015302) (xy 178.776886 -49.983805)
			(xy 178.805205 -49.946487) (xy 178.826206 -49.904612) (xy 178.83918 -49.859597) (xy 178.843685 -49.812968)
			(xy 178.842162 -49.789588) (xy 178.837145 -49.72777) (xy 178.834175 -49.603767) (xy 178.839278 -49.479834)
			(xy 178.852432 -49.356495) (xy 178.87358 -49.234272) (xy 178.902633 -49.113684) (xy 178.939469 -48.995242)
			(xy 178.983931 -48.879446) (xy 179.03583 -48.766787) (xy 179.094948 -48.657743) (xy 179.161033 -48.552775)
			(xy 179.233806 -48.452328) (xy 179.312958 -48.356827) (xy 179.398155 -48.266676) (xy 179.489035 -48.182259)
			(xy 179.585214 -48.103931) (xy 179.686284 -48.032025) (xy 179.791816 -47.966846) (xy 179.901365 -47.908669)
			(xy 180.014467 -47.857741) (xy 180.130641 -47.814278) (xy 180.249396 -47.778463) (xy 180.37023 -47.750448)
			(xy 180.49263 -47.730353) (xy 180.616077 -47.718261) (xy 180.74005 -47.714225) (xy 180.864023 -47.718261)
			(xy 180.98747 -47.730353) (xy 181.10987 -47.750448) (xy 181.230704 -47.778463) (xy 181.349459 -47.814278)
			(xy 181.465633 -47.857741) (xy 181.578735 -47.908669) (xy 181.688284 -47.966846) (xy 181.793816 -48.032025)
			(xy 181.894886 -48.103931) (xy 181.991065 -48.182259) (xy 182.081945 -48.266676) (xy 182.167142 -48.356827)
			(xy 182.246294 -48.452328) (xy 182.319067 -48.552775) (xy 182.385152 -48.657743) (xy 182.44427 -48.766787)
			(xy 182.496169 -48.879446) (xy 182.540631 -48.995242) (xy 182.577467 -49.113684) (xy 182.60652 -49.234272)
			(xy 182.627668 -49.356495) (xy 182.640822 -49.479834) (xy 182.645925 -49.603767) (xy 182.642955 -49.72777)
			(xy 182.637938 -49.789588) (xy 182.636418 -49.81297) (xy 182.640908 -49.859605) (xy 182.653872 -49.904627)
			(xy 182.674869 -49.946509) (xy 182.703188 -49.983832) (xy 182.737869 -50.015331) (xy 182.777736 -50.039939)
			(xy 182.821439 -50.056821) (xy 182.867497 -50.065406) (xy 182.890922 -50.06594) (xy 184.04713 -50.06594)
			(xy 184.116726 -50.13579) (xy 184.133185 -50.151603) (xy 184.170687 -50.177611) (xy 184.212232 -50.196504)
			(xy 184.256482 -50.207674) (xy 184.302016 -50.210762) (xy 184.34737 -50.205668) (xy 184.391084 -50.192557)
			(xy 184.431755 -50.171849) (xy 184.468073 -50.144211) (xy 184.498872 -50.110532) (xy 184.523161 -50.071893)
			(xy 184.540159 -50.029539) (xy 184.54932 -49.984829) (xy 184.550349 -49.939202) (xy 184.547256 -49.916588)
			(xy 184.538145 -49.855548) (xy 184.526872 -49.732636) (xy 184.523578 -49.609252) (xy 184.528276 -49.485914)
			(xy 184.540948 -49.363138) (xy 184.56154 -49.24144) (xy 184.589966 -49.12133) (xy 184.626106 -49.003312)
			(xy 184.669809 -48.887881) (xy 184.720892 -48.77552) (xy 184.77914 -48.666701) (xy 184.84431 -48.56188)
			(xy 184.916127 -48.461497) (xy 184.994291 -48.365973) (xy 185.078474 -48.275709) (xy 185.168323 -48.191083)
			(xy 185.263461 -48.112449) (xy 185.363489 -48.040139) (xy 185.467987 -47.974454) (xy 185.576518 -47.915671)
			(xy 185.688626 -47.864035) (xy 185.803841 -47.819764) (xy 185.92168 -47.783043) (xy 186.041649 -47.754027)
			(xy 186.163244 -47.732836) (xy 186.285956 -47.71956) (xy 186.409269 -47.714254) (xy 186.532668 -47.716941)
			(xy 186.655634 -47.727609) (xy 186.777652 -47.746214) (xy 186.898209 -47.772678) (xy 187.016801 -47.806889)
			(xy 187.13293 -47.848704) (xy 187.246109 -47.897948) (xy 187.355863 -47.954414) (xy 187.461732 -48.017866)
			(xy 187.563273 -48.088037) (xy 187.660058 -48.164633) (xy 187.751683 -48.247333) (xy 187.837763 -48.33579)
			(xy 187.917938 -48.429633) (xy 187.99187 -48.528469) (xy 188.05925 -48.631882) (xy 188.119795 -48.73944)
			(xy 188.173251 -48.850691) (xy 188.219395 -48.965169) (xy 188.258032 -49.082394) (xy 188.289001 -49.201873)
			(xy 188.312172 -49.323107) (xy 188.327447 -49.445586) (xy 188.334763 -49.568797) (xy 188.334088 -49.692223)
			(xy 188.325426 -49.815346) (xy 188.308814 -49.937651) (xy 188.284319 -50.058624) (xy 188.252046 -50.177758)
			(xy 188.21213 -50.294553) (xy 188.164738 -50.40852) (xy 188.110069 -50.51918) (xy 188.048352 -50.62607)
			(xy 187.979846 -50.728741) (xy 187.904838 -50.826763) (xy 187.823643 -50.919724) (xy 187.736601 -51.007235)
			(xy 187.644078 -51.088929) (xy 187.546461 -51.164463) (xy 187.44416 -51.23352) (xy 187.337603 -51.295811)
			(xy 187.227239 -51.351074) (xy 187.113528 -51.399078) (xy 186.996949 -51.439622) (xy 186.877991 -51.472535)
			(xy 186.757151 -51.497679) (xy 186.634938 -51.514949) (xy 186.511862 -51.524273) (xy 186.388442 -51.525611)
			(xy 186.265193 -51.518958) (xy 186.142634 -51.504341) (xy 186.021278 -51.481823) (xy 185.901634 -51.451497)
			(xy 185.784203 -51.413491) (xy 185.669479 -51.367963) (xy 185.557942 -51.315106) (xy 185.45006 -51.25514)
			(xy 185.397902 -51.222148) (xy 185.378545 -51.210303) (xy 185.336628 -51.192926) (xy 185.292292 -51.183268)
			(xy 185.246945 -51.181636) (xy 185.202029 -51.188082) (xy 185.158972 -51.202401) (xy 185.119141 -51.224138)
			(xy 185.083803 -51.252602) (xy 185.054081 -51.286889) (xy 185.03092 -51.325908) (xy 185.015055 -51.36842)
			(xy 185.006991 -51.413074) (xy 185.006488 -51.435762) (xy 185.006488 -54.664102) (xy 185.00701 -54.68679)
			(xy 185.015068 -54.731446) (xy 185.030929 -54.77396) (xy 185.054087 -54.812983) (xy 185.083807 -54.847272)
			(xy 185.119144 -54.875738) (xy 185.158975 -54.897477) (xy 185.202033 -54.911797) (xy 185.24695 -54.918243)
			(xy 185.292297 -54.91661) (xy 185.336633 -54.90695) (xy 185.37855 -54.889569) (xy 185.397902 -54.877716)
			(xy 185.450195 -54.844635) (xy 185.558365 -54.784518) (xy 185.670209 -54.731547) (xy 185.785254 -54.685945)
			(xy 185.903015 -54.647906) (xy 186.022997 -54.617588) (xy 186.144694 -54.595121) (xy 186.267592 -54.580598)
			(xy 186.391173 -54.574081) (xy 186.514917 -54.575598) (xy 186.638301 -54.585141) (xy 186.760807 -54.602672)
			(xy 186.881916 -54.628115) (xy 187.001119 -54.661364) (xy 187.117913 -54.702278) (xy 187.231806 -54.750685)
			(xy 187.342317 -54.806381) (xy 187.448981 -54.869131) (xy 187.551349 -54.938671) (xy 187.648988 -55.014707)
			(xy 187.741486 -55.096919) (xy 187.828455 -55.18496) (xy 187.909527 -55.278459) (xy 187.984361 -55.377023)
			(xy 188.052641 -55.480235) (xy 188.114079 -55.58766) (xy 188.168416 -55.698846) (xy 188.215424 -55.813323)
			(xy 188.254903 -55.93061) (xy 188.286689 -56.050212) (xy 188.310646 -56.171624) (xy 188.326673 -56.294334)
			(xy 188.334704 -56.417827) (xy 188.334703 -56.54158) (xy 188.326672 -56.665072) (xy 188.310644 -56.787783)
			(xy 188.286687 -56.909195) (xy 188.254902 -57.028796) (xy 188.215421 -57.146083) (xy 188.168413 -57.26056)
			(xy 188.114076 -57.371746) (xy 188.052637 -57.479171) (xy 187.984357 -57.582382) (xy 187.909523 -57.680946)
			(xy 187.828451 -57.774445) (xy 187.741482 -57.862486) (xy 187.648983 -57.944697) (xy 187.551343 -58.020733)
			(xy 187.448976 -58.090272) (xy 187.342312 -58.153022) (xy 187.2318 -58.208718) (xy 187.117907 -58.257125)
			(xy 187.001113 -58.298038) (xy 186.88191 -58.331287) (xy 186.7608 -58.35673) (xy 186.638295 -58.374259)
			(xy 186.51491 -58.383803) (xy 186.391167 -58.385319) (xy 186.267585 -58.378801) (xy 186.144687 -58.364278)
			(xy 186.022991 -58.34181) (xy 185.903009 -58.311492) (xy 185.785247 -58.273453) (xy 185.670203 -58.227851)
			(xy 185.55836 -58.174879) (xy 185.45019 -58.114762) (xy 185.397902 -58.081672) (xy 185.378555 -58.069809)
			(xy 185.336636 -58.052429) (xy 185.292297 -58.042768) (xy 185.246947 -58.041136) (xy 185.202028 -58.047582)
			(xy 185.158968 -58.061902) (xy 185.119135 -58.083642) (xy 185.083796 -58.112109) (xy 185.054074 -58.146399)
			(xy 185.030913 -58.185423) (xy 185.01505 -58.227939) (xy 185.006989 -58.272597) (xy 185.006488 -58.295286)
			(xy 185.006488 -60.897008) (xy 184.436512 -61.46673) (xy 184.426098 -61.554106) (xy 184.449212 -61.591698)
			(xy 184.470536 -61.627656) (xy 184.507034 -61.70287) (xy 184.536098 -61.781258) (xy 184.557455 -61.862086)
			(xy 184.570907 -61.944599) (xy 184.576327 -62.028026) (xy 184.573664 -62.111586) (xy 184.562944 -62.194498)
			(xy 184.544266 -62.275987) (xy 184.517806 -62.355292) (xy 184.483811 -62.431671) (xy 184.442598 -62.504409)
			(xy 184.394553 -62.572827) (xy 184.340125 -62.636285) (xy 184.279822 -62.69419) (xy 184.21421 -62.746001)
			(xy 184.1439 -62.791232) (xy 184.069551 -62.829462) (xy 183.991857 -62.860333) (xy 183.911544 -62.883556)
			(xy 183.829365 -62.898915) (xy 183.746086 -62.906264) (xy 183.662487 -62.905537) (xy 183.579349 -62.896739)
			(xy 183.497449 -62.879954) (xy 183.417553 -62.855337) (xy 183.340408 -62.823119) (xy 183.266735 -62.783601)
			(xy 183.197223 -62.737153) (xy 183.132521 -62.684208) (xy 183.073236 -62.625263) (xy 183.01992 -62.560867)
			(xy 182.973073 -62.491624) (xy 182.933132 -62.418179) (xy 182.90047 -62.341221) (xy 182.875394 -62.261468)
			(xy 182.858137 -62.179666) (xy 182.848861 -62.09658) (xy 182.847653 -62.012986) (xy 182.854523 -61.929667)
			(xy 182.869408 -61.8474) (xy 182.892169 -61.766955) (xy 182.906924 -61.727842) (xy 182.914686 -61.706753)
			(xy 182.923482 -61.662688) (xy 182.92439 -61.617763) (xy 182.917383 -61.573379) (xy 182.902679 -61.530918)
			(xy 182.880736 -61.491706) (xy 182.852238 -61.456965) (xy 182.818074 -61.427777) (xy 182.77931 -61.405054)
			(xy 182.737152 -61.389502) (xy 182.692917 -61.381608) (xy 182.67045 -61.381132) (xy 182.13705 -61.381132)
			(xy 182.114581 -61.381528) (xy 182.070346 -61.389438) (xy 182.02819 -61.405003) (xy 181.989428 -61.427738)
			(xy 181.955268 -61.456935) (xy 181.926773 -61.491683) (xy 181.904832 -61.5309) (xy 181.890129 -61.573364)
			(xy 181.883122 -61.617752) (xy 181.884028 -61.66268) (xy 181.892821 -61.706749) (xy 181.900576 -61.727842)
			(xy 181.915391 -61.767136) (xy 181.938217 -61.847955) (xy 181.953096 -61.930608) (xy 181.959886 -62.014314)
			(xy 181.958524 -62.098284) (xy 181.949023 -62.181726) (xy 181.931472 -62.263853) (xy 181.906037 -62.34389)
			(xy 181.872957 -62.421082) (xy 181.832546 -62.4947) (xy 181.785183 -62.564052) (xy 181.731316 -62.628481)
			(xy 181.671453 -62.687382) (xy 181.606158 -62.740197) (xy 181.536048 -62.786429) (xy 181.461783 -62.825641)
			(xy 181.384065 -62.857465) (xy 181.303626 -62.881599) (xy 181.221226 -62.897816) (xy 181.137641 -62.905963)
			(xy 181.053659 -62.905963) (xy 180.970074 -62.897816) (xy 180.887674 -62.881599) (xy 180.807235 -62.857465)
			(xy 180.729517 -62.825641) (xy 180.655252 -62.786429) (xy 180.585142 -62.740197) (xy 180.519847 -62.687382)
			(xy 180.459984 -62.628481) (xy 180.406117 -62.564052) (xy 180.358754 -62.4947) (xy 180.318343 -62.421082)
			(xy 180.285263 -62.34389) (xy 180.259828 -62.263853) (xy 180.242277 -62.181726) (xy 180.232776 -62.098284)
			(xy 180.231414 -62.014314) (xy 180.238204 -61.930608) (xy 180.253083 -61.847955) (xy 180.275909 -61.767136)
			(xy 180.290724 -61.727842) (xy 180.298486 -61.706753) (xy 180.307282 -61.662688) (xy 180.30819 -61.617763)
			(xy 180.301183 -61.573379) (xy 180.286479 -61.530918) (xy 180.264536 -61.491706) (xy 180.236038 -61.456965)
			(xy 180.201874 -61.427777) (xy 180.16311 -61.405054) (xy 180.120952 -61.389502) (xy 180.076717 -61.381608)
			(xy 180.05425 -61.381132) (xy 172.195744 -61.381132) (xy 171.490132 -60.675774) (xy 167.452499 -60.675774)
			(xy 167.447663 -60.691847) (xy 167.423991 -60.742344) (xy 167.393218 -60.788857) (xy 167.356001 -60.830394)
			(xy 167.313133 -60.866069) (xy 167.265527 -60.895123) (xy 167.214198 -60.916935) (xy 167.160241 -60.931041)
			(xy 167.104804 -60.937141) (xy 167.04907 -60.935104) (xy 166.994227 -60.924974) (xy 166.941443 -60.906967)
			(xy 166.891843 -60.881466) (xy 166.846485 -60.849015) (xy 166.806336 -60.810306) (xy 166.77225 -60.766163)
			(xy 166.744954 -60.717528) (xy 166.725031 -60.665437) (xy 166.712905 -60.611) (xy 166.708834 -60.555378)
			(xy 159.422338 -60.555378) (xy 160.692338 -61.825378) (xy 166.708834 -61.825378) (xy 166.712905 -61.769756)
			(xy 166.725031 -61.715319) (xy 166.744954 -61.663228) (xy 166.77225 -61.614593) (xy 166.806336 -61.57045)
			(xy 166.846485 -61.531741) (xy 166.891843 -61.49929) (xy 166.941443 -61.473789) (xy 166.994227 -61.455782)
			(xy 167.04907 -61.445652) (xy 167.104804 -61.443615) (xy 167.160241 -61.449715) (xy 167.214198 -61.463821)
			(xy 167.265527 -61.485633) (xy 167.313133 -61.514687) (xy 167.356001 -61.550362) (xy 167.393218 -61.591899)
			(xy 167.423991 -61.638412) (xy 167.447663 -61.688909) (xy 167.463731 -61.742316) (xy 167.471851 -61.797492)
			(xy 167.47236 -61.825378) (xy 167.471851 -61.853264) (xy 167.463731 -61.90844) (xy 167.447663 -61.961847)
			(xy 167.423991 -62.012344) (xy 167.393218 -62.058857) (xy 167.356001 -62.100394) (xy 167.313133 -62.136069)
			(xy 167.265527 -62.165123) (xy 167.214198 -62.186935) (xy 167.160241 -62.201041) (xy 167.104804 -62.207141)
			(xy 167.04907 -62.205104) (xy 166.994227 -62.194974) (xy 166.941443 -62.176967) (xy 166.891843 -62.151466)
			(xy 166.846485 -62.119015) (xy 166.806336 -62.080306) (xy 166.77225 -62.036163) (xy 166.744954 -61.987528)
			(xy 166.725031 -61.935437) (xy 166.712905 -61.881) (xy 166.708834 -61.825378) (xy 160.692338 -61.825378)
			(xy 161.37255 -62.50559) (xy 167.560242 -62.50559) (xy 167.564313 -62.449968) (xy 167.576439 -62.395531)
			(xy 167.596362 -62.34344) (xy 167.623658 -62.294805) (xy 167.657744 -62.250662) (xy 167.697893 -62.211953)
			(xy 167.743251 -62.179502) (xy 167.792851 -62.154001) (xy 167.845635 -62.135994) (xy 167.900478 -62.125864)
			(xy 167.956212 -62.123827) (xy 168.011649 -62.129927) (xy 168.065606 -62.144033) (xy 168.116935 -62.165845)
			(xy 168.164541 -62.194899) (xy 168.207409 -62.230574) (xy 168.244626 -62.272111) (xy 168.275399 -62.318624)
			(xy 168.299071 -62.369121) (xy 168.315139 -62.422528) (xy 168.323259 -62.477704) (xy 168.323768 -62.50559)
			(xy 168.323259 -62.533476) (xy 168.315139 -62.588652) (xy 168.299071 -62.642059) (xy 168.275399 -62.692556)
			(xy 168.244626 -62.739069) (xy 168.207409 -62.780606) (xy 168.164541 -62.816281) (xy 168.116935 -62.845335)
			(xy 168.065606 -62.867147) (xy 168.011649 -62.881253) (xy 167.956212 -62.887353) (xy 167.900478 -62.885316)
			(xy 167.845635 -62.875186) (xy 167.792851 -62.857179) (xy 167.743251 -62.831678) (xy 167.697893 -62.799227)
			(xy 167.657744 -62.760518) (xy 167.623658 -62.716375) (xy 167.596362 -62.66774) (xy 167.576439 -62.615649)
			(xy 167.564313 -62.561212) (xy 167.560242 -62.50559) (xy 161.37255 -62.50559) (xy 162.055556 -63.188596)
			(xy 162.226752 -63.188596) (xy 162.231324 -63.186564) (xy 162.255703 -63.175499) (xy 162.306807 -63.159538)
			(xy 162.35964 -63.150877) (xy 162.413165 -63.149683) (xy 162.466331 -63.155982) (xy 162.518096 -63.169648)
			(xy 162.567442 -63.190415) (xy 162.613402 -63.217875) (xy 162.655073 -63.251487) (xy 162.691639 -63.290594)
			(xy 162.72238 -63.334427) (xy 162.746693 -63.382126) (xy 162.755834 -63.40729) (xy 162.764027 -63.432679)
			(xy 162.774104 -63.485067) (xy 162.7759 -63.511684) (xy 162.776831 -63.539324) (xy 162.77166 -63.594386)
			(xy 162.75858 -63.64812) (xy 162.737864 -63.699397) (xy 162.724338 -63.72352) (xy 162.716352 -63.738191)
			(xy 162.707579 -63.770412) (xy 162.707476 -63.803805) (xy 162.716048 -63.836079) (xy 162.732708 -63.865019)
			(xy 162.74415 -63.87719) (xy 162.81654 -63.94958) (xy 174.264318 -63.94958) (xy 174.268389 -63.893958)
			(xy 174.280515 -63.839521) (xy 174.300438 -63.78743) (xy 174.327734 -63.738795) (xy 174.36182 -63.694652)
			(xy 174.401969 -63.655943) (xy 174.447327 -63.623492) (xy 174.496927 -63.597991) (xy 174.549711 -63.579984)
			(xy 174.604554 -63.569854) (xy 174.660288 -63.567817) (xy 174.715725 -63.573917) (xy 174.769682 -63.588023)
			(xy 174.821011 -63.609835) (xy 174.868617 -63.638889) (xy 174.911485 -63.674564) (xy 174.948702 -63.716101)
			(xy 174.979475 -63.762614) (xy 175.003147 -63.813111) (xy 175.019215 -63.866518) (xy 175.027335 -63.921694)
			(xy 175.027844 -63.94958) (xy 175.027335 -63.977466) (xy 175.019215 -64.032642) (xy 175.006684 -64.074294)
			(xy 180.231037 -64.074294) (xy 180.235073 -63.990847) (xy 180.247145 -63.908179) (xy 180.267138 -63.827062)
			(xy 180.294867 -63.748253) (xy 180.330073 -63.672488) (xy 180.372427 -63.600475) (xy 180.421533 -63.532886)
			(xy 180.476934 -63.470352) (xy 180.538111 -63.413457) (xy 180.604494 -63.362731) (xy 180.675462 -63.31865)
			(xy 180.750354 -63.281624) (xy 180.82847 -63.251998) (xy 180.90908 -63.23005) (xy 180.991432 -63.215985)
			(xy 181.074758 -63.209933) (xy 181.158278 -63.211952) (xy 181.241214 -63.222022) (xy 181.32279 -63.24005)
			(xy 181.402246 -63.265867) (xy 181.478839 -63.299232) (xy 181.551855 -63.339833) (xy 181.620611 -63.387292)
			(xy 181.684465 -63.441165) (xy 181.742822 -63.50095) (xy 181.795137 -63.566087) (xy 181.84092 -63.63597)
			(xy 181.879745 -63.709945) (xy 181.91125 -63.787322) (xy 181.935139 -63.867379) (xy 181.95119 -63.949367)
			(xy 181.959253 -64.032522) (xy 181.959758 -64.074294) (xy 182.847237 -64.074294) (xy 182.851273 -63.990847)
			(xy 182.863345 -63.908179) (xy 182.883338 -63.827062) (xy 182.911067 -63.748253) (xy 182.946273 -63.672488)
			(xy 182.988627 -63.600475) (xy 183.037733 -63.532886) (xy 183.093134 -63.470352) (xy 183.154311 -63.413457)
			(xy 183.220694 -63.362731) (xy 183.291662 -63.31865) (xy 183.366554 -63.281624) (xy 183.44467 -63.251998)
			(xy 183.52528 -63.23005) (xy 183.607632 -63.215985) (xy 183.690958 -63.209933) (xy 183.774478 -63.211952)
			(xy 183.857414 -63.222022) (xy 183.93899 -63.24005) (xy 184.018446 -63.265867) (xy 184.095039 -63.299232)
			(xy 184.168055 -63.339833) (xy 184.236811 -63.387292) (xy 184.300665 -63.441165) (xy 184.359022 -63.50095)
			(xy 184.411337 -63.566087) (xy 184.45712 -63.63597) (xy 184.495945 -63.709945) (xy 184.52745 -63.787322)
			(xy 184.551339 -63.867379) (xy 184.56739 -63.949367) (xy 184.575453 -64.032522) (xy 184.575958 -64.074294)
			(xy 184.575453 -64.116066) (xy 184.56739 -64.199221) (xy 184.551339 -64.281209) (xy 184.52745 -64.361266)
			(xy 184.495945 -64.438643) (xy 184.45712 -64.512618) (xy 184.411337 -64.582501) (xy 184.359022 -64.647638)
			(xy 184.300665 -64.707423) (xy 184.236811 -64.761296) (xy 184.168055 -64.808755) (xy 184.095039 -64.849356)
			(xy 184.018446 -64.882721) (xy 183.93899 -64.908538) (xy 183.857414 -64.926566) (xy 183.774478 -64.936636)
			(xy 183.690958 -64.938655) (xy 183.607632 -64.932603) (xy 183.52528 -64.918538) (xy 183.44467 -64.89659)
			(xy 183.366554 -64.866964) (xy 183.291662 -64.829938) (xy 183.220694 -64.785857) (xy 183.154311 -64.735131)
			(xy 183.093134 -64.678236) (xy 183.037733 -64.615702) (xy 182.988627 -64.548113) (xy 182.946273 -64.4761)
			(xy 182.911067 -64.400335) (xy 182.883338 -64.321526) (xy 182.863345 -64.240409) (xy 182.851273 -64.157741)
			(xy 182.847237 -64.074294) (xy 181.959758 -64.074294) (xy 181.959253 -64.116066) (xy 181.95119 -64.199221)
			(xy 181.935139 -64.281209) (xy 181.91125 -64.361266) (xy 181.879745 -64.438643) (xy 181.84092 -64.512618)
			(xy 181.795137 -64.582501) (xy 181.742822 -64.647638) (xy 181.684465 -64.707423) (xy 181.620611 -64.761296)
			(xy 181.551855 -64.808755) (xy 181.478839 -64.849356) (xy 181.402246 -64.882721) (xy 181.32279 -64.908538)
			(xy 181.241214 -64.926566) (xy 181.158278 -64.936636) (xy 181.074758 -64.938655) (xy 180.991432 -64.932603)
			(xy 180.90908 -64.918538) (xy 180.82847 -64.89659) (xy 180.750354 -64.866964) (xy 180.675462 -64.829938)
			(xy 180.604494 -64.785857) (xy 180.538111 -64.735131) (xy 180.476934 -64.678236) (xy 180.421533 -64.615702)
			(xy 180.372427 -64.548113) (xy 180.330073 -64.4761) (xy 180.294867 -64.400335) (xy 180.267138 -64.321526)
			(xy 180.247145 -64.240409) (xy 180.235073 -64.157741) (xy 180.231037 -64.074294) (xy 175.006684 -64.074294)
			(xy 175.003147 -64.086049) (xy 174.979475 -64.136546) (xy 174.948702 -64.183059) (xy 174.911485 -64.224596)
			(xy 174.868617 -64.260271) (xy 174.821011 -64.289325) (xy 174.769682 -64.311137) (xy 174.715725 -64.325243)
			(xy 174.660288 -64.331343) (xy 174.604554 -64.329306) (xy 174.549711 -64.319176) (xy 174.496927 -64.301169)
			(xy 174.447327 -64.275668) (xy 174.401969 -64.243217) (xy 174.36182 -64.204508) (xy 174.327734 -64.160365)
			(xy 174.300438 -64.11173) (xy 174.280515 -64.059639) (xy 174.268389 -64.005202) (xy 174.264318 -63.94958)
			(xy 162.81654 -63.94958) (xy 165.430454 -66.563494) (xy 180.231037 -66.563494) (xy 180.235073 -66.480047)
			(xy 180.247145 -66.397379) (xy 180.267138 -66.316262) (xy 180.294867 -66.237453) (xy 180.330073 -66.161688)
			(xy 180.372427 -66.089675) (xy 180.421533 -66.022086) (xy 180.476934 -65.959552) (xy 180.538111 -65.902657)
			(xy 180.604494 -65.851931) (xy 180.675462 -65.80785) (xy 180.750354 -65.770824) (xy 180.82847 -65.741198)
			(xy 180.90908 -65.71925) (xy 180.991432 -65.705185) (xy 181.074758 -65.699133) (xy 181.158278 -65.701152)
			(xy 181.241214 -65.711222) (xy 181.32279 -65.72925) (xy 181.402246 -65.755067) (xy 181.478839 -65.788432)
			(xy 181.551855 -65.829033) (xy 181.620611 -65.876492) (xy 181.684465 -65.930365) (xy 181.742822 -65.99015)
			(xy 181.795137 -66.055287) (xy 181.84092 -66.12517) (xy 181.879745 -66.199145) (xy 181.91125 -66.276522)
			(xy 181.935139 -66.356579) (xy 181.95119 -66.438567) (xy 181.959253 -66.521722) (xy 181.959758 -66.563494)
			(xy 182.847237 -66.563494) (xy 182.851273 -66.480047) (xy 182.863345 -66.397379) (xy 182.883338 -66.316262)
			(xy 182.911067 -66.237453) (xy 182.946273 -66.161688) (xy 182.988627 -66.089675) (xy 183.037733 -66.022086)
			(xy 183.093134 -65.959552) (xy 183.154311 -65.902657) (xy 183.220694 -65.851931) (xy 183.291662 -65.80785)
			(xy 183.366554 -65.770824) (xy 183.44467 -65.741198) (xy 183.52528 -65.71925) (xy 183.607632 -65.705185)
			(xy 183.690958 -65.699133) (xy 183.774478 -65.701152) (xy 183.857414 -65.711222) (xy 183.93899 -65.72925)
			(xy 184.018446 -65.755067) (xy 184.095039 -65.788432) (xy 184.168055 -65.829033) (xy 184.236811 -65.876492)
			(xy 184.300665 -65.930365) (xy 184.359022 -65.99015) (xy 184.411337 -66.055287) (xy 184.45712 -66.12517)
			(xy 184.495945 -66.199145) (xy 184.52745 -66.276522) (xy 184.551339 -66.356579) (xy 184.56739 -66.438567)
			(xy 184.575453 -66.521722) (xy 184.575958 -66.563494) (xy 184.575453 -66.605266) (xy 184.56739 -66.688421)
			(xy 184.551339 -66.770409) (xy 184.52745 -66.850466) (xy 184.495945 -66.927843) (xy 184.45712 -67.001818)
			(xy 184.411337 -67.071701) (xy 184.359022 -67.136838) (xy 184.300665 -67.196623) (xy 184.236811 -67.250496)
			(xy 184.168055 -67.297955) (xy 184.095039 -67.338556) (xy 184.018446 -67.371921) (xy 183.93899 -67.397738)
			(xy 183.857414 -67.415766) (xy 183.774478 -67.425836) (xy 183.690958 -67.427855) (xy 183.607632 -67.421803)
			(xy 183.52528 -67.407738) (xy 183.44467 -67.38579) (xy 183.366554 -67.356164) (xy 183.291662 -67.319138)
			(xy 183.220694 -67.275057) (xy 183.154311 -67.224331) (xy 183.093134 -67.167436) (xy 183.037733 -67.104902)
			(xy 182.988627 -67.037313) (xy 182.946273 -66.9653) (xy 182.911067 -66.889535) (xy 182.883338 -66.810726)
			(xy 182.863345 -66.729609) (xy 182.851273 -66.646941) (xy 182.847237 -66.563494) (xy 181.959758 -66.563494)
			(xy 181.959253 -66.605266) (xy 181.95119 -66.688421) (xy 181.935139 -66.770409) (xy 181.91125 -66.850466)
			(xy 181.879745 -66.927843) (xy 181.84092 -67.001818) (xy 181.795137 -67.071701) (xy 181.742822 -67.136838)
			(xy 181.684465 -67.196623) (xy 181.620611 -67.250496) (xy 181.551855 -67.297955) (xy 181.478839 -67.338556)
			(xy 181.402246 -67.371921) (xy 181.32279 -67.397738) (xy 181.241214 -67.415766) (xy 181.158278 -67.425836)
			(xy 181.074758 -67.427855) (xy 180.991432 -67.421803) (xy 180.90908 -67.407738) (xy 180.82847 -67.38579)
			(xy 180.750354 -67.356164) (xy 180.675462 -67.319138) (xy 180.604494 -67.275057) (xy 180.538111 -67.224331)
			(xy 180.476934 -67.167436) (xy 180.421533 -67.104902) (xy 180.372427 -67.037313) (xy 180.330073 -66.9653)
			(xy 180.294867 -66.889535) (xy 180.267138 -66.810726) (xy 180.247145 -66.729609) (xy 180.235073 -66.646941)
			(xy 180.231037 -66.563494) (xy 165.430454 -66.563494) (xy 168.503854 -69.636894) (xy 178.834042 -69.636894)
			(xy 178.838039 -69.513518) (xy 178.850014 -69.39066) (xy 178.869917 -69.268835) (xy 178.897663 -69.148554)
			(xy 178.933137 -69.03032) (xy 178.97619 -68.914631) (xy 179.026641 -68.801972) (xy 179.084278 -68.692814)
			(xy 179.148861 -68.587616) (xy 179.220118 -68.486819) (xy 179.297749 -68.390846) (xy 179.381431 -68.300099)
			(xy 179.47081 -68.21496) (xy 179.565514 -68.135784) (xy 179.665143 -68.062905) (xy 179.769282 -67.996627)
			(xy 179.877492 -67.937229) (xy 179.98932 -67.884961) (xy 180.104296 -67.84004) (xy 180.22194 -67.802656)
			(xy 180.341756 -67.772966) (xy 180.463243 -67.751093) (xy 180.585891 -67.73713) (xy 180.709186 -67.731136)
			(xy 180.83261 -67.733135) (xy 180.955646 -67.743119) (xy 181.077777 -67.761046) (xy 181.198492 -67.786841)
			(xy 181.317285 -67.820396) (xy 181.433656 -67.861569) (xy 181.547118 -67.910189) (xy 181.657194 -67.966052)
			(xy 181.763424 -68.028923) (xy 181.865362 -68.098538) (xy 181.962579 -68.174605) (xy 182.054669 -68.256806)
			(xy 182.141245 -68.344795) (xy 182.221944 -68.438204) (xy 182.296427 -68.536641) (xy 182.364382 -68.639692)
			(xy 182.425524 -68.746926) (xy 182.479597 -68.857893) (xy 182.526373 -68.972127) (xy 182.565657 -69.08915)
			(xy 182.597284 -69.20847) (xy 182.621121 -69.329587) (xy 182.637068 -69.451992) (xy 182.645058 -69.575174)
			(xy 182.645558 -69.636894) (xy 184.523642 -69.636894) (xy 184.527639 -69.513518) (xy 184.539614 -69.39066)
			(xy 184.559517 -69.268835) (xy 184.587263 -69.148554) (xy 184.622737 -69.03032) (xy 184.66579 -68.914631)
			(xy 184.716241 -68.801972) (xy 184.773878 -68.692814) (xy 184.838461 -68.587616) (xy 184.909718 -68.486819)
			(xy 184.987349 -68.390846) (xy 185.071031 -68.300099) (xy 185.16041 -68.21496) (xy 185.255114 -68.135784)
			(xy 185.354743 -68.062905) (xy 185.458882 -67.996627) (xy 185.567092 -67.937229) (xy 185.67892 -67.884961)
			(xy 185.793896 -67.84004) (xy 185.91154 -67.802656) (xy 186.031356 -67.772966) (xy 186.152843 -67.751093)
			(xy 186.275491 -67.73713) (xy 186.398786 -67.731136) (xy 186.52221 -67.733135) (xy 186.645246 -67.743119)
			(xy 186.767377 -67.761046) (xy 186.888092 -67.786841) (xy 187.006885 -67.820396) (xy 187.123256 -67.861569)
			(xy 187.236718 -67.910189) (xy 187.346794 -67.966052) (xy 187.453024 -68.028923) (xy 187.554962 -68.098538)
			(xy 187.652179 -68.174605) (xy 187.744269 -68.256806) (xy 187.830845 -68.344795) (xy 187.911544 -68.438204)
			(xy 187.986027 -68.536641) (xy 188.053982 -68.639692) (xy 188.115124 -68.746926) (xy 188.169197 -68.857893)
			(xy 188.215973 -68.972127) (xy 188.255257 -69.08915) (xy 188.286884 -69.20847) (xy 188.310721 -69.329587)
			(xy 188.326668 -69.451992) (xy 188.334658 -69.575174) (xy 188.335158 -69.636894) (xy 188.334658 -69.698614)
			(xy 188.326668 -69.821796) (xy 188.310721 -69.944201) (xy 188.286884 -70.065318) (xy 188.255257 -70.184638)
			(xy 188.215973 -70.301661) (xy 188.169197 -70.415895) (xy 188.115124 -70.526862) (xy 188.053982 -70.634096)
			(xy 187.986027 -70.737147) (xy 187.911544 -70.835584) (xy 187.830845 -70.928993) (xy 187.744269 -71.016982)
			(xy 187.652179 -71.099183) (xy 187.554962 -71.17525) (xy 187.453024 -71.244865) (xy 187.346794 -71.307736)
			(xy 187.236718 -71.363599) (xy 187.123256 -71.412219) (xy 187.006885 -71.453392) (xy 186.888092 -71.486947)
			(xy 186.767377 -71.512742) (xy 186.645246 -71.530669) (xy 186.52221 -71.540653) (xy 186.398786 -71.542652)
			(xy 186.275491 -71.536658) (xy 186.152843 -71.522695) (xy 186.031356 -71.500822) (xy 185.91154 -71.471132)
			(xy 185.793896 -71.433748) (xy 185.67892 -71.388827) (xy 185.567092 -71.336559) (xy 185.458882 -71.277161)
			(xy 185.354743 -71.210883) (xy 185.255114 -71.138004) (xy 185.16041 -71.058828) (xy 185.071031 -70.973689)
			(xy 184.987349 -70.882942) (xy 184.909718 -70.786969) (xy 184.838461 -70.686172) (xy 184.773878 -70.580974)
			(xy 184.716241 -70.471816) (xy 184.66579 -70.359157) (xy 184.622737 -70.243468) (xy 184.587263 -70.125234)
			(xy 184.559517 -70.004953) (xy 184.539614 -69.883128) (xy 184.527639 -69.76027) (xy 184.523642 -69.636894)
			(xy 182.645558 -69.636894) (xy 182.645058 -69.698614) (xy 182.637068 -69.821796) (xy 182.621121 -69.944201)
			(xy 182.597284 -70.065318) (xy 182.565657 -70.184638) (xy 182.526373 -70.301661) (xy 182.479597 -70.415895)
			(xy 182.425524 -70.526862) (xy 182.364382 -70.634096) (xy 182.296427 -70.737147) (xy 182.221944 -70.835584)
			(xy 182.141245 -70.928993) (xy 182.054669 -71.016982) (xy 181.962579 -71.099183) (xy 181.865362 -71.17525)
			(xy 181.763424 -71.244865) (xy 181.657194 -71.307736) (xy 181.547118 -71.363599) (xy 181.433656 -71.412219)
			(xy 181.317285 -71.453392) (xy 181.198492 -71.486947) (xy 181.077777 -71.512742) (xy 180.955646 -71.530669)
			(xy 180.83261 -71.540653) (xy 180.709186 -71.542652) (xy 180.585891 -71.536658) (xy 180.463243 -71.522695)
			(xy 180.341756 -71.500822) (xy 180.22194 -71.471132) (xy 180.104296 -71.433748) (xy 179.98932 -71.388827)
			(xy 179.877492 -71.336559) (xy 179.769282 -71.277161) (xy 179.665143 -71.210883) (xy 179.565514 -71.138004)
			(xy 179.47081 -71.058828) (xy 179.381431 -70.973689) (xy 179.297749 -70.882942) (xy 179.220118 -70.786969)
			(xy 179.148861 -70.686172) (xy 179.084278 -70.580974) (xy 179.026641 -70.471816) (xy 178.97619 -70.359157)
			(xy 178.933137 -70.243468) (xy 178.897663 -70.125234) (xy 178.869917 -70.004953) (xy 178.850014 -69.883128)
			(xy 178.838039 -69.76027) (xy 178.834042 -69.636894) (xy 168.503854 -69.636894) (xy 173.486572 -74.619612)
			(xy 173.486572 -79.090692) (xy 190.207142 -79.090692) (xy 190.209655 -79.036326) (xy 190.219871 -78.982869)
			(xy 190.237583 -78.931408) (xy 190.26243 -78.882987) (xy 190.293908 -78.83859) (xy 190.331378 -78.799118)
			(xy 190.374078 -78.765374) (xy 190.421141 -78.738043) (xy 190.471612 -78.717679) (xy 190.524465 -78.704697)
			(xy 190.578626 -78.699359) (xy 190.632996 -78.701776) (xy 190.686471 -78.711896) (xy 190.737964 -78.729516)
			(xy 190.786429 -78.754277) (xy 190.830883 -78.785675) (xy 190.870421 -78.823074) (xy 190.904241 -78.865714)
			(xy 190.931657 -78.912728) (xy 190.952111 -78.963162) (xy 190.965188 -79.015992) (xy 190.970622 -79.070144)
			(xy 190.968302 -79.124519) (xy 190.958277 -79.178011) (xy 190.94075 -79.229536) (xy 190.916076 -79.278045)
			(xy 190.900812 -79.300578) (xy 190.88784 -79.319864) (xy 190.86849 -79.36212) (xy 190.857132 -79.407187)
			(xy 190.854144 -79.453567) (xy 190.859625 -79.499718) (xy 190.873393 -79.544108) (xy 190.894991 -79.585261)
			(xy 190.90894 -79.603854) (xy 190.925434 -79.625505) (xy 190.952685 -79.672619) (xy 190.972963 -79.723128)
			(xy 190.985855 -79.776007) (xy 190.991099 -79.830182) (xy 190.988589 -79.884551) (xy 190.978376 -79.938012)
			(xy 190.960668 -79.989479) (xy 190.935823 -80.037905) (xy 190.904347 -80.082308) (xy 190.866878 -80.121786)
			(xy 190.824179 -80.155537) (xy 190.777115 -80.182876) (xy 190.726643 -80.203247) (xy 190.673788 -80.216236)
			(xy 190.619623 -80.22158) (xy 190.565249 -80.219171) (xy 190.511769 -80.209057) (xy 190.46027 -80.191443)
			(xy 190.411798 -80.166688) (xy 190.367337 -80.135294) (xy 190.32779 -80.097899) (xy 190.29396 -80.055261)
			(xy 190.266535 -80.008248) (xy 190.246071 -79.957814) (xy 190.232984 -79.904983) (xy 190.227539 -79.850828)
			(xy 190.229848 -79.79645) (xy 190.239864 -79.742951) (xy 190.257382 -79.69142) (xy 190.282048 -79.642902)
			(xy 190.297308 -79.620364) (xy 190.310246 -79.601056) (xy 190.329607 -79.558807) (xy 190.340974 -79.513745)
			(xy 190.343969 -79.467368) (xy 190.338492 -79.421218) (xy 190.324726 -79.37683) (xy 190.303129 -79.335679)
			(xy 190.28918 -79.317088) (xy 190.272791 -79.295358) (xy 190.245543 -79.248246) (xy 190.22527 -79.197739)
			(xy 190.212382 -79.144863) (xy 190.207142 -79.090692) (xy 173.486572 -79.090692) (xy 173.486572 -82.200985)
			(xy 189.509211 -82.200985) (xy 189.509561 -82.145791) (xy 189.51786 -82.091224) (xy 189.533936 -82.038423)
			(xy 189.557453 -81.988489) (xy 189.58792 -81.942465) (xy 189.624702 -81.901312) (xy 189.66703 -81.865889)
			(xy 189.714021 -81.836935) (xy 189.764693 -81.815055) (xy 189.81799 -81.800705) (xy 189.872798 -81.794186)
			(xy 189.927974 -81.795632) (xy 189.982366 -81.805015) (xy 190.034837 -81.822138) (xy 190.084294 -81.846643)
			(xy 190.129703 -81.878019) (xy 190.150242 -81.896458) (xy 190.16615 -81.910637) (xy 190.201739 -81.934069)
			(xy 190.24074 -81.95123) (xy 190.282059 -81.961638) (xy 190.324535 -81.965002) (xy 190.366977 -81.961226)
			(xy 190.408193 -81.950416) (xy 190.447026 -81.932877) (xy 190.464948 -81.92135) (xy 190.488096 -81.906317)
			(xy 190.537858 -81.882441) (xy 190.590541 -81.865985) (xy 190.645047 -81.857293) (xy 190.700235 -81.856545)
			(xy 190.754956 -81.863759) (xy 190.808066 -81.878782) (xy 190.858456 -81.901302) (xy 190.905076 -81.930849)
			(xy 190.946951 -81.966805) (xy 190.983207 -82.00842) (xy 191.013089 -82.054826) (xy 191.035971 -82.105053)
			(xy 191.051376 -82.158053) (xy 191.058983 -82.21272) (xy 191.058633 -82.267913) (xy 191.050333 -82.322479)
			(xy 191.034257 -82.37528) (xy 191.010739 -82.425213) (xy 190.980272 -82.471236) (xy 190.94349 -82.512388)
			(xy 190.901162 -82.54781) (xy 190.854172 -82.576762) (xy 190.8035 -82.598641) (xy 190.750204 -82.61299)
			(xy 190.695396 -82.619509) (xy 190.640221 -82.618061) (xy 190.585831 -82.608678) (xy 190.53336 -82.591555)
			(xy 190.483905 -82.567049) (xy 190.438497 -82.535673) (xy 190.417958 -82.517234) (xy 190.40205 -82.503055)
			(xy 190.366461 -82.479624) (xy 190.32746 -82.462463) (xy 190.286141 -82.452055) (xy 190.243665 -82.448692)
			(xy 190.201223 -82.452468) (xy 190.160007 -82.463276) (xy 190.121174 -82.480815) (xy 190.103252 -82.492342)
			(xy 190.080111 -82.507385) (xy 190.030348 -82.531263) (xy 189.977664 -82.54772) (xy 189.923158 -82.556413)
			(xy 189.867969 -82.557161) (xy 189.813247 -82.549948) (xy 189.760137 -82.534925) (xy 189.709745 -82.512405)
			(xy 189.663125 -82.482859) (xy 189.621248 -82.446903) (xy 189.584991 -82.405287) (xy 189.555108 -82.358881)
			(xy 189.532225 -82.308654) (xy 189.516819 -82.255653) (xy 189.509211 -82.200985) (xy 173.486572 -82.200985)
			(xy 173.486572 -83.1215) (xy 188.903862 -83.1215) (xy 188.907933 -83.065878) (xy 188.920059 -83.011441)
			(xy 188.939982 -82.95935) (xy 188.967278 -82.910715) (xy 189.001364 -82.866572) (xy 189.041513 -82.827863)
			(xy 189.086871 -82.795412) (xy 189.136471 -82.769911) (xy 189.189255 -82.751904) (xy 189.244098 -82.741774)
			(xy 189.299832 -82.739737) (xy 189.355269 -82.745837) (xy 189.409226 -82.759943) (xy 189.460555 -82.781755)
			(xy 189.508161 -82.810809) (xy 189.551029 -82.846484) (xy 189.588246 -82.888021) (xy 189.619019 -82.934534)
			(xy 189.642691 -82.985031) (xy 189.658759 -83.038438) (xy 189.666879 -83.093614) (xy 189.667388 -83.1215)
			(xy 189.666879 -83.149386) (xy 189.658759 -83.204562) (xy 189.642691 -83.257969) (xy 189.619019 -83.308466)
			(xy 189.588246 -83.354979) (xy 189.567128 -83.378548) (xy 190.938402 -83.378548) (xy 190.942473 -83.322926)
			(xy 190.954599 -83.268489) (xy 190.974522 -83.216398) (xy 191.001818 -83.167763) (xy 191.035904 -83.12362)
			(xy 191.076053 -83.084911) (xy 191.121411 -83.05246) (xy 191.171011 -83.026959) (xy 191.223795 -83.008952)
			(xy 191.278638 -82.998822) (xy 191.334372 -82.996785) (xy 191.389809 -83.002885) (xy 191.443766 -83.016991)
			(xy 191.495095 -83.038803) (xy 191.542701 -83.067857) (xy 191.585569 -83.103532) (xy 191.622786 -83.145069)
			(xy 191.653559 -83.191582) (xy 191.677231 -83.242079) (xy 191.693299 -83.295486) (xy 191.701419 -83.350662)
			(xy 191.701928 -83.378548) (xy 191.701419 -83.406434) (xy 191.693299 -83.46161) (xy 191.677231 -83.515017)
			(xy 191.653559 -83.565514) (xy 191.622786 -83.612027) (xy 191.585569 -83.653564) (xy 191.542701 -83.689239)
			(xy 191.495095 -83.718293) (xy 191.443766 -83.740105) (xy 191.389809 -83.754211) (xy 191.334372 -83.760311)
			(xy 191.278638 -83.758274) (xy 191.223795 -83.748144) (xy 191.171011 -83.730137) (xy 191.121411 -83.704636)
			(xy 191.076053 -83.672185) (xy 191.035904 -83.633476) (xy 191.001818 -83.589333) (xy 190.974522 -83.540698)
			(xy 190.954599 -83.488607) (xy 190.942473 -83.43417) (xy 190.938402 -83.378548) (xy 189.567128 -83.378548)
			(xy 189.551029 -83.396516) (xy 189.508161 -83.432191) (xy 189.460555 -83.461245) (xy 189.409226 -83.483057)
			(xy 189.355269 -83.497163) (xy 189.299832 -83.503263) (xy 189.244098 -83.501226) (xy 189.189255 -83.491096)
			(xy 189.136471 -83.473089) (xy 189.086871 -83.447588) (xy 189.041513 -83.415137) (xy 189.001364 -83.376428)
			(xy 188.967278 -83.332285) (xy 188.939982 -83.28365) (xy 188.920059 -83.231559) (xy 188.907933 -83.177122)
			(xy 188.903862 -83.1215) (xy 173.486572 -83.1215) (xy 173.486572 -84.312252) (xy 177.867562 -84.312252)
			(xy 177.871633 -84.25663) (xy 177.883759 -84.202193) (xy 177.903682 -84.150102) (xy 177.930978 -84.101467)
			(xy 177.965064 -84.057324) (xy 178.005213 -84.018615) (xy 178.050571 -83.986164) (xy 178.100171 -83.960663)
			(xy 178.152955 -83.942656) (xy 178.207798 -83.932526) (xy 178.263532 -83.930489) (xy 178.318969 -83.936589)
			(xy 178.372926 -83.950695) (xy 178.424255 -83.972507) (xy 178.471861 -84.001561) (xy 178.514729 -84.037236)
			(xy 178.551946 -84.078773) (xy 178.582719 -84.125286) (xy 178.606391 -84.175783) (xy 178.622459 -84.22919)
			(xy 178.630579 -84.284366) (xy 178.631088 -84.312252) (xy 178.630579 -84.340138) (xy 178.622459 -84.395314)
			(xy 178.606391 -84.448721) (xy 178.582719 -84.499218) (xy 178.551946 -84.545731) (xy 178.514729 -84.587268)
			(xy 178.471861 -84.622943) (xy 178.424255 -84.651997) (xy 178.372926 -84.673809) (xy 178.318969 -84.687915)
			(xy 178.263532 -84.694015) (xy 178.207798 -84.691978) (xy 178.152955 -84.681848) (xy 178.100171 -84.663841)
			(xy 178.050571 -84.63834) (xy 178.005213 -84.605889) (xy 177.965064 -84.56718) (xy 177.930978 -84.523037)
			(xy 177.903682 -84.474402) (xy 177.883759 -84.422311) (xy 177.871633 -84.367874) (xy 177.867562 -84.312252)
			(xy 173.486572 -84.312252) (xy 173.486572 -85.125797) (xy 191.350677 -85.125797) (xy 191.351577 -85.069766)
			(xy 191.360666 -85.014471) (xy 191.377748 -84.9611) (xy 191.402455 -84.910803) (xy 191.434255 -84.864663)
			(xy 191.472465 -84.823672) (xy 191.51626 -84.788713) (xy 191.5647 -84.760538) (xy 191.616741 -84.739755)
			(xy 191.671263 -84.726809) (xy 191.727092 -84.721981) (xy 191.783027 -84.725373) (xy 191.837864 -84.736913)
			(xy 191.890421 -84.756353) (xy 191.939569 -84.783273) (xy 191.984249 -84.817095) (xy 192.023499 -84.857091)
			(xy 192.056475 -84.902399) (xy 192.082466 -84.952044) (xy 192.100913 -85.004958) (xy 192.10934 -85.049106)
			(xy 192.505582 -85.049106) (xy 192.509653 -84.993484) (xy 192.521779 -84.939047) (xy 192.541702 -84.886956)
			(xy 192.568998 -84.838321) (xy 192.603084 -84.794178) (xy 192.643233 -84.755469) (xy 192.688591 -84.723018)
			(xy 192.738191 -84.697517) (xy 192.790975 -84.67951) (xy 192.845818 -84.66938) (xy 192.901552 -84.667343)
			(xy 192.956989 -84.673443) (xy 193.010946 -84.687549) (xy 193.062275 -84.709361) (xy 193.109881 -84.738415)
			(xy 193.152749 -84.77409) (xy 193.189966 -84.815627) (xy 193.220739 -84.86214) (xy 193.244411 -84.912637)
			(xy 193.260479 -84.966044) (xy 193.268599 -85.02122) (xy 193.269108 -85.049106) (xy 193.268599 -85.076992)
			(xy 193.260479 -85.132168) (xy 193.244411 -85.185575) (xy 193.220739 -85.236072) (xy 193.189966 -85.282585)
			(xy 193.152749 -85.324122) (xy 193.109881 -85.359797) (xy 193.062275 -85.388851) (xy 193.010946 -85.410663)
			(xy 192.956989 -85.424769) (xy 192.901552 -85.430869) (xy 192.845818 -85.428832) (xy 192.790975 -85.418702)
			(xy 192.738191 -85.400695) (xy 192.688591 -85.375194) (xy 192.643233 -85.342743) (xy 192.603084 -85.304034)
			(xy 192.568998 -85.259891) (xy 192.541702 -85.211256) (xy 192.521779 -85.159165) (xy 192.509653 -85.104728)
			(xy 192.505582 -85.049106) (xy 192.10934 -85.049106) (xy 192.11142 -85.060002) (xy 192.11376 -85.115991)
			(xy 192.107882 -85.17172) (xy 192.093913 -85.225988) (xy 192.072154 -85.277629) (xy 192.058036 -85.301836)
			(xy 192.049905 -85.31623) (xy 192.040543 -85.347923) (xy 192.039639 -85.380957) (xy 192.047253 -85.413114)
			(xy 192.062874 -85.442236) (xy 192.085453 -85.466366) (xy 192.099184 -85.475572) (xy 192.12265 -85.490893)
			(xy 192.165303 -85.527241) (xy 192.202178 -85.569439) (xy 192.232482 -85.616578) (xy 192.255562 -85.667644)
			(xy 192.270922 -85.721538) (xy 192.278231 -85.777099) (xy 192.277331 -85.833131) (xy 192.268243 -85.888429)
			(xy 192.251161 -85.941801) (xy 192.226453 -85.9921) (xy 192.194652 -86.038242) (xy 192.156441 -86.079234)
			(xy 192.112643 -86.114195) (xy 192.064202 -86.14237) (xy 192.012159 -86.163154) (xy 191.957635 -86.1761)
			(xy 191.901804 -86.180928) (xy 191.845868 -86.177535) (xy 191.791029 -86.165994) (xy 191.73847 -86.146553)
			(xy 191.689321 -86.11963) (xy 191.64464 -86.085806) (xy 191.60539 -86.045809) (xy 191.572414 -86.000498)
			(xy 191.546423 -85.950851) (xy 191.527976 -85.897934) (xy 191.517471 -85.842888) (xy 191.515133 -85.786897)
			(xy 191.521012 -85.731167) (xy 191.534983 -85.676897) (xy 191.556745 -85.625255) (xy 191.570864 -85.601048)
			(xy 191.579013 -85.586663) (xy 191.588372 -85.554967) (xy 191.589273 -85.52193) (xy 191.581656 -85.489771)
			(xy 191.566031 -85.460648) (xy 191.543449 -85.436518) (xy 191.529716 -85.427312) (xy 191.506248 -85.411995)
			(xy 191.463598 -85.375648) (xy 191.426725 -85.33345) (xy 191.396422 -85.286312) (xy 191.373344 -85.235248)
			(xy 191.357985 -85.181356) (xy 191.350677 -85.125797) (xy 173.486572 -85.125797) (xy 173.486572 -85.471508)
			(xy 178.916327 -90.901263) (xy 193.992209 -90.901263) (xy 193.992916 -90.845822) (xy 194.001642 -90.791069)
			(xy 194.018202 -90.738155) (xy 194.042248 -90.688196) (xy 194.073274 -90.642245) (xy 194.110625 -90.601269)
			(xy 194.153514 -90.566132) (xy 194.201038 -90.537574) (xy 194.252196 -90.516197) (xy 194.30591 -90.502452)
			(xy 194.361048 -90.496628) (xy 194.416448 -90.498847) (xy 194.470944 -90.509063) (xy 194.523386 -90.52706)
			(xy 194.57267 -90.552461) (xy 194.617758 -90.584728) (xy 194.6577 -90.623183) (xy 194.691653 -90.667015)
			(xy 194.718904 -90.715301) (xy 194.738877 -90.767023) (xy 194.751152 -90.821092) (xy 194.75547 -90.876368)
			(xy 194.75174 -90.931687) (xy 194.740041 -90.985883) (xy 194.72062 -91.037815) (xy 194.693884 -91.086388)
			(xy 194.677538 -91.108784) (xy 194.663487 -91.128183) (xy 194.642244 -91.17111) (xy 194.629414 -91.217255)
			(xy 194.62545 -91.264986) (xy 194.630495 -91.312616) (xy 194.644367 -91.358458) (xy 194.666578 -91.400892)
			(xy 194.696342 -91.438417) (xy 194.714114 -91.454478) (xy 194.734755 -91.47299) (xy 194.771045 -91.514905)
			(xy 194.800885 -91.561632) (xy 194.823646 -91.612187) (xy 194.838848 -91.665504) (xy 194.846171 -91.720461)
			(xy 194.845461 -91.775898) (xy 194.836732 -91.830649) (xy 194.82017 -91.88356) (xy 194.796121 -91.933515)
			(xy 194.765094 -91.979462) (xy 194.727742 -92.020434) (xy 194.684852 -92.055566) (xy 194.637328 -92.084119)
			(xy 194.586171 -92.105491) (xy 194.532458 -92.119232) (xy 194.477322 -92.125052) (xy 194.421925 -92.122829)
			(xy 194.367433 -92.112609) (xy 194.314994 -92.094608) (xy 194.265714 -92.069205) (xy 194.220631 -92.036935)
			(xy 194.180694 -91.998479) (xy 194.146746 -91.954646) (xy 194.119501 -91.90636) (xy 194.099533 -91.854638)
			(xy 194.087264 -91.80057) (xy 194.082951 -91.745296) (xy 194.086686 -91.68998) (xy 194.098389 -91.635787)
			(xy 194.117815 -91.583859) (xy 194.144554 -91.535291) (xy 194.160902 -91.512898) (xy 194.174859 -91.493435)
			(xy 194.196105 -91.450523) (xy 194.208941 -91.404392) (xy 194.212914 -91.356674) (xy 194.207883 -91.309056)
			(xy 194.194026 -91.263221) (xy 194.171833 -91.220791) (xy 194.142088 -91.183267) (xy 194.124326 -91.167204)
			(xy 194.103644 -91.148738) (xy 194.06735 -91.106823) (xy 194.037506 -91.060096) (xy 194.014742 -91.00954)
			(xy 193.999536 -90.956221) (xy 193.992209 -90.901263) (xy 178.916327 -90.901263) (xy 182.38724 -94.372176)
			(xy 182.38724 -112.302544) (xy 185.435746 -112.302544) (xy 185.439817 -112.246922) (xy 185.451943 -112.192485)
			(xy 185.471866 -112.140394) (xy 185.499162 -112.091759) (xy 185.533248 -112.047616) (xy 185.573397 -112.008907)
			(xy 185.618755 -111.976456) (xy 185.668355 -111.950955) (xy 185.721139 -111.932948) (xy 185.775982 -111.922818)
			(xy 185.831716 -111.920781) (xy 185.887153 -111.926881) (xy 185.94111 -111.940987) (xy 185.992439 -111.962799)
			(xy 186.040045 -111.991853) (xy 186.082913 -112.027528) (xy 186.12013 -112.069065) (xy 186.150903 -112.115578)
			(xy 186.174575 -112.166075) (xy 186.190643 -112.219482) (xy 186.198763 -112.274658) (xy 186.199272 -112.302544)
			(xy 186.198763 -112.33043) (xy 186.190643 -112.385606) (xy 186.174575 -112.439013) (xy 186.150903 -112.48951)
			(xy 186.12013 -112.536023) (xy 186.082913 -112.57756) (xy 186.040045 -112.613235) (xy 185.992439 -112.642289)
			(xy 185.94111 -112.664101) (xy 185.887153 -112.678207) (xy 185.831716 -112.684307) (xy 185.775982 -112.68227)
			(xy 185.721139 -112.67214) (xy 185.668355 -112.654133) (xy 185.618755 -112.628632) (xy 185.573397 -112.596181)
			(xy 185.533248 -112.557472) (xy 185.499162 -112.513329) (xy 185.471866 -112.464694) (xy 185.451943 -112.412603)
			(xy 185.439817 -112.358166) (xy 185.435746 -112.302544) (xy 182.38724 -112.302544) (xy 182.38724 -113.419128)
			(xy 192.206624 -113.419128) (xy 192.210695 -113.363506) (xy 192.222821 -113.309069) (xy 192.242744 -113.256978)
			(xy 192.27004 -113.208343) (xy 192.304126 -113.1642) (xy 192.344275 -113.125491) (xy 192.389633 -113.09304)
			(xy 192.439233 -113.067539) (xy 192.492017 -113.049532) (xy 192.54686 -113.039402) (xy 192.602594 -113.037365)
			(xy 192.658031 -113.043465) (xy 192.711988 -113.057571) (xy 192.763317 -113.079383) (xy 192.810923 -113.108437)
			(xy 192.853791 -113.144112) (xy 192.891008 -113.185649) (xy 192.921781 -113.232162) (xy 192.945453 -113.282659)
			(xy 192.961521 -113.336066) (xy 192.969641 -113.391242) (xy 192.97015 -113.419128) (xy 192.969641 -113.447014)
			(xy 192.961521 -113.50219) (xy 192.945453 -113.555597) (xy 192.921781 -113.606094) (xy 192.891008 -113.652607)
			(xy 192.853791 -113.694144) (xy 192.810923 -113.729819) (xy 192.763317 -113.758873) (xy 192.711988 -113.780685)
			(xy 192.658031 -113.794791) (xy 192.602594 -113.800891) (xy 192.54686 -113.798854) (xy 192.492017 -113.788724)
			(xy 192.439233 -113.770717) (xy 192.389633 -113.745216) (xy 192.344275 -113.712765) (xy 192.304126 -113.674056)
			(xy 192.27004 -113.629913) (xy 192.242744 -113.581278) (xy 192.222821 -113.529187) (xy 192.210695 -113.47475)
			(xy 192.206624 -113.419128) (xy 182.38724 -113.419128) (xy 182.38724 -114.496596) (xy 186.640722 -114.496596)
			(xy 186.644793 -114.440974) (xy 186.656919 -114.386537) (xy 186.676842 -114.334446) (xy 186.704138 -114.285811)
			(xy 186.738224 -114.241668) (xy 186.778373 -114.202959) (xy 186.823731 -114.170508) (xy 186.873331 -114.145007)
			(xy 186.926115 -114.127) (xy 186.980958 -114.11687) (xy 187.036692 -114.114833) (xy 187.092129 -114.120933)
			(xy 187.146086 -114.135039) (xy 187.197415 -114.156851) (xy 187.245021 -114.185905) (xy 187.287889 -114.22158)
			(xy 187.325106 -114.263117) (xy 187.355879 -114.30963) (xy 187.379551 -114.360127) (xy 187.395619 -114.413534)
			(xy 187.403739 -114.46871) (xy 187.404248 -114.496596) (xy 187.403739 -114.524482) (xy 187.398199 -114.562128)
			(xy 192.105024 -114.562128) (xy 192.109095 -114.506506) (xy 192.121221 -114.452069) (xy 192.141144 -114.399978)
			(xy 192.16844 -114.351343) (xy 192.202526 -114.3072) (xy 192.242675 -114.268491) (xy 192.288033 -114.23604)
			(xy 192.337633 -114.210539) (xy 192.390417 -114.192532) (xy 192.44526 -114.182402) (xy 192.500994 -114.180365)
			(xy 192.556431 -114.186465) (xy 192.610388 -114.200571) (xy 192.661717 -114.222383) (xy 192.709323 -114.251437)
			(xy 192.752191 -114.287112) (xy 192.789408 -114.328649) (xy 192.820181 -114.375162) (xy 192.843853 -114.425659)
			(xy 192.859921 -114.479066) (xy 192.868041 -114.534242) (xy 192.86855 -114.562128) (xy 192.868041 -114.590014)
			(xy 192.859921 -114.64519) (xy 192.843853 -114.698597) (xy 192.820181 -114.749094) (xy 192.789408 -114.795607)
			(xy 192.752191 -114.837144) (xy 192.709323 -114.872819) (xy 192.661717 -114.901873) (xy 192.610388 -114.923685)
			(xy 192.556431 -114.937791) (xy 192.500994 -114.943891) (xy 192.44526 -114.941854) (xy 192.390417 -114.931724)
			(xy 192.337633 -114.913717) (xy 192.288033 -114.888216) (xy 192.242675 -114.855765) (xy 192.202526 -114.817056)
			(xy 192.16844 -114.772913) (xy 192.141144 -114.724278) (xy 192.121221 -114.672187) (xy 192.109095 -114.61775)
			(xy 192.105024 -114.562128) (xy 187.398199 -114.562128) (xy 187.395619 -114.579658) (xy 187.379551 -114.633065)
			(xy 187.355879 -114.683562) (xy 187.325106 -114.730075) (xy 187.287889 -114.771612) (xy 187.245021 -114.807287)
			(xy 187.197415 -114.836341) (xy 187.146086 -114.858153) (xy 187.092129 -114.872259) (xy 187.036692 -114.878359)
			(xy 186.980958 -114.876322) (xy 186.926115 -114.866192) (xy 186.873331 -114.848185) (xy 186.823731 -114.822684)
			(xy 186.778373 -114.790233) (xy 186.738224 -114.751524) (xy 186.704138 -114.707381) (xy 186.676842 -114.658746)
			(xy 186.656919 -114.606655) (xy 186.644793 -114.552218) (xy 186.640722 -114.496596) (xy 182.38724 -114.496596)
			(xy 182.38724 -114.713512) (xy 182.46598 -114.792252) (xy 185.071512 -114.792252) (xy 185.643012 -115.363752)
			(xy 186.976766 -115.363752) (xy 187.140304 -115.527328) (xy 187.933836 -115.527328) (xy 187.937907 -115.471706)
			(xy 187.950033 -115.417269) (xy 187.969956 -115.365178) (xy 187.997252 -115.316543) (xy 188.031338 -115.2724)
			(xy 188.071487 -115.233691) (xy 188.116845 -115.20124) (xy 188.166445 -115.175739) (xy 188.219229 -115.157732)
			(xy 188.274072 -115.147602) (xy 188.329806 -115.145565) (xy 188.385243 -115.151665) (xy 188.4392 -115.165771)
			(xy 188.490529 -115.187583) (xy 188.538135 -115.216637) (xy 188.581003 -115.252312) (xy 188.61822 -115.293849)
			(xy 188.648993 -115.340362) (xy 188.672665 -115.390859) (xy 188.688733 -115.444266) (xy 188.696853 -115.499442)
			(xy 188.697362 -115.527328) (xy 188.696853 -115.555214) (xy 188.688733 -115.61039) (xy 188.675514 -115.654328)
			(xy 189.793624 -115.654328) (xy 189.797695 -115.598706) (xy 189.809821 -115.544269) (xy 189.829744 -115.492178)
			(xy 189.85704 -115.443543) (xy 189.891126 -115.3994) (xy 189.931275 -115.360691) (xy 189.976633 -115.32824)
			(xy 190.026233 -115.302739) (xy 190.079017 -115.284732) (xy 190.13386 -115.274602) (xy 190.189594 -115.272565)
			(xy 190.245031 -115.278665) (xy 190.298988 -115.292771) (xy 190.350317 -115.314583) (xy 190.397923 -115.343637)
			(xy 190.440791 -115.379312) (xy 190.478008 -115.420849) (xy 190.508781 -115.467362) (xy 190.532453 -115.517859)
			(xy 190.548521 -115.571266) (xy 190.556641 -115.626442) (xy 190.55715 -115.654328) (xy 190.556641 -115.682214)
			(xy 190.553269 -115.705128) (xy 192.275458 -115.705128) (xy 192.279529 -115.649506) (xy 192.291655 -115.595069)
			(xy 192.311578 -115.542978) (xy 192.338874 -115.494343) (xy 192.37296 -115.4502) (xy 192.413109 -115.411491)
			(xy 192.458467 -115.37904) (xy 192.508067 -115.353539) (xy 192.560851 -115.335532) (xy 192.615694 -115.325402)
			(xy 192.671428 -115.323365) (xy 192.726865 -115.329465) (xy 192.780822 -115.343571) (xy 192.832151 -115.365383)
			(xy 192.879757 -115.394437) (xy 192.922625 -115.430112) (xy 192.959842 -115.471649) (xy 192.990615 -115.518162)
			(xy 193.014287 -115.568659) (xy 193.030355 -115.622066) (xy 193.038475 -115.677242) (xy 193.038984 -115.705128)
			(xy 193.038475 -115.733014) (xy 193.030355 -115.78819) (xy 193.014287 -115.841597) (xy 192.990615 -115.892094)
			(xy 192.959842 -115.938607) (xy 192.922625 -115.980144) (xy 192.879757 -116.015819) (xy 192.832151 -116.044873)
			(xy 192.780822 -116.066685) (xy 192.726865 -116.080791) (xy 192.671428 -116.086891) (xy 192.615694 -116.084854)
			(xy 192.560851 -116.074724) (xy 192.508067 -116.056717) (xy 192.458467 -116.031216) (xy 192.413109 -115.998765)
			(xy 192.37296 -115.960056) (xy 192.338874 -115.915913) (xy 192.311578 -115.867278) (xy 192.291655 -115.815187)
			(xy 192.279529 -115.76075) (xy 192.275458 -115.705128) (xy 190.553269 -115.705128) (xy 190.548521 -115.73739)
			(xy 190.532453 -115.790797) (xy 190.508781 -115.841294) (xy 190.478008 -115.887807) (xy 190.440791 -115.929344)
			(xy 190.397923 -115.965019) (xy 190.350317 -115.994073) (xy 190.298988 -116.015885) (xy 190.245031 -116.029991)
			(xy 190.189594 -116.036091) (xy 190.13386 -116.034054) (xy 190.079017 -116.023924) (xy 190.026233 -116.005917)
			(xy 189.976633 -115.980416) (xy 189.931275 -115.947965) (xy 189.891126 -115.909256) (xy 189.85704 -115.865113)
			(xy 189.829744 -115.816478) (xy 189.809821 -115.764387) (xy 189.797695 -115.70995) (xy 189.793624 -115.654328)
			(xy 188.675514 -115.654328) (xy 188.672665 -115.663797) (xy 188.648993 -115.714294) (xy 188.61822 -115.760807)
			(xy 188.581003 -115.802344) (xy 188.538135 -115.838019) (xy 188.490529 -115.867073) (xy 188.4392 -115.888885)
			(xy 188.385243 -115.902991) (xy 188.329806 -115.909091) (xy 188.274072 -115.907054) (xy 188.219229 -115.896924)
			(xy 188.166445 -115.878917) (xy 188.116845 -115.853416) (xy 188.071487 -115.820965) (xy 188.031338 -115.782256)
			(xy 187.997252 -115.738113) (xy 187.969956 -115.689478) (xy 187.950033 -115.637387) (xy 187.937907 -115.58295)
			(xy 187.933836 -115.527328) (xy 187.140304 -115.527328) (xy 188.07938 -116.46662) (xy 188.07938 -117.57152)
			(xy 187.6679 -117.983) (xy 187.660026 -118.01983) (xy 187.654427 -118.043881) (xy 187.637857 -118.090399)
			(xy 187.615434 -118.134397) (xy 187.587533 -118.175141) (xy 187.57138 -118.19382) (xy 187.552866 -118.213876)
			(xy 187.5111 -118.249015) (xy 187.464752 -118.277842) (xy 187.414769 -118.299769) (xy 187.36217 -118.314348)
			(xy 187.33516 -118.31828) (xy 187.306412 -118.321407) (xy 187.248603 -118.319982) (xy 187.191672 -118.309849)
			(xy 187.136921 -118.291242) (xy 187.085606 -118.264585) (xy 187.0389 -118.230491) (xy 186.997875 -118.189738)
			(xy 186.963468 -118.143262) (xy 186.936469 -118.092126) (xy 186.917496 -118.037501) (xy 186.911742 -118.009162)
			(xy 186.906621 -117.977973) (xy 186.905467 -117.914785) (xy 186.909456 -117.883432) (xy 186.914344 -117.854504)
			(xy 186.931826 -117.798502) (xy 186.944254 -117.771926) (xy 186.950612 -117.749442) (xy 186.96843 -117.706248)
			(xy 186.991761 -117.665764) (xy 187.0202 -117.62869) (xy 187.036456 -117.611906) (xy 187.240926 -117.407436)
			(xy 187.244911 -117.384879) (xy 187.245648 -117.339084) (xy 187.238172 -117.293897) (xy 187.222726 -117.250778)
			(xy 187.199809 -117.211123) (xy 187.170161 -117.176212) (xy 187.13474 -117.147175) (xy 187.114942 -117.135656)
			(xy 187.08484 -117.119586) (xy 187.030404 -117.078451) (xy 187.006738 -117.053868) (xy 186.99441 -117.040228)
			(xy 186.972143 -117.010969) (xy 186.962288 -116.995448) (xy 186.947736 -116.970925) (xy 186.925283 -116.91851)
			(xy 186.917584 -116.891054) (xy 186.908948 -116.85778) (xy 186.53252 -116.481352) (xy 185.157364 -116.481352)
			(xy 185.1341 -116.482925) (xy 185.088686 -116.493475) (xy 185.045956 -116.512125) (xy 185.007341 -116.538251)
			(xy 184.974133 -116.570976) (xy 184.947446 -116.609206) (xy 184.928173 -116.651658) (xy 184.916959 -116.696913)
			(xy 184.914181 -116.743453) (xy 184.919931 -116.78972) (xy 184.934016 -116.834164) (xy 184.944512 -116.854986)
			(xy 184.957702 -116.878561) (xy 184.978037 -116.928606) (xy 184.991107 -116.98102) (xy 184.996653 -117.034754)
			(xy 184.994562 -117.088733) (xy 184.984878 -117.141877) (xy 184.967793 -117.193123) (xy 184.943649 -117.241447)
			(xy 184.912929 -117.285881) (xy 184.876248 -117.325536) (xy 184.834339 -117.359621) (xy 184.788041 -117.387452)
			(xy 184.73828 -117.408473) (xy 184.686051 -117.422264) (xy 184.632398 -117.428548) (xy 184.578396 -117.427201)
			(xy 184.525123 -117.418248) (xy 184.49925 -117.410484) (xy 184.482505 -117.405811) (xy 184.447774 -117.404648)
			(xy 184.414012 -117.412875) (xy 184.38371 -117.429885) (xy 184.37098 -117.441726) (xy 184.359522 -117.453857)
			(xy 184.342818 -117.482731) (xy 184.334174 -117.51495) (xy 184.334181 -117.548309) (xy 184.34284 -117.580524)
			(xy 184.359558 -117.609391) (xy 184.37098 -117.621558) (xy 184.531254 -117.781578) (xy 184.575958 -117.826282)
			(xy 184.609232 -117.834918) (xy 184.635884 -117.842358) (xy 184.686863 -117.863873) (xy 184.6919 -117.866922)
			(xy 185.436762 -117.866922) (xy 185.440833 -117.8113) (xy 185.452959 -117.756863) (xy 185.472882 -117.704772)
			(xy 185.500178 -117.656137) (xy 185.534264 -117.611994) (xy 185.574413 -117.573285) (xy 185.619771 -117.540834)
			(xy 185.669371 -117.515333) (xy 185.722155 -117.497326) (xy 185.776998 -117.487196) (xy 185.832732 -117.485159)
			(xy 185.888169 -117.491259) (xy 185.942126 -117.505365) (xy 185.993455 -117.527177) (xy 186.041061 -117.556231)
			(xy 186.083929 -117.591906) (xy 186.121146 -117.633443) (xy 186.151919 -117.679956) (xy 186.175591 -117.730453)
			(xy 186.191659 -117.78386) (xy 186.199779 -117.839036) (xy 186.200288 -117.866922) (xy 186.199779 -117.894808)
			(xy 186.191659 -117.949984) (xy 186.175591 -118.003391) (xy 186.151919 -118.053888) (xy 186.121146 -118.100401)
			(xy 186.083929 -118.141938) (xy 186.041061 -118.177613) (xy 185.993455 -118.206667) (xy 185.942126 -118.228479)
			(xy 185.888169 -118.242585) (xy 185.832732 -118.248685) (xy 185.776998 -118.246648) (xy 185.722155 -118.236518)
			(xy 185.669371 -118.218511) (xy 185.619771 -118.19301) (xy 185.574413 -118.160559) (xy 185.534264 -118.12185)
			(xy 185.500178 -118.077707) (xy 185.472882 -118.029072) (xy 185.452959 -117.976981) (xy 185.440833 -117.922544)
			(xy 185.436762 -117.866922) (xy 184.6919 -117.866922) (xy 184.734199 -117.892526) (xy 184.776901 -117.927716)
			(xy 184.814071 -117.968705) (xy 184.844931 -118.014633) (xy 184.868834 -118.064537) (xy 184.885278 -118.117371)
			(xy 184.893918 -118.172025) (xy 184.894573 -118.227354) (xy 184.887229 -118.282198) (xy 184.87204 -118.335405)
			(xy 184.849326 -118.385861) (xy 184.819561 -118.432507) (xy 184.783371 -118.474364) (xy 184.741515 -118.510555)
			(xy 184.69487 -118.540321) (xy 184.644415 -118.563037) (xy 184.591207 -118.578227) (xy 184.536364 -118.585572)
			(xy 184.481035 -118.584919) (xy 184.42638 -118.57628) (xy 184.373547 -118.559838) (xy 184.323642 -118.535936)
			(xy 184.277713 -118.505077) (xy 184.236723 -118.467908) (xy 184.201532 -118.425207) (xy 184.172878 -118.377872)
			(xy 184.151361 -118.326894) (xy 184.143904 -118.300246) (xy 184.135268 -118.266972) (xy 183.288432 -117.420136)
			(xy 182.51424 -117.420136) (xy 182.497583 -117.420626) (xy 182.465404 -117.429241) (xy 182.436552 -117.445894)
			(xy 182.412996 -117.469449) (xy 182.396342 -117.4983) (xy 182.387726 -117.53048) (xy 182.38724 -117.547136)
			(xy 182.38724 -119.225314) (xy 182.527448 -119.365522) (xy 184.514742 -119.365522) (xy 184.518813 -119.3099)
			(xy 184.530939 -119.255463) (xy 184.550862 -119.203372) (xy 184.578158 -119.154737) (xy 184.612244 -119.110594)
			(xy 184.652393 -119.071885) (xy 184.697751 -119.039434) (xy 184.747351 -119.013933) (xy 184.800135 -118.995926)
			(xy 184.854978 -118.985796) (xy 184.910712 -118.983759) (xy 184.966149 -118.989859) (xy 185.020106 -119.003965)
			(xy 185.071435 -119.025777) (xy 185.119041 -119.054831) (xy 185.161909 -119.090506) (xy 185.199126 -119.132043)
			(xy 185.229899 -119.178556) (xy 185.253571 -119.229053) (xy 185.260776 -119.253) (xy 192.276982 -119.253)
			(xy 192.281053 -119.197378) (xy 192.293179 -119.142941) (xy 192.313102 -119.09085) (xy 192.340398 -119.042215)
			(xy 192.374484 -118.998072) (xy 192.414633 -118.959363) (xy 192.459991 -118.926912) (xy 192.509591 -118.901411)
			(xy 192.562375 -118.883404) (xy 192.617218 -118.873274) (xy 192.672952 -118.871237) (xy 192.728389 -118.877337)
			(xy 192.782346 -118.891443) (xy 192.833675 -118.913255) (xy 192.881281 -118.942309) (xy 192.924149 -118.977984)
			(xy 192.961366 -119.019521) (xy 192.992139 -119.066034) (xy 193.015811 -119.116531) (xy 193.031879 -119.169938)
			(xy 193.039999 -119.225114) (xy 193.040508 -119.253) (xy 193.039999 -119.280886) (xy 193.031879 -119.336062)
			(xy 193.015811 -119.389469) (xy 192.992139 -119.439966) (xy 192.961366 -119.486479) (xy 192.924149 -119.528016)
			(xy 192.881281 -119.563691) (xy 192.833675 -119.592745) (xy 192.782346 -119.614557) (xy 192.728389 -119.628663)
			(xy 192.672952 -119.634763) (xy 192.617218 -119.632726) (xy 192.562375 -119.622596) (xy 192.509591 -119.604589)
			(xy 192.459991 -119.579088) (xy 192.414633 -119.546637) (xy 192.374484 -119.507928) (xy 192.340398 -119.463785)
			(xy 192.313102 -119.41515) (xy 192.293179 -119.363059) (xy 192.281053 -119.308622) (xy 192.276982 -119.253)
			(xy 185.260776 -119.253) (xy 185.269639 -119.28246) (xy 185.277759 -119.337636) (xy 185.278268 -119.365522)
			(xy 185.277759 -119.393408) (xy 185.269639 -119.448584) (xy 185.253571 -119.501991) (xy 185.229899 -119.552488)
			(xy 185.199126 -119.599001) (xy 185.161909 -119.640538) (xy 185.119041 -119.676213) (xy 185.071435 -119.705267)
			(xy 185.020106 -119.727079) (xy 184.966149 -119.741185) (xy 184.910712 -119.747285) (xy 184.854978 -119.745248)
			(xy 184.800135 -119.735118) (xy 184.747351 -119.717111) (xy 184.697751 -119.69161) (xy 184.652393 -119.659159)
			(xy 184.612244 -119.62045) (xy 184.578158 -119.576307) (xy 184.550862 -119.527672) (xy 184.530939 -119.475581)
			(xy 184.518813 -119.421144) (xy 184.514742 -119.365522) (xy 182.527448 -119.365522) (xy 182.782718 -119.620792)
			(xy 182.815992 -119.629428) (xy 182.842416 -119.636786) (xy 182.892981 -119.65804) (xy 182.939983 -119.686314)
			(xy 182.982453 -119.721026) (xy 183.019516 -119.76146) (xy 183.050408 -119.806783) (xy 183.074494 -119.856063)
			(xy 183.091277 -119.908283) (xy 183.100411 -119.962367) (xy 183.101709 -120.017203) (xy 183.095142 -120.071659)
			(xy 183.080848 -120.124614) (xy 183.059119 -120.174977) (xy 183.030404 -120.221711) (xy 182.995295 -120.263852)
			(xy 182.954514 -120.300534) (xy 182.908902 -120.330999) (xy 182.859399 -120.35462) (xy 182.807023 -120.370912)
			(xy 182.752855 -120.379537) (xy 182.69801 -120.380319) (xy 182.643618 -120.373241) (xy 182.5908 -120.358449)
			(xy 182.565548 -120.34774) (xy 182.541164 -120.336818) (xy 182.51424 -120.336818) (xy 182.497583 -120.337308)
			(xy 182.465401 -120.345923) (xy 182.436547 -120.362575) (xy 182.412989 -120.38613) (xy 182.40729 -120.396)
			(xy 192.022982 -120.396) (xy 192.027053 -120.340378) (xy 192.039179 -120.285941) (xy 192.059102 -120.23385)
			(xy 192.086398 -120.185215) (xy 192.120484 -120.141072) (xy 192.160633 -120.102363) (xy 192.205991 -120.069912)
			(xy 192.255591 -120.044411) (xy 192.308375 -120.026404) (xy 192.363218 -120.016274) (xy 192.418952 -120.014237)
			(xy 192.474389 -120.020337) (xy 192.528346 -120.034443) (xy 192.579675 -120.056255) (xy 192.627281 -120.085309)
			(xy 192.670149 -120.120984) (xy 192.707366 -120.162521) (xy 192.738139 -120.209034) (xy 192.761811 -120.259531)
			(xy 192.777879 -120.312938) (xy 192.785999 -120.368114) (xy 192.786508 -120.396) (xy 192.785999 -120.423886)
			(xy 192.777879 -120.479062) (xy 192.761811 -120.532469) (xy 192.738139 -120.582966) (xy 192.707366 -120.629479)
			(xy 192.670149 -120.671016) (xy 192.627281 -120.706691) (xy 192.579675 -120.735745) (xy 192.528346 -120.757557)
			(xy 192.474389 -120.771663) (xy 192.418952 -120.777763) (xy 192.363218 -120.775726) (xy 192.308375 -120.765596)
			(xy 192.255591 -120.747589) (xy 192.205991 -120.722088) (xy 192.160633 -120.689637) (xy 192.120484 -120.650928)
			(xy 192.086398 -120.606785) (xy 192.059102 -120.55815) (xy 192.039179 -120.506059) (xy 192.027053 -120.451622)
			(xy 192.022982 -120.396) (xy 182.40729 -120.396) (xy 182.396331 -120.414981) (xy 182.387711 -120.447161)
			(xy 182.38724 -120.463818) (xy 182.38724 -120.527572) (xy 182.94731 -121.087642) (xy 185.378342 -121.087642)
			(xy 185.382413 -121.03202) (xy 185.394539 -120.977583) (xy 185.414462 -120.925492) (xy 185.441758 -120.876857)
			(xy 185.475844 -120.832714) (xy 185.515993 -120.794005) (xy 185.561351 -120.761554) (xy 185.610951 -120.736053)
			(xy 185.663735 -120.718046) (xy 185.718578 -120.707916) (xy 185.774312 -120.705879) (xy 185.829749 -120.711979)
			(xy 185.883706 -120.726085) (xy 185.935035 -120.747897) (xy 185.982641 -120.776951) (xy 186.025509 -120.812626)
			(xy 186.062726 -120.854163) (xy 186.093499 -120.900676) (xy 186.117171 -120.951173) (xy 186.133239 -121.00458)
			(xy 186.141359 -121.059756) (xy 186.141868 -121.087642) (xy 186.141359 -121.115528) (xy 186.133239 -121.170704)
			(xy 186.117171 -121.224111) (xy 186.093499 -121.274608) (xy 186.062726 -121.321121) (xy 186.025509 -121.362658)
			(xy 185.982641 -121.398333) (xy 185.935035 -121.427387) (xy 185.883706 -121.449199) (xy 185.829749 -121.463305)
			(xy 185.774312 -121.469405) (xy 185.718578 -121.467368) (xy 185.663735 -121.457238) (xy 185.610951 -121.439231)
			(xy 185.561351 -121.41373) (xy 185.515993 -121.381279) (xy 185.475844 -121.34257) (xy 185.441758 -121.298427)
			(xy 185.414462 -121.249792) (xy 185.394539 -121.197701) (xy 185.382413 -121.143264) (xy 185.378342 -121.087642)
			(xy 182.94731 -121.087642) (xy 182.978298 -121.11863) (xy 183.011572 -121.127266) (xy 183.039216 -121.134978)
			(xy 183.091973 -121.157566) (xy 183.140743 -121.187814) (xy 183.184423 -121.225037) (xy 183.203596 -121.246392)
			(xy 183.212994 -121.257822) (xy 183.229695 -121.279378) (xy 183.257419 -121.326335) (xy 183.278175 -121.37676)
			(xy 183.29154 -121.429627) (xy 183.297244 -121.483858) (xy 183.295168 -121.538349) (xy 183.285357 -121.591989)
			(xy 183.268008 -121.643686) (xy 183.259967 -121.65965) (xy 188.432438 -121.65965) (xy 188.436509 -121.604028)
			(xy 188.448635 -121.549591) (xy 188.468558 -121.4975) (xy 188.495854 -121.448865) (xy 188.52994 -121.404722)
			(xy 188.570089 -121.366013) (xy 188.615447 -121.333562) (xy 188.665047 -121.308061) (xy 188.717831 -121.290054)
			(xy 188.772674 -121.279924) (xy 188.828408 -121.277887) (xy 188.883845 -121.283987) (xy 188.937802 -121.298093)
			(xy 188.989131 -121.319905) (xy 189.036737 -121.348959) (xy 189.079605 -121.384634) (xy 189.116822 -121.426171)
			(xy 189.147595 -121.472684) (xy 189.171267 -121.523181) (xy 189.187335 -121.576588) (xy 189.195455 -121.631764)
			(xy 189.195964 -121.65965) (xy 189.195455 -121.687536) (xy 189.187335 -121.742712) (xy 189.171267 -121.796119)
			(xy 189.147595 -121.846616) (xy 189.116822 -121.893129) (xy 189.079605 -121.934666) (xy 189.036737 -121.970341)
			(xy 188.989131 -121.999395) (xy 188.937802 -122.021207) (xy 188.883845 -122.035313) (xy 188.828408 -122.041413)
			(xy 188.772674 -122.039376) (xy 188.717831 -122.029246) (xy 188.665047 -122.011239) (xy 188.615447 -121.985738)
			(xy 188.570089 -121.953287) (xy 188.52994 -121.914578) (xy 188.495854 -121.870435) (xy 188.468558 -121.8218)
			(xy 188.448635 -121.769709) (xy 188.436509 -121.715272) (xy 188.432438 -121.65965) (xy 183.259967 -121.65965)
			(xy 183.243477 -121.692387) (xy 183.212262 -121.737099) (xy 183.175 -121.776912) (xy 183.13245 -121.811014)
			(xy 183.085478 -121.838712) (xy 183.035041 -121.85944) (xy 182.982167 -121.872777) (xy 182.927932 -121.878451)
			(xy 182.873443 -121.876345) (xy 182.819808 -121.866504) (xy 182.768121 -121.849128) (xy 182.743602 -121.837196)
			(xy 182.722398 -121.828392) (xy 182.677746 -121.817729) (xy 182.631905 -121.815262) (xy 182.586366 -121.821069)
			(xy 182.542612 -121.834962) (xy 182.502065 -121.85649) (xy 182.466045 -121.884951) (xy 182.435724 -121.91942)
			(xy 182.412088 -121.958776) (xy 182.395906 -122.001737) (xy 182.387706 -122.046906) (xy 182.38724 -122.06986)
			(xy 182.38724 -122.26798) (xy 182.503826 -122.392186) (xy 182.545736 -122.399298) (xy 182.575341 -122.404925)
			(xy 182.632406 -122.424281) (xy 182.685709 -122.452386) (xy 182.733917 -122.48854) (xy 182.755286 -122.509788)
			(xy 182.763668 -122.518678) (xy 182.773299 -122.529446) (xy 182.791098 -122.552203) (xy 182.799228 -122.564144)
			(xy 182.802276 -122.56897) (xy 182.815613 -122.587974) (xy 182.848006 -122.621226) (xy 182.885899 -122.648042)
			(xy 182.928031 -122.667532) (xy 182.973003 -122.679047) (xy 183.019317 -122.682204) (xy 183.065435 -122.676898)
			(xy 183.087772 -122.67057) (xy 183.113889 -122.662418) (xy 183.167752 -122.652817) (xy 183.222434 -122.651007)
			(xy 183.276813 -122.657025) (xy 183.329776 -122.670749) (xy 183.380235 -122.691897) (xy 183.427156 -122.720035)
			(xy 183.469578 -122.754586) (xy 183.50663 -122.794842) (xy 183.516678 -122.809508) (xy 188.378082 -122.809508)
			(xy 188.382153 -122.753886) (xy 188.394279 -122.699449) (xy 188.414202 -122.647358) (xy 188.441498 -122.598723)
			(xy 188.475584 -122.55458) (xy 188.515733 -122.515871) (xy 188.561091 -122.48342) (xy 188.610691 -122.457919)
			(xy 188.663475 -122.439912) (xy 188.718318 -122.429782) (xy 188.774052 -122.427745) (xy 188.829489 -122.433845)
			(xy 188.883446 -122.447951) (xy 188.934775 -122.469763) (xy 188.982381 -122.498817) (xy 189.025249 -122.534492)
			(xy 189.062466 -122.576029) (xy 189.093239 -122.622542) (xy 189.116911 -122.673039) (xy 189.132979 -122.726446)
			(xy 189.141099 -122.781622) (xy 189.141608 -122.809508) (xy 189.141099 -122.837394) (xy 189.132979 -122.89257)
			(xy 189.116911 -122.945977) (xy 189.093239 -122.996474) (xy 189.062466 -123.042987) (xy 189.025249 -123.084524)
			(xy 188.982381 -123.120199) (xy 188.934775 -123.149253) (xy 188.883446 -123.171065) (xy 188.829489 -123.185171)
			(xy 188.774052 -123.191271) (xy 188.718318 -123.189234) (xy 188.663475 -123.179104) (xy 188.610691 -123.161097)
			(xy 188.561091 -123.135596) (xy 188.515733 -123.103145) (xy 188.475584 -123.064436) (xy 188.441498 -123.020293)
			(xy 188.414202 -122.971658) (xy 188.394279 -122.919567) (xy 188.382153 -122.86513) (xy 188.378082 -122.809508)
			(xy 183.516678 -122.809508) (xy 183.537552 -122.839977) (xy 183.561711 -122.889066) (xy 183.578611 -122.941102)
			(xy 183.587905 -122.995019) (xy 183.589403 -123.04971) (xy 183.583074 -123.104054) (xy 183.569049 -123.156938)
			(xy 183.547614 -123.207276) (xy 183.519209 -123.254036) (xy 183.484417 -123.29626) (xy 183.464454 -123.314968)
			(xy 183.445012 -123.332131) (xy 183.402322 -123.361579) (xy 183.379364 -123.373642) (xy 183.354159 -123.385797)
			(xy 183.301047 -123.403413) (xy 183.245932 -123.413079) (xy 183.189995 -123.414586) (xy 183.134438 -123.407904)
			(xy 183.080455 -123.393175) (xy 183.029203 -123.370715) (xy 182.981784 -123.341008) (xy 182.939214 -123.304689)
			(xy 182.902409 -123.26254) (xy 182.886858 -123.239276) (xy 182.873522 -123.220274) (xy 182.84113 -123.187026)
			(xy 182.803238 -123.160214) (xy 182.761106 -123.140731) (xy 182.716136 -123.129225) (xy 182.669825 -123.126078)
			(xy 182.623712 -123.131395) (xy 182.601362 -123.137676) (xy 182.585868 -123.142502) (xy 182.575948 -123.145258)
			(xy 182.555871 -123.149834) (xy 182.545736 -123.151646) (xy 182.503826 -123.158758) (xy 182.38724 -123.282964)
			(xy 182.38724 -123.665895) (xy 183.954029 -123.665895) (xy 183.954887 -123.610498) (xy 183.96375 -123.555807)
			(xy 183.980431 -123.502975) (xy 184.00458 -123.45311) (xy 184.035687 -123.407264) (xy 184.0731 -123.366399)
			(xy 184.11603 -123.331377) (xy 184.163574 -123.302933) (xy 184.214734 -123.281665) (xy 184.268432 -123.268022)
			(xy 184.323538 -123.262291) (xy 184.378894 -123.264591) (xy 184.433335 -123.274874) (xy 184.485716 -123.292925)
			(xy 184.534935 -123.318362) (xy 184.579956 -123.350653) (xy 184.619833 -123.389116) (xy 184.637172 -123.410726)
			(xy 184.65152 -123.428457) (xy 184.685415 -123.458973) (xy 184.724212 -123.482951) (xy 184.766664 -123.49962)
			(xy 184.81141 -123.508447) (xy 184.857013 -123.509146) (xy 184.902008 -123.501697) (xy 184.944952 -123.486337)
			(xy 184.984466 -123.463561) (xy 185.019281 -123.434099) (xy 185.034174 -123.416822) (xy 185.052142 -123.395728)
			(xy 185.093192 -123.358509) (xy 185.139194 -123.32762) (xy 185.189181 -123.303711) (xy 185.242101 -123.287284)
			(xy 185.296841 -123.278686) (xy 185.352248 -123.278096) (xy 185.407158 -123.285527) (xy 185.460416 -123.300824)
			(xy 185.510901 -123.323664) (xy 185.55755 -123.353567) (xy 185.599383 -123.389903) (xy 185.63552 -123.431909)
			(xy 185.6652 -123.4787) (xy 185.6878 -123.529293) (xy 185.702842 -123.582623) (xy 185.710013 -123.637568)
			(xy 185.709159 -123.692972) (xy 185.7003 -123.74767) (xy 185.683621 -123.800511) (xy 185.659474 -123.850383)
			(xy 185.652742 -123.860306) (xy 188.283848 -123.860306) (xy 188.287919 -123.804684) (xy 188.300045 -123.750247)
			(xy 188.319968 -123.698156) (xy 188.347264 -123.649521) (xy 188.38135 -123.605378) (xy 188.421499 -123.566669)
			(xy 188.466857 -123.534218) (xy 188.516457 -123.508717) (xy 188.569241 -123.49071) (xy 188.624084 -123.48058)
			(xy 188.679818 -123.478543) (xy 188.735255 -123.484643) (xy 188.789212 -123.498749) (xy 188.840541 -123.520561)
			(xy 188.888147 -123.549615) (xy 188.931015 -123.58529) (xy 188.968232 -123.626827) (xy 188.999005 -123.67334)
			(xy 189.022677 -123.723837) (xy 189.038745 -123.777244) (xy 189.046865 -123.83242) (xy 189.047374 -123.860306)
			(xy 189.046865 -123.888192) (xy 189.038745 -123.943368) (xy 189.022677 -123.996775) (xy 188.999005 -124.047272)
			(xy 188.968232 -124.093785) (xy 188.931015 -124.135322) (xy 188.888147 -124.170997) (xy 188.840541 -124.200051)
			(xy 188.789212 -124.221863) (xy 188.735255 -124.235969) (xy 188.679818 -124.242069) (xy 188.624084 -124.240032)
			(xy 188.569241 -124.229902) (xy 188.516457 -124.211895) (xy 188.466857 -124.186394) (xy 188.421499 -124.153943)
			(xy 188.38135 -124.115234) (xy 188.347264 -124.071091) (xy 188.319968 -124.022456) (xy 188.300045 -123.970365)
			(xy 188.287919 -123.915928) (xy 188.283848 -123.860306) (xy 185.652742 -123.860306) (xy 185.628366 -123.896238)
			(xy 185.590953 -123.937111) (xy 185.54802 -123.972141) (xy 185.500471 -124.000593) (xy 185.449307 -124.021867)
			(xy 185.395604 -124.035515) (xy 185.34049 -124.041252) (xy 185.285127 -124.038955) (xy 185.230679 -124.028674)
			(xy 185.17829 -124.010625) (xy 185.129063 -123.985187) (xy 185.084034 -123.952896) (xy 185.04415 -123.91443)
			(xy 185.026808 -123.892818) (xy 185.012484 -123.875065) (xy 184.978587 -123.844544) (xy 184.939787 -123.820563)
			(xy 184.897331 -123.803891) (xy 184.85258 -123.795065) (xy 184.806973 -123.794368) (xy 184.761973 -123.801821)
			(xy 184.719026 -123.817187) (xy 184.679511 -123.83997) (xy 184.644697 -123.869441) (xy 184.629806 -123.886722)
			(xy 184.611795 -123.907776) (xy 184.570745 -123.944985) (xy 184.524745 -123.975864) (xy 184.474762 -123.999765)
			(xy 184.421847 -124.016183) (xy 184.367113 -124.024775) (xy 184.311712 -124.025358) (xy 184.25681 -124.017922)
			(xy 184.203561 -124.002621) (xy 184.153085 -123.979779) (xy 184.106444 -123.949875) (xy 184.06462 -123.913539)
			(xy 184.028492 -123.871535) (xy 183.99882 -123.824747) (xy 183.976229 -123.774158) (xy 183.961193 -123.720834)
			(xy 183.954029 -123.665895) (xy 182.38724 -123.665895) (xy 182.38724 -124.29603) (xy 185.754073 -124.29603)
			(xy 185.760947 -124.241563) (xy 185.775558 -124.188644) (xy 185.797604 -124.138366) (xy 185.82663 -124.091768)
			(xy 185.862035 -124.049812) (xy 185.90309 -124.013365) (xy 185.948945 -123.983179) (xy 185.998654 -123.959879)
			(xy 186.05119 -123.943945) (xy 186.105467 -123.935707) (xy 186.160365 -123.935335) (xy 186.214749 -123.942836)
			(xy 186.267496 -123.958055) (xy 186.317516 -123.980679) (xy 186.363777 -124.01024) (xy 186.405322 -124.046127)
			(xy 186.441294 -124.087599) (xy 186.470949 -124.1338) (xy 186.493675 -124.183774) (xy 186.509002 -124.23649)
			(xy 186.516614 -124.290858) (xy 186.516354 -124.345756) (xy 186.508226 -124.40005) (xy 186.50077 -124.426472)
			(xy 186.494722 -124.448322) (xy 186.489601 -124.493365) (xy 186.492547 -124.538602) (xy 186.503467 -124.582601)
			(xy 186.522014 -124.623966) (xy 186.547602 -124.661387) (xy 186.579419 -124.693679) (xy 186.616457 -124.719818)
			(xy 186.657543 -124.738976) (xy 186.679332 -124.745242) (xy 186.705731 -124.75277) (xy 186.756252 -124.774239)
			(xy 186.803172 -124.802729) (xy 186.845524 -124.837651) (xy 186.882432 -124.878284) (xy 186.913134 -124.923788)
			(xy 186.936996 -124.973223) (xy 186.953525 -125.025568) (xy 186.962379 -125.079742) (xy 186.962656 -125.095)
			(xy 188.974982 -125.095) (xy 188.979053 -125.039378) (xy 188.991179 -124.984941) (xy 189.011102 -124.93285)
			(xy 189.038398 -124.884215) (xy 189.072484 -124.840072) (xy 189.112633 -124.801363) (xy 189.157991 -124.768912)
			(xy 189.207591 -124.743411) (xy 189.260375 -124.725404) (xy 189.315218 -124.715274) (xy 189.370952 -124.713237)
			(xy 189.426389 -124.719337) (xy 189.480346 -124.733443) (xy 189.531675 -124.755255) (xy 189.579281 -124.784309)
			(xy 189.622149 -124.819984) (xy 189.659366 -124.861521) (xy 189.690139 -124.908034) (xy 189.713811 -124.958531)
			(xy 189.729879 -125.011938) (xy 189.737999 -125.067114) (xy 189.738508 -125.095) (xy 189.737999 -125.122886)
			(xy 189.729879 -125.178062) (xy 189.713811 -125.231469) (xy 189.690139 -125.281966) (xy 189.659366 -125.328479)
			(xy 189.622149 -125.370016) (xy 189.579281 -125.405691) (xy 189.531675 -125.434745) (xy 189.480346 -125.456557)
			(xy 189.426389 -125.470663) (xy 189.370952 -125.476763) (xy 189.315218 -125.474726) (xy 189.260375 -125.464596)
			(xy 189.207591 -125.446589) (xy 189.157991 -125.421088) (xy 189.112633 -125.388637) (xy 189.072484 -125.349928)
			(xy 189.038398 -125.305785) (xy 189.011102 -125.25715) (xy 188.991179 -125.205059) (xy 188.979053 -125.150622)
			(xy 188.974982 -125.095) (xy 186.962656 -125.095) (xy 186.963376 -125.134626) (xy 186.956494 -125.189085)
			(xy 186.941877 -125.241996) (xy 186.919826 -125.292265) (xy 186.890796 -125.338853) (xy 186.855387 -125.380799)
			(xy 186.814331 -125.417236) (xy 186.768476 -125.44741) (xy 186.718768 -125.4707) (xy 186.666236 -125.486623)
			(xy 186.611963 -125.494851) (xy 186.557071 -125.495213) (xy 186.502695 -125.487703) (xy 186.449956 -125.472476)
			(xy 186.399945 -125.449845) (xy 186.353695 -125.420279) (xy 186.312161 -125.384389) (xy 186.276201 -125.342915)
			(xy 186.246558 -125.296714) (xy 186.223845 -125.246741) (xy 186.208529 -125.194028) (xy 186.200929 -125.139664)
			(xy 186.2012 -125.084772) (xy 186.209337 -125.030485) (xy 186.216798 -125.004068) (xy 186.222823 -124.982211)
			(xy 186.227951 -124.93717) (xy 186.225011 -124.891933) (xy 186.214096 -124.847935) (xy 186.195552 -124.806569)
			(xy 186.169966 -124.769147) (xy 186.138149 -124.736856) (xy 186.101111 -124.710718) (xy 186.060025 -124.691562)
			(xy 186.038236 -124.685298) (xy 186.011801 -124.677892) (xy 185.961273 -124.656427) (xy 185.914343 -124.62794)
			(xy 185.871982 -124.59302) (xy 185.835064 -124.552388) (xy 185.804352 -124.506884) (xy 185.78048 -124.457447)
			(xy 185.763942 -124.405098) (xy 185.755078 -124.35092) (xy 185.754073 -124.29603) (xy 182.38724 -124.29603)
			(xy 182.38724 -124.30252) (xy 182.387759 -124.325739) (xy 182.3962 -124.371402) (xy 182.412798 -124.414772)
			(xy 182.437 -124.454404) (xy 182.468 -124.488978) (xy 182.504766 -124.517345) (xy 182.546075 -124.538558)
			(xy 182.59055 -124.551913) (xy 182.636712 -124.556964) (xy 182.683023 -124.553544) (xy 182.727942 -124.541766)
			(xy 182.74919 -124.53239) (xy 182.774215 -124.520584) (xy 182.826847 -124.503511) (xy 182.881393 -124.494221)
			(xy 182.936708 -124.492907) (xy 182.991634 -124.499597) (xy 183.045017 -124.514151) (xy 183.095738 -124.536263)
			(xy 183.142733 -124.56547) (xy 183.185016 -124.601159) (xy 183.221701 -124.642581) (xy 183.252017 -124.688868)
			(xy 183.275329 -124.739049) (xy 183.291148 -124.792071) (xy 183.299143 -124.846822) (xy 183.299145 -124.902153)
			(xy 183.291154 -124.956905) (xy 183.275338 -125.009928) (xy 183.252029 -125.06011) (xy 183.221716 -125.106399)
			(xy 183.185034 -125.147824) (xy 183.142753 -125.183516) (xy 183.09576 -125.212726) (xy 183.045041 -125.234841)
			(xy 182.991658 -125.249398) (xy 182.936733 -125.256092) (xy 182.881417 -125.254782) (xy 182.826871 -125.245494)
			(xy 182.774238 -125.228426) (xy 182.74919 -125.216666) (xy 182.727951 -125.207262) (xy 182.683024 -125.195485)
			(xy 182.636706 -125.192065) (xy 182.590537 -125.197118) (xy 182.546055 -125.210474) (xy 182.504739 -125.231689)
			(xy 182.467966 -125.260058) (xy 182.436958 -125.294635) (xy 182.412748 -125.33427) (xy 182.396142 -125.377645)
			(xy 182.387693 -125.423314) (xy 182.38724 -125.446536) (xy 182.38724 -126.1872) (xy 189.686182 -126.1872)
			(xy 189.690253 -126.131578) (xy 189.702379 -126.077141) (xy 189.722302 -126.02505) (xy 189.749598 -125.976415)
			(xy 189.783684 -125.932272) (xy 189.823833 -125.893563) (xy 189.869191 -125.861112) (xy 189.918791 -125.835611)
			(xy 189.971575 -125.817604) (xy 190.026418 -125.807474) (xy 190.082152 -125.805437) (xy 190.137589 -125.811537)
			(xy 190.191546 -125.825643) (xy 190.242875 -125.847455) (xy 190.290481 -125.876509) (xy 190.333349 -125.912184)
			(xy 190.370566 -125.953721) (xy 190.401339 -126.000234) (xy 190.425011 -126.050731) (xy 190.441079 -126.104138)
			(xy 190.449199 -126.159314) (xy 190.449708 -126.1872) (xy 190.449199 -126.215086) (xy 190.441079 -126.270262)
			(xy 190.425011 -126.323669) (xy 190.401339 -126.374166) (xy 190.370566 -126.420679) (xy 190.333349 -126.462216)
			(xy 190.290481 -126.497891) (xy 190.242875 -126.526945) (xy 190.191546 -126.548757) (xy 190.137589 -126.562863)
			(xy 190.082152 -126.568963) (xy 190.026418 -126.566926) (xy 189.971575 -126.556796) (xy 189.918791 -126.538789)
			(xy 189.869191 -126.513288) (xy 189.823833 -126.480837) (xy 189.783684 -126.442128) (xy 189.749598 -126.397985)
			(xy 189.722302 -126.34935) (xy 189.702379 -126.297259) (xy 189.690253 -126.242822) (xy 189.686182 -126.1872)
			(xy 182.38724 -126.1872) (xy 182.38724 -127.0254) (xy 184.42889 -127.0254) (xy 184.432961 -126.969778)
			(xy 184.445087 -126.915341) (xy 184.46501 -126.86325) (xy 184.492306 -126.814615) (xy 184.526392 -126.770472)
			(xy 184.566541 -126.731763) (xy 184.611899 -126.699312) (xy 184.661499 -126.673811) (xy 184.714283 -126.655804)
			(xy 184.769126 -126.645674) (xy 184.82486 -126.643637) (xy 184.880297 -126.649737) (xy 184.934254 -126.663843)
			(xy 184.985583 -126.685655) (xy 185.033189 -126.714709) (xy 185.076057 -126.750384) (xy 185.113274 -126.791921)
			(xy 185.144047 -126.838434) (xy 185.167719 -126.888931) (xy 185.183787 -126.942338) (xy 185.191907 -126.997514)
			(xy 185.192416 -127.0254) (xy 185.191907 -127.053286) (xy 185.183787 -127.108462) (xy 185.167719 -127.161869)
			(xy 185.144047 -127.212366) (xy 185.113274 -127.258879) (xy 185.076057 -127.300416) (xy 185.033189 -127.336091)
			(xy 184.985583 -127.365145) (xy 184.934254 -127.386957) (xy 184.880297 -127.401063) (xy 184.82486 -127.407163)
			(xy 184.769126 -127.405126) (xy 184.714283 -127.394996) (xy 184.661499 -127.376989) (xy 184.611899 -127.351488)
			(xy 184.566541 -127.319037) (xy 184.526392 -127.280328) (xy 184.492306 -127.236185) (xy 184.46501 -127.18755)
			(xy 184.445087 -127.135459) (xy 184.432961 -127.081022) (xy 184.42889 -127.0254) (xy 182.38724 -127.0254)
			(xy 182.38724 -127.697992) (xy 187.103002 -127.697992) (xy 187.107073 -127.64237) (xy 187.119199 -127.587933)
			(xy 187.139122 -127.535842) (xy 187.166418 -127.487207) (xy 187.200504 -127.443064) (xy 187.240653 -127.404355)
			(xy 187.286011 -127.371904) (xy 187.335611 -127.346403) (xy 187.388395 -127.328396) (xy 187.443238 -127.318266)
			(xy 187.498972 -127.316229) (xy 187.554409 -127.322329) (xy 187.608366 -127.336435) (xy 187.659695 -127.358247)
			(xy 187.707301 -127.387301) (xy 187.750169 -127.422976) (xy 187.787386 -127.464513) (xy 187.818159 -127.511026)
			(xy 187.841831 -127.561523) (xy 187.857899 -127.61493) (xy 187.866019 -127.670106) (xy 187.866528 -127.697992)
			(xy 187.866019 -127.725878) (xy 187.857899 -127.781054) (xy 187.841831 -127.834461) (xy 187.818159 -127.884958)
			(xy 187.787386 -127.931471) (xy 187.750169 -127.973008) (xy 187.707301 -128.008683) (xy 187.659695 -128.037737)
			(xy 187.608366 -128.059549) (xy 187.554409 -128.073655) (xy 187.498972 -128.079755) (xy 187.443238 -128.077718)
			(xy 187.388395 -128.067588) (xy 187.335611 -128.049581) (xy 187.286011 -128.02408) (xy 187.240653 -127.991629)
			(xy 187.200504 -127.95292) (xy 187.166418 -127.908777) (xy 187.139122 -127.860142) (xy 187.119199 -127.808051)
			(xy 187.107073 -127.753614) (xy 187.103002 -127.697992) (xy 182.38724 -127.697992) (xy 182.38724 -130.37058)
			(xy 182.387752 -130.394119) (xy 182.396421 -130.440391) (xy 182.413467 -130.484274) (xy 182.438306 -130.524266)
			(xy 182.470088 -130.558996) (xy 182.507724 -130.587278) (xy 182.549926 -130.608141) (xy 182.595249 -130.620872)
			(xy 182.642142 -130.625035) (xy 182.665624 -130.62331) (xy 182.693513 -130.62052) (xy 182.749536 -130.62217)
			(xy 182.804715 -130.631998) (xy 182.857863 -130.64979) (xy 182.907837 -130.675165) (xy 182.953562 -130.707577)
			(xy 182.994054 -130.746328) (xy 183.028443 -130.790585) (xy 183.055988 -130.839397) (xy 183.076098 -130.891712)
			(xy 183.088339 -130.946406) (xy 183.092447 -131.002278) (xy 185.02325 -131.002278) (xy 185.027321 -130.946656)
			(xy 185.039447 -130.892219) (xy 185.05937 -130.840128) (xy 185.086666 -130.791493) (xy 185.120752 -130.74735)
			(xy 185.160901 -130.708641) (xy 185.206259 -130.67619) (xy 185.255859 -130.650689) (xy 185.308643 -130.632682)
			(xy 185.363486 -130.622552) (xy 185.41922 -130.620515) (xy 185.474657 -130.626615) (xy 185.528614 -130.640721)
			(xy 185.579943 -130.662533) (xy 185.627549 -130.691587) (xy 185.670417 -130.727262) (xy 185.707634 -130.768799)
			(xy 185.738407 -130.815312) (xy 185.762079 -130.865809) (xy 185.778147 -130.919216) (xy 185.786267 -130.974392)
			(xy 185.786776 -131.002278) (xy 185.786267 -131.030164) (xy 185.778147 -131.08534) (xy 185.762079 -131.138747)
			(xy 185.738407 -131.189244) (xy 185.707634 -131.235757) (xy 185.670417 -131.277294) (xy 185.627549 -131.312969)
			(xy 185.579943 -131.342023) (xy 185.528614 -131.363835) (xy 185.474657 -131.377941) (xy 185.41922 -131.384041)
			(xy 185.363486 -131.382004) (xy 185.308643 -131.371874) (xy 185.255859 -131.353867) (xy 185.206259 -131.328366)
			(xy 185.160901 -131.295915) (xy 185.120752 -131.257206) (xy 185.086666 -131.213063) (xy 185.05937 -131.164428)
			(xy 185.039447 -131.112337) (xy 185.027321 -131.0579) (xy 185.02325 -131.002278) (xy 183.092447 -131.002278)
			(xy 183.092449 -131.002303) (xy 183.088339 -131.058199) (xy 183.076097 -131.112893) (xy 183.055986 -131.165208)
			(xy 183.02844 -131.214019) (xy 182.994051 -131.258276) (xy 182.953558 -131.297026) (xy 182.907832 -131.329437)
			(xy 182.857858 -131.354812) (xy 182.80471 -131.372604) (xy 182.749531 -131.38243) (xy 182.693508 -131.38408)
			(xy 182.665624 -131.381246) (xy 182.642149 -131.379503) (xy 182.595269 -131.383697) (xy 182.549961 -131.396449)
			(xy 182.507776 -131.417324) (xy 182.470154 -131.445607) (xy 182.438381 -131.480333) (xy 182.413543 -131.520314)
			(xy 182.39649 -131.564183) (xy 182.387803 -131.610442) (xy 182.38724 -131.633976) (xy 182.38724 -133.829806)
			(xy 180.979318 -135.237728) (xy 182.437276 -135.237728) (xy 182.441347 -135.182106) (xy 182.453473 -135.127669)
			(xy 182.473396 -135.075578) (xy 182.500692 -135.026943) (xy 182.534778 -134.9828) (xy 182.574927 -134.944091)
			(xy 182.620285 -134.91164) (xy 182.669885 -134.886139) (xy 182.722669 -134.868132) (xy 182.777512 -134.858002)
			(xy 182.833246 -134.855965) (xy 182.888683 -134.862065) (xy 182.94264 -134.876171) (xy 182.993969 -134.897983)
			(xy 183.041575 -134.927037) (xy 183.084443 -134.962712) (xy 183.12166 -135.004249) (xy 183.152433 -135.050762)
			(xy 183.176105 -135.101259) (xy 183.192173 -135.154666) (xy 183.200293 -135.209842) (xy 183.200802 -135.237728)
			(xy 183.200293 -135.265614) (xy 183.192173 -135.32079) (xy 183.176105 -135.374197) (xy 183.152433 -135.424694)
			(xy 183.12166 -135.471207) (xy 183.084443 -135.512744) (xy 183.041575 -135.548419) (xy 182.993969 -135.577473)
			(xy 182.94264 -135.599285) (xy 182.888683 -135.613391) (xy 182.833246 -135.619491) (xy 182.777512 -135.617454)
			(xy 182.722669 -135.607324) (xy 182.669885 -135.589317) (xy 182.620285 -135.563816) (xy 182.574927 -135.531365)
			(xy 182.534778 -135.492656) (xy 182.500692 -135.448513) (xy 182.473396 -135.399878) (xy 182.453473 -135.347787)
			(xy 182.441347 -135.29335) (xy 182.437276 -135.237728) (xy 180.979318 -135.237728) (xy 180.56606 -135.650986)
			(xy 179.53609 -135.650986) (xy 179.519072 -135.655812) (xy 179.493751 -135.66249) (xy 179.441877 -135.669651)
			(xy 179.389511 -135.669651) (xy 179.337637 -135.66249) (xy 179.312316 -135.655812) (xy 179.295298 -135.650986)
			(xy 176.885346 -135.650986) (xy 176.862125 -135.6515) (xy 176.816456 -135.659932) (xy 176.77308 -135.676524)
			(xy 176.733442 -135.700723) (xy 176.698863 -135.731724) (xy 176.670493 -135.768493) (xy 176.649279 -135.809805)
			(xy 176.635927 -135.854285) (xy 176.630881 -135.900452) (xy 176.63431 -135.946766) (xy 176.646099 -135.991686)
			(xy 176.655476 -136.012936) (xy 176.667417 -136.037966) (xy 176.684744 -136.090645) (xy 176.694263 -136.145278)
			(xy 176.695773 -136.200714) (xy 176.689242 -136.255784) (xy 176.674807 -136.309328) (xy 176.652773 -136.360219)
			(xy 176.623604 -136.407384) (xy 176.587915 -136.449829) (xy 176.546457 -136.486661) (xy 176.500103 -136.517103)
			(xy 176.449831 -136.540514) (xy 176.3967 -136.556401) (xy 176.341828 -136.564429) (xy 176.286372 -136.564429)
			(xy 176.2315 -136.556401) (xy 176.178369 -136.540514) (xy 176.128097 -136.517103) (xy 176.081743 -136.486661)
			(xy 176.040285 -136.449829) (xy 176.004596 -136.407384) (xy 175.975427 -136.360219) (xy 175.953393 -136.309328)
			(xy 175.938958 -136.255784) (xy 175.932427 -136.200714) (xy 175.933937 -136.145278) (xy 175.943456 -136.090645)
			(xy 175.960783 -136.037966) (xy 175.972724 -136.012936) (xy 175.982122 -135.991699) (xy 175.99389 -135.94678)
			(xy 175.997302 -135.90047) (xy 175.992244 -135.854311) (xy 175.978885 -135.809839) (xy 175.957669 -135.768533)
			(xy 175.929302 -135.73177) (xy 175.894729 -135.700771) (xy 175.855099 -135.676569) (xy 175.811732 -135.659969)
			(xy 175.766072 -135.651524) (xy 175.742854 -135.650986) (xy 175.669702 -135.650986) (xy 175.653053 -135.651529)
			(xy 175.620889 -135.660146) (xy 175.592051 -135.676794) (xy 175.568504 -135.700338) (xy 175.551852 -135.729174)
			(xy 175.543231 -135.761337) (xy 175.542702 -135.777986) (xy 175.542702 -135.821928) (xy 175.56988 -135.856472)
			(xy 175.586553 -135.878389) (xy 175.614095 -135.926073) (xy 175.624744 -135.951468) (xy 175.634521 -135.977332)
			(xy 175.64736 -136.031113) (xy 175.652301 -136.086184) (xy 175.649241 -136.141391) (xy 175.638244 -136.195579)
			(xy 175.619541 -136.247611) (xy 175.593523 -136.296399) (xy 175.560736 -136.340921) (xy 175.521866 -136.380244)
			(xy 175.477726 -136.413545) (xy 175.429242 -136.440125) (xy 175.377429 -136.459429) (xy 175.323373 -136.471052)
			(xy 175.268205 -136.47475) (xy 175.21308 -136.470447) (xy 175.159155 -136.458232) (xy 175.107557 -136.438361)
			(xy 175.059367 -136.41125) (xy 175.015596 -136.377468) (xy 174.996094 -136.357868) (xy 174.978659 -136.339294)
			(xy 174.948399 -136.298313) (xy 174.923871 -136.253664) (xy 174.905514 -136.206144) (xy 174.893654 -136.156601)
			(xy 174.890684 -136.1313) (xy 174.888432 -136.105238) (xy 174.890231 -136.052957) (xy 174.899158 -136.001413)
			(xy 174.906686 -135.97636) (xy 174.912816 -135.953575) (xy 174.917488 -135.906628) (xy 174.913417 -135.859625)
			(xy 174.900743 -135.814181) (xy 174.879902 -135.771855) (xy 174.851609 -135.734101) (xy 174.816836 -135.702216)
			(xy 174.776776 -135.677294) (xy 174.732806 -135.660192) (xy 174.686436 -135.651497) (xy 174.662846 -135.650986)
			(xy 174.489872 -135.650986) (xy 174.467655 -135.651439) (xy 174.423896 -135.65916) (xy 174.382149 -135.67438)
			(xy 174.343688 -135.696633) (xy 174.309687 -135.72524) (xy 174.281185 -135.759329) (xy 174.25905 -135.797858)
			(xy 174.243959 -135.839651) (xy 174.236372 -135.883433) (xy 174.236521 -135.927868) (xy 174.244402 -135.971598)
			(xy 174.25162 -135.992616) (xy 174.260563 -136.018307) (xy 174.271915 -136.071508) (xy 174.275596 -136.125782)
			(xy 174.271534 -136.180029) (xy 174.25981 -136.233149) (xy 174.240661 -136.284066) (xy 174.214477 -136.331748)
			(xy 174.181787 -136.375229) (xy 174.143254 -136.413627) (xy 174.099659 -136.446164) (xy 174.051885 -136.472181)
			(xy 174.000901 -136.491151) (xy 173.947741 -136.502689) (xy 173.89348 -136.506561) (xy 173.839219 -136.502689)
			(xy 173.786059 -136.491151) (xy 173.735075 -136.472181) (xy 173.687301 -136.446164) (xy 173.643706 -136.413627)
			(xy 173.605173 -136.375229) (xy 173.572483 -136.331748) (xy 173.546299 -136.284066) (xy 173.52715 -136.233149)
			(xy 173.515426 -136.180029) (xy 173.511364 -136.125782) (xy 173.515045 -136.071508) (xy 173.526397 -136.018307)
			(xy 173.53534 -135.992616) (xy 173.542572 -135.97161) (xy 173.550411 -135.927883) (xy 173.550528 -135.88346)
			(xy 173.542921 -135.839693) (xy 173.52782 -135.797915) (xy 173.505686 -135.759399) (xy 173.477193 -135.725317)
			(xy 173.443208 -135.696709) (xy 173.404767 -135.674444) (xy 173.36304 -135.659202) (xy 173.319299 -135.651446)
			(xy 173.297088 -135.650986) (xy 170.062652 -135.650986) (xy 170.038971 -135.651508) (xy 169.992429 -135.660278)
			(xy 169.94832 -135.677523) (xy 169.908171 -135.702645) (xy 169.873375 -135.734774) (xy 169.845137 -135.772796)
			(xy 169.824437 -135.815394) (xy 169.811992 -135.861091) (xy 169.808233 -135.908302) (xy 169.810176 -135.93191)
			(xy 169.812477 -135.957381) (xy 169.811046 -136.008504) (xy 169.802782 -136.058974) (xy 169.795698 -136.083548)
			(xy 169.788211 -136.106731) (xy 169.76816 -136.15113) (xy 169.742621 -136.192617) (xy 169.727626 -136.211818)
			(xy 169.717177 -136.224479) (xy 169.694413 -136.248137) (xy 169.68216 -136.259062) (xy 169.681906 -136.259316)
			(xy 169.668837 -136.271677) (xy 169.649592 -136.302049) (xy 169.640471 -136.33356) (xy 171.885137 -136.33356)
			(xy 171.889464 -136.277643) (xy 171.90193 -136.222962) (xy 171.922268 -136.170695) (xy 171.950037 -136.121969)
			(xy 171.984641 -136.077833) (xy 172.025334 -136.039238) (xy 172.071238 -136.007016) (xy 172.121364 -135.981862)
			(xy 172.174634 -135.964317) (xy 172.229897 -135.954759) (xy 172.285965 -135.953395) (xy 172.341628 -135.960254)
			(xy 172.395687 -135.975187) (xy 172.446978 -135.997874) (xy 172.494395 -136.027824) (xy 172.536916 -136.064394)
			(xy 172.573626 -136.106795) (xy 172.603733 -136.154113) (xy 172.626588 -136.205329) (xy 172.641699 -136.259339)
			(xy 172.648741 -136.314979) (xy 172.647561 -136.371051) (xy 172.638186 -136.426346) (xy 172.620816 -136.479672)
			(xy 172.595827 -136.529881) (xy 172.563756 -136.575891) (xy 172.525296 -136.616711) (xy 172.503592 -136.634474)
			(xy 172.485428 -136.649468) (xy 172.454479 -136.684965) (xy 172.430602 -136.725558) (xy 172.414616 -136.769856)
			(xy 172.407069 -136.816342) (xy 172.408218 -136.863422) (xy 172.418025 -136.909484) (xy 172.436153 -136.95295)
			(xy 172.461982 -136.992329) (xy 172.494626 -137.026274) (xy 172.513498 -137.040366) (xy 172.536071 -137.057013)
			(xy 172.57648 -137.095911) (xy 172.610758 -137.140306) (xy 172.638168 -137.18924) (xy 172.65812 -137.24166)
			(xy 172.670182 -137.296436) (xy 172.674095 -137.352387) (xy 172.669776 -137.408309) (xy 172.657316 -137.462996)
			(xy 172.636985 -137.51527) (xy 172.60922 -137.564004) (xy 172.57462 -137.608148) (xy 172.53393 -137.646751)
			(xy 172.488027 -137.678982) (xy 172.4379 -137.704146) (xy 172.38463 -137.7217) (xy 172.329363 -137.731267)
			(xy 172.273292 -137.73264) (xy 172.217624 -137.725789) (xy 172.163558 -137.710863) (xy 172.11226 -137.688183)
			(xy 172.064834 -137.658237) (xy 172.022304 -137.621671) (xy 171.985585 -137.579273) (xy 171.955468 -137.531956)
			(xy 171.932603 -137.48074) (xy 171.917482 -137.426729) (xy 171.91043 -137.371086) (xy 171.911601 -137.31501)
			(xy 171.920968 -137.259709) (xy 171.93833 -137.206376) (xy 171.963312 -137.156158) (xy 171.995377 -137.11014)
			(xy 172.033834 -137.069311) (xy 172.055536 -137.051542) (xy 172.073681 -137.036528) (xy 172.104627 -137.001033)
			(xy 172.128501 -136.960443) (xy 172.144486 -136.916148) (xy 172.152034 -136.869666) (xy 172.150887 -136.82259)
			(xy 172.141083 -136.776531) (xy 172.12296 -136.733067) (xy 172.097137 -136.693689) (xy 172.064499 -136.659743)
			(xy 172.04563 -136.64565) (xy 172.023111 -136.62893) (xy 171.982711 -136.59003) (xy 171.948441 -136.545634)
			(xy 171.921039 -136.4967) (xy 171.901096 -136.444281) (xy 171.889042 -136.389508) (xy 171.885137 -136.33356)
			(xy 169.640471 -136.33356) (xy 169.639595 -136.336587) (xy 169.63898 -136.354566) (xy 169.63898 -138.001884)
			(xy 174.057684 -138.001884) (xy 174.062173 -137.946058) (xy 174.074778 -137.891489) (xy 174.095228 -137.839349)
			(xy 174.123084 -137.790762) (xy 174.157746 -137.74677) (xy 174.198469 -137.708321) (xy 174.22114 -137.691876)
			(xy 174.238595 -137.679095) (xy 174.269338 -137.648662) (xy 174.294484 -137.613463) (xy 174.313308 -137.574515)
			(xy 174.325267 -137.532943) (xy 174.330016 -137.489946) (xy 174.327416 -137.446766) (xy 174.317544 -137.404649)
			(xy 174.300684 -137.364811) (xy 174.277323 -137.328403) (xy 174.26305 -137.312146) (xy 174.24448 -137.291173)
			(xy 174.213106 -137.244766) (xy 174.188856 -137.194269) (xy 174.172252 -137.140769) (xy 174.163651 -137.085415)
			(xy 174.163239 -137.029399) (xy 174.171023 -136.973925) (xy 174.186836 -136.920185) (xy 174.210339 -136.869337)
			(xy 174.241026 -136.822472) (xy 174.278237 -136.780599) (xy 174.321172 -136.744619) (xy 174.368907 -136.715305)
			(xy 174.420417 -136.693287) (xy 174.474592 -136.679039) (xy 174.530269 -136.672868) (xy 174.586249 -136.674906)
			(xy 174.64133 -136.685109) (xy 174.694326 -136.703258) (xy 174.744098 -136.728963) (xy 174.789576 -136.76167)
			(xy 174.809533 -136.781032) (xy 177.715162 -136.781032) (xy 177.719233 -136.72541) (xy 177.731359 -136.670973)
			(xy 177.751282 -136.618882) (xy 177.778578 -136.570247) (xy 177.812664 -136.526104) (xy 177.852813 -136.487395)
			(xy 177.898171 -136.454944) (xy 177.947771 -136.429443) (xy 178.000555 -136.411436) (xy 178.055398 -136.401306)
			(xy 178.111132 -136.399269) (xy 178.166569 -136.405369) (xy 178.220526 -136.419475) (xy 178.271855 -136.441287)
			(xy 178.319461 -136.470341) (xy 178.362329 -136.506016) (xy 178.399546 -136.547553) (xy 178.430319 -136.594066)
			(xy 178.453991 -136.644563) (xy 178.470059 -136.69797) (xy 178.478179 -136.753146) (xy 178.478688 -136.781032)
			(xy 178.478179 -136.808918) (xy 178.470059 -136.864094) (xy 178.453991 -136.917501) (xy 178.447118 -136.932162)
			(xy 180.106572 -136.932162) (xy 180.110643 -136.87654) (xy 180.122769 -136.822103) (xy 180.142692 -136.770012)
			(xy 180.169988 -136.721377) (xy 180.204074 -136.677234) (xy 180.244223 -136.638525) (xy 180.289581 -136.606074)
			(xy 180.339181 -136.580573) (xy 180.391965 -136.562566) (xy 180.446808 -136.552436) (xy 180.502542 -136.550399)
			(xy 180.557979 -136.556499) (xy 180.611936 -136.570605) (xy 180.663265 -136.592417) (xy 180.710871 -136.621471)
			(xy 180.753739 -136.657146) (xy 180.790956 -136.698683) (xy 180.821729 -136.745196) (xy 180.845401 -136.795693)
			(xy 180.861469 -136.8491) (xy 180.869589 -136.904276) (xy 180.870098 -136.932162) (xy 180.869589 -136.960048)
			(xy 180.861469 -137.015224) (xy 180.845401 -137.068631) (xy 180.821729 -137.119128) (xy 180.790956 -137.165641)
			(xy 180.753739 -137.207178) (xy 180.710871 -137.242853) (xy 180.663265 -137.271907) (xy 180.611936 -137.293719)
			(xy 180.557979 -137.307825) (xy 180.502542 -137.313925) (xy 180.446808 -137.311888) (xy 180.391965 -137.301758)
			(xy 180.339181 -137.283751) (xy 180.289581 -137.25825) (xy 180.244223 -137.225799) (xy 180.204074 -137.18709)
			(xy 180.169988 -137.142947) (xy 180.142692 -137.094312) (xy 180.122769 -137.042221) (xy 180.110643 -136.987784)
			(xy 180.106572 -136.932162) (xy 178.447118 -136.932162) (xy 178.430319 -136.967998) (xy 178.399546 -137.014511)
			(xy 178.362329 -137.056048) (xy 178.319461 -137.091723) (xy 178.271855 -137.120777) (xy 178.220526 -137.142589)
			(xy 178.166569 -137.156695) (xy 178.111132 -137.162795) (xy 178.055398 -137.160758) (xy 178.000555 -137.150628)
			(xy 177.947771 -137.132621) (xy 177.898171 -137.10712) (xy 177.852813 -137.074669) (xy 177.812664 -137.03596)
			(xy 177.778578 -136.991817) (xy 177.751282 -136.943182) (xy 177.731359 -136.891091) (xy 177.719233 -136.836654)
			(xy 177.715162 -136.781032) (xy 174.809533 -136.781032) (xy 174.829781 -136.800677) (xy 174.863849 -136.845145)
			(xy 174.891047 -136.894116) (xy 174.910791 -136.946539) (xy 174.922655 -137.001286) (xy 174.926385 -137.05718)
			(xy 174.9219 -137.113018) (xy 174.909298 -137.167599) (xy 174.888848 -137.219751) (xy 174.860991 -137.268351)
			(xy 174.826325 -137.312354) (xy 174.785597 -137.350815) (xy 174.762922 -137.367264) (xy 174.74543 -137.379996)
			(xy 174.71469 -137.410438) (xy 174.689547 -137.445645) (xy 174.670727 -137.484599) (xy 174.658773 -137.526177)
			(xy 174.654029 -137.569179) (xy 174.656633 -137.612364) (xy 174.666509 -137.654484) (xy 174.683373 -137.694324)
			(xy 174.706738 -137.730735) (xy 174.721012 -137.746994) (xy 174.73951 -137.768025) (xy 174.770869 -137.814429)
			(xy 174.795105 -137.86492) (xy 174.811696 -137.918412) (xy 174.820285 -137.973756) (xy 174.820688 -138.029761)
			(xy 174.812897 -138.085222) (xy 174.797078 -138.138948) (xy 174.773571 -138.189783) (xy 174.742883 -138.236633)
			(xy 174.705674 -138.278492) (xy 174.662742 -138.314458) (xy 174.615012 -138.34376) (xy 174.56351 -138.365765)
			(xy 174.509344 -138.380003) (xy 174.453678 -138.386165) (xy 174.397709 -138.38412) (xy 174.342641 -138.373912)
			(xy 174.289657 -138.35576) (xy 174.239899 -138.330055) (xy 174.194434 -138.297349) (xy 174.154242 -138.258345)
			(xy 174.120186 -138.213883) (xy 174.092998 -138.164918) (xy 174.073264 -138.112503) (xy 174.061408 -138.057767)
			(xy 174.057684 -138.001884) (xy 169.63898 -138.001884) (xy 169.63898 -139.65301) (xy 179.515514 -139.65301)
			(xy 179.519585 -139.597388) (xy 179.531711 -139.542951) (xy 179.551634 -139.49086) (xy 179.57893 -139.442225)
			(xy 179.613016 -139.398082) (xy 179.653165 -139.359373) (xy 179.698523 -139.326922) (xy 179.748123 -139.301421)
			(xy 179.800907 -139.283414) (xy 179.85575 -139.273284) (xy 179.911484 -139.271247) (xy 179.966921 -139.277347)
			(xy 180.020878 -139.291453) (xy 180.072207 -139.313265) (xy 180.119813 -139.342319) (xy 180.162681 -139.377994)
			(xy 180.199898 -139.419531) (xy 180.230671 -139.466044) (xy 180.254343 -139.516541) (xy 180.270411 -139.569948)
			(xy 180.278531 -139.625124) (xy 180.27904 -139.65301) (xy 180.278531 -139.680896) (xy 180.270411 -139.736072)
			(xy 180.254343 -139.789479) (xy 180.230671 -139.839976) (xy 180.199898 -139.886489) (xy 180.162681 -139.928026)
			(xy 180.119813 -139.963701) (xy 180.072207 -139.992755) (xy 180.020878 -140.014567) (xy 179.966921 -140.028673)
			(xy 179.911484 -140.034773) (xy 179.85575 -140.032736) (xy 179.800907 -140.022606) (xy 179.748123 -140.004599)
			(xy 179.698523 -139.979098) (xy 179.653165 -139.946647) (xy 179.613016 -139.907938) (xy 179.57893 -139.863795)
			(xy 179.551634 -139.81516) (xy 179.531711 -139.763069) (xy 179.519585 -139.708632) (xy 179.515514 -139.65301)
			(xy 169.63898 -139.65301) (xy 169.63898 -140.629132) (xy 177.677824 -140.629132) (xy 177.681895 -140.57351)
			(xy 177.694021 -140.519073) (xy 177.713944 -140.466982) (xy 177.74124 -140.418347) (xy 177.775326 -140.374204)
			(xy 177.815475 -140.335495) (xy 177.860833 -140.303044) (xy 177.910433 -140.277543) (xy 177.963217 -140.259536)
			(xy 178.01806 -140.249406) (xy 178.073794 -140.247369) (xy 178.129231 -140.253469) (xy 178.183188 -140.267575)
			(xy 178.234517 -140.289387) (xy 178.282123 -140.318441) (xy 178.324991 -140.354116) (xy 178.362208 -140.395653)
			(xy 178.392981 -140.442166) (xy 178.416653 -140.492663) (xy 178.432721 -140.54607) (xy 178.440841 -140.601246)
			(xy 178.44135 -140.629132) (xy 178.440841 -140.657018) (xy 178.432721 -140.712194) (xy 178.416653 -140.765601)
			(xy 178.392981 -140.816098) (xy 178.362208 -140.862611) (xy 178.324991 -140.904148) (xy 178.282123 -140.939823)
			(xy 178.234517 -140.968877) (xy 178.183188 -140.990689) (xy 178.129231 -141.004795) (xy 178.073794 -141.010895)
			(xy 178.01806 -141.008858) (xy 177.963217 -140.998728) (xy 177.910433 -140.980721) (xy 177.860833 -140.95522)
			(xy 177.815475 -140.922769) (xy 177.775326 -140.88406) (xy 177.74124 -140.839917) (xy 177.713944 -140.791282)
			(xy 177.694021 -140.739191) (xy 177.681895 -140.684754) (xy 177.677824 -140.629132) (xy 169.63898 -140.629132)
			(xy 169.63898 -148.282404) (xy 175.267127 -148.282404) (xy 175.271001 -148.228131) (xy 175.282548 -148.174959)
			(xy 175.301533 -148.123968) (xy 175.32757 -148.076191) (xy 175.360131 -148.032599) (xy 175.398556 -147.994075)
			(xy 175.42002 -147.977352) (xy 175.438515 -147.96279) (xy 175.470279 -147.928059) (xy 175.495105 -147.888073)
			(xy 175.512143 -147.844198) (xy 175.520811 -147.797937) (xy 175.520812 -147.75087) (xy 175.512145 -147.704609)
			(xy 175.495108 -147.660734) (xy 175.470284 -147.620747) (xy 175.43852 -147.586014) (xy 175.42002 -147.57146)
			(xy 175.398561 -147.55473) (xy 175.360136 -147.516207) (xy 175.327574 -147.472615) (xy 175.301536 -147.424839)
			(xy 175.28255 -147.373848) (xy 175.271002 -147.320676) (xy 175.267127 -147.266404) (xy 175.271001 -147.212131)
			(xy 175.282548 -147.158959) (xy 175.301533 -147.107968) (xy 175.32757 -147.060191) (xy 175.360131 -147.016599)
			(xy 175.398556 -146.978075) (xy 175.42002 -146.961352) (xy 175.438515 -146.94679) (xy 175.470279 -146.912059)
			(xy 175.495105 -146.872073) (xy 175.512143 -146.828198) (xy 175.520811 -146.781937) (xy 175.520812 -146.73487)
			(xy 175.512145 -146.688609) (xy 175.495108 -146.644734) (xy 175.470284 -146.604747) (xy 175.43852 -146.570014)
			(xy 175.42002 -146.55546) (xy 175.398561 -146.53873) (xy 175.360136 -146.500207) (xy 175.327574 -146.456615)
			(xy 175.301536 -146.408839) (xy 175.28255 -146.357848) (xy 175.271002 -146.304676) (xy 175.267127 -146.250404)
			(xy 175.271001 -146.196131) (xy 175.282548 -146.142959) (xy 175.301533 -146.091968) (xy 175.32757 -146.044191)
			(xy 175.360131 -146.000599) (xy 175.398556 -145.962075) (xy 175.42002 -145.945352) (xy 175.438515 -145.93079)
			(xy 175.470279 -145.896059) (xy 175.495105 -145.856073) (xy 175.512143 -145.812198) (xy 175.520811 -145.765937)
			(xy 175.520812 -145.71887) (xy 175.512145 -145.672609) (xy 175.495108 -145.628734) (xy 175.470284 -145.588747)
			(xy 175.43852 -145.554014) (xy 175.42002 -145.53946) (xy 175.398561 -145.52273) (xy 175.360136 -145.484207)
			(xy 175.327574 -145.440615) (xy 175.301536 -145.392839) (xy 175.28255 -145.341848) (xy 175.271002 -145.288676)
			(xy 175.267127 -145.234404) (xy 175.271001 -145.180131) (xy 175.282548 -145.126959) (xy 175.301533 -145.075968)
			(xy 175.32757 -145.028191) (xy 175.360131 -144.984599) (xy 175.398556 -144.946075) (xy 175.42002 -144.929352)
			(xy 175.438515 -144.91479) (xy 175.470279 -144.880059) (xy 175.495105 -144.840073) (xy 175.512143 -144.796198)
			(xy 175.520811 -144.749937) (xy 175.520812 -144.70287) (xy 175.512145 -144.656609) (xy 175.495108 -144.612734)
			(xy 175.470284 -144.572747) (xy 175.43852 -144.538014) (xy 175.42002 -144.52346) (xy 175.398561 -144.50673)
			(xy 175.360136 -144.468207) (xy 175.327574 -144.424615) (xy 175.301536 -144.376839) (xy 175.28255 -144.325848)
			(xy 175.271002 -144.272676) (xy 175.267127 -144.218404) (xy 175.271001 -144.164131) (xy 175.282548 -144.110959)
			(xy 175.301533 -144.059968) (xy 175.32757 -144.012191) (xy 175.360131 -143.968599) (xy 175.398556 -143.930075)
			(xy 175.42002 -143.913352) (xy 175.438515 -143.89879) (xy 175.470279 -143.864059) (xy 175.495105 -143.824073)
			(xy 175.512143 -143.780198) (xy 175.520811 -143.733937) (xy 175.520812 -143.68687) (xy 175.512145 -143.640609)
			(xy 175.495108 -143.596734) (xy 175.470284 -143.556747) (xy 175.43852 -143.522014) (xy 175.42002 -143.50746)
			(xy 175.398561 -143.49073) (xy 175.360136 -143.452207) (xy 175.327574 -143.408615) (xy 175.301536 -143.360839)
			(xy 175.28255 -143.309848) (xy 175.271002 -143.256676) (xy 175.267127 -143.202404) (xy 175.271001 -143.148131)
			(xy 175.282548 -143.094959) (xy 175.301533 -143.043968) (xy 175.32757 -142.996191) (xy 175.360131 -142.952599)
			(xy 175.398556 -142.914075) (xy 175.42002 -142.897352) (xy 175.438515 -142.88279) (xy 175.470279 -142.848059)
			(xy 175.495105 -142.808073) (xy 175.512143 -142.764198) (xy 175.520811 -142.717937) (xy 175.520812 -142.67087)
			(xy 175.512145 -142.624609) (xy 175.495108 -142.580734) (xy 175.470284 -142.540747) (xy 175.43852 -142.506014)
			(xy 175.42002 -142.49146) (xy 175.397899 -142.474227) (xy 175.358474 -142.434352) (xy 175.32531 -142.389135)
			(xy 175.299123 -142.339551) (xy 175.280476 -142.286668) (xy 175.26977 -142.231625) (xy 175.267238 -142.175608)
			(xy 175.272932 -142.119823) (xy 175.28673 -142.065473) (xy 175.308336 -142.013728) (xy 175.337283 -141.965703)
			(xy 175.372949 -141.922432) (xy 175.414564 -141.884849) (xy 175.461233 -141.853762) (xy 175.511949 -141.829841)
			(xy 175.56562 -141.813601) (xy 175.621091 -141.805393) (xy 175.677165 -141.805393) (xy 175.732636 -141.813601)
			(xy 175.786307 -141.829841) (xy 175.837023 -141.853762) (xy 175.883692 -141.884849) (xy 175.925307 -141.922432)
			(xy 175.960973 -141.965703) (xy 175.961464 -141.966517) (xy 182.611467 -141.966517) (xy 182.618023 -141.911046)
			(xy 182.632598 -141.857124) (xy 182.654881 -141.805904) (xy 182.684395 -141.758481) (xy 182.720508 -141.715869)
			(xy 182.76245 -141.678979) (xy 182.809323 -141.648599) (xy 182.860125 -141.62538) (xy 182.91377 -141.609817)
			(xy 182.969111 -141.602243) (xy 183.024965 -141.60282) (xy 183.080138 -141.611537) (xy 183.13345 -141.628205)
			(xy 183.183761 -141.65247) (xy 183.207152 -141.667738) (xy 183.226195 -141.680064) (xy 183.267668 -141.69843)
			(xy 183.311743 -141.709144) (xy 183.35702 -141.711867) (xy 183.402061 -141.706511) (xy 183.445436 -141.693247)
			(xy 183.48577 -141.672496) (xy 183.504078 -141.659102) (xy 183.526511 -141.642648) (xy 183.575132 -141.615617)
			(xy 183.627162 -141.595931) (xy 183.681499 -141.584009) (xy 183.736991 -141.580104) (xy 183.792463 -141.584297)
			(xy 183.846737 -141.596501) (xy 183.898665 -141.616456) (xy 183.947144 -141.64374) (xy 183.991148 -141.677774)
			(xy 184.010808 -141.697456) (xy 184.022464 -141.708867) (xy 184.050314 -141.72583) (xy 184.081555 -141.735178)
			(xy 184.114145 -141.736299) (xy 184.145955 -141.729121) (xy 184.174905 -141.714112) (xy 184.187338 -141.703552)
			(xy 184.207225 -141.686136) (xy 184.250941 -141.656414) (xy 184.298343 -141.633016) (xy 184.348523 -141.616391)
			(xy 184.400519 -141.606857) (xy 184.453333 -141.604598) (xy 184.505953 -141.609657) (xy 184.55737 -141.621937)
			(xy 184.606597 -141.641202) (xy 184.652691 -141.667083) (xy 184.674002 -141.682724) (xy 184.688033 -141.692729)
			(xy 184.72003 -141.705496) (xy 184.754277 -141.709221) (xy 184.78827 -141.703632) (xy 184.819521 -141.689138)
			(xy 184.833006 -141.678406) (xy 184.854039 -141.661206) (xy 184.900013 -141.632251) (xy 184.94963 -141.610114)
			(xy 185.001887 -141.595243) (xy 185.055726 -141.587941) (xy 185.110056 -141.588353) (xy 185.163778 -141.596472)
			(xy 185.215803 -141.612134) (xy 185.265079 -141.635022) (xy 185.310608 -141.664672) (xy 185.331354 -141.682216)
			(xy 185.342826 -141.691769) (xy 185.369221 -141.705701) (xy 185.398137 -141.7131) (xy 185.42798 -141.713559)
			(xy 185.457109 -141.707052) (xy 185.48392 -141.693938) (xy 185.495692 -141.684756) (xy 185.517655 -141.667367)
			(xy 185.565684 -141.638538) (xy 185.617412 -141.61704) (xy 185.671727 -141.603336) (xy 185.727462 -141.59772)
			(xy 185.783419 -141.600313) (xy 185.838396 -141.611059) (xy 185.891211 -141.629728) (xy 185.940729 -141.655917)
			(xy 185.985886 -141.689065) (xy 186.025712 -141.728458) (xy 186.05935 -141.773251) (xy 186.086078 -141.822481)
			(xy 186.105322 -141.875089) (xy 186.116667 -141.929946) (xy 186.11987 -141.985871) (xy 186.114862 -142.041664)
			(xy 186.101752 -142.096126) (xy 186.080819 -142.148085) (xy 186.052515 -142.196426) (xy 186.017448 -142.240109)
			(xy 185.976371 -142.278196) (xy 185.930167 -142.309868) (xy 185.879829 -142.334444) (xy 185.826438 -142.351397)
			(xy 185.771143 -142.360362) (xy 185.715131 -142.361147) (xy 185.659607 -142.353734) (xy 185.605762 -142.338283)
			(xy 185.554756 -142.315126) (xy 185.507683 -142.28476) (xy 185.486294 -142.26667) (xy 185.474786 -142.257163)
			(xy 185.448401 -142.243229) (xy 185.419495 -142.235824) (xy 185.38966 -142.235357) (xy 185.360537 -142.241853)
			(xy 185.333728 -142.254955) (xy 185.321956 -142.26413) (xy 185.299741 -142.281767) (xy 185.251055 -142.310872)
			(xy 185.198597 -142.332448) (xy 185.143523 -142.34602) (xy 185.087046 -142.351287) (xy 185.030412 -142.348136)
			(xy 184.974868 -142.336633) (xy 184.92164 -142.317034) (xy 184.8719 -142.289771) (xy 184.849008 -142.27302)
			(xy 184.834972 -142.263021) (xy 184.802978 -142.250248) (xy 184.768731 -142.246519) (xy 184.734738 -142.252108)
			(xy 184.703487 -142.266604) (xy 184.690004 -142.277338) (xy 184.66775 -142.295604) (xy 184.618765 -142.325853)
			(xy 184.56579 -142.348398) (xy 184.510029 -142.362727) (xy 184.452749 -142.368513) (xy 184.395249 -142.365626)
			(xy 184.338835 -142.354132) (xy 184.28479 -142.334291) (xy 184.23434 -142.306553) (xy 184.188631 -142.27155)
			(xy 184.168288 -142.251176) (xy 184.156635 -142.239764) (xy 184.128782 -142.22281) (xy 184.097542 -142.213468)
			(xy 184.064953 -142.212348) (xy 184.033145 -142.219523) (xy 184.004194 -142.234525) (xy 183.991758 -142.24508)
			(xy 183.970452 -142.263591) (xy 183.923478 -142.294874) (xy 183.872407 -142.318891) (xy 183.818353 -142.335117)
			(xy 183.762497 -142.343199) (xy 183.706061 -142.342958) (xy 183.650276 -142.334402) (xy 183.596362 -142.317716)
			(xy 183.545497 -142.293265) (xy 183.521858 -142.277846) (xy 183.502809 -142.26553) (xy 183.461337 -142.247165)
			(xy 183.417264 -142.23645) (xy 183.371989 -142.233726) (xy 183.326949 -142.23908) (xy 183.283574 -142.252342)
			(xy 183.243241 -142.27309) (xy 183.224932 -142.286482) (xy 183.202439 -142.303046) (xy 183.153603 -142.330157)
			(xy 183.101336 -142.349857) (xy 183.046754 -142.361724) (xy 182.991025 -142.365505) (xy 182.935341 -142.361119)
			(xy 182.880891 -142.34866) (xy 182.82884 -142.328393) (xy 182.780302 -142.300753) (xy 182.736312 -142.26633)
			(xy 182.697813 -142.22586) (xy 182.665627 -142.180208) (xy 182.640443 -142.130351) (xy 182.622798 -142.077354)
			(xy 182.61307 -142.022351) (xy 182.611467 -141.966517) (xy 175.961464 -141.966517) (xy 175.98992 -142.013728)
			(xy 176.011526 -142.065473) (xy 176.025324 -142.119823) (xy 176.031018 -142.175608) (xy 176.028486 -142.231625)
			(xy 176.01778 -142.286668) (xy 175.999133 -142.339551) (xy 175.972946 -142.389135) (xy 175.939782 -142.434352)
			(xy 175.900357 -142.474227) (xy 175.878236 -142.49146) (xy 175.859732 -142.506009) (xy 175.827973 -142.540744)
			(xy 175.803151 -142.580733) (xy 175.786117 -142.624609) (xy 175.777452 -142.670871) (xy 175.777453 -142.717937)
			(xy 175.786119 -142.764198) (xy 175.803155 -142.808073) (xy 175.827977 -142.848061) (xy 175.859738 -142.882796)
			(xy 175.878236 -142.897352) (xy 175.899704 -142.914069) (xy 175.938125 -142.952596) (xy 175.970682 -142.996191)
			(xy 175.996716 -143.043969) (xy 176.00284 -143.06042) (xy 180.179724 -143.06042) (xy 180.183795 -143.004798)
			(xy 180.195921 -142.950361) (xy 180.215844 -142.89827) (xy 180.24314 -142.849635) (xy 180.277226 -142.805492)
			(xy 180.317375 -142.766783) (xy 180.362733 -142.734332) (xy 180.412333 -142.708831) (xy 180.465117 -142.690824)
			(xy 180.51996 -142.680694) (xy 180.575694 -142.678657) (xy 180.631131 -142.684757) (xy 180.685088 -142.698863)
			(xy 180.736417 -142.720675) (xy 180.784023 -142.749729) (xy 180.826891 -142.785404) (xy 180.864108 -142.826941)
			(xy 180.894881 -142.873454) (xy 180.918553 -142.923951) (xy 180.934621 -142.977358) (xy 180.942741 -143.032534)
			(xy 180.94325 -143.06042) (xy 180.942741 -143.088306) (xy 180.934621 -143.143482) (xy 180.918553 -143.196889)
			(xy 180.894881 -143.247386) (xy 180.864108 -143.293899) (xy 180.826891 -143.335436) (xy 180.784023 -143.371111)
			(xy 180.736417 -143.400165) (xy 180.685088 -143.421977) (xy 180.631131 -143.436083) (xy 180.575694 -143.442183)
			(xy 180.51996 -143.440146) (xy 180.465117 -143.430016) (xy 180.412333 -143.412009) (xy 180.362733 -143.386508)
			(xy 180.317375 -143.354057) (xy 180.277226 -143.315348) (xy 180.24314 -143.271205) (xy 180.215844 -143.22257)
			(xy 180.195921 -143.170479) (xy 180.183795 -143.116042) (xy 180.179724 -143.06042) (xy 176.00284 -143.06042)
			(xy 176.015698 -143.09496) (xy 176.027243 -143.148132) (xy 176.031117 -143.202404) (xy 176.027242 -143.256676)
			(xy 176.015696 -143.309847) (xy 175.996713 -143.360838) (xy 175.970678 -143.408615) (xy 175.93812 -143.452209)
			(xy 175.899699 -143.490736) (xy 175.878236 -143.50746) (xy 175.859732 -143.522009) (xy 175.827973 -143.556744)
			(xy 175.803151 -143.596733) (xy 175.786117 -143.640609) (xy 175.777452 -143.686871) (xy 175.777453 -143.733937)
			(xy 175.786119 -143.780198) (xy 175.793933 -143.800322) (xy 188.599062 -143.800322) (xy 188.603133 -143.7447)
			(xy 188.615259 -143.690263) (xy 188.635182 -143.638172) (xy 188.662478 -143.589537) (xy 188.696564 -143.545394)
			(xy 188.736713 -143.506685) (xy 188.782071 -143.474234) (xy 188.831671 -143.448733) (xy 188.884455 -143.430726)
			(xy 188.939298 -143.420596) (xy 188.995032 -143.418559) (xy 189.050469 -143.424659) (xy 189.104426 -143.438765)
			(xy 189.155755 -143.460577) (xy 189.203361 -143.489631) (xy 189.246229 -143.525306) (xy 189.283446 -143.566843)
			(xy 189.314219 -143.613356) (xy 189.337891 -143.663853) (xy 189.353959 -143.71726) (xy 189.362079 -143.772436)
			(xy 189.362588 -143.800322) (xy 189.362079 -143.828208) (xy 189.353959 -143.883384) (xy 189.337891 -143.936791)
			(xy 189.314219 -143.987288) (xy 189.283446 -144.033801) (xy 189.246229 -144.075338) (xy 189.203361 -144.111013)
			(xy 189.155755 -144.140067) (xy 189.104426 -144.161879) (xy 189.050469 -144.175985) (xy 188.995032 -144.182085)
			(xy 188.939298 -144.180048) (xy 188.884455 -144.169918) (xy 188.831671 -144.151911) (xy 188.782071 -144.12641)
			(xy 188.736713 -144.093959) (xy 188.696564 -144.05525) (xy 188.662478 -144.011107) (xy 188.635182 -143.962472)
			(xy 188.615259 -143.910381) (xy 188.603133 -143.855944) (xy 188.599062 -143.800322) (xy 175.793933 -143.800322)
			(xy 175.803155 -143.824073) (xy 175.827977 -143.864061) (xy 175.859738 -143.898796) (xy 175.878236 -143.913352)
			(xy 175.899704 -143.930069) (xy 175.938125 -143.968596) (xy 175.970682 -144.012191) (xy 175.996716 -144.059969)
			(xy 176.015698 -144.11096) (xy 176.027243 -144.164132) (xy 176.031117 -144.218404) (xy 176.027242 -144.272676)
			(xy 176.015696 -144.325847) (xy 175.996713 -144.376838) (xy 175.970678 -144.424615) (xy 175.93812 -144.468209)
			(xy 175.899699 -144.506736) (xy 175.878236 -144.52346) (xy 175.859732 -144.538009) (xy 175.827973 -144.572744)
			(xy 175.803151 -144.612733) (xy 175.786117 -144.656609) (xy 175.777452 -144.702871) (xy 175.777453 -144.749937)
			(xy 175.779867 -144.762823) (xy 194.390268 -144.762823) (xy 194.392873 -144.708609) (xy 194.40314 -144.655311)
			(xy 194.420859 -144.604008) (xy 194.445674 -144.555735) (xy 194.477083 -144.511468) (xy 194.49542 -144.491456)
			(xy 194.505658 -144.479911) (xy 194.520849 -144.453065) (xy 194.529155 -144.423358) (xy 194.53009 -144.392526)
			(xy 194.523601 -144.36237) (xy 194.510065 -144.334652) (xy 194.5005 -144.322546) (xy 194.483802 -144.302007)
			(xy 194.455689 -144.257158) (xy 194.434045 -144.208853) (xy 194.419287 -144.158019) (xy 194.411699 -144.105634)
			(xy 194.411425 -144.052702) (xy 194.418472 -144.000241) (xy 194.432704 -143.949257) (xy 194.453848 -143.900731)
			(xy 194.481497 -143.855594) (xy 194.49796 -143.834866) (xy 194.511372 -143.817861) (xy 194.532788 -143.780219)
			(xy 194.547514 -143.739492) (xy 194.555124 -143.696858) (xy 194.555398 -143.653552) (xy 194.548328 -143.610825)
			(xy 194.534119 -143.569915) (xy 194.513181 -143.532005) (xy 194.499992 -143.514826) (xy 194.483439 -143.493405)
			(xy 194.455897 -143.446801) (xy 194.435221 -143.396772) (xy 194.421828 -143.344321) (xy 194.415985 -143.290503)
			(xy 194.417811 -143.2364) (xy 194.427269 -143.183099) (xy 194.444168 -143.13167) (xy 194.46817 -143.083148)
			(xy 194.498792 -143.038507) (xy 194.516756 -143.018256) (xy 194.527398 -143.005827) (xy 194.542672 -142.976907)
			(xy 194.550089 -142.945053) (xy 194.54916 -142.912361) (xy 194.539946 -142.88098) (xy 194.523054 -142.852974)
			(xy 194.511676 -142.841218) (xy 194.491864 -142.821266) (xy 194.457728 -142.776586) (xy 194.430516 -142.727382)
			(xy 194.410816 -142.674719) (xy 194.399057 -142.619735) (xy 194.39549 -142.563621) (xy 194.400195 -142.507591)
			(xy 194.413068 -142.452857) (xy 194.433832 -142.400604) (xy 194.462037 -142.351962) (xy 194.479164 -142.329662)
			(xy 194.493159 -142.311263) (xy 194.514967 -142.270509) (xy 194.529051 -142.226486) (xy 194.534948 -142.180642)
			(xy 194.532464 -142.134487) (xy 194.521679 -142.089541) (xy 194.50295 -142.047284) (xy 194.49034 -142.02791)
			(xy 194.474954 -142.004409) (xy 194.450415 -141.953884) (xy 194.433551 -141.900307) (xy 194.424724 -141.844836)
			(xy 194.424126 -141.788671) (xy 194.431771 -141.733025) (xy 194.447492 -141.679101) (xy 194.470949 -141.628066)
			(xy 194.501637 -141.581021) (xy 194.538891 -141.538985) (xy 194.581906 -141.502866) (xy 194.629752 -141.473444)
			(xy 194.681395 -141.451355) (xy 194.735719 -141.437078) (xy 194.791549 -141.430921) (xy 194.847679 -141.433016)
			(xy 194.902894 -141.44332) (xy 194.956002 -141.461607) (xy 195.005855 -141.487485) (xy 195.051374 -141.520392)
			(xy 195.091576 -141.559618) (xy 195.125592 -141.604315) (xy 195.152686 -141.653517) (xy 195.172274 -141.70616)
			(xy 195.18393 -141.761105) (xy 195.187404 -141.817166) (xy 195.18262 -141.873131) (xy 195.169682 -141.927789)
			(xy 195.14887 -141.979959) (xy 195.120632 -142.028514) (xy 195.103496 -142.05077) (xy 195.089473 -142.069148)
			(xy 195.06767 -142.109908) (xy 195.053592 -142.153936) (xy 195.0477 -142.199783) (xy 195.050189 -142.245941)
			(xy 195.060977 -142.290888) (xy 195.079708 -142.333147) (xy 195.09232 -142.352522) (xy 195.107947 -142.376314)
			(xy 195.132724 -142.427558) (xy 195.149609 -142.481915) (xy 195.158226 -142.538179) (xy 195.158385 -142.595098)
			(xy 195.150081 -142.651409) (xy 195.1335 -142.70586) (xy 195.109009 -142.757241) (xy 195.077152 -142.804412)
			(xy 195.058284 -142.825724) (xy 195.047567 -142.838092) (xy 195.032307 -142.867031) (xy 195.024906 -142.8989)
			(xy 195.02585 -142.931603) (xy 195.035077 -142.962992) (xy 195.05198 -142.991003) (xy 195.063364 -143.002762)
			(xy 195.083393 -143.022903) (xy 195.11785 -143.068058) (xy 195.145224 -143.117826) (xy 195.164911 -143.171106)
			(xy 195.176473 -143.226716) (xy 195.179656 -143.283427) (xy 195.174388 -143.339982) (xy 195.160786 -143.39513)
			(xy 195.139151 -143.447648) (xy 195.109963 -143.496375) (xy 195.09232 -143.518636) (xy 195.078907 -143.53564)
			(xy 195.057493 -143.573283) (xy 195.042768 -143.61401) (xy 195.035159 -143.656643) (xy 195.034885 -143.69995)
			(xy 195.041955 -143.742676) (xy 195.056163 -143.783586) (xy 195.0771 -143.821496) (xy 195.090288 -143.838676)
			(xy 195.107003 -143.860345) (xy 195.134767 -143.907502) (xy 195.155507 -143.958144) (xy 195.168796 -144.01123)
			(xy 195.174363 -144.06567) (xy 195.172092 -144.120346) (xy 195.16203 -144.174137) (xy 195.144385 -144.225938)
			(xy 195.119517 -144.274686) (xy 195.087939 -144.319379) (xy 195.06946 -144.339564) (xy 195.059204 -144.351094)
			(xy 195.044016 -144.377945) (xy 195.035715 -144.407655) (xy 195.034783 -144.43849) (xy 195.041276 -144.468648)
			(xy 195.054814 -144.496367) (xy 195.06438 -144.508474) (xy 195.081901 -144.529992) (xy 195.111089 -144.577187)
			(xy 195.133127 -144.628114) (xy 195.147552 -144.681698) (xy 195.154057 -144.736807) (xy 195.152507 -144.792277)
			(xy 195.142933 -144.846936) (xy 195.125537 -144.89963) (xy 195.100688 -144.949247) (xy 195.085208 -144.972278)
			(xy 195.072406 -144.991493) (xy 195.053285 -145.033516) (xy 195.042069 -145.078301) (xy 195.039126 -145.124375)
			(xy 195.044552 -145.170224) (xy 195.058171 -145.214338) (xy 195.079533 -145.255267) (xy 195.093336 -145.273776)
			(xy 195.110232 -145.296221) (xy 195.13795 -145.345083) (xy 195.158206 -145.397482) (xy 195.170561 -145.452284)
			(xy 195.174748 -145.508305) (xy 195.170677 -145.564335) (xy 195.158435 -145.619162) (xy 195.138288 -145.671602)
			(xy 195.11067 -145.720522) (xy 195.076179 -145.764864) (xy 195.035559 -145.803671) (xy 194.98969 -145.836103)
			(xy 194.939561 -145.86146) (xy 194.886256 -145.879194) (xy 194.830927 -145.888921) (xy 194.77477 -145.890432)
			(xy 194.718998 -145.883693) (xy 194.664817 -145.868851) (xy 194.613397 -145.846226) (xy 194.56585 -145.816306)
			(xy 194.523203 -145.77974) (xy 194.486378 -145.737316) (xy 194.45617 -145.689951) (xy 194.433233 -145.63867)
			(xy 194.418061 -145.58458) (xy 194.410983 -145.528851) (xy 194.412153 -145.472685) (xy 194.421543 -145.417298)
			(xy 194.438953 -145.363887) (xy 194.464005 -145.313605) (xy 194.479672 -145.290286) (xy 194.492415 -145.271034)
			(xy 194.511543 -145.229021) (xy 194.522768 -145.184245) (xy 194.525721 -145.138177) (xy 194.520304 -145.092334)
			(xy 194.506695 -145.048224) (xy 194.485343 -145.007297) (xy 194.471544 -144.988788) (xy 194.455183 -144.967131)
			(xy 194.428165 -144.920056) (xy 194.408093 -144.869626) (xy 194.395375 -144.81686) (xy 194.390268 -144.762823)
			(xy 175.779867 -144.762823) (xy 175.786119 -144.796198) (xy 175.803155 -144.840073) (xy 175.827977 -144.880061)
			(xy 175.859738 -144.914796) (xy 175.878236 -144.929352) (xy 175.899704 -144.946069) (xy 175.938125 -144.984596)
			(xy 175.970682 -145.028191) (xy 175.996716 -145.075969) (xy 176.015698 -145.12696) (xy 176.027243 -145.180132)
			(xy 176.031117 -145.234404) (xy 176.027242 -145.288676) (xy 176.015696 -145.341847) (xy 175.996713 -145.392838)
			(xy 175.970678 -145.440615) (xy 175.93812 -145.484209) (xy 175.899699 -145.522736) (xy 175.878236 -145.53946)
			(xy 175.859732 -145.554009) (xy 175.827973 -145.588744) (xy 175.803151 -145.628733) (xy 175.786117 -145.672609)
			(xy 175.777452 -145.718871) (xy 175.777453 -145.765937) (xy 175.786119 -145.812198) (xy 175.803155 -145.856073)
			(xy 175.827977 -145.896061) (xy 175.859738 -145.930796) (xy 175.878236 -145.945352) (xy 175.899704 -145.962069)
			(xy 175.938125 -146.000596) (xy 175.970682 -146.044191) (xy 175.996716 -146.091969) (xy 176.015698 -146.14296)
			(xy 176.027243 -146.196132) (xy 176.031117 -146.250404) (xy 176.027242 -146.304676) (xy 176.015696 -146.357847)
			(xy 175.996713 -146.408838) (xy 175.970678 -146.456615) (xy 175.93812 -146.500209) (xy 175.899699 -146.538736)
			(xy 175.878236 -146.55546) (xy 175.859732 -146.570009) (xy 175.827973 -146.604744) (xy 175.803151 -146.644733)
			(xy 175.786117 -146.688609) (xy 175.777452 -146.734871) (xy 175.777453 -146.781937) (xy 175.786119 -146.828198)
			(xy 175.803155 -146.872073) (xy 175.827977 -146.912061) (xy 175.859738 -146.946796) (xy 175.878236 -146.961352)
			(xy 175.899704 -146.978069) (xy 175.938125 -147.016596) (xy 175.970682 -147.060191) (xy 175.973155 -147.06473)
			(xy 180.796182 -147.06473) (xy 180.800253 -147.009108) (xy 180.812379 -146.954671) (xy 180.832302 -146.90258)
			(xy 180.859598 -146.853945) (xy 180.893684 -146.809802) (xy 180.933833 -146.771093) (xy 180.979191 -146.738642)
			(xy 181.028791 -146.713141) (xy 181.081575 -146.695134) (xy 181.136418 -146.685004) (xy 181.192152 -146.682967)
			(xy 181.247589 -146.689067) (xy 181.301546 -146.703173) (xy 181.352875 -146.724985) (xy 181.400481 -146.754039)
			(xy 181.443349 -146.789714) (xy 181.480566 -146.831251) (xy 181.511339 -146.877764) (xy 181.535011 -146.928261)
			(xy 181.551079 -146.981668) (xy 181.559199 -147.036844) (xy 181.559409 -147.048337) (xy 188.582408 -147.048337)
			(xy 188.582893 -146.992274) (xy 188.591579 -146.936885) (xy 188.608279 -146.883365) (xy 188.632633 -146.832865)
			(xy 188.664116 -146.786474) (xy 188.702051 -146.745191) (xy 188.723524 -146.727164) (xy 188.740091 -146.71316)
			(xy 188.768656 -146.680518) (xy 188.791266 -146.6435) (xy 188.807263 -146.603182) (xy 188.816182 -146.560732)
			(xy 188.817766 -146.517385) (xy 188.811967 -146.474398) (xy 188.798954 -146.43302) (xy 188.779106 -146.394451)
			(xy 188.752998 -146.359813) (xy 188.737494 -146.34464) (xy 188.716888 -146.324593) (xy 188.681371 -146.279389)
			(xy 188.653041 -146.229365) (xy 188.632541 -146.175656) (xy 188.620334 -146.119479) (xy 188.616697 -146.062105)
			(xy 188.621713 -146.004836) (xy 188.635268 -145.948969) (xy 188.657055 -145.895768) (xy 188.68658 -145.846441)
			(xy 188.704474 -145.82394) (xy 188.718345 -145.806454) (xy 188.74028 -145.767584) (xy 188.755094 -145.725482)
			(xy 188.762334 -145.681441) (xy 188.761776 -145.636813) (xy 188.753437 -145.592967) (xy 188.737575 -145.551249)
			(xy 188.714675 -145.512939) (xy 188.70041 -145.495772) (xy 188.682395 -145.474339) (xy 188.652291 -145.427132)
			(xy 188.629406 -145.376033) (xy 188.614234 -145.322139) (xy 188.607098 -145.266606) (xy 188.608154 -145.210627)
			(xy 188.617377 -145.155402) (xy 188.63457 -145.102118) (xy 188.659364 -145.051918) (xy 188.691226 -145.005879)
			(xy 188.729474 -144.96499) (xy 188.773285 -144.930127) (xy 188.82172 -144.902041) (xy 188.873739 -144.881332)
			(xy 188.928225 -144.868447) (xy 188.98401 -144.86366) (xy 189.039895 -144.867076) (xy 189.094681 -144.878621)
			(xy 189.147192 -144.898046) (xy 189.196302 -144.924935) (xy 189.240956 -144.958712) (xy 189.280195 -144.99865)
			(xy 189.313178 -145.043893) (xy 189.339197 -145.09347) (xy 189.357693 -145.146316) (xy 189.368268 -145.201297)
			(xy 189.370697 -145.257234) (xy 189.364927 -145.312925) (xy 189.351082 -145.367175) (xy 189.329459 -145.418821)
			(xy 189.300522 -145.466752) (xy 189.283086 -145.48866) (xy 189.269211 -145.506144) (xy 189.247272 -145.545013)
			(xy 189.232454 -145.587115) (xy 189.225212 -145.631158) (xy 189.225771 -145.675788) (xy 189.234111 -145.719635)
			(xy 189.249977 -145.761354) (xy 189.272882 -145.799662) (xy 189.28715 -145.816828) (xy 189.304943 -145.838232)
			(xy 189.334886 -145.885147) (xy 189.357696 -145.935915) (xy 189.372887 -145.989457) (xy 189.380139 -146.044639)
			(xy 189.379297 -146.100289) (xy 189.37038 -146.155226) (xy 189.353575 -146.208285) (xy 189.329241 -146.258339)
			(xy 189.326563 -146.262267) (xy 195.414448 -146.262267) (xy 195.415697 -146.206627) (xy 195.425019 -146.15176)
			(xy 195.442216 -146.09883) (xy 195.466923 -146.048961) (xy 195.498614 -146.003212) (xy 195.536617 -145.962555)
			(xy 195.580126 -145.927851) (xy 195.628216 -145.899839) (xy 195.679866 -145.879114) (xy 195.73398 -145.866114)
			(xy 195.789408 -145.861116) (xy 195.844975 -145.864227) (xy 195.899499 -145.87538) (xy 195.951824 -145.894338)
			(xy 196.000838 -145.9207) (xy 196.045501 -145.953904) (xy 196.084864 -145.993247) (xy 196.118092 -146.037892)
			(xy 196.144479 -146.086892) (xy 196.163465 -146.139207) (xy 196.174647 -146.193726) (xy 196.177787 -146.249291)
			(xy 196.172819 -146.304722) (xy 196.159847 -146.358843) (xy 196.139149 -146.410504) (xy 196.125592 -146.43481)
			(xy 196.114748 -146.454436) (xy 196.099308 -146.496527) (xy 196.091502 -146.540675) (xy 196.091571 -146.585508)
			(xy 196.099514 -146.629632) (xy 196.115084 -146.671675) (xy 196.137796 -146.71033) (xy 196.152008 -146.727672)
			(xy 196.169641 -146.749198) (xy 196.199231 -146.796317) (xy 196.221659 -146.847237) (xy 196.23645 -146.900875)
			(xy 196.24329 -146.956094) (xy 196.242032 -147.01172) (xy 196.232705 -147.066573) (xy 196.215505 -147.119488)
			(xy 196.190799 -147.169342) (xy 196.15911 -147.215077) (xy 196.121112 -147.255721) (xy 196.077611 -147.290413)
			(xy 196.02953 -147.318414) (xy 195.97789 -147.339131) (xy 195.923788 -147.352125) (xy 195.868372 -147.357118)
			(xy 195.812819 -147.354006) (xy 195.758308 -147.342854) (xy 195.705996 -147.323899) (xy 195.656994 -147.297543)
			(xy 195.612342 -147.264346) (xy 195.572987 -147.225013) (xy 195.539767 -147.180378) (xy 195.513385 -147.13139)
			(xy 195.494402 -147.079088) (xy 195.48322 -147.024583) (xy 195.480078 -146.969032) (xy 195.485042 -146.913613)
			(xy 195.498007 -146.859504) (xy 195.518696 -146.807854) (xy 195.532248 -146.783552) (xy 195.543123 -146.763943)
			(xy 195.558556 -146.721847) (xy 195.566356 -146.677695) (xy 195.566281 -146.632859) (xy 195.558334 -146.588733)
			(xy 195.54276 -146.546689) (xy 195.520045 -146.508033) (xy 195.505832 -146.49069) (xy 195.488148 -146.469199)
			(xy 195.458543 -146.422073) (xy 195.4361 -146.371146) (xy 195.421297 -146.317497) (xy 195.414448 -146.262267)
			(xy 189.326563 -146.262267) (xy 189.297892 -146.304327) (xy 189.260195 -146.345273) (xy 189.23889 -146.363182)
			(xy 189.222279 -146.377136) (xy 189.193711 -146.409785) (xy 189.171102 -146.44681) (xy 189.155107 -146.487137)
			(xy 189.146191 -146.529593) (xy 189.144612 -146.572947) (xy 189.150417 -146.61594) (xy 189.163437 -146.657322)
			(xy 189.183294 -146.695894) (xy 189.209412 -146.730534) (xy 189.22492 -146.745706) (xy 189.245 -146.765273)
			(xy 189.279782 -146.809245) (xy 189.307753 -146.857835) (xy 189.32831 -146.909995) (xy 189.34101 -146.964603)
			(xy 189.345581 -147.020482) (xy 189.341923 -147.076428) (xy 189.330116 -147.131236) (xy 189.310413 -147.183725)
			(xy 189.283239 -147.232765) (xy 189.24918 -147.277299) (xy 189.208969 -147.316369) (xy 189.163472 -147.349131)
			(xy 189.11367 -147.374881) (xy 189.060635 -147.393064) (xy 189.005509 -147.403288) (xy 188.949481 -147.405333)
			(xy 188.893757 -147.399155) (xy 188.839538 -147.384886) (xy 188.787991 -147.362836) (xy 188.740227 -147.333477)
			(xy 188.697275 -147.297443) (xy 188.66006 -147.25551) (xy 188.629383 -147.208582) (xy 188.605906 -147.157669)
			(xy 188.590135 -147.103867) (xy 188.582408 -147.048337) (xy 181.559409 -147.048337) (xy 181.559708 -147.06473)
			(xy 181.559199 -147.092616) (xy 181.551079 -147.147792) (xy 181.535011 -147.201199) (xy 181.511339 -147.251696)
			(xy 181.480566 -147.298209) (xy 181.443349 -147.339746) (xy 181.400481 -147.375421) (xy 181.352875 -147.404475)
			(xy 181.301546 -147.426287) (xy 181.247589 -147.440393) (xy 181.192152 -147.446493) (xy 181.136418 -147.444456)
			(xy 181.081575 -147.434326) (xy 181.028791 -147.416319) (xy 180.979191 -147.390818) (xy 180.933833 -147.358367)
			(xy 180.893684 -147.319658) (xy 180.859598 -147.275515) (xy 180.832302 -147.22688) (xy 180.812379 -147.174789)
			(xy 180.800253 -147.120352) (xy 180.796182 -147.06473) (xy 175.973155 -147.06473) (xy 175.996716 -147.107969)
			(xy 176.015698 -147.15896) (xy 176.027243 -147.212132) (xy 176.031117 -147.266404) (xy 176.027242 -147.320676)
			(xy 176.015696 -147.373847) (xy 175.996713 -147.424838) (xy 175.970678 -147.472615) (xy 175.93812 -147.516209)
			(xy 175.899699 -147.554736) (xy 175.878236 -147.57146) (xy 175.859732 -147.586009) (xy 175.827973 -147.620744)
			(xy 175.803151 -147.660733) (xy 175.786117 -147.704609) (xy 175.777452 -147.750871) (xy 175.777453 -147.797937)
			(xy 175.786119 -147.844198) (xy 175.803155 -147.888073) (xy 175.827977 -147.928061) (xy 175.859738 -147.962796)
			(xy 175.878236 -147.977352) (xy 175.899704 -147.994069) (xy 175.938125 -148.032596) (xy 175.970682 -148.076191)
			(xy 175.978276 -148.090128) (xy 180.768242 -148.090128) (xy 180.772313 -148.034506) (xy 180.784439 -147.980069)
			(xy 180.804362 -147.927978) (xy 180.831658 -147.879343) (xy 180.865744 -147.8352) (xy 180.905893 -147.796491)
			(xy 180.951251 -147.76404) (xy 181.000851 -147.738539) (xy 181.053635 -147.720532) (xy 181.108478 -147.710402)
			(xy 181.164212 -147.708365) (xy 181.219649 -147.714465) (xy 181.273606 -147.728571) (xy 181.324935 -147.750383)
			(xy 181.372541 -147.779437) (xy 181.415409 -147.815112) (xy 181.452626 -147.856649) (xy 181.483399 -147.903162)
			(xy 181.49384 -147.925435) (xy 189.47325 -147.925435) (xy 189.474909 -147.869549) (xy 189.484709 -147.814503)
			(xy 189.502438 -147.761478) (xy 189.527717 -147.711608) (xy 189.560005 -147.665962) (xy 189.598609 -147.625518)
			(xy 189.642704 -147.591142) (xy 189.691344 -147.563571) (xy 189.743488 -147.543395) (xy 189.798018 -147.531046)
			(xy 189.853766 -147.526789) (xy 189.909539 -147.530715) (xy 189.964142 -147.54274) (xy 190.016404 -147.562606)
			(xy 190.065207 -147.589889) (xy 190.109505 -147.624002) (xy 190.148349 -147.664216) (xy 190.180907 -147.709669)
			(xy 190.206482 -147.759388) (xy 190.224525 -147.812308) (xy 190.234651 -147.867294) (xy 190.236642 -147.92317)
			(xy 190.230456 -147.978737) (xy 190.216225 -148.032807) (xy 190.194254 -148.08422) (xy 190.188291 -148.093938)
			(xy 190.557402 -148.093938) (xy 190.561473 -148.038316) (xy 190.573599 -147.983879) (xy 190.593522 -147.931788)
			(xy 190.620818 -147.883153) (xy 190.654904 -147.83901) (xy 190.695053 -147.800301) (xy 190.740411 -147.76785)
			(xy 190.790011 -147.742349) (xy 190.842795 -147.724342) (xy 190.897638 -147.714212) (xy 190.953372 -147.712175)
			(xy 191.008809 -147.718275) (xy 191.062766 -147.732381) (xy 191.114095 -147.754193) (xy 191.161701 -147.783247)
			(xy 191.204569 -147.818922) (xy 191.241786 -147.860459) (xy 191.272559 -147.906972) (xy 191.296231 -147.957469)
			(xy 191.312299 -148.010876) (xy 191.320419 -148.066052) (xy 191.320928 -148.093938) (xy 191.320419 -148.121824)
			(xy 191.312299 -148.177) (xy 191.296231 -148.230407) (xy 191.272559 -148.280904) (xy 191.241786 -148.327417)
			(xy 191.214461 -148.357914) (xy 195.3782 -148.357914) (xy 195.381125 -148.301801) (xy 195.392246 -148.246724)
			(xy 195.411322 -148.193873) (xy 195.437941 -148.144389) (xy 195.471527 -148.099343) (xy 195.511356 -148.059709)
			(xy 195.556565 -148.026343) (xy 195.606178 -147.999965) (xy 195.659122 -147.981147) (xy 195.714253 -147.970296)
			(xy 195.770379 -147.967644) (xy 195.826287 -147.973251) (xy 195.880769 -147.986995) (xy 195.932647 -148.008578)
			(xy 195.9808 -148.037534) (xy 196.024187 -148.073238) (xy 196.061871 -148.114917) (xy 196.093036 -148.161671)
			(xy 196.117009 -148.212489) (xy 196.133272 -148.266273) (xy 196.141473 -148.32186) (xy 196.141436 -148.378048)
			(xy 196.13316 -148.433624) (xy 196.116826 -148.487386) (xy 196.092785 -148.538173) (xy 196.077586 -148.561806)
			(xy 196.065166 -148.581291) (xy 196.046882 -148.623722) (xy 196.036562 -148.668758) (xy 196.034548 -148.714918)
			(xy 196.040904 -148.760682) (xy 196.055422 -148.804545) (xy 196.077624 -148.845064) (xy 196.09181 -148.863304)
			(xy 196.109124 -148.885427) (xy 196.137829 -148.933714) (xy 196.159143 -148.985688) (xy 196.172608 -149.040226)
			(xy 196.177932 -149.096148) (xy 196.174999 -149.152246) (xy 196.163873 -149.207308) (xy 196.144794 -149.260144)
			(xy 196.118176 -149.309612) (xy 196.084592 -149.354643) (xy 196.04477 -149.394263) (xy 195.999569 -149.427617)
			(xy 195.949966 -149.453983) (xy 195.897033 -149.472792) (xy 195.841915 -149.483638) (xy 195.785803 -149.486285)
			(xy 195.729909 -149.480677) (xy 195.675441 -149.466935) (xy 195.623576 -149.445356) (xy 195.575435 -149.416406)
			(xy 195.532059 -149.38071) (xy 195.494386 -149.339042) (xy 195.463228 -149.2923) (xy 195.43926 -149.241495)
			(xy 195.422999 -149.187725) (xy 195.414798 -149.132152) (xy 195.414833 -149.075977) (xy 195.423103 -149.020414)
			(xy 195.43943 -148.966664) (xy 195.463461 -148.915889) (xy 195.478654 -148.89226) (xy 195.491017 -148.87274)
			(xy 195.509312 -148.830319) (xy 195.519642 -148.785291) (xy 195.521667 -148.739137) (xy 195.515319 -148.693377)
			(xy 195.500809 -148.649517) (xy 195.478613 -148.609001) (xy 195.46443 -148.590762) (xy 195.447062 -148.568674)
			(xy 195.418341 -148.52038) (xy 195.397011 -148.468398) (xy 195.383534 -148.413849) (xy 195.3782 -148.357914)
			(xy 191.214461 -148.357914) (xy 191.204569 -148.368954) (xy 191.161701 -148.404629) (xy 191.114095 -148.433683)
			(xy 191.062766 -148.455495) (xy 191.008809 -148.469601) (xy 190.953372 -148.475701) (xy 190.897638 -148.473664)
			(xy 190.842795 -148.463534) (xy 190.790011 -148.445527) (xy 190.740411 -148.420026) (xy 190.695053 -148.387575)
			(xy 190.654904 -148.348866) (xy 190.620818 -148.304723) (xy 190.593522 -148.256088) (xy 190.573599 -148.203997)
			(xy 190.561473 -148.14956) (xy 190.557402 -148.093938) (xy 190.188291 -148.093938) (xy 190.165014 -148.131875)
			(xy 190.147448 -148.153628) (xy 190.133486 -148.170963) (xy 190.111293 -148.209544) (xy 190.096158 -148.251401)
			(xy 190.088546 -148.295254) (xy 190.088688 -148.339763) (xy 190.09658 -148.383566) (xy 190.111981 -148.425326)
			(xy 190.13442 -148.463764) (xy 190.148464 -148.481034) (xy 190.166209 -148.502651) (xy 190.195752 -148.55014)
			(xy 190.218047 -148.601433) (xy 190.232616 -148.65543) (xy 190.239146 -148.710976) (xy 190.237498 -148.766881)
			(xy 190.227707 -148.821946) (xy 190.209983 -148.874991) (xy 190.184706 -148.924882) (xy 190.152417 -148.970548)
			(xy 190.113807 -149.011011) (xy 190.069704 -149.045405) (xy 190.021053 -149.072993) (xy 189.968897 -149.093184)
			(xy 189.914351 -149.105544) (xy 189.858585 -149.109811) (xy 189.802794 -149.105891) (xy 189.748173 -149.093869)
			(xy 189.695892 -149.074002) (xy 189.647071 -149.046717) (xy 189.602756 -149.012597) (xy 189.563896 -148.972374)
			(xy 189.531324 -148.926909) (xy 189.505737 -148.877176) (xy 189.487684 -148.824241) (xy 189.477552 -148.769238)
			(xy 189.475557 -148.713345) (xy 189.481743 -148.65776) (xy 189.495976 -148.603673) (xy 189.517952 -148.552243)
			(xy 189.547201 -148.504572) (xy 189.564772 -148.482812) (xy 189.578694 -148.465446) (xy 189.600888 -148.426872)
			(xy 189.616025 -148.385021) (xy 189.623641 -148.341174) (xy 189.623505 -148.29667) (xy 189.615619 -148.252871)
			(xy 189.600226 -148.211114) (xy 189.577796 -148.172676) (xy 189.563756 -148.155406) (xy 189.546115 -148.133712)
			(xy 189.516593 -148.086231) (xy 189.494317 -148.034949) (xy 189.479766 -147.980965) (xy 189.47325 -147.925435)
			(xy 181.49384 -147.925435) (xy 181.507071 -147.953659) (xy 181.523139 -148.007066) (xy 181.531259 -148.062242)
			(xy 181.531768 -148.090128) (xy 181.531259 -148.118014) (xy 181.523139 -148.17319) (xy 181.507071 -148.226597)
			(xy 181.483399 -148.277094) (xy 181.452626 -148.323607) (xy 181.415409 -148.365144) (xy 181.372541 -148.400819)
			(xy 181.324935 -148.429873) (xy 181.273606 -148.451685) (xy 181.219649 -148.465791) (xy 181.164212 -148.471891)
			(xy 181.108478 -148.469854) (xy 181.053635 -148.459724) (xy 181.000851 -148.441717) (xy 180.951251 -148.416216)
			(xy 180.905893 -148.383765) (xy 180.865744 -148.345056) (xy 180.831658 -148.300913) (xy 180.804362 -148.252278)
			(xy 180.784439 -148.200187) (xy 180.772313 -148.14575) (xy 180.768242 -148.090128) (xy 175.978276 -148.090128)
			(xy 175.996716 -148.123969) (xy 176.015698 -148.17496) (xy 176.027243 -148.228132) (xy 176.031117 -148.282404)
			(xy 176.027242 -148.336676) (xy 176.015696 -148.389847) (xy 175.996713 -148.440838) (xy 175.970678 -148.488615)
			(xy 175.93812 -148.532209) (xy 175.899699 -148.570736) (xy 175.878236 -148.58746) (xy 175.859732 -148.602009)
			(xy 175.827973 -148.636744) (xy 175.803151 -148.676733) (xy 175.786117 -148.720609) (xy 175.777452 -148.766871)
			(xy 175.777453 -148.813937) (xy 175.786119 -148.860198) (xy 175.803155 -148.904073) (xy 175.827977 -148.944061)
			(xy 175.859738 -148.978796) (xy 175.878236 -148.993352) (xy 175.900357 -149.010585) (xy 175.939782 -149.05046)
			(xy 175.972946 -149.095677) (xy 175.999133 -149.145261) (xy 176.01778 -149.198144) (xy 176.028486 -149.253187)
			(xy 176.031018 -149.309204) (xy 176.025324 -149.364989) (xy 176.011526 -149.419339) (xy 175.98992 -149.471084)
			(xy 175.960973 -149.519109) (xy 175.925307 -149.56238) (xy 175.883692 -149.599963) (xy 175.837023 -149.63105)
			(xy 175.786307 -149.654971) (xy 175.732636 -149.671211) (xy 175.677165 -149.679419) (xy 175.621091 -149.679419)
			(xy 175.56562 -149.671211) (xy 175.511949 -149.654971) (xy 175.461233 -149.63105) (xy 175.414564 -149.599963)
			(xy 175.372949 -149.56238) (xy 175.337283 -149.519109) (xy 175.308336 -149.471084) (xy 175.28673 -149.419339)
			(xy 175.272932 -149.364989) (xy 175.267238 -149.309204) (xy 175.26977 -149.253187) (xy 175.280476 -149.198144)
			(xy 175.299123 -149.145261) (xy 175.32531 -149.095677) (xy 175.358474 -149.05046) (xy 175.397899 -149.010585)
			(xy 175.42002 -148.993352) (xy 175.438515 -148.97879) (xy 175.470279 -148.944059) (xy 175.495105 -148.904073)
			(xy 175.512143 -148.860198) (xy 175.520811 -148.813937) (xy 175.520812 -148.76687) (xy 175.512145 -148.720609)
			(xy 175.495108 -148.676734) (xy 175.470284 -148.636747) (xy 175.43852 -148.602014) (xy 175.42002 -148.58746)
			(xy 175.398561 -148.57073) (xy 175.360136 -148.532207) (xy 175.327574 -148.488615) (xy 175.301536 -148.440839)
			(xy 175.28255 -148.389848) (xy 175.271002 -148.336676) (xy 175.267127 -148.282404) (xy 169.63898 -148.282404)
			(xy 169.63898 -150.060152) (xy 176.300382 -150.060152) (xy 176.304453 -150.00453) (xy 176.316579 -149.950093)
			(xy 176.336502 -149.898002) (xy 176.363798 -149.849367) (xy 176.397884 -149.805224) (xy 176.438033 -149.766515)
			(xy 176.483391 -149.734064) (xy 176.532991 -149.708563) (xy 176.585775 -149.690556) (xy 176.640618 -149.680426)
			(xy 176.696352 -149.678389) (xy 176.751789 -149.684489) (xy 176.805746 -149.698595) (xy 176.857075 -149.720407)
			(xy 176.904681 -149.749461) (xy 176.947549 -149.785136) (xy 176.984766 -149.826673) (xy 177.015539 -149.873186)
			(xy 177.039211 -149.923683) (xy 177.055279 -149.97709) (xy 177.063399 -150.032266) (xy 177.063908 -150.060152)
			(xy 177.063399 -150.088038) (xy 177.055279 -150.143214) (xy 177.039211 -150.196621) (xy 177.015539 -150.247118)
			(xy 176.984766 -150.293631) (xy 176.947549 -150.335168) (xy 176.904681 -150.370843) (xy 176.857075 -150.399897)
			(xy 176.805746 -150.421709) (xy 176.751789 -150.435815) (xy 176.696352 -150.441915) (xy 176.640618 -150.439878)
			(xy 176.585775 -150.429748) (xy 176.532991 -150.411741) (xy 176.483391 -150.38624) (xy 176.438033 -150.353789)
			(xy 176.397884 -150.31508) (xy 176.363798 -150.270937) (xy 176.336502 -150.222302) (xy 176.316579 -150.170211)
			(xy 176.304453 -150.115774) (xy 176.300382 -150.060152) (xy 169.63898 -150.060152) (xy 169.63898 -150.647654)
			(xy 180.653942 -150.647654) (xy 180.658013 -150.592032) (xy 180.670139 -150.537595) (xy 180.690062 -150.485504)
			(xy 180.717358 -150.436869) (xy 180.751444 -150.392726) (xy 180.791593 -150.354017) (xy 180.836951 -150.321566)
			(xy 180.886551 -150.296065) (xy 180.939335 -150.278058) (xy 180.994178 -150.267928) (xy 181.049912 -150.265891)
			(xy 181.105349 -150.271991) (xy 181.159306 -150.286097) (xy 181.210635 -150.307909) (xy 181.258241 -150.336963)
			(xy 181.301109 -150.372638) (xy 181.338326 -150.414175) (xy 181.369099 -150.460688) (xy 181.392771 -150.511185)
			(xy 181.408839 -150.564592) (xy 181.416959 -150.619768) (xy 181.417468 -150.647654) (xy 181.416959 -150.67554)
			(xy 181.408839 -150.730716) (xy 181.392771 -150.784123) (xy 181.369099 -150.83462) (xy 181.338326 -150.881133)
			(xy 181.301109 -150.92267) (xy 181.258241 -150.958345) (xy 181.210635 -150.987399) (xy 181.159306 -151.009211)
			(xy 181.105349 -151.023317) (xy 181.049912 -151.029417) (xy 180.994178 -151.02738) (xy 180.939335 -151.01725)
			(xy 180.886551 -150.999243) (xy 180.836951 -150.973742) (xy 180.791593 -150.941291) (xy 180.751444 -150.902582)
			(xy 180.717358 -150.858439) (xy 180.690062 -150.809804) (xy 180.670139 -150.757713) (xy 180.658013 -150.703276)
			(xy 180.653942 -150.647654) (xy 169.63898 -150.647654) (xy 169.63898 -154.997912) (xy 169.813986 -155.172918)
			(xy 169.831118 -155.189328) (xy 169.870279 -155.216096) (xy 169.913727 -155.235132) (xy 169.959952 -155.245775)
			(xy 170.00735 -155.247656) (xy 170.054274 -155.240709) (xy 170.099093 -155.225176) (xy 170.140252 -155.201596)
			(xy 170.158664 -155.186634) (xy 170.179418 -155.167959) (xy 170.225375 -155.136255) (xy 170.27546 -155.111587)
			(xy 170.328606 -155.094481) (xy 170.383677 -155.085301) (xy 170.439498 -155.084245) (xy 170.494877 -155.091333)
			(xy 170.548632 -155.106416) (xy 170.599616 -155.129172) (xy 170.646739 -155.159113) (xy 170.688996 -155.195602)
			(xy 170.725485 -155.237859) (xy 170.755427 -155.284982) (xy 170.778183 -155.335965) (xy 170.793266 -155.38972)
			(xy 170.800355 -155.445099) (xy 170.799299 -155.50092) (xy 170.79012 -155.555991) (xy 170.773014 -155.609137)
			(xy 170.748346 -155.659223) (xy 170.716643 -155.705179) (xy 170.697906 -155.725876) (xy 170.682924 -155.744267)
			(xy 170.65938 -155.78544) (xy 170.643873 -155.830263) (xy 170.636942 -155.877183) (xy 170.638827 -155.924576)
			(xy 170.649461 -155.970798) (xy 170.668477 -156.014248) (xy 170.695216 -156.053422) (xy 170.711622 -156.070554)
			(xy 171.99356 -157.352492) (xy 180.382164 -157.352492)
		)
		(stroke
			(width 0)
			(type solid)
		)
		(fill yes)
		(layer "In7.Cu")
		(net "P5V_NODE1")
	)
	(gr_line
		(start -18.237962 -206.70012)
		(end -18.237962 -1.999996)
		(stroke
			(width 1.016)
			(type default)
		)
		(layer "In8.Cu")
	)
	(gr_arc
		(start -18.237962 -206.70012)
		(mid -17.652177 -208.114331)
		(end -16.237966 -208.700116)
		(stroke
			(width 1.016)
			(type default)
		)
		(layer "In8.Cu")
	)
	(gr_arc
		(start -16.237966 0)
		(mid -17.652177 -0.585785)
		(end -18.237962 -1.999996)
		(stroke
			(width 1.016)
			(type default)
		)
		(layer "In8.Cu")
	)
	(gr_line
		(start -16.237966 0)
		(end -1.999996 0)
		(stroke
			(width 1.016)
			(type default)
		)
		(layer "In8.Cu")
	)
	(gr_line
		(start -1.999996 -160.375092)
		(end -1.999742 -160.375092)
		(stroke
			(width 1.016)
			(type default)
		)
		(layer "In8.Cu")
	)
	(gr_line
		(start -1.999996 0)
		(end -1.999996 -160.375092)
		(stroke
			(width 1.016)
			(type default)
		)
		(layer "In8.Cu")
	)
	(gr_line
		(start -1.999742 -208.700116)
		(end -16.237966 -208.700116)
		(stroke
			(width 1.016)
			(type default)
		)
		(layer "In8.Cu")
	)
	(gr_line
		(start -1.999742 -160.375092)
		(end -1.999742 -208.700116)
		(stroke
			(width 1.016)
			(type default)
		)
		(layer "In8.Cu")
	)
	(gr_arc
		(start 0 -168.699942)
		(mid 0.585785 -170.114153)
		(end 1.999996 -170.699938)
		(stroke
			(width 1.016)
			(type default)
		)
		(layer "In8.Cu")
	)
	(gr_line
		(start 0 -72.300084)
		(end 0 -168.699942)
		(stroke
			(width 1.016)
			(type default)
		)
		(layer "In8.Cu")
	)
	(gr_line
		(start 0 -29.299916)
		(end 0 -1.999996)
		(stroke
			(width 1.016)
			(type default)
		)
		(layer "In8.Cu")
	)
	(gr_arc
		(start 0 -29.299916)
		(mid 0.439376 -30.360664)
		(end 1.500124 -30.80004)
		(stroke
			(width 1.016)
			(type default)
		)
		(layer "In8.Cu")
	)
	(gr_poly
		(pts
			(xy -2.634742 -208.192116) (xy -2.618087 -208.191622) (xy -2.585913 -208.183001) (xy -2.557066 -208.166346)
			(xy -2.533512 -208.142792) (xy -2.516857 -208.113945) (xy -2.508236 -208.081771) (xy -2.507742 -208.065116)
			(xy -2.507742 -160.883092) (xy -2.507996 -160.883092) (xy -2.507996 -0.635) (xy -2.50849 -0.618345)
			(xy -2.517111 -0.586171) (xy -2.533766 -0.557324) (xy -2.55732 -0.53377) (xy -2.586167 -0.517115)
			(xy -2.618341 -0.508494) (xy -2.634996 -0.508) (xy -16.237966 -0.508) (xy -16.293773 -0.508522) (xy -16.405075 -0.516863)
			(xy -16.515442 -0.533498) (xy -16.624258 -0.558335) (xy -16.730913 -0.591234) (xy -16.834812 -0.632011)
			(xy -16.935372 -0.680438) (xy -17.032033 -0.736246) (xy -17.124253 -0.79912) (xy -17.211516 -0.86871)
			(xy -17.293335 -0.944627) (xy -17.369252 -1.026446) (xy -17.438842 -1.113709) (xy -17.501716 -1.205929)
			(xy -17.557524 -1.30259) (xy -17.605951 -1.40315) (xy -17.646728 -1.507049) (xy -17.679627 -1.613704)
			(xy -17.704464 -1.72252) (xy -17.721099 -1.832887) (xy -17.72944 -1.944189) (xy -17.729962 -1.999996)
			(xy -17.729962 -31.846463) (xy -12.286746 -31.846463) (xy -12.286746 -31.761741) (xy -12.278693 -31.677404)
			(xy -12.262659 -31.594214) (xy -12.238791 -31.512924) (xy -12.207303 -31.434272) (xy -12.168481 -31.358969)
			(xy -12.122678 -31.287697) (xy -12.070307 -31.221101) (xy -12.011842 -31.159786) (xy -11.947814 -31.104305)
			(xy -11.878802 -31.055162) (xy -11.805432 -31.012802) (xy -11.728367 -30.977607) (xy -11.648305 -30.949898)
			(xy -11.565972 -30.929924) (xy -11.482113 -30.917867) (xy -11.397488 -30.913836) (xy -11.312863 -30.917867)
			(xy -11.229004 -30.929924) (xy -11.146671 -30.949898) (xy -11.066609 -30.977607) (xy -10.989544 -31.012802)
			(xy -10.916174 -31.055162) (xy -10.847162 -31.104305) (xy -10.783134 -31.159786) (xy -10.724669 -31.221101)
			(xy -10.672298 -31.287697) (xy -10.626495 -31.358969) (xy -10.587673 -31.434272) (xy -10.556185 -31.512924)
			(xy -10.532317 -31.594214) (xy -10.516283 -31.677404) (xy -10.50823 -31.761741) (xy -10.507726 -31.804102)
			(xy -10.50823 -31.846463) (xy -7.714746 -31.846463) (xy -7.714746 -31.761741) (xy -7.706693 -31.677404)
			(xy -7.690659 -31.594214) (xy -7.666791 -31.512924) (xy -7.635303 -31.434272) (xy -7.596481 -31.358969)
			(xy -7.550678 -31.287697) (xy -7.498307 -31.221101) (xy -7.439842 -31.159786) (xy -7.375814 -31.104305)
			(xy -7.306802 -31.055162) (xy -7.233432 -31.012802) (xy -7.156367 -30.977607) (xy -7.076305 -30.949898)
			(xy -6.993972 -30.929924) (xy -6.910113 -30.917867) (xy -6.825488 -30.913836) (xy -6.740863 -30.917867)
			(xy -6.657004 -30.929924) (xy -6.574671 -30.949898) (xy -6.494609 -30.977607) (xy -6.417544 -31.012802)
			(xy -6.344174 -31.055162) (xy -6.275162 -31.104305) (xy -6.211134 -31.159786) (xy -6.152669 -31.221101)
			(xy -6.100298 -31.287697) (xy -6.054495 -31.358969) (xy -6.015673 -31.434272) (xy -5.984185 -31.512924)
			(xy -5.960317 -31.594214) (xy -5.944283 -31.677404) (xy -5.93623 -31.761741) (xy -5.935726 -31.804102)
			(xy -5.93623 -31.846463) (xy -5.944283 -31.9308) (xy -5.960317 -32.01399) (xy -5.984185 -32.09528)
			(xy -6.015673 -32.173932) (xy -6.054495 -32.249235) (xy -6.100298 -32.320507) (xy -6.152669 -32.387103)
			(xy -6.211134 -32.448418) (xy -6.275162 -32.503899) (xy -6.344174 -32.553042) (xy -6.417544 -32.595402)
			(xy -6.494609 -32.630597) (xy -6.574671 -32.658306) (xy -6.657004 -32.67828) (xy -6.740863 -32.690337)
			(xy -6.825488 -32.694369) (xy -6.910113 -32.690337) (xy -6.993972 -32.67828) (xy -7.076305 -32.658306)
			(xy -7.156367 -32.630597) (xy -7.233432 -32.595402) (xy -7.306802 -32.553042) (xy -7.375814 -32.503899)
			(xy -7.439842 -32.448418) (xy -7.498307 -32.387103) (xy -7.550678 -32.320507) (xy -7.596481 -32.249235)
			(xy -7.635303 -32.173932) (xy -7.666791 -32.09528) (xy -7.690659 -32.01399) (xy -7.706693 -31.9308)
			(xy -7.714746 -31.846463) (xy -10.50823 -31.846463) (xy -10.516283 -31.9308) (xy -10.532317 -32.01399)
			(xy -10.556185 -32.09528) (xy -10.587673 -32.173932) (xy -10.626495 -32.249235) (xy -10.672298 -32.320507)
			(xy -10.724669 -32.387103) (xy -10.783134 -32.448418) (xy -10.847162 -32.503899) (xy -10.916174 -32.553042)
			(xy -10.989544 -32.595402) (xy -11.066609 -32.630597) (xy -11.146671 -32.658306) (xy -11.229004 -32.67828)
			(xy -11.312863 -32.690337) (xy -11.397488 -32.694369) (xy -11.482113 -32.690337) (xy -11.565972 -32.67828)
			(xy -11.648305 -32.658306) (xy -11.728367 -32.630597) (xy -11.805432 -32.595402) (xy -11.878802 -32.553042)
			(xy -11.947814 -32.503899) (xy -12.011842 -32.448418) (xy -12.070307 -32.387103) (xy -12.122678 -32.320507)
			(xy -12.168481 -32.249235) (xy -12.207303 -32.173932) (xy -12.238791 -32.09528) (xy -12.262659 -32.01399)
			(xy -12.278693 -31.9308) (xy -12.286746 -31.846463) (xy -17.729962 -31.846463) (xy -17.729962 -35.910463)
			(xy -12.286746 -35.910463) (xy -12.286746 -35.825741) (xy -12.278693 -35.741404) (xy -12.262659 -35.658214)
			(xy -12.238791 -35.576924) (xy -12.207303 -35.498272) (xy -12.168481 -35.422969) (xy -12.122678 -35.351697)
			(xy -12.070307 -35.285101) (xy -12.011842 -35.223786) (xy -11.947814 -35.168305) (xy -11.878802 -35.119162)
			(xy -11.805432 -35.076802) (xy -11.728367 -35.041607) (xy -11.648305 -35.013898) (xy -11.565972 -34.993924)
			(xy -11.482113 -34.981867) (xy -11.397488 -34.977836) (xy -11.312863 -34.981867) (xy -11.229004 -34.993924)
			(xy -11.146671 -35.013898) (xy -11.066609 -35.041607) (xy -10.989544 -35.076802) (xy -10.916174 -35.119162)
			(xy -10.847162 -35.168305) (xy -10.783134 -35.223786) (xy -10.724669 -35.285101) (xy -10.672298 -35.351697)
			(xy -10.626495 -35.422969) (xy -10.587673 -35.498272) (xy -10.556185 -35.576924) (xy -10.532317 -35.658214)
			(xy -10.516283 -35.741404) (xy -10.50823 -35.825741) (xy -10.507726 -35.868102) (xy -10.50823 -35.910463)
			(xy -7.714746 -35.910463) (xy -7.714746 -35.825741) (xy -7.706693 -35.741404) (xy -7.690659 -35.658214)
			(xy -7.666791 -35.576924) (xy -7.635303 -35.498272) (xy -7.596481 -35.422969) (xy -7.550678 -35.351697)
			(xy -7.498307 -35.285101) (xy -7.439842 -35.223786) (xy -7.375814 -35.168305) (xy -7.306802 -35.119162)
			(xy -7.233432 -35.076802) (xy -7.156367 -35.041607) (xy -7.076305 -35.013898) (xy -6.993972 -34.993924)
			(xy -6.910113 -34.981867) (xy -6.825488 -34.977836) (xy -6.740863 -34.981867) (xy -6.657004 -34.993924)
			(xy -6.574671 -35.013898) (xy -6.494609 -35.041607) (xy -6.417544 -35.076802) (xy -6.344174 -35.119162)
			(xy -6.275162 -35.168305) (xy -6.211134 -35.223786) (xy -6.152669 -35.285101) (xy -6.100298 -35.351697)
			(xy -6.054495 -35.422969) (xy -6.015673 -35.498272) (xy -5.984185 -35.576924) (xy -5.960317 -35.658214)
			(xy -5.944283 -35.741404) (xy -5.93623 -35.825741) (xy -5.935726 -35.868102) (xy -5.93623 -35.910463)
			(xy -5.944283 -35.9948) (xy -5.960317 -36.07799) (xy -5.984185 -36.15928) (xy -6.015673 -36.237932)
			(xy -6.054495 -36.313235) (xy -6.100298 -36.384507) (xy -6.152669 -36.451103) (xy -6.211134 -36.512418)
			(xy -6.275162 -36.567899) (xy -6.344174 -36.617042) (xy -6.417544 -36.659402) (xy -6.494609 -36.694597)
			(xy -6.574671 -36.722306) (xy -6.657004 -36.74228) (xy -6.740863 -36.754337) (xy -6.825488 -36.758369)
			(xy -6.910113 -36.754337) (xy -6.993972 -36.74228) (xy -7.076305 -36.722306) (xy -7.156367 -36.694597)
			(xy -7.233432 -36.659402) (xy -7.306802 -36.617042) (xy -7.375814 -36.567899) (xy -7.439842 -36.512418)
			(xy -7.498307 -36.451103) (xy -7.550678 -36.384507) (xy -7.596481 -36.313235) (xy -7.635303 -36.237932)
			(xy -7.666791 -36.15928) (xy -7.690659 -36.07799) (xy -7.706693 -35.9948) (xy -7.714746 -35.910463)
			(xy -10.50823 -35.910463) (xy -10.516283 -35.9948) (xy -10.532317 -36.07799) (xy -10.556185 -36.15928)
			(xy -10.587673 -36.237932) (xy -10.626495 -36.313235) (xy -10.672298 -36.384507) (xy -10.724669 -36.451103)
			(xy -10.783134 -36.512418) (xy -10.847162 -36.567899) (xy -10.916174 -36.617042) (xy -10.989544 -36.659402)
			(xy -11.066609 -36.694597) (xy -11.146671 -36.722306) (xy -11.229004 -36.74228) (xy -11.312863 -36.754337)
			(xy -11.397488 -36.758369) (xy -11.482113 -36.754337) (xy -11.565972 -36.74228) (xy -11.648305 -36.722306)
			(xy -11.728367 -36.694597) (xy -11.805432 -36.659402) (xy -11.878802 -36.617042) (xy -11.947814 -36.567899)
			(xy -12.011842 -36.512418) (xy -12.070307 -36.451103) (xy -12.122678 -36.384507) (xy -12.168481 -36.313235)
			(xy -12.207303 -36.237932) (xy -12.238791 -36.15928) (xy -12.262659 -36.07799) (xy -12.278693 -35.9948)
			(xy -12.286746 -35.910463) (xy -17.729962 -35.910463) (xy -17.729962 -59.105743) (xy -12.286746 -59.105743)
			(xy -12.286746 -59.021021) (xy -12.278693 -58.936684) (xy -12.262659 -58.853494) (xy -12.238791 -58.772204)
			(xy -12.207303 -58.693552) (xy -12.168481 -58.618249) (xy -12.122678 -58.546977) (xy -12.070307 -58.480381)
			(xy -12.011842 -58.419066) (xy -11.947814 -58.363585) (xy -11.878802 -58.314442) (xy -11.805432 -58.272082)
			(xy -11.728367 -58.236887) (xy -11.648305 -58.209178) (xy -11.565972 -58.189204) (xy -11.482113 -58.177147)
			(xy -11.397488 -58.173116) (xy -11.312863 -58.177147) (xy -11.229004 -58.189204) (xy -11.146671 -58.209178)
			(xy -11.066609 -58.236887) (xy -10.989544 -58.272082) (xy -10.916174 -58.314442) (xy -10.847162 -58.363585)
			(xy -10.783134 -58.419066) (xy -10.724669 -58.480381) (xy -10.672298 -58.546977) (xy -10.626495 -58.618249)
			(xy -10.587673 -58.693552) (xy -10.556185 -58.772204) (xy -10.532317 -58.853494) (xy -10.516283 -58.936684)
			(xy -10.50823 -59.021021) (xy -10.507726 -59.063382) (xy -10.50823 -59.105743) (xy -7.714746 -59.105743)
			(xy -7.714746 -59.021021) (xy -7.706693 -58.936684) (xy -7.690659 -58.853494) (xy -7.666791 -58.772204)
			(xy -7.635303 -58.693552) (xy -7.596481 -58.618249) (xy -7.550678 -58.546977) (xy -7.498307 -58.480381)
			(xy -7.439842 -58.419066) (xy -7.375814 -58.363585) (xy -7.306802 -58.314442) (xy -7.233432 -58.272082)
			(xy -7.156367 -58.236887) (xy -7.076305 -58.209178) (xy -6.993972 -58.189204) (xy -6.910113 -58.177147)
			(xy -6.825488 -58.173116) (xy -6.740863 -58.177147) (xy -6.657004 -58.189204) (xy -6.574671 -58.209178)
			(xy -6.494609 -58.236887) (xy -6.417544 -58.272082) (xy -6.344174 -58.314442) (xy -6.275162 -58.363585)
			(xy -6.211134 -58.419066) (xy -6.152669 -58.480381) (xy -6.100298 -58.546977) (xy -6.054495 -58.618249)
			(xy -6.015673 -58.693552) (xy -5.984185 -58.772204) (xy -5.960317 -58.853494) (xy -5.944283 -58.936684)
			(xy -5.93623 -59.021021) (xy -5.935726 -59.063382) (xy -5.93623 -59.105743) (xy -5.944283 -59.19008)
			(xy -5.960317 -59.27327) (xy -5.984185 -59.35456) (xy -6.015673 -59.433212) (xy -6.054495 -59.508515)
			(xy -6.100298 -59.579787) (xy -6.152669 -59.646383) (xy -6.211134 -59.707698) (xy -6.275162 -59.763179)
			(xy -6.344174 -59.812322) (xy -6.417544 -59.854682) (xy -6.494609 -59.889877) (xy -6.574671 -59.917586)
			(xy -6.657004 -59.93756) (xy -6.740863 -59.949617) (xy -6.825488 -59.953649) (xy -6.910113 -59.949617)
			(xy -6.993972 -59.93756) (xy -7.076305 -59.917586) (xy -7.156367 -59.889877) (xy -7.233432 -59.854682)
			(xy -7.306802 -59.812322) (xy -7.375814 -59.763179) (xy -7.439842 -59.707698) (xy -7.498307 -59.646383)
			(xy -7.550678 -59.579787) (xy -7.596481 -59.508515) (xy -7.635303 -59.433212) (xy -7.666791 -59.35456)
			(xy -7.690659 -59.27327) (xy -7.706693 -59.19008) (xy -7.714746 -59.105743) (xy -10.50823 -59.105743)
			(xy -10.516283 -59.19008) (xy -10.532317 -59.27327) (xy -10.556185 -59.35456) (xy -10.587673 -59.433212)
			(xy -10.626495 -59.508515) (xy -10.672298 -59.579787) (xy -10.724669 -59.646383) (xy -10.783134 -59.707698)
			(xy -10.847162 -59.763179) (xy -10.916174 -59.812322) (xy -10.989544 -59.854682) (xy -11.066609 -59.889877)
			(xy -11.146671 -59.917586) (xy -11.229004 -59.93756) (xy -11.312863 -59.949617) (xy -11.397488 -59.953649)
			(xy -11.482113 -59.949617) (xy -11.565972 -59.93756) (xy -11.648305 -59.917586) (xy -11.728367 -59.889877)
			(xy -11.805432 -59.854682) (xy -11.878802 -59.812322) (xy -11.947814 -59.763179) (xy -12.011842 -59.707698)
			(xy -12.070307 -59.646383) (xy -12.122678 -59.579787) (xy -12.168481 -59.508515) (xy -12.207303 -59.433212)
			(xy -12.238791 -59.35456) (xy -12.262659 -59.27327) (xy -12.278693 -59.19008) (xy -12.286746 -59.105743)
			(xy -17.729962 -59.105743) (xy -17.729962 -63.169743) (xy -12.286746 -63.169743) (xy -12.286746 -63.085021)
			(xy -12.278693 -63.000684) (xy -12.262659 -62.917494) (xy -12.238791 -62.836204) (xy -12.207303 -62.757552)
			(xy -12.168481 -62.682249) (xy -12.122678 -62.610977) (xy -12.070307 -62.544381) (xy -12.011842 -62.483066)
			(xy -11.947814 -62.427585) (xy -11.878802 -62.378442) (xy -11.805432 -62.336082) (xy -11.728367 -62.300887)
			(xy -11.648305 -62.273178) (xy -11.565972 -62.253204) (xy -11.482113 -62.241147) (xy -11.397488 -62.237116)
			(xy -11.312863 -62.241147) (xy -11.229004 -62.253204) (xy -11.146671 -62.273178) (xy -11.066609 -62.300887)
			(xy -10.989544 -62.336082) (xy -10.916174 -62.378442) (xy -10.847162 -62.427585) (xy -10.783134 -62.483066)
			(xy -10.724669 -62.544381) (xy -10.672298 -62.610977) (xy -10.626495 -62.682249) (xy -10.587673 -62.757552)
			(xy -10.556185 -62.836204) (xy -10.532317 -62.917494) (xy -10.516283 -63.000684) (xy -10.50823 -63.085021)
			(xy -10.507726 -63.127382) (xy -10.50823 -63.169743) (xy -7.714746 -63.169743) (xy -7.714746 -63.085021)
			(xy -7.706693 -63.000684) (xy -7.690659 -62.917494) (xy -7.666791 -62.836204) (xy -7.635303 -62.757552)
			(xy -7.596481 -62.682249) (xy -7.550678 -62.610977) (xy -7.498307 -62.544381) (xy -7.439842 -62.483066)
			(xy -7.375814 -62.427585) (xy -7.306802 -62.378442) (xy -7.233432 -62.336082) (xy -7.156367 -62.300887)
			(xy -7.076305 -62.273178) (xy -6.993972 -62.253204) (xy -6.910113 -62.241147) (xy -6.825488 -62.237116)
			(xy -6.740863 -62.241147) (xy -6.657004 -62.253204) (xy -6.574671 -62.273178) (xy -6.494609 -62.300887)
			(xy -6.417544 -62.336082) (xy -6.344174 -62.378442) (xy -6.275162 -62.427585) (xy -6.211134 -62.483066)
			(xy -6.152669 -62.544381) (xy -6.100298 -62.610977) (xy -6.054495 -62.682249) (xy -6.015673 -62.757552)
			(xy -5.984185 -62.836204) (xy -5.960317 -62.917494) (xy -5.944283 -63.000684) (xy -5.93623 -63.085021)
			(xy -5.935726 -63.127382) (xy -5.93623 -63.169743) (xy -5.944283 -63.25408) (xy -5.960317 -63.33727)
			(xy -5.984185 -63.41856) (xy -6.015673 -63.497212) (xy -6.054495 -63.572515) (xy -6.100298 -63.643787)
			(xy -6.152669 -63.710383) (xy -6.211134 -63.771698) (xy -6.275162 -63.827179) (xy -6.344174 -63.876322)
			(xy -6.417544 -63.918682) (xy -6.494609 -63.953877) (xy -6.574671 -63.981586) (xy -6.657004 -64.00156)
			(xy -6.740863 -64.013617) (xy -6.825488 -64.017649) (xy -6.910113 -64.013617) (xy -6.993972 -64.00156)
			(xy -7.076305 -63.981586) (xy -7.156367 -63.953877) (xy -7.233432 -63.918682) (xy -7.306802 -63.876322)
			(xy -7.375814 -63.827179) (xy -7.439842 -63.771698) (xy -7.498307 -63.710383) (xy -7.550678 -63.643787)
			(xy -7.596481 -63.572515) (xy -7.635303 -63.497212) (xy -7.666791 -63.41856) (xy -7.690659 -63.33727)
			(xy -7.706693 -63.25408) (xy -7.714746 -63.169743) (xy -10.50823 -63.169743) (xy -10.516283 -63.25408)
			(xy -10.532317 -63.33727) (xy -10.556185 -63.41856) (xy -10.587673 -63.497212) (xy -10.626495 -63.572515)
			(xy -10.672298 -63.643787) (xy -10.724669 -63.710383) (xy -10.783134 -63.771698) (xy -10.847162 -63.827179)
			(xy -10.916174 -63.876322) (xy -10.989544 -63.918682) (xy -11.066609 -63.953877) (xy -11.146671 -63.981586)
			(xy -11.229004 -64.00156) (xy -11.312863 -64.013617) (xy -11.397488 -64.017649) (xy -11.482113 -64.013617)
			(xy -11.565972 -64.00156) (xy -11.648305 -63.981586) (xy -11.728367 -63.953877) (xy -11.805432 -63.918682)
			(xy -11.878802 -63.876322) (xy -11.947814 -63.827179) (xy -12.011842 -63.771698) (xy -12.070307 -63.710383)
			(xy -12.122678 -63.643787) (xy -12.168481 -63.572515) (xy -12.207303 -63.497212) (xy -12.238791 -63.41856)
			(xy -12.262659 -63.33727) (xy -12.278693 -63.25408) (xy -12.286746 -63.169743) (xy -17.729962 -63.169743)
			(xy -17.729962 -187.619583) (xy -12.286746 -187.619583) (xy -12.286746 -187.534861) (xy -12.278693 -187.450524)
			(xy -12.262659 -187.367334) (xy -12.238791 -187.286044) (xy -12.207303 -187.207392) (xy -12.168481 -187.132089)
			(xy -12.122678 -187.060817) (xy -12.070307 -186.994221) (xy -12.011842 -186.932906) (xy -11.947814 -186.877425)
			(xy -11.878802 -186.828282) (xy -11.805432 -186.785922) (xy -11.728367 -186.750727) (xy -11.648305 -186.723018)
			(xy -11.565972 -186.703044) (xy -11.482113 -186.690987) (xy -11.397488 -186.686956) (xy -11.312863 -186.690987)
			(xy -11.229004 -186.703044) (xy -11.146671 -186.723018) (xy -11.066609 -186.750727) (xy -10.989544 -186.785922)
			(xy -10.916174 -186.828282) (xy -10.847162 -186.877425) (xy -10.783134 -186.932906) (xy -10.724669 -186.994221)
			(xy -10.672298 -187.060817) (xy -10.626495 -187.132089) (xy -10.587673 -187.207392) (xy -10.556185 -187.286044)
			(xy -10.532317 -187.367334) (xy -10.516283 -187.450524) (xy -10.50823 -187.534861) (xy -10.507726 -187.577222)
			(xy -10.50823 -187.619583) (xy -7.714746 -187.619583) (xy -7.714746 -187.534861) (xy -7.706693 -187.450524)
			(xy -7.690659 -187.367334) (xy -7.666791 -187.286044) (xy -7.635303 -187.207392) (xy -7.596481 -187.132089)
			(xy -7.550678 -187.060817) (xy -7.498307 -186.994221) (xy -7.439842 -186.932906) (xy -7.375814 -186.877425)
			(xy -7.306802 -186.828282) (xy -7.233432 -186.785922) (xy -7.156367 -186.750727) (xy -7.076305 -186.723018)
			(xy -6.993972 -186.703044) (xy -6.910113 -186.690987) (xy -6.825488 -186.686956) (xy -6.740863 -186.690987)
			(xy -6.657004 -186.703044) (xy -6.574671 -186.723018) (xy -6.494609 -186.750727) (xy -6.417544 -186.785922)
			(xy -6.344174 -186.828282) (xy -6.275162 -186.877425) (xy -6.211134 -186.932906) (xy -6.152669 -186.994221)
			(xy -6.100298 -187.060817) (xy -6.054495 -187.132089) (xy -6.015673 -187.207392) (xy -5.984185 -187.286044)
			(xy -5.960317 -187.367334) (xy -5.944283 -187.450524) (xy -5.93623 -187.534861) (xy -5.935726 -187.577222)
			(xy -5.93623 -187.619583) (xy -5.944283 -187.70392) (xy -5.960317 -187.78711) (xy -5.984185 -187.8684)
			(xy -6.015673 -187.947052) (xy -6.054495 -188.022355) (xy -6.100298 -188.093627) (xy -6.152669 -188.160223)
			(xy -6.211134 -188.221538) (xy -6.275162 -188.277019) (xy -6.344174 -188.326162) (xy -6.417544 -188.368522)
			(xy -6.494609 -188.403717) (xy -6.574671 -188.431426) (xy -6.657004 -188.4514) (xy -6.740863 -188.463457)
			(xy -6.825488 -188.467489) (xy -6.910113 -188.463457) (xy -6.993972 -188.4514) (xy -7.076305 -188.431426)
			(xy -7.156367 -188.403717) (xy -7.233432 -188.368522) (xy -7.306802 -188.326162) (xy -7.375814 -188.277019)
			(xy -7.439842 -188.221538) (xy -7.498307 -188.160223) (xy -7.550678 -188.093627) (xy -7.596481 -188.022355)
			(xy -7.635303 -187.947052) (xy -7.666791 -187.8684) (xy -7.690659 -187.78711) (xy -7.706693 -187.70392)
			(xy -7.714746 -187.619583) (xy -10.50823 -187.619583) (xy -10.516283 -187.70392) (xy -10.532317 -187.78711)
			(xy -10.556185 -187.8684) (xy -10.587673 -187.947052) (xy -10.626495 -188.022355) (xy -10.672298 -188.093627)
			(xy -10.724669 -188.160223) (xy -10.783134 -188.221538) (xy -10.847162 -188.277019) (xy -10.916174 -188.326162)
			(xy -10.989544 -188.368522) (xy -11.066609 -188.403717) (xy -11.146671 -188.431426) (xy -11.229004 -188.4514)
			(xy -11.312863 -188.463457) (xy -11.397488 -188.467489) (xy -11.482113 -188.463457) (xy -11.565972 -188.4514)
			(xy -11.648305 -188.431426) (xy -11.728367 -188.403717) (xy -11.805432 -188.368522) (xy -11.878802 -188.326162)
			(xy -11.947814 -188.277019) (xy -12.011842 -188.221538) (xy -12.070307 -188.160223) (xy -12.122678 -188.093627)
			(xy -12.168481 -188.022355) (xy -12.207303 -187.947052) (xy -12.238791 -187.8684) (xy -12.262659 -187.78711)
			(xy -12.278693 -187.70392) (xy -12.286746 -187.619583) (xy -17.729962 -187.619583) (xy -17.729962 -191.683583)
			(xy -12.286746 -191.683583) (xy -12.286746 -191.598861) (xy -12.278693 -191.514524) (xy -12.262659 -191.431334)
			(xy -12.238791 -191.350044) (xy -12.207303 -191.271392) (xy -12.168481 -191.196089) (xy -12.122678 -191.124817)
			(xy -12.070307 -191.058221) (xy -12.011842 -190.996906) (xy -11.947814 -190.941425) (xy -11.878802 -190.892282)
			(xy -11.805432 -190.849922) (xy -11.728367 -190.814727) (xy -11.648305 -190.787018) (xy -11.565972 -190.767044)
			(xy -11.482113 -190.754987) (xy -11.397488 -190.750956) (xy -11.312863 -190.754987) (xy -11.229004 -190.767044)
			(xy -11.146671 -190.787018) (xy -11.066609 -190.814727) (xy -10.989544 -190.849922) (xy -10.916174 -190.892282)
			(xy -10.847162 -190.941425) (xy -10.783134 -190.996906) (xy -10.724669 -191.058221) (xy -10.672298 -191.124817)
			(xy -10.626495 -191.196089) (xy -10.587673 -191.271392) (xy -10.556185 -191.350044) (xy -10.532317 -191.431334)
			(xy -10.516283 -191.514524) (xy -10.50823 -191.598861) (xy -10.507726 -191.641222) (xy -10.50823 -191.683583)
			(xy -7.714746 -191.683583) (xy -7.714746 -191.598861) (xy -7.706693 -191.514524) (xy -7.690659 -191.431334)
			(xy -7.666791 -191.350044) (xy -7.635303 -191.271392) (xy -7.596481 -191.196089) (xy -7.550678 -191.124817)
			(xy -7.498307 -191.058221) (xy -7.439842 -190.996906) (xy -7.375814 -190.941425) (xy -7.306802 -190.892282)
			(xy -7.233432 -190.849922) (xy -7.156367 -190.814727) (xy -7.076305 -190.787018) (xy -6.993972 -190.767044)
			(xy -6.910113 -190.754987) (xy -6.825488 -190.750956) (xy -6.740863 -190.754987) (xy -6.657004 -190.767044)
			(xy -6.574671 -190.787018) (xy -6.494609 -190.814727) (xy -6.417544 -190.849922) (xy -6.344174 -190.892282)
			(xy -6.275162 -190.941425) (xy -6.211134 -190.996906) (xy -6.152669 -191.058221) (xy -6.100298 -191.124817)
			(xy -6.054495 -191.196089) (xy -6.015673 -191.271392) (xy -5.984185 -191.350044) (xy -5.960317 -191.431334)
			(xy -5.944283 -191.514524) (xy -5.93623 -191.598861) (xy -5.935726 -191.641222) (xy -5.93623 -191.683583)
			(xy -5.944283 -191.76792) (xy -5.960317 -191.85111) (xy -5.984185 -191.9324) (xy -6.015673 -192.011052)
			(xy -6.054495 -192.086355) (xy -6.100298 -192.157627) (xy -6.152669 -192.224223) (xy -6.211134 -192.285538)
			(xy -6.275162 -192.341019) (xy -6.344174 -192.390162) (xy -6.417544 -192.432522) (xy -6.494609 -192.467717)
			(xy -6.574671 -192.495426) (xy -6.657004 -192.5154) (xy -6.740863 -192.527457) (xy -6.825488 -192.531489)
			(xy -6.910113 -192.527457) (xy -6.993972 -192.5154) (xy -7.076305 -192.495426) (xy -7.156367 -192.467717)
			(xy -7.233432 -192.432522) (xy -7.306802 -192.390162) (xy -7.375814 -192.341019) (xy -7.439842 -192.285538)
			(xy -7.498307 -192.224223) (xy -7.550678 -192.157627) (xy -7.596481 -192.086355) (xy -7.635303 -192.011052)
			(xy -7.666791 -191.9324) (xy -7.690659 -191.85111) (xy -7.706693 -191.76792) (xy -7.714746 -191.683583)
			(xy -10.50823 -191.683583) (xy -10.516283 -191.76792) (xy -10.532317 -191.85111) (xy -10.556185 -191.9324)
			(xy -10.587673 -192.011052) (xy -10.626495 -192.086355) (xy -10.672298 -192.157627) (xy -10.724669 -192.224223)
			(xy -10.783134 -192.285538) (xy -10.847162 -192.341019) (xy -10.916174 -192.390162) (xy -10.989544 -192.432522)
			(xy -11.066609 -192.467717) (xy -11.146671 -192.495426) (xy -11.229004 -192.5154) (xy -11.312863 -192.527457)
			(xy -11.397488 -192.531489) (xy -11.482113 -192.527457) (xy -11.565972 -192.5154) (xy -11.648305 -192.495426)
			(xy -11.728367 -192.467717) (xy -11.805432 -192.432522) (xy -11.878802 -192.390162) (xy -11.947814 -192.341019)
			(xy -12.011842 -192.285538) (xy -12.070307 -192.224223) (xy -12.122678 -192.157627) (xy -12.168481 -192.086355)
			(xy -12.207303 -192.011052) (xy -12.238791 -191.9324) (xy -12.262659 -191.85111) (xy -12.278693 -191.76792)
			(xy -12.286746 -191.683583) (xy -17.729962 -191.683583) (xy -17.729962 -206.70012) (xy -17.72944 -206.755927)
			(xy -17.721099 -206.867229) (xy -17.704464 -206.977596) (xy -17.679627 -207.086412) (xy -17.646728 -207.193067)
			(xy -17.605951 -207.296966) (xy -17.557524 -207.397526) (xy -17.501716 -207.494187) (xy -17.438842 -207.586407)
			(xy -17.369252 -207.67367) (xy -17.293335 -207.755489) (xy -17.211516 -207.831406) (xy -17.124253 -207.900996)
			(xy -17.032033 -207.96387) (xy -16.935372 -208.019678) (xy -16.834812 -208.068105) (xy -16.730913 -208.108882)
			(xy -16.624258 -208.141781) (xy -16.515442 -208.166618) (xy -16.405075 -208.183253) (xy -16.293773 -208.191594)
			(xy -16.237966 -208.192116)
		)
		(stroke
			(width 0)
			(type solid)
		)
		(fill yes)
		(layer "In8.Cu")
		(net "GND")
	)
	(gr_poly
		(pts
			(xy 82.923888 -203.003404) (xy 82.940544 -203.002911) (xy 82.972722 -202.994292) (xy 83.001572 -202.977638)
			(xy 83.025128 -202.954084) (xy 83.041786 -202.925236) (xy 83.050409 -202.89306) (xy 83.050888 -202.876404)
			(xy 83.050888 -201.250042) (xy 83.051381 -201.195462) (xy 83.05953 -201.086606) (xy 83.075791 -200.978664)
			(xy 83.100073 -200.872238) (xy 83.132241 -200.767925) (xy 83.172115 -200.666308) (xy 83.219472 -200.567955)
			(xy 83.274047 -200.473416) (xy 83.335534 -200.38322) (xy 83.40359 -200.297872) (xy 83.477835 -200.217848)
			(xy 83.557852 -200.143597) (xy 83.643194 -200.075534) (xy 83.733385 -200.014038) (xy 83.827919 -199.959456)
			(xy 83.926268 -199.91209) (xy 84.027881 -199.872207) (xy 84.132192 -199.84003) (xy 84.238615 -199.815738)
			(xy 84.346556 -199.799468) (xy 84.455411 -199.79131) (xy 84.564571 -199.79131) (xy 84.673426 -199.799468)
			(xy 84.781367 -199.815738) (xy 84.88779 -199.84003) (xy 84.992101 -199.872207) (xy 85.093714 -199.91209)
			(xy 85.192063 -199.959456) (xy 85.286597 -200.014038) (xy 85.376788 -200.075534) (xy 85.46213 -200.143597)
			(xy 85.542147 -200.217848) (xy 85.616392 -200.297872) (xy 85.684448 -200.38322) (xy 85.745935 -200.473416)
			(xy 85.80051 -200.567955) (xy 85.847867 -200.666308) (xy 85.887741 -200.767925) (xy 85.919909 -200.872238)
			(xy 85.944191 -200.978664) (xy 85.960452 -201.086606) (xy 85.968601 -201.195462) (xy 85.969094 -201.250042)
			(xy 85.969094 -202.876404) (xy 85.969638 -202.893052) (xy 85.978256 -202.925214) (xy 85.994905 -202.95405)
			(xy 86.018449 -202.977594) (xy 86.047284 -202.994243) (xy 86.079446 -203.002862) (xy 86.096094 -203.003404)
			(xy 96.023938 -203.003404) (xy 96.040583 -203.002856) (xy 96.072738 -202.994232) (xy 96.101565 -202.977581)
			(xy 96.125102 -202.954038) (xy 96.141745 -202.925206) (xy 96.150361 -202.893049) (xy 96.150938 -202.876404)
			(xy 96.150938 -188.250068) (xy 96.151438 -188.162213) (xy 96.159435 -187.986685) (xy 96.175414 -187.811703)
			(xy 96.199339 -187.637629) (xy 96.231163 -187.464825) (xy 96.27082 -187.293648) (xy 96.318226 -187.124454)
			(xy 96.373283 -186.957593) (xy 96.435879 -186.79341) (xy 96.505882 -186.632247) (xy 96.583147 -186.474437)
			(xy 96.667516 -186.320307) (xy 96.758812 -186.170177) (xy 96.856847 -186.024358) (xy 96.961417 -185.883151)
			(xy 97.072305 -185.746851) (xy 97.189283 -185.615739) (xy 97.312106 -185.490087) (xy 97.440521 -185.370156)
			(xy 97.574262 -185.256193) (xy 97.713051 -185.148436) (xy 97.856601 -185.047107) (xy 98.004614 -184.952418)
			(xy 98.156784 -184.864562) (xy 98.312794 -184.783724) (xy 98.472322 -184.710071) (xy 98.635037 -184.643754)
			(xy 98.800602 -184.584913) (xy 98.968673 -184.533668) (xy 99.138903 -184.490125) (xy 99.310938 -184.454376)
			(xy 99.484422 -184.426494) (xy 99.658995 -184.406537) (xy 99.834295 -184.394546) (xy 100.00996 -184.390546)
			(xy 100.185625 -184.394546) (xy 100.360925 -184.406537) (xy 100.535498 -184.426494) (xy 100.708982 -184.454376)
			(xy 100.881017 -184.490125) (xy 101.051247 -184.533668) (xy 101.219318 -184.584913) (xy 101.384883 -184.643754)
			(xy 101.547598 -184.710071) (xy 101.707126 -184.783724) (xy 101.863136 -184.864562) (xy 102.015306 -184.952418)
			(xy 102.163319 -185.047107) (xy 102.306869 -185.148436) (xy 102.445658 -185.256193) (xy 102.579399 -185.370156)
			(xy 102.707814 -185.490087) (xy 102.830637 -185.615739) (xy 102.947615 -185.746851) (xy 103.058503 -185.883151)
			(xy 103.163073 -186.024358) (xy 103.261108 -186.170177) (xy 103.352404 -186.320307) (xy 103.436773 -186.474437)
			(xy 103.514038 -186.632247) (xy 103.584041 -186.79341) (xy 103.646637 -186.957593) (xy 103.701694 -187.124454)
			(xy 103.7491 -187.293648) (xy 103.788757 -187.464825) (xy 103.820581 -187.637629) (xy 103.844506 -187.811703)
			(xy 103.860485 -187.986685) (xy 103.868482 -188.162213) (xy 103.868982 -188.250068) (xy 103.868982 -202.876404)
			(xy 103.869526 -202.893053) (xy 103.878144 -202.925216) (xy 103.894792 -202.954053) (xy 103.918336 -202.9776)
			(xy 103.947171 -202.994251) (xy 103.979333 -203.002873) (xy 103.995982 -203.003404) (xy 173.92396 -203.003404)
			(xy 173.940618 -203.002914) (xy 173.972802 -202.9943) (xy 174.001659 -202.977648) (xy 174.025221 -202.954094)
			(xy 174.041883 -202.925243) (xy 174.050508 -202.893062) (xy 174.05096 -202.876404) (xy 174.05096 -201.250042)
			(xy 174.05147 -201.19547) (xy 174.059626 -201.086631) (xy 174.075893 -200.978707) (xy 174.10018 -200.872299)
			(xy 174.132351 -200.768004) (xy 174.172226 -200.666405) (xy 174.219582 -200.56807) (xy 174.274153 -200.473548)
			(xy 174.335636 -200.383369) (xy 174.403687 -200.298037) (xy 174.477923 -200.218029) (xy 174.557931 -200.143793)
			(xy 174.643263 -200.075742) (xy 174.733442 -200.014259) (xy 174.827964 -199.959688) (xy 174.926299 -199.912332)
			(xy 175.027898 -199.872457) (xy 175.132193 -199.840286) (xy 175.238601 -199.815999) (xy 175.346525 -199.799732)
			(xy 175.455364 -199.791576) (xy 175.564508 -199.791576) (xy 175.673347 -199.799732) (xy 175.781271 -199.815999)
			(xy 175.887679 -199.840286) (xy 175.991974 -199.872457) (xy 176.093573 -199.912332) (xy 176.191908 -199.959688)
			(xy 176.28643 -200.014259) (xy 176.376609 -200.075742) (xy 176.461941 -200.143793) (xy 176.541949 -200.218029)
			(xy 176.616185 -200.298037) (xy 176.684236 -200.383369) (xy 176.745719 -200.473548) (xy 176.80029 -200.56807)
			(xy 176.847646 -200.666405) (xy 176.887521 -200.768004) (xy 176.919692 -200.872299) (xy 176.943979 -200.978707)
			(xy 176.960246 -201.086631) (xy 176.968402 -201.19547) (xy 176.968912 -201.250042) (xy 176.968912 -202.876404)
			(xy 176.969407 -202.893058) (xy 176.978029 -202.92523) (xy 176.994684 -202.954075) (xy 177.018238 -202.977625)
			(xy 177.047085 -202.994277) (xy 177.079258 -203.002895) (xy 177.095912 -203.003404) (xy 187.02401 -203.003404)
			(xy 187.040658 -203.00286) (xy 187.072818 -202.99424) (xy 187.101652 -202.977591) (xy 187.125195 -202.954047)
			(xy 187.141842 -202.925213) (xy 187.15046 -202.893052) (xy 187.15101 -202.876404) (xy 187.15101 -172.699934)
			(xy 187.151494 -172.629551) (xy 187.159385 -172.489007) (xy 187.175144 -172.349126) (xy 187.198721 -172.210349)
			(xy 187.230043 -172.073112) (xy 187.269011 -171.937847) (xy 187.315502 -171.804981) (xy 187.369369 -171.67493)
			(xy 187.430445 -171.548104) (xy 187.498535 -171.424902) (xy 187.573426 -171.305711) (xy 187.654883 -171.190908)
			(xy 187.742648 -171.080853) (xy 187.836447 -170.975891) (xy 187.935983 -170.876355) (xy 188.040943 -170.782556)
			(xy 188.150998 -170.69479) (xy 188.265801 -170.613333) (xy 188.384991 -170.538441) (xy 188.508193 -170.47035)
			(xy 188.635019 -170.409274) (xy 188.765069 -170.355406) (xy 188.897936 -170.308915) (xy 189.0332 -170.269946)
			(xy 189.170437 -170.238624) (xy 189.309214 -170.215046) (xy 189.449095 -170.199286) (xy 189.589639 -170.191394)
			(xy 189.660022 -170.190922) (xy 198.000112 -170.190922) (xy 198.055881 -170.1904) (xy 198.167108 -170.182064)
			(xy 198.277401 -170.16544) (xy 198.386143 -170.14062) (xy 198.492726 -170.107743) (xy 198.596554 -170.066993)
			(xy 198.697047 -170.018599) (xy 198.793643 -169.96283) (xy 198.885801 -169.899998) (xy 198.973006 -169.830456)
			(xy 199.05477 -169.754591) (xy 199.130636 -169.672828) (xy 199.200181 -169.585625) (xy 199.263014 -169.493468)
			(xy 199.318785 -169.396874) (xy 199.367181 -169.296382) (xy 199.407933 -169.192554) (xy 199.440812 -169.085972)
			(xy 199.465634 -168.97723) (xy 199.482261 -168.866938) (xy 199.490599 -168.755711) (xy 199.491092 -168.699942)
			(xy 199.491092 -75.65009) (xy 199.490579 -75.604293) (xy 199.482127 -75.513089) (xy 199.465295 -75.423053)
			(xy 199.440228 -75.334955) (xy 199.407139 -75.249546) (xy 199.366311 -75.167554) (xy 199.318091 -75.089679)
			(xy 199.262892 -75.016586) (xy 199.201184 -74.948897) (xy 199.133494 -74.887191) (xy 199.060399 -74.831994)
			(xy 198.982523 -74.783776) (xy 198.90053 -74.74295) (xy 198.81512 -74.709864) (xy 198.727021 -74.684799)
			(xy 198.636986 -74.66797) (xy 198.545781 -74.65952) (xy 198.499984 -74.658982) (xy 198.20001 -74.658982)
			(xy 198.13689 -74.658487) (xy 198.0109 -74.650562) (xy 197.885655 -74.634742) (xy 197.761651 -74.611089)
			(xy 197.639377 -74.579698) (xy 197.519314 -74.540692) (xy 197.401938 -74.494225) (xy 197.287711 -74.44048)
			(xy 197.177083 -74.379669) (xy 197.070492 -74.312032) (xy 196.968357 -74.237837) (xy 196.871082 -74.157375)
			(xy 196.779051 -74.070965) (xy 196.692627 -73.978947) (xy 196.612151 -73.881685) (xy 196.53794 -73.779562)
			(xy 196.470287 -73.67298) (xy 196.409459 -73.562362) (xy 196.355697 -73.448143) (xy 196.309212 -73.330774)
			(xy 196.270187 -73.210717) (xy 196.238777 -73.088448) (xy 196.215106 -72.964447) (xy 196.199267 -72.839205)
			(xy 196.191323 -72.713216) (xy 196.19087 -72.650096) (xy 196.19087 -33.64992) (xy 196.191374 -33.586802)
			(xy 196.199318 -33.460815) (xy 196.215155 -33.335575) (xy 196.238825 -33.211577) (xy 196.270233 -33.08931)
			(xy 196.309256 -32.969256) (xy 196.35574 -32.851889) (xy 196.4095 -32.737672) (xy 196.470326 -32.627055)
			(xy 196.537977 -32.520476) (xy 196.612186 -32.418354) (xy 196.69266 -32.321094) (xy 196.779082 -32.229077)
			(xy 196.871111 -32.142669) (xy 196.968384 -32.062208) (xy 197.070516 -31.988014) (xy 197.177105 -31.920379)
			(xy 197.28773 -31.859569) (xy 197.401955 -31.805825) (xy 197.519329 -31.759358) (xy 197.639389 -31.720352)
			(xy 197.76166 -31.688962) (xy 197.885662 -31.66531) (xy 198.010904 -31.64949) (xy 198.136892 -31.641565)
			(xy 198.20001 -31.641034) (xy 198.499984 -31.641034) (xy 198.545782 -31.640506) (xy 198.636988 -31.632056)
			(xy 198.727025 -31.615227) (xy 198.815125 -31.590162) (xy 198.900537 -31.557075) (xy 198.982531 -31.516249)
			(xy 199.060409 -31.468031) (xy 199.133505 -31.412833) (xy 199.201197 -31.351127) (xy 199.262907 -31.283438)
			(xy 199.318107 -31.210343) (xy 199.366328 -31.132468) (xy 199.407158 -31.050475) (xy 199.440249 -30.965065)
			(xy 199.465317 -30.876966) (xy 199.48215 -30.78693) (xy 199.490604 -30.695724) (xy 199.491092 -30.649926)
			(xy 199.491092 -1.999996) (xy 199.49057 -1.944227) (xy 199.482235 -1.833001) (xy 199.465611 -1.722708)
			(xy 199.440791 -1.613967) (xy 199.407915 -1.507384) (xy 199.367165 -1.403556) (xy 199.31877 -1.303063)
			(xy 199.263001 -1.206468) (xy 199.20017 -1.114311) (xy 199.130627 -1.027107) (xy 199.054762 -0.945344)
			(xy 198.972999 -0.869478) (xy 198.885795 -0.799935) (xy 198.793638 -0.737103) (xy 198.697044 -0.681333)
			(xy 198.596552 -0.632938) (xy 198.492724 -0.592188) (xy 198.386141 -0.559311) (xy 198.2774 -0.534491)
			(xy 198.167107 -0.517866) (xy 198.055881 -0.50953) (xy 198.000112 -0.509016) (xy 1.999996 -0.509016)
			(xy 1.944227 -0.509538) (xy 1.833001 -0.517873) (xy 1.722709 -0.534497) (xy 1.613967 -0.559317) (xy 1.507385 -0.592194)
			(xy 1.403557 -0.632943) (xy 1.303065 -0.681338) (xy 1.20647 -0.737107) (xy 1.114313 -0.799938) (xy 1.027109 -0.869481)
			(xy 0.945346 -0.945346) (xy 0.869481 -1.027109) (xy 0.799938 -1.114313) (xy 0.737107 -1.20647) (xy 0.681338 -1.303065)
			(xy 0.632943 -1.403557) (xy 0.592194 -1.507385) (xy 0.559317 -1.613967) (xy 0.534497 -1.722709) (xy 0.517873 -1.833001)
			(xy 0.509538 -1.944227) (xy 0.509016 -1.999996) (xy 0.509016 -9.750405) (xy 89.064349 -9.750405)
			(xy 89.072055 -9.665303) (xy 89.08745 -9.58125) (xy 89.110408 -9.498942) (xy 89.140739 -9.419055)
			(xy 89.178194 -9.342251) (xy 89.222464 -9.269162) (xy 89.273182 -9.20039) (xy 89.329931 -9.136505)
			(xy 89.360756 -9.106916) (xy 89.44864 -9.106916) (xy 89.465307 -9.106475) (xy 89.497514 -9.097891)
			(xy 89.526391 -9.081243) (xy 89.549958 -9.057672) (xy 89.5666 -9.028792) (xy 89.575178 -8.996583)
			(xy 89.57564 -8.979916) (xy 89.57564 -8.955532) (xy 89.615755 -8.935545) (xy 89.69906 -8.902468)
			(xy 89.785135 -8.877468) (xy 89.873199 -8.860773) (xy 89.962451 -8.852535) (xy 90.052082 -8.852827)
			(xy 90.141279 -8.861648) (xy 90.229232 -8.878917) (xy 90.315142 -8.904478) (xy 90.398229 -8.938099)
			(xy 90.438224 -8.958326) (xy 90.438224 -8.979408) (xy 90.438881 -8.996035) (xy 90.447554 -9.028141)
			(xy 90.464208 -9.056928) (xy 90.487718 -9.08045) (xy 90.516496 -9.09712) (xy 90.548598 -9.10581)
			(xy 90.565224 -9.106408) (xy 90.647266 -9.106408) (xy 90.678125 -9.135996) (xy 90.734975 -9.199856)
			(xy 90.785794 -9.268611) (xy 90.830163 -9.341696) (xy 90.867716 -9.418505) (xy 90.898142 -9.498406)
			(xy 90.921191 -9.580739) (xy 90.936672 -9.664824) (xy 90.944458 -9.749967) (xy 90.944463 -9.750405)
			(xy 99.064304 -9.750405) (xy 99.07201 -9.665301) (xy 99.087407 -9.581247) (xy 99.110367 -9.498937)
			(xy 99.140701 -9.41905) (xy 99.178159 -9.342246) (xy 99.222432 -9.269157) (xy 99.273155 -9.200387)
			(xy 99.329909 -9.136503) (xy 99.360736 -9.106916) (xy 99.44862 -9.106916) (xy 99.465286 -9.106457)
			(xy 99.497493 -9.097878) (xy 99.526369 -9.081234) (xy 99.549936 -9.057666) (xy 99.566579 -9.028789)
			(xy 99.575157 -8.996582) (xy 99.57562 -8.979916) (xy 99.57562 -8.955532) (xy 99.615743 -8.935561)
			(xy 99.699047 -8.902482) (xy 99.78512 -8.877481) (xy 99.873182 -8.860785) (xy 99.962434 -8.852545)
			(xy 100.052064 -8.852835) (xy 100.14126 -8.861655) (xy 100.229212 -8.878922) (xy 100.315122 -8.904481)
			(xy 100.398209 -8.9381) (xy 100.438204 -8.958326) (xy 100.438204 -8.979408) (xy 100.438782 -8.996041)
			(xy 100.447462 -9.028159) (xy 100.464129 -9.056954) (xy 100.487655 -9.080479) (xy 100.516452 -9.097143)
			(xy 100.548571 -9.10582) (xy 100.565204 -9.106408) (xy 100.647246 -9.106408) (xy 100.678101 -9.136)
			(xy 100.734952 -9.199859) (xy 100.785772 -9.268614) (xy 100.830141 -9.341697) (xy 100.867694 -9.418507)
			(xy 100.898121 -9.498407) (xy 100.92117 -9.58074) (xy 100.936652 -9.664824) (xy 100.944438 -9.749967)
			(xy 100.944934 -9.792716) (xy 100.94442 -9.835465) (xy 100.936641 -9.920609) (xy 100.921165 -10.004695)
			(xy 100.898121 -10.08703) (xy 100.867699 -10.166933) (xy 100.83015 -10.243745) (xy 100.785784 -10.316831)
			(xy 100.734968 -10.38559) (xy 100.67812 -10.449452) (xy 100.647246 -10.479024) (xy 100.565204 -10.479024)
			(xy 100.548566 -10.479581) (xy 100.516434 -10.488245) (xy 100.487627 -10.504909) (xy 100.464097 -10.528443)
			(xy 100.447438 -10.557252) (xy 100.438779 -10.589386) (xy 100.438204 -10.606024) (xy 100.438204 -10.627106)
			(xy 100.39822 -10.647284) (xy 100.315185 -10.680859) (xy 100.229335 -10.706392) (xy 100.141446 -10.72365)
			(xy 100.052316 -10.732478) (xy 99.96275 -10.732795) (xy 99.873559 -10.724599) (xy 99.78555 -10.707965)
			(xy 99.699521 -10.683041) (xy 99.61625 -10.650055) (xy 99.576128 -10.630154) (xy 99.576128 -10.606024)
			(xy 99.575536 -10.589379) (xy 99.566926 -10.557222) (xy 99.550287 -10.528389) (xy 99.526753 -10.504845)
			(xy 99.497926 -10.488194) (xy 99.465773 -10.479571) (xy 99.449128 -10.479024) (xy 99.361498 -10.479024)
			(xy 99.33065 -10.449458) (xy 99.273824 -10.385638) (xy 99.223024 -10.316926) (xy 99.178669 -10.243887)
			(xy 99.141124 -10.167125) (xy 99.110699 -10.087272) (xy 99.087646 -10.004988) (xy 99.072154 -9.920952)
			(xy 99.064352 -9.835857) (xy 99.064304 -9.750405) (xy 90.944463 -9.750405) (xy 90.944954 -9.792716)
			(xy 90.944434 -9.835465) (xy 90.936654 -9.920608) (xy 90.921179 -10.004694) (xy 90.898135 -10.087029)
			(xy 90.867714 -10.166931) (xy 90.830166 -10.243743) (xy 90.785801 -10.31683) (xy 90.734986 -10.385589)
			(xy 90.67814 -10.449451) (xy 90.647266 -10.479024) (xy 90.565224 -10.479024) (xy 90.548586 -10.479599)
			(xy 90.516455 -10.488258) (xy 90.487648 -10.504918) (xy 90.464118 -10.528448) (xy 90.447458 -10.557255)
			(xy 90.438799 -10.589386) (xy 90.438224 -10.606024) (xy 90.438224 -10.627106) (xy 90.398233 -10.647268)
			(xy 90.315199 -10.680845) (xy 90.22935 -10.706379) (xy 90.141463 -10.723638) (xy 90.052333 -10.732468)
			(xy 89.962768 -10.732787) (xy 89.873578 -10.724593) (xy 89.78557 -10.70796) (xy 89.699541 -10.683038)
			(xy 89.61627 -10.650054) (xy 89.576148 -10.630154) (xy 89.576148 -10.606024) (xy 89.575536 -10.589381)
			(xy 89.566928 -10.557227) (xy 89.550292 -10.528395) (xy 89.526762 -10.504852) (xy 89.49794 -10.488199)
			(xy 89.465791 -10.479573) (xy 89.449148 -10.479024) (xy 89.361518 -10.479024) (xy 89.330672 -10.449456)
			(xy 89.273851 -10.385635) (xy 89.223055 -10.316921) (xy 89.178703 -10.243882) (xy 89.141162 -10.16712)
			(xy 89.11074 -10.087268) (xy 89.087689 -10.004985) (xy 89.072199 -9.92095) (xy 89.064398 -9.835856)
			(xy 89.064349 -9.750405) (xy 0.509016 -9.750405) (xy 0.509016 -17.571212) (xy 147.308316 -17.571212)
			(xy 147.308773 -17.52685) (xy 147.316505 -17.438465) (xy 147.331911 -17.351089) (xy 147.354874 -17.265389)
			(xy 147.385219 -17.182016) (xy 147.422715 -17.101605) (xy 147.467076 -17.024769) (xy 147.517966 -16.952091)
			(xy 147.574997 -16.884125) (xy 147.637734 -16.821389) (xy 147.7057 -16.764359) (xy 147.778379 -16.71347)
			(xy 147.855216 -16.669109) (xy 147.935627 -16.631614) (xy 148.019 -16.60127) (xy 148.104701 -16.578309)
			(xy 148.192076 -16.562904) (xy 148.280462 -16.555173) (xy 148.324824 -16.554704) (xy 148.370622 -16.555198)
			(xy 148.461827 -16.563651) (xy 148.551863 -16.580484) (xy 148.639962 -16.605552) (xy 148.725372 -16.638643)
			(xy 148.807365 -16.679472) (xy 148.88524 -16.727693) (xy 148.958334 -16.782893) (xy 149.026023 -16.844602)
			(xy 149.08773 -16.912294) (xy 149.142928 -16.98539) (xy 149.191145 -17.063267) (xy 149.231972 -17.145261)
			(xy 149.265059 -17.230672) (xy 149.290124 -17.318772) (xy 149.306954 -17.408809) (xy 149.315404 -17.500014)
			(xy 149.315932 -17.545812) (xy 149.315932 -17.571212) (xy 153.571448 -17.571212) (xy 153.571987 -17.526853)
			(xy 153.579718 -17.438472) (xy 153.595123 -17.351101) (xy 153.618083 -17.265406) (xy 153.648425 -17.182037)
			(xy 153.685918 -17.10163) (xy 153.730275 -17.024797) (xy 153.78116 -16.952122) (xy 153.838185 -16.884158)
			(xy 153.900917 -16.821423) (xy 153.968877 -16.764394) (xy 154.04155 -16.713505) (xy 154.118381 -16.669144)
			(xy 154.198785 -16.631647) (xy 154.282152 -16.6013) (xy 154.367847 -16.578335) (xy 154.455216 -16.562926)
			(xy 154.543597 -16.55519) (xy 154.587956 -16.554704) (xy 154.633754 -16.555247) (xy 154.724958 -16.563695)
			(xy 154.814995 -16.580522) (xy 154.903094 -16.605585) (xy 154.988505 -16.63867) (xy 155.070499 -16.679496)
			(xy 155.148376 -16.727712) (xy 155.221471 -16.782909) (xy 155.289162 -16.844615) (xy 155.35087 -16.912304)
			(xy 155.40607 -16.985398) (xy 155.454289 -17.063273) (xy 155.495117 -17.145266) (xy 155.528205 -17.230676)
			(xy 155.553271 -17.318774) (xy 155.570101 -17.40881) (xy 155.578551 -17.500014) (xy 155.579064 -17.545812)
			(xy 155.579064 -17.571212) (xy 155.578559 -17.61627) (xy 155.570481 -17.706024) (xy 155.55439 -17.794693)
			(xy 155.530415 -17.881562) (xy 155.498751 -17.965933) (xy 155.45965 -18.047125) (xy 155.41343 -18.124486)
			(xy 155.36046 -18.197392) (xy 155.301169 -18.265256) (xy 155.236033 -18.327532) (xy 155.165577 -18.383719)
			(xy 155.090368 -18.433364) (xy 155.011012 -18.476068) (xy 154.928147 -18.511486) (xy 154.842441 -18.539333)
			(xy 154.754583 -18.559386) (xy 154.665282 -18.571483) (xy 154.575256 -18.575526) (xy 154.48523 -18.571483)
			(xy 154.395929 -18.559386) (xy 154.308071 -18.539333) (xy 154.222365 -18.511486) (xy 154.1395 -18.476068)
			(xy 154.060144 -18.433364) (xy 153.984935 -18.383719) (xy 153.914479 -18.327532) (xy 153.849343 -18.265256)
			(xy 153.790052 -18.197392) (xy 153.737082 -18.124486) (xy 153.690862 -18.047125) (xy 153.651761 -17.965933)
			(xy 153.620097 -17.881562) (xy 153.596122 -17.794693) (xy 153.580031 -17.706024) (xy 153.571953 -17.61627)
			(xy 153.571448 -17.571212) (xy 149.315932 -17.571212) (xy 149.315427 -17.61627) (xy 149.307349 -17.706024)
			(xy 149.291258 -17.794693) (xy 149.267283 -17.881562) (xy 149.235619 -17.965933) (xy 149.196518 -18.047125)
			(xy 149.150298 -18.124486) (xy 149.097328 -18.197392) (xy 149.038037 -18.265256) (xy 148.972901 -18.327532)
			(xy 148.902445 -18.383719) (xy 148.827236 -18.433364) (xy 148.74788 -18.476068) (xy 148.665015 -18.511486)
			(xy 148.579309 -18.539333) (xy 148.491451 -18.559386) (xy 148.40215 -18.571483) (xy 148.312124 -18.575526)
			(xy 148.222098 -18.571483) (xy 148.132797 -18.559386) (xy 148.044939 -18.539333) (xy 147.959233 -18.511486)
			(xy 147.876368 -18.476068) (xy 147.797012 -18.433364) (xy 147.721803 -18.383719) (xy 147.651347 -18.327532)
			(xy 147.586211 -18.265256) (xy 147.52692 -18.197392) (xy 147.47395 -18.124486) (xy 147.42773 -18.047125)
			(xy 147.388629 -17.965933) (xy 147.356965 -17.881562) (xy 147.33299 -17.794693) (xy 147.316899 -17.706024)
			(xy 147.308821 -17.61627) (xy 147.308316 -17.571212) (xy 0.509016 -17.571212) (xy 0.509016 -25.099663)
			(xy 37.367456 -25.099663) (xy 37.367456 -25.000313) (xy 37.37545 -24.901285) (xy 37.391387 -24.803222)
			(xy 37.415163 -24.706759) (xy 37.446624 -24.612522) (xy 37.485566 -24.521123) (xy 37.531736 -24.433153)
			(xy 37.584835 -24.349183) (xy 37.644519 -24.269759) (xy 37.7104 -24.195394) (xy 37.782051 -24.126572)
			(xy 37.859008 -24.063739) (xy 37.940771 -24.007302) (xy 38.026811 -23.957627) (xy 38.116568 -23.915036)
			(xy 38.209462 -23.879807) (xy 38.304889 -23.852166) (xy 38.402231 -23.832293) (xy 38.500857 -23.820318)
			(xy 38.600126 -23.816318) (xy 38.699395 -23.820318) (xy 38.798021 -23.832293) (xy 38.895363 -23.852166)
			(xy 38.99079 -23.879807) (xy 39.083684 -23.915036) (xy 39.173441 -23.957627) (xy 39.259481 -24.007302)
			(xy 39.341244 -24.063739) (xy 39.418201 -24.126572) (xy 39.489852 -24.195394) (xy 39.555733 -24.269759)
			(xy 39.615417 -24.349183) (xy 39.668516 -24.433153) (xy 39.714686 -24.521123) (xy 39.753628 -24.612522)
			(xy 39.785089 -24.706759) (xy 39.808865 -24.803222) (xy 39.824802 -24.901285) (xy 39.832796 -25.000313)
			(xy 39.833296 -25.049988) (xy 39.832848 -25.094499) (xy 104.408977 -25.094499) (xy 104.408977 -25.005477)
			(xy 104.416957 -24.916813) (xy 104.432853 -24.829222) (xy 104.456536 -24.743407) (xy 104.487816 -24.660062)
			(xy 104.526442 -24.579856) (xy 104.572101 -24.503435) (xy 104.624427 -24.431414) (xy 104.682998 -24.364374)
			(xy 104.747343 -24.302854) (xy 104.816943 -24.24735) (xy 104.891239 -24.198308) (xy 104.969631 -24.156123)
			(xy 105.05149 -24.121135) (xy 105.136155 -24.093626) (xy 105.222945 -24.073816) (xy 105.311161 -24.061866)
			(xy 105.400094 -24.057873) (xy 105.489027 -24.061866) (xy 105.577243 -24.073816) (xy 105.664033 -24.093626)
			(xy 105.748698 -24.121135) (xy 105.830557 -24.156123) (xy 105.908949 -24.198308) (xy 105.983245 -24.24735)
			(xy 106.052845 -24.302854) (xy 106.11719 -24.364374) (xy 106.175761 -24.431414) (xy 106.228087 -24.503435)
			(xy 106.273746 -24.579856) (xy 106.312372 -24.660062) (xy 106.343652 -24.743407) (xy 106.367335 -24.829222)
			(xy 106.383231 -24.916813) (xy 106.391211 -25.005477) (xy 106.39171 -25.049988) (xy 106.391211 -25.094499)
			(xy 106.383231 -25.183163) (xy 106.367335 -25.270754) (xy 106.343652 -25.356569) (xy 106.312372 -25.439914)
			(xy 106.273746 -25.52012) (xy 106.228087 -25.596541) (xy 106.175761 -25.668562) (xy 106.11719 -25.735602)
			(xy 106.052845 -25.797122) (xy 105.983245 -25.852626) (xy 105.908949 -25.901668) (xy 105.830557 -25.943853)
			(xy 105.748698 -25.978841) (xy 105.664033 -26.00635) (xy 105.577243 -26.02616) (xy 105.489027 -26.03811)
			(xy 105.400094 -26.042104) (xy 105.311161 -26.03811) (xy 105.222945 -26.02616) (xy 105.136155 -26.00635)
			(xy 105.05149 -25.978841) (xy 104.969631 -25.943853) (xy 104.891239 -25.901668) (xy 104.816943 -25.852626)
			(xy 104.747343 -25.797122) (xy 104.682998 -25.735602) (xy 104.624427 -25.668562) (xy 104.572101 -25.596541)
			(xy 104.526442 -25.52012) (xy 104.487816 -25.439914) (xy 104.456536 -25.356569) (xy 104.432853 -25.270754)
			(xy 104.416957 -25.183163) (xy 104.408977 -25.094499) (xy 39.832848 -25.094499) (xy 39.832796 -25.099663)
			(xy 39.824802 -25.198691) (xy 39.808865 -25.296754) (xy 39.785089 -25.393217) (xy 39.753628 -25.487454)
			(xy 39.714686 -25.578853) (xy 39.668516 -25.666823) (xy 39.615417 -25.750793) (xy 39.555733 -25.830217)
			(xy 39.489852 -25.904582) (xy 39.418201 -25.973404) (xy 39.341244 -26.036237) (xy 39.259481 -26.092674)
			(xy 39.173441 -26.142349) (xy 39.083684 -26.18494) (xy 38.99079 -26.220169) (xy 38.895363 -26.24781)
			(xy 38.798021 -26.267683) (xy 38.699395 -26.279658) (xy 38.600126 -26.283659) (xy 38.500857 -26.279658)
			(xy 38.402231 -26.267683) (xy 38.304889 -26.24781) (xy 38.209462 -26.220169) (xy 38.116568 -26.18494)
			(xy 38.026811 -26.142349) (xy 37.940771 -26.092674) (xy 37.859008 -26.036237) (xy 37.782051 -25.973404)
			(xy 37.7104 -25.904582) (xy 37.644519 -25.830217) (xy 37.584835 -25.750793) (xy 37.531736 -25.666823)
			(xy 37.485566 -25.578853) (xy 37.446624 -25.487454) (xy 37.415163 -25.393217) (xy 37.391387 -25.296754)
			(xy 37.37545 -25.198691) (xy 37.367456 -25.099663) (xy 0.509016 -25.099663) (xy 0.509016 -29.299916)
			(xy 0.509545 -29.345713) (xy 0.517996 -29.436917) (xy 0.534827 -29.526952) (xy 0.559893 -29.61505)
			(xy 0.59298 -29.700459) (xy 0.633808 -29.782451) (xy 0.682026 -29.860326) (xy 0.737224 -29.93342)
			(xy 0.798931 -30.001109) (xy 0.86662 -30.062816) (xy 0.939714 -30.118014) (xy 1.017589 -30.166232)
			(xy 1.099581 -30.20706) (xy 1.18499 -30.240147) (xy 1.273088 -30.265213) (xy 1.363123 -30.282044)
			(xy 1.454327 -30.290495) (xy 1.500124 -30.291024) (xy 6.500114 -30.291024) (xy 6.56323 -30.29152)
			(xy 6.689213 -30.299446) (xy 6.81445 -30.315267) (xy 6.938446 -30.338921) (xy 7.060713 -30.370314)
			(xy 7.180767 -30.409322) (xy 7.298135 -30.455792) (xy 7.412353 -30.509539) (xy 7.522971 -30.570352)
			(xy 7.629552 -30.637991) (xy 7.731676 -30.712188) (xy 7.82894 -30.792652) (xy 7.920959 -30.879064)
			(xy 8.007371 -30.971083) (xy 8.087834 -31.068347) (xy 8.162032 -31.170471) (xy 8.22967 -31.277053)
			(xy 8.290483 -31.387671) (xy 8.34423 -31.501889) (xy 8.390699 -31.619257) (xy 8.429707 -31.739311)
			(xy 8.4611 -31.861577) (xy 8.484753 -31.985574) (xy 8.500574 -32.110811) (xy 8.5085 -32.236794) (xy 8.509 -32.29991)
			(xy 8.509 -42.857987) (xy 9.994378 -42.857987) (xy 9.994378 -42.762365) (xy 10.002274 -42.667069)
			(xy 10.018013 -42.572751) (xy 10.041487 -42.480054) (xy 10.072536 -42.389613) (xy 10.110947 -42.302045)
			(xy 10.156458 -42.217947) (xy 10.208758 -42.137895) (xy 10.267491 -42.062436) (xy 10.332254 -41.992084)
			(xy 10.402606 -41.927321) (xy 10.478065 -41.868588) (xy 10.558117 -41.816288) (xy 10.642215 -41.770777)
			(xy 10.729783 -41.732366) (xy 10.820224 -41.701317) (xy 10.912921 -41.677843) (xy 11.007239 -41.662104)
			(xy 11.102535 -41.654208) (xy 11.198157 -41.654208) (xy 11.293453 -41.662104) (xy 11.387771 -41.677843)
			(xy 11.480468 -41.701317) (xy 11.570909 -41.732366) (xy 11.658477 -41.770777) (xy 11.742575 -41.816288)
			(xy 11.822627 -41.868588) (xy 11.898086 -41.927321) (xy 11.968438 -41.992084) (xy 12.033201 -42.062436)
			(xy 12.091934 -42.137895) (xy 12.144234 -42.217947) (xy 12.189745 -42.302045) (xy 12.228156 -42.389613)
			(xy 12.259205 -42.480054) (xy 12.282679 -42.572751) (xy 12.298418 -42.667069) (xy 12.306314 -42.762365)
			(xy 12.306808 -42.810176) (xy 12.306314 -42.857987) (xy 12.298418 -42.953283) (xy 12.282679 -43.047601)
			(xy 12.259205 -43.140298) (xy 12.228156 -43.230739) (xy 12.189745 -43.318307) (xy 12.144234 -43.402405)
			(xy 12.091934 -43.482457) (xy 12.033201 -43.557916) (xy 11.968438 -43.628268) (xy 11.898086 -43.693031)
			(xy 11.822627 -43.751764) (xy 11.742575 -43.804064) (xy 11.658477 -43.849575) (xy 11.570909 -43.887986)
			(xy 11.480468 -43.919035) (xy 11.387771 -43.942509) (xy 11.293453 -43.958248) (xy 11.198157 -43.966144)
			(xy 11.102535 -43.966144) (xy 11.007239 -43.958248) (xy 10.912921 -43.942509) (xy 10.820224 -43.919035)
			(xy 10.729783 -43.887986) (xy 10.642215 -43.849575) (xy 10.558117 -43.804064) (xy 10.478065 -43.751764)
			(xy 10.402606 -43.693031) (xy 10.332254 -43.628268) (xy 10.267491 -43.557916) (xy 10.208758 -43.482457)
			(xy 10.156458 -43.402405) (xy 10.110947 -43.318307) (xy 10.072536 -43.230739) (xy 10.041487 -43.140298)
			(xy 10.018013 -43.047601) (xy 10.002274 -42.953283) (xy 9.994378 -42.857987) (xy 8.509 -42.857987)
			(xy 8.509 -47.517812) (xy 154.521408 -47.517812) (xy 154.521408 -45.112686) (xy 155.019756 -44.614338)
			(xy 155.72486 -44.614338) (xy 156.223208 -45.112686) (xy 156.223208 -47.146464) (xy 158.2928 -47.146464)
			(xy 158.2928 -45.53966) (xy 158.530798 -45.301662) (xy 158.867602 -45.301662) (xy 159.1056 -45.53966)
			(xy 159.1056 -47.146464) (xy 158.867602 -47.384462) (xy 158.530798 -47.384462) (xy 158.2928 -47.146464)
			(xy 156.223208 -47.146464) (xy 156.223208 -47.517812) (xy 155.72486 -48.01616) (xy 155.019756 -48.01616)
			(xy 154.521408 -47.517812) (xy 8.509 -47.517812) (xy 8.509 -51.327812) (xy 154.521408 -51.327812)
			(xy 154.521408 -48.922686) (xy 155.019756 -48.424338) (xy 155.72486 -48.424338) (xy 156.223208 -48.922686)
			(xy 156.223208 -50.999136) (xy 160.873948 -50.999136) (xy 160.873948 -49.392332) (xy 161.111946 -49.154334)
			(xy 161.44875 -49.154334) (xy 161.686748 -49.392332) (xy 161.686748 -50.999136) (xy 161.44875 -51.237134)
			(xy 161.111946 -51.237134) (xy 160.873948 -50.999136) (xy 156.223208 -50.999136) (xy 156.223208 -51.327812)
			(xy 155.72486 -51.82616) (xy 155.019756 -51.82616) (xy 154.521408 -51.327812) (xy 8.509 -51.327812)
			(xy 8.509 -58.837889) (xy 9.994378 -58.837889) (xy 9.994378 -58.742267) (xy 10.002274 -58.646971)
			(xy 10.018013 -58.552653) (xy 10.041487 -58.459956) (xy 10.072536 -58.369515) (xy 10.110947 -58.281947)
			(xy 10.156458 -58.197849) (xy 10.208758 -58.117797) (xy 10.267491 -58.042338) (xy 10.332254 -57.971986)
			(xy 10.402606 -57.907223) (xy 10.478065 -57.84849) (xy 10.558117 -57.79619) (xy 10.642215 -57.750679)
			(xy 10.729783 -57.712268) (xy 10.820224 -57.681219) (xy 10.912921 -57.657745) (xy 11.007239 -57.642006)
			(xy 11.102535 -57.63411) (xy 11.198157 -57.63411) (xy 11.293453 -57.642006) (xy 11.387771 -57.657745)
			(xy 11.480468 -57.681219) (xy 11.570909 -57.712268) (xy 11.658477 -57.750679) (xy 11.742575 -57.79619)
			(xy 11.822627 -57.84849) (xy 11.898086 -57.907223) (xy 11.968438 -57.971986) (xy 12.033201 -58.042338)
			(xy 12.091934 -58.117797) (xy 12.144234 -58.197849) (xy 12.189745 -58.281947) (xy 12.228156 -58.369515)
			(xy 12.259205 -58.459956) (xy 12.282679 -58.552653) (xy 12.298418 -58.646971) (xy 12.306314 -58.742267)
			(xy 12.306808 -58.790078) (xy 12.306314 -58.837889) (xy 12.298418 -58.933185) (xy 12.282679 -59.027503)
			(xy 12.259205 -59.1202) (xy 12.253908 -59.13563) (xy 109.258606 -59.13563) (xy 109.258606 -59.04549)
			(xy 109.266686 -58.955714) (xy 109.282781 -58.867023) (xy 109.306761 -58.780131) (xy 109.338434 -58.69574)
			(xy 109.377544 -58.614527) (xy 109.423776 -58.537147) (xy 109.476759 -58.464222) (xy 109.536065 -58.396341)
			(xy 109.601218 -58.334049) (xy 109.671692 -58.277847) (xy 109.74692 -58.22819) (xy 109.826296 -58.185476)
			(xy 109.909182 -58.150048) (xy 109.99491 -58.122194) (xy 110.082789 -58.102136) (xy 110.172113 -58.090036)
			(xy 110.262162 -58.085992) (xy 110.352211 -58.090036) (xy 110.441535 -58.102136) (xy 110.529414 -58.122194)
			(xy 110.615142 -58.150048) (xy 110.698028 -58.185476) (xy 110.777404 -58.22819) (xy 110.852632 -58.277847)
			(xy 110.923106 -58.334049) (xy 110.988259 -58.396341) (xy 111.047565 -58.464222) (xy 111.100548 -58.537147)
			(xy 111.14678 -58.614527) (xy 111.18589 -58.69574) (xy 111.217563 -58.780131) (xy 111.241543 -58.867023)
			(xy 111.257638 -58.955714) (xy 111.265718 -59.04549) (xy 111.266224 -59.09056) (xy 111.265718 -59.13563)
			(xy 111.257638 -59.225406) (xy 111.241543 -59.314097) (xy 111.217563 -59.400989) (xy 111.18589 -59.48538)
			(xy 111.14678 -59.566593) (xy 111.100548 -59.643973) (xy 111.047565 -59.716898) (xy 110.988259 -59.784779)
			(xy 110.923106 -59.847071) (xy 110.852632 -59.903273) (xy 110.777404 -59.95293) (xy 110.698028 -59.995644)
			(xy 110.615142 -60.031072) (xy 110.529414 -60.058926) (xy 110.441535 -60.078984) (xy 110.352211 -60.091084)
			(xy 110.262162 -60.095128) (xy 110.172113 -60.091084) (xy 110.082789 -60.078984) (xy 109.99491 -60.058926)
			(xy 109.909182 -60.031072) (xy 109.826296 -59.995644) (xy 109.74692 -59.95293) (xy 109.671692 -59.903273)
			(xy 109.601218 -59.847071) (xy 109.536065 -59.784779) (xy 109.476759 -59.716898) (xy 109.423776 -59.643973)
			(xy 109.377544 -59.566593) (xy 109.338434 -59.48538) (xy 109.306761 -59.400989) (xy 109.282781 -59.314097)
			(xy 109.266686 -59.225406) (xy 109.258606 -59.13563) (xy 12.253908 -59.13563) (xy 12.228156 -59.210641)
			(xy 12.189745 -59.298209) (xy 12.144234 -59.382307) (xy 12.091934 -59.462359) (xy 12.033201 -59.537818)
			(xy 11.968438 -59.60817) (xy 11.898086 -59.672933) (xy 11.822627 -59.731666) (xy 11.742575 -59.783966)
			(xy 11.658477 -59.829477) (xy 11.570909 -59.867888) (xy 11.480468 -59.898937) (xy 11.387771 -59.922411)
			(xy 11.293453 -59.93815) (xy 11.198157 -59.946046) (xy 11.102535 -59.946046) (xy 11.007239 -59.93815)
			(xy 10.912921 -59.922411) (xy 10.820224 -59.898937) (xy 10.729783 -59.867888) (xy 10.642215 -59.829477)
			(xy 10.558117 -59.783966) (xy 10.478065 -59.731666) (xy 10.402606 -59.672933) (xy 10.332254 -59.60817)
			(xy 10.267491 -59.537818) (xy 10.208758 -59.462359) (xy 10.156458 -59.382307) (xy 10.110947 -59.298209)
			(xy 10.072536 -59.210641) (xy 10.041487 -59.1202) (xy 10.018013 -59.027503) (xy 10.002274 -58.933185)
			(xy 9.994378 -58.837889) (xy 8.509 -58.837889) (xy 8.509 -62.863044) (xy 23.993081 -62.863044) (xy 23.993081 -62.736908)
			(xy 24.001001 -62.61102) (xy 24.016811 -62.485878) (xy 24.040446 -62.361975) (xy 24.071815 -62.239802)
			(xy 24.110793 -62.119839) (xy 24.157227 -62.00256) (xy 24.210934 -61.888428) (xy 24.271701 -61.777893)
			(xy 24.339288 -61.671393) (xy 24.413429 -61.569346) (xy 24.493832 -61.472156) (xy 24.580178 -61.380206)
			(xy 24.672128 -61.29386) (xy 24.769318 -61.213457) (xy 24.871365 -61.139316) (xy 24.977865 -61.071729)
			(xy 25.0884 -61.010962) (xy 25.202532 -60.957255) (xy 25.319811 -60.910821) (xy 25.439774 -60.871843)
			(xy 25.561947 -60.840474) (xy 25.68585 -60.816839) (xy 25.810992 -60.801029) (xy 25.93688 -60.793109)
			(xy 26.063016 -60.793109) (xy 26.188904 -60.801029) (xy 26.314046 -60.816839) (xy 26.437949 -60.840474)
			(xy 26.560122 -60.871843) (xy 26.680085 -60.910821) (xy 26.797364 -60.957255) (xy 26.911496 -61.010962)
			(xy 27.022031 -61.071729) (xy 27.128531 -61.139316) (xy 27.230578 -61.213457) (xy 27.327768 -61.29386)
			(xy 27.419718 -61.380206) (xy 27.506064 -61.472156) (xy 27.586467 -61.569346) (xy 27.660608 -61.671393)
			(xy 27.728195 -61.777893) (xy 27.788962 -61.888428) (xy 27.842669 -62.00256) (xy 27.889103 -62.119839)
			(xy 27.928081 -62.239802) (xy 27.95945 -62.361975) (xy 27.983085 -62.485878) (xy 27.998895 -62.61102)
			(xy 28.006815 -62.736908) (xy 28.00731 -62.799976) (xy 28.006815 -62.863044) (xy 87.993207 -62.863044)
			(xy 87.993207 -62.736908) (xy 88.001127 -62.61102) (xy 88.016937 -62.485878) (xy 88.040572 -62.361975)
			(xy 88.071941 -62.239802) (xy 88.110919 -62.119839) (xy 88.157353 -62.00256) (xy 88.21106 -61.888428)
			(xy 88.271827 -61.777893) (xy 88.339414 -61.671393) (xy 88.413555 -61.569346) (xy 88.493958 -61.472156)
			(xy 88.580304 -61.380206) (xy 88.672254 -61.29386) (xy 88.769444 -61.213457) (xy 88.871491 -61.139316)
			(xy 88.977991 -61.071729) (xy 89.088526 -61.010962) (xy 89.202658 -60.957255) (xy 89.319937 -60.910821)
			(xy 89.4399 -60.871843) (xy 89.562073 -60.840474) (xy 89.685976 -60.816839) (xy 89.811118 -60.801029)
			(xy 89.937006 -60.793109) (xy 90.063142 -60.793109) (xy 90.18903 -60.801029) (xy 90.314172 -60.816839)
			(xy 90.438075 -60.840474) (xy 90.560248 -60.871843) (xy 90.680211 -60.910821) (xy 90.79749 -60.957255)
			(xy 90.911622 -61.010962) (xy 91.022157 -61.071729) (xy 91.128657 -61.139316) (xy 91.230704 -61.213457)
			(xy 91.327894 -61.29386) (xy 91.419844 -61.380206) (xy 91.50619 -61.472156) (xy 91.586593 -61.569346)
			(xy 91.660734 -61.671393) (xy 91.728321 -61.777893) (xy 91.789088 -61.888428) (xy 91.842795 -62.00256)
			(xy 91.889229 -62.119839) (xy 91.928207 -62.239802) (xy 91.959576 -62.361975) (xy 91.983211 -62.485878)
			(xy 91.999021 -62.61102) (xy 92.006941 -62.736908) (xy 92.007436 -62.799976) (xy 92.006941 -62.863044)
			(xy 91.999021 -62.988932) (xy 91.983211 -63.114074) (xy 91.959576 -63.237977) (xy 91.928207 -63.36015)
			(xy 91.889229 -63.480113) (xy 91.842795 -63.597392) (xy 91.789088 -63.711524) (xy 91.728321 -63.822059)
			(xy 91.660734 -63.928559) (xy 91.586593 -64.030606) (xy 91.50619 -64.127796) (xy 91.419844 -64.219746)
			(xy 91.327894 -64.306092) (xy 91.230704 -64.386495) (xy 91.128657 -64.460636) (xy 91.022157 -64.528223)
			(xy 90.911622 -64.58899) (xy 90.79749 -64.642697) (xy 90.680211 -64.689131) (xy 90.560248 -64.728109)
			(xy 90.438075 -64.759478) (xy 90.314172 -64.783113) (xy 90.18903 -64.798923) (xy 90.063142 -64.806843)
			(xy 89.937006 -64.806843) (xy 89.811118 -64.798923) (xy 89.685976 -64.783113) (xy 89.562073 -64.759478)
			(xy 89.4399 -64.728109) (xy 89.319937 -64.689131) (xy 89.202658 -64.642697) (xy 89.088526 -64.58899)
			(xy 88.977991 -64.528223) (xy 88.871491 -64.460636) (xy 88.769444 -64.386495) (xy 88.672254 -64.306092)
			(xy 88.580304 -64.219746) (xy 88.493958 -64.127796) (xy 88.413555 -64.030606) (xy 88.339414 -63.928559)
			(xy 88.271827 -63.822059) (xy 88.21106 -63.711524) (xy 88.157353 -63.597392) (xy 88.110919 -63.480113)
			(xy 88.071941 -63.36015) (xy 88.040572 -63.237977) (xy 88.016937 -63.114074) (xy 88.001127 -62.988932)
			(xy 87.993207 -62.863044) (xy 28.006815 -62.863044) (xy 27.998895 -62.988932) (xy 27.983085 -63.114074)
			(xy 27.95945 -63.237977) (xy 27.928081 -63.36015) (xy 27.889103 -63.480113) (xy 27.842669 -63.597392)
			(xy 27.788962 -63.711524) (xy 27.728195 -63.822059) (xy 27.660608 -63.928559) (xy 27.586467 -64.030606)
			(xy 27.506064 -64.127796) (xy 27.419718 -64.219746) (xy 27.327768 -64.306092) (xy 27.230578 -64.386495)
			(xy 27.128531 -64.460636) (xy 27.022031 -64.528223) (xy 26.911496 -64.58899) (xy 26.797364 -64.642697)
			(xy 26.680085 -64.689131) (xy 26.560122 -64.728109) (xy 26.437949 -64.759478) (xy 26.314046 -64.783113)
			(xy 26.188904 -64.798923) (xy 26.063016 -64.806843) (xy 25.93688 -64.806843) (xy 25.810992 -64.798923)
			(xy 25.68585 -64.783113) (xy 25.561947 -64.759478) (xy 25.439774 -64.728109) (xy 25.319811 -64.689131)
			(xy 25.202532 -64.642697) (xy 25.0884 -64.58899) (xy 24.977865 -64.528223) (xy 24.871365 -64.460636)
			(xy 24.769318 -64.386495) (xy 24.672128 -64.306092) (xy 24.580178 -64.219746) (xy 24.493832 -64.127796)
			(xy 24.413429 -64.030606) (xy 24.339288 -63.928559) (xy 24.271701 -63.822059) (xy 24.210934 -63.711524)
			(xy 24.157227 -63.597392) (xy 24.110793 -63.480113) (xy 24.071815 -63.36015) (xy 24.040446 -63.237977)
			(xy 24.016811 -63.114074) (xy 24.001001 -62.988932) (xy 23.993081 -62.863044) (xy 8.509 -62.863044)
			(xy 8.509 -69.30009) (xy 8.508504 -69.363206) (xy 8.500578 -69.48919) (xy 8.484757 -69.614427) (xy 8.461104 -69.738423)
			(xy 8.429711 -69.86069) (xy 8.390703 -69.980744) (xy 8.344234 -70.098112) (xy 8.290487 -70.212331)
			(xy 8.229674 -70.32295) (xy 8.162035 -70.429531) (xy 8.087837 -70.531656) (xy 8.007374 -70.628919)
			(xy 7.920962 -70.720939) (xy 7.828942 -70.807351) (xy 7.731679 -70.887815) (xy 7.629555 -70.962013)
			(xy 7.522973 -71.029652) (xy 7.412355 -71.090465) (xy 7.298136 -71.144212) (xy 7.180768 -71.190682)
			(xy 7.060714 -71.22969) (xy 6.938447 -71.261083) (xy 6.814451 -71.284737) (xy 6.689214 -71.300558)
			(xy 6.56323 -71.308484) (xy 6.500114 -71.308976) (xy 1.500124 -71.308976) (xy 1.454327 -71.309505)
			(xy 1.363123 -71.317956) (xy 1.273088 -71.334787) (xy 1.18499 -71.359853) (xy 1.099581 -71.39294)
			(xy 1.017589 -71.433768) (xy 0.939714 -71.481986) (xy 0.86662 -71.537184) (xy 0.798931 -71.598891)
			(xy 0.737224 -71.66658) (xy 0.682026 -71.739674) (xy 0.633808 -71.817549) (xy 0.59298 -71.899541)
			(xy 0.559893 -71.98495) (xy 0.534827 -72.073048) (xy 0.517996 -72.163083) (xy 0.509545 -72.254287)
			(xy 0.509016 -72.300084) (xy 0.509016 -77.082841) (xy 4.534904 -77.082841) (xy 4.534904 -76.959015)
			(xy 4.542837 -76.835444) (xy 4.558672 -76.712636) (xy 4.582342 -76.591094) (xy 4.613751 -76.471318)
			(xy 4.652769 -76.353801) (xy 4.699237 -76.239025) (xy 4.752963 -76.127462) (xy 4.813726 -76.019571)
			(xy 4.881277 -75.915794) (xy 4.955339 -75.816559) (xy 5.035606 -75.722272) (xy 5.121749 -75.633322)
			(xy 5.213414 -75.550074) (xy 5.310225 -75.472871) (xy 5.411783 -75.402028) (xy 5.517671 -75.337838)
			(xy 5.627455 -75.280564) (xy 5.740682 -75.230441) (xy 5.856889 -75.187676) (xy 5.975596 -75.152445)
			(xy 6.096317 -75.124891) (xy 6.218555 -75.105128) (xy 6.341808 -75.093238) (xy 6.46557 -75.08927)
			(xy 6.589332 -75.093238) (xy 6.712585 -75.105128) (xy 6.834823 -75.124891) (xy 6.955544 -75.152445)
			(xy 7.074251 -75.187676) (xy 7.190458 -75.230441) (xy 7.303685 -75.280564) (xy 7.413469 -75.337838)
			(xy 7.519357 -75.402028) (xy 7.620915 -75.472871) (xy 7.717726 -75.550074) (xy 7.809391 -75.633322)
			(xy 7.895534 -75.722272) (xy 7.975801 -75.816559) (xy 8.049863 -75.915794) (xy 8.117414 -76.019571)
			(xy 8.178177 -76.127462) (xy 8.231903 -76.239025) (xy 8.278371 -76.353801) (xy 8.317389 -76.471318)
			(xy 8.348798 -76.591094) (xy 8.372468 -76.712636) (xy 8.388303 -76.835444) (xy 8.396236 -76.959015)
			(xy 8.396732 -77.020928) (xy 8.396236 -77.082841) (xy 8.388303 -77.206412) (xy 8.372468 -77.32922)
			(xy 8.348798 -77.450762) (xy 8.317389 -77.570538) (xy 8.278371 -77.688055) (xy 8.231903 -77.802831)
			(xy 8.178177 -77.914394) (xy 8.117414 -78.022285) (xy 8.049863 -78.126062) (xy 7.975801 -78.225297)
			(xy 7.895534 -78.319584) (xy 7.809391 -78.408534) (xy 7.717726 -78.491782) (xy 7.620915 -78.568985)
			(xy 7.519357 -78.639828) (xy 7.413469 -78.704018) (xy 7.303685 -78.761292) (xy 7.190458 -78.811415)
			(xy 7.074251 -78.85418) (xy 6.955544 -78.889411) (xy 6.834823 -78.916965) (xy 6.712585 -78.936728)
			(xy 6.589332 -78.948618) (xy 6.46557 -78.952587) (xy 6.341808 -78.948618) (xy 6.218555 -78.936728)
			(xy 6.096317 -78.916965) (xy 5.975596 -78.889411) (xy 5.856889 -78.85418) (xy 5.740682 -78.811415)
			(xy 5.627455 -78.761292) (xy 5.517671 -78.704018) (xy 5.411783 -78.639828) (xy 5.310225 -78.568985)
			(xy 5.213414 -78.491782) (xy 5.121749 -78.408534) (xy 5.035606 -78.319584) (xy 4.955339 -78.225297)
			(xy 4.881277 -78.126062) (xy 4.813726 -78.022285) (xy 4.752963 -77.914394) (xy 4.699237 -77.802831)
			(xy 4.652769 -77.688055) (xy 4.613751 -77.570538) (xy 4.582342 -77.450762) (xy 4.558672 -77.32922)
			(xy 4.542837 -77.206412) (xy 4.534904 -77.082841) (xy 0.509016 -77.082841) (xy 0.509016 -79.26132)
			(xy 109.258606 -79.26132) (xy 109.258606 -79.17118) (xy 109.266686 -79.081404) (xy 109.282781 -78.992713)
			(xy 109.306761 -78.905821) (xy 109.338434 -78.82143) (xy 109.377544 -78.740217) (xy 109.423776 -78.662837)
			(xy 109.476759 -78.589912) (xy 109.536065 -78.522031) (xy 109.601218 -78.459739) (xy 109.671692 -78.403537)
			(xy 109.74692 -78.35388) (xy 109.826296 -78.311166) (xy 109.909182 -78.275738) (xy 109.99491 -78.247884)
			(xy 110.082789 -78.227826) (xy 110.172113 -78.215726) (xy 110.262162 -78.211682) (xy 110.352211 -78.215726)
			(xy 110.441535 -78.227826) (xy 110.529414 -78.247884) (xy 110.615142 -78.275738) (xy 110.698028 -78.311166)
			(xy 110.777404 -78.35388) (xy 110.852632 -78.403537) (xy 110.923106 -78.459739) (xy 110.988259 -78.522031)
			(xy 111.047565 -78.589912) (xy 111.100548 -78.662837) (xy 111.14678 -78.740217) (xy 111.18589 -78.82143)
			(xy 111.217563 -78.905821) (xy 111.241543 -78.992713) (xy 111.257638 -79.081404) (xy 111.265718 -79.17118)
			(xy 111.266224 -79.21625) (xy 111.265718 -79.26132) (xy 111.257638 -79.351096) (xy 111.241543 -79.439787)
			(xy 111.217563 -79.526679) (xy 111.18589 -79.61107) (xy 111.14678 -79.692283) (xy 111.100548 -79.769663)
			(xy 111.047565 -79.842588) (xy 110.988259 -79.910469) (xy 110.923106 -79.972761) (xy 110.852632 -80.028963)
			(xy 110.777404 -80.07862) (xy 110.698028 -80.121334) (xy 110.615142 -80.156762) (xy 110.529414 -80.184616)
			(xy 110.441535 -80.204674) (xy 110.352211 -80.216774) (xy 110.262162 -80.220818) (xy 110.172113 -80.216774)
			(xy 110.082789 -80.204674) (xy 109.99491 -80.184616) (xy 109.909182 -80.156762) (xy 109.826296 -80.121334)
			(xy 109.74692 -80.07862) (xy 109.671692 -80.028963) (xy 109.601218 -79.972761) (xy 109.536065 -79.910469)
			(xy 109.476759 -79.842588) (xy 109.423776 -79.769663) (xy 109.377544 -79.692283) (xy 109.338434 -79.61107)
			(xy 109.306761 -79.526679) (xy 109.282781 -79.439787) (xy 109.266686 -79.351096) (xy 109.258606 -79.26132)
			(xy 0.509016 -79.26132) (xy 0.509016 -90.697241) (xy 4.534904 -90.697241) (xy 4.534904 -90.573415)
			(xy 4.542837 -90.449844) (xy 4.558672 -90.327036) (xy 4.582342 -90.205494) (xy 4.613751 -90.085718)
			(xy 4.652769 -89.968201) (xy 4.699237 -89.853425) (xy 4.752963 -89.741862) (xy 4.813726 -89.633971)
			(xy 4.881277 -89.530194) (xy 4.955339 -89.430959) (xy 5.035606 -89.336672) (xy 5.121749 -89.247722)
			(xy 5.213414 -89.164474) (xy 5.310225 -89.087271) (xy 5.411783 -89.016428) (xy 5.517671 -88.952238)
			(xy 5.627455 -88.894964) (xy 5.740682 -88.844841) (xy 5.856889 -88.802076) (xy 5.975596 -88.766845)
			(xy 6.096317 -88.739291) (xy 6.218555 -88.719528) (xy 6.341808 -88.707638) (xy 6.46557 -88.70367)
			(xy 6.589332 -88.707638) (xy 6.712585 -88.719528) (xy 6.834823 -88.739291) (xy 6.955544 -88.766845)
			(xy 7.074251 -88.802076) (xy 7.190458 -88.844841) (xy 7.231461 -88.862992) (xy 23.993081 -88.862992)
			(xy 23.993081 -88.736856) (xy 24.001001 -88.610968) (xy 24.016811 -88.485826) (xy 24.040446 -88.361923)
			(xy 24.071815 -88.23975) (xy 24.110793 -88.119787) (xy 24.157227 -88.002508) (xy 24.210934 -87.888376)
			(xy 24.271701 -87.777841) (xy 24.339288 -87.671341) (xy 24.413429 -87.569294) (xy 24.493832 -87.472104)
			(xy 24.580178 -87.380154) (xy 24.672128 -87.293808) (xy 24.769318 -87.213405) (xy 24.871365 -87.139264)
			(xy 24.977865 -87.071677) (xy 25.0884 -87.01091) (xy 25.202532 -86.957203) (xy 25.319811 -86.910769)
			(xy 25.439774 -86.871791) (xy 25.561947 -86.840422) (xy 25.68585 -86.816787) (xy 25.810992 -86.800977)
			(xy 25.93688 -86.793057) (xy 26.063016 -86.793057) (xy 26.188904 -86.800977) (xy 26.314046 -86.816787)
			(xy 26.437949 -86.840422) (xy 26.560122 -86.871791) (xy 26.680085 -86.910769) (xy 26.797364 -86.957203)
			(xy 26.911496 -87.01091) (xy 27.022031 -87.071677) (xy 27.128531 -87.139264) (xy 27.230578 -87.213405)
			(xy 27.327768 -87.293808) (xy 27.419718 -87.380154) (xy 27.506064 -87.472104) (xy 27.586467 -87.569294)
			(xy 27.660608 -87.671341) (xy 27.728195 -87.777841) (xy 27.788962 -87.888376) (xy 27.842669 -88.002508)
			(xy 27.889103 -88.119787) (xy 27.928081 -88.23975) (xy 27.95945 -88.361923) (xy 27.983085 -88.485826)
			(xy 27.998895 -88.610968) (xy 28.006815 -88.736856) (xy 28.00731 -88.799924) (xy 28.006815 -88.862992)
			(xy 87.993207 -88.862992) (xy 87.993207 -88.736856) (xy 88.001127 -88.610968) (xy 88.016937 -88.485826)
			(xy 88.040572 -88.361923) (xy 88.071941 -88.23975) (xy 88.110919 -88.119787) (xy 88.157353 -88.002508)
			(xy 88.21106 -87.888376) (xy 88.271827 -87.777841) (xy 88.339414 -87.671341) (xy 88.413555 -87.569294)
			(xy 88.493958 -87.472104) (xy 88.580304 -87.380154) (xy 88.672254 -87.293808) (xy 88.769444 -87.213405)
			(xy 88.871491 -87.139264) (xy 88.977991 -87.071677) (xy 89.088526 -87.01091) (xy 89.202658 -86.957203)
			(xy 89.319937 -86.910769) (xy 89.4399 -86.871791) (xy 89.562073 -86.840422) (xy 89.685976 -86.816787)
			(xy 89.811118 -86.800977) (xy 89.937006 -86.793057) (xy 90.063142 -86.793057) (xy 90.18903 -86.800977)
			(xy 90.314172 -86.816787) (xy 90.438075 -86.840422) (xy 90.560248 -86.871791) (xy 90.680211 -86.910769)
			(xy 90.79749 -86.957203) (xy 90.911622 -87.01091) (xy 91.022157 -87.071677) (xy 91.128657 -87.139264)
			(xy 91.230704 -87.213405) (xy 91.327894 -87.293808) (xy 91.419844 -87.380154) (xy 91.50619 -87.472104)
			(xy 91.586593 -87.569294) (xy 91.660734 -87.671341) (xy 91.728321 -87.777841) (xy 91.789088 -87.888376)
			(xy 91.842795 -88.002508) (xy 91.889229 -88.119787) (xy 91.928207 -88.23975) (xy 91.959576 -88.361923)
			(xy 91.983211 -88.485826) (xy 91.999021 -88.610968) (xy 92.006941 -88.736856) (xy 92.007436 -88.799924)
			(xy 92.006941 -88.862992) (xy 91.999021 -88.98888) (xy 91.983211 -89.114022) (xy 91.959576 -89.237925)
			(xy 91.928207 -89.360098) (xy 91.889229 -89.480061) (xy 91.842795 -89.59734) (xy 91.789088 -89.711472)
			(xy 91.728321 -89.822007) (xy 91.660734 -89.928507) (xy 91.586593 -90.030554) (xy 91.50619 -90.127744)
			(xy 91.419844 -90.219694) (xy 91.327894 -90.30604) (xy 91.230704 -90.386443) (xy 91.128657 -90.460584)
			(xy 91.022157 -90.528171) (xy 90.911622 -90.588938) (xy 90.79749 -90.642645) (xy 90.680211 -90.689079)
			(xy 90.560248 -90.728057) (xy 90.438075 -90.759426) (xy 90.314172 -90.783061) (xy 90.18903 -90.798871)
			(xy 90.063142 -90.806791) (xy 89.937006 -90.806791) (xy 89.811118 -90.798871) (xy 89.685976 -90.783061)
			(xy 89.562073 -90.759426) (xy 89.4399 -90.728057) (xy 89.319937 -90.689079) (xy 89.202658 -90.642645)
			(xy 89.088526 -90.588938) (xy 88.977991 -90.528171) (xy 88.871491 -90.460584) (xy 88.769444 -90.386443)
			(xy 88.672254 -90.30604) (xy 88.580304 -90.219694) (xy 88.493958 -90.127744) (xy 88.413555 -90.030554)
			(xy 88.339414 -89.928507) (xy 88.271827 -89.822007) (xy 88.21106 -89.711472) (xy 88.157353 -89.59734)
			(xy 88.110919 -89.480061) (xy 88.071941 -89.360098) (xy 88.040572 -89.237925) (xy 88.016937 -89.114022)
			(xy 88.001127 -88.98888) (xy 87.993207 -88.862992) (xy 28.006815 -88.862992) (xy 27.998895 -88.98888)
			(xy 27.983085 -89.114022) (xy 27.95945 -89.237925) (xy 27.928081 -89.360098) (xy 27.889103 -89.480061)
			(xy 27.842669 -89.59734) (xy 27.788962 -89.711472) (xy 27.728195 -89.822007) (xy 27.660608 -89.928507)
			(xy 27.586467 -90.030554) (xy 27.506064 -90.127744) (xy 27.419718 -90.219694) (xy 27.327768 -90.30604)
			(xy 27.230578 -90.386443) (xy 27.128531 -90.460584) (xy 27.022031 -90.528171) (xy 26.911496 -90.588938)
			(xy 26.797364 -90.642645) (xy 26.680085 -90.689079) (xy 26.560122 -90.728057) (xy 26.437949 -90.759426)
			(xy 26.314046 -90.783061) (xy 26.188904 -90.798871) (xy 26.063016 -90.806791) (xy 25.93688 -90.806791)
			(xy 25.810992 -90.798871) (xy 25.68585 -90.783061) (xy 25.561947 -90.759426) (xy 25.439774 -90.728057)
			(xy 25.319811 -90.689079) (xy 25.202532 -90.642645) (xy 25.0884 -90.588938) (xy 24.977865 -90.528171)
			(xy 24.871365 -90.460584) (xy 24.769318 -90.386443) (xy 24.672128 -90.30604) (xy 24.580178 -90.219694)
			(xy 24.493832 -90.127744) (xy 24.413429 -90.030554) (xy 24.339288 -89.928507) (xy 24.271701 -89.822007)
			(xy 24.210934 -89.711472) (xy 24.157227 -89.59734) (xy 24.110793 -89.480061) (xy 24.071815 -89.360098)
			(xy 24.040446 -89.237925) (xy 24.016811 -89.114022) (xy 24.001001 -88.98888) (xy 23.993081 -88.862992)
			(xy 7.231461 -88.862992) (xy 7.303685 -88.894964) (xy 7.413469 -88.952238) (xy 7.519357 -89.016428)
			(xy 7.620915 -89.087271) (xy 7.717726 -89.164474) (xy 7.809391 -89.247722) (xy 7.895534 -89.336672)
			(xy 7.975801 -89.430959) (xy 8.049863 -89.530194) (xy 8.117414 -89.633971) (xy 8.178177 -89.741862)
			(xy 8.231903 -89.853425) (xy 8.278371 -89.968201) (xy 8.317389 -90.085718) (xy 8.348798 -90.205494)
			(xy 8.372468 -90.327036) (xy 8.388303 -90.449844) (xy 8.396236 -90.573415) (xy 8.396732 -90.635328)
			(xy 8.396236 -90.697241) (xy 8.388303 -90.820812) (xy 8.372468 -90.94362) (xy 8.348798 -91.065162)
			(xy 8.317389 -91.184938) (xy 8.278371 -91.302455) (xy 8.231903 -91.417231) (xy 8.178177 -91.528794)
			(xy 8.117414 -91.636685) (xy 8.049863 -91.740462) (xy 7.975801 -91.839697) (xy 7.895534 -91.933984)
			(xy 7.809391 -92.022934) (xy 7.717726 -92.106182) (xy 7.620915 -92.183385) (xy 7.519357 -92.254228)
			(xy 7.413469 -92.318418) (xy 7.303685 -92.375692) (xy 7.190458 -92.425815) (xy 7.074251 -92.46858)
			(xy 6.955544 -92.503811) (xy 6.834823 -92.531365) (xy 6.712585 -92.551128) (xy 6.589332 -92.563018)
			(xy 6.46557 -92.566987) (xy 6.341808 -92.563018) (xy 6.218555 -92.551128) (xy 6.096317 -92.531365)
			(xy 5.975596 -92.503811) (xy 5.856889 -92.46858) (xy 5.740682 -92.425815) (xy 5.627455 -92.375692)
			(xy 5.517671 -92.318418) (xy 5.411783 -92.254228) (xy 5.310225 -92.183385) (xy 5.213414 -92.106182)
			(xy 5.121749 -92.022934) (xy 5.035606 -91.933984) (xy 4.955339 -91.839697) (xy 4.881277 -91.740462)
			(xy 4.813726 -91.636685) (xy 4.752963 -91.528794) (xy 4.699237 -91.417231) (xy 4.652769 -91.302455)
			(xy 4.613751 -91.184938) (xy 4.582342 -91.065162) (xy 4.558672 -90.94362) (xy 4.542837 -90.820812)
			(xy 4.534904 -90.697241) (xy 0.509016 -90.697241) (xy 0.509016 -95.79991) (xy 102.486719 -95.79991)
			(xy 102.490744 -95.657718) (xy 102.502807 -95.515982) (xy 102.52287 -95.375156) (xy 102.550868 -95.23569)
			(xy 102.586712 -95.098031) (xy 102.630286 -94.962621) (xy 102.681451 -94.829893) (xy 102.740044 -94.700272)
			(xy 102.805875 -94.574174) (xy 102.878736 -94.452002) (xy 102.958391 -94.334148) (xy 103.044587 -94.220989)
			(xy 103.137046 -94.112887) (xy 103.235474 -94.01019) (xy 103.339553 -93.913226) (xy 103.448952 -93.822306)
			(xy 103.56332 -93.73772) (xy 103.682289 -93.65974) (xy 103.80548 -93.588616) (xy 103.932497 -93.524575)
			(xy 104.062934 -93.467823) (xy 104.196373 -93.418541) (xy 104.332386 -93.376887) (xy 104.470538 -93.342995)
			(xy 104.610387 -93.316974) (xy 104.751483 -93.298906) (xy 104.893375 -93.288849) (xy 105.03561 -93.286836)
			(xy 105.17773 -93.292873) (xy 105.319281 -93.306941) (xy 105.45981 -93.328995) (xy 105.598865 -93.358964)
			(xy 105.736003 -93.396752) (xy 105.870783 -93.442238) (xy 106.002774 -93.495276) (xy 106.131553 -93.555697)
			(xy 106.256707 -93.623306) (xy 106.377835 -93.697888) (xy 106.494551 -93.779204) (xy 106.606479 -93.866992)
			(xy 106.713261 -93.960972) (xy 106.814555 -94.060842) (xy 106.910036 -94.166284) (xy 106.9994 -94.276958)
			(xy 107.082358 -94.392511) (xy 107.158647 -94.512572) (xy 107.228021 -94.636757) (xy 107.290258 -94.764668)
			(xy 107.345159 -94.895895) (xy 107.392547 -95.030018) (xy 107.432272 -95.166607) (xy 107.464205 -95.305225)
			(xy 107.488246 -95.445427) (xy 107.504315 -95.586765) (xy 107.512363 -95.728786) (xy 107.512866 -95.79991)
			(xy 107.512363 -95.871034) (xy 107.504315 -96.013055) (xy 107.488246 -96.154393) (xy 107.464205 -96.294595)
			(xy 107.432272 -96.433213) (xy 107.392547 -96.569802) (xy 107.345159 -96.703925) (xy 107.290258 -96.835152)
			(xy 107.228021 -96.963063) (xy 107.158647 -97.087248) (xy 107.082358 -97.207309) (xy 106.9994 -97.322862)
			(xy 106.910036 -97.433536) (xy 106.814555 -97.538978) (xy 106.713261 -97.638848) (xy 106.606479 -97.732828)
			(xy 106.494551 -97.820616) (xy 106.377835 -97.901932) (xy 106.256707 -97.976514) (xy 106.131553 -98.044123)
			(xy 106.002774 -98.104544) (xy 105.870783 -98.157582) (xy 105.736003 -98.203068) (xy 105.598865 -98.240856)
			(xy 105.45981 -98.270825) (xy 105.319281 -98.292879) (xy 105.17773 -98.306947) (xy 105.03561 -98.312984)
			(xy 104.893375 -98.310971) (xy 104.751483 -98.300914) (xy 104.610387 -98.282846) (xy 104.470538 -98.256825)
			(xy 104.332386 -98.222933) (xy 104.196373 -98.181279) (xy 104.062934 -98.131997) (xy 103.932497 -98.075245)
			(xy 103.80548 -98.011204) (xy 103.682289 -97.94008) (xy 103.56332 -97.8621) (xy 103.448952 -97.777514)
			(xy 103.339553 -97.686594) (xy 103.235474 -97.58963) (xy 103.137046 -97.486933) (xy 103.044587 -97.378831)
			(xy 102.958391 -97.265672) (xy 102.878736 -97.147818) (xy 102.805875 -97.025646) (xy 102.740044 -96.899548)
			(xy 102.681451 -96.769927) (xy 102.630286 -96.637199) (xy 102.586712 -96.501789) (xy 102.550868 -96.36413)
			(xy 102.52287 -96.224664) (xy 102.502807 -96.083838) (xy 102.490744 -95.942102) (xy 102.486719 -95.79991)
			(xy 0.509016 -95.79991) (xy 0.509016 -165.180264) (xy 0.508 -165.179248) (xy 0.508 -167.433752) (xy 0.509016 -167.433752)
			(xy 0.509016 -168.699942) (xy 0.509537 -168.755711) (xy 0.517873 -168.866937) (xy 0.534497 -168.977229)
			(xy 0.559316 -169.085971) (xy 0.592193 -169.192554) (xy 0.632942 -169.296382) (xy 0.681337 -169.396874)
			(xy 0.737106 -169.493469) (xy 0.799937 -169.585626) (xy 0.86948 -169.67283) (xy 0.945345 -169.754593)
			(xy 1.027108 -169.830458) (xy 1.114312 -169.900001) (xy 1.206469 -169.962832) (xy 1.303064 -170.018601)
			(xy 1.403556 -170.066996) (xy 1.507384 -170.107745) (xy 1.613967 -170.140622) (xy 1.722709 -170.165441)
			(xy 1.833001 -170.182065) (xy 1.944227 -170.190401) (xy 1.999996 -170.190922) (xy 10.359898 -170.190922)
			(xy 10.43028 -170.191416) (xy 10.570824 -170.199308) (xy 10.710703 -170.215069) (xy 10.849479 -170.238648)
			(xy 10.986714 -170.269971) (xy 11.121978 -170.308939) (xy 11.254843 -170.35543) (xy 11.384893 -170.409299)
			(xy 11.511717 -170.470374) (xy 11.634918 -170.538464) (xy 11.754107 -170.613356) (xy 11.868909 -170.694812)
			(xy 11.978964 -170.782577) (xy 12.083924 -170.876375) (xy 12.18346 -170.97591) (xy 12.277258 -171.08087)
			(xy 12.365023 -171.190924) (xy 12.44648 -171.305726) (xy 12.521372 -171.424915) (xy 12.589462 -171.548115)
			(xy 12.650538 -171.67494) (xy 12.704407 -171.804989) (xy 12.750899 -171.937855) (xy 12.789867 -172.073118)
			(xy 12.821191 -172.210353) (xy 12.84477 -172.349129) (xy 12.860531 -172.489008) (xy 12.868424 -172.629552)
			(xy 12.86891 -172.699934) (xy 12.86891 -202.876404) (xy 12.869405 -202.893058) (xy 12.878027 -202.925231)
			(xy 12.894682 -202.954075) (xy 12.918236 -202.977626) (xy 12.947082 -202.994278) (xy 12.979256 -203.002897)
			(xy 12.99591 -203.003404)
		)
		(stroke
			(width 0)
			(type solid)
		)
		(fill yes)
		(layer "In8.Cu")
		(net "GND")
	)
	(gr_arc
		(start 1.500124 -70.79996)
		(mid 0.439376 -71.239336)
		(end 0 -72.300084)
		(stroke
			(width 1.016)
			(type default)
		)
		(layer "In8.Cu")
	)
	(gr_line
		(start 1.500124 -70.79996)
		(end 6.500114 -70.79996)
		(stroke
			(width 1.016)
			(type default)
		)
		(layer "In8.Cu")
	)
	(gr_line
		(start 1.999996 -170.699938)
		(end 10.359898 -170.699938)
		(stroke
			(width 1.016)
			(type default)
		)
		(layer "In8.Cu")
	)
	(gr_arc
		(start 1.999996 0)
		(mid 0.585785 -0.585785)
		(end 0 -1.999996)
		(stroke
			(width 1.016)
			(type default)
		)
		(layer "In8.Cu")
	)
	(gr_line
		(start 1.999996 0)
		(end 198.000112 0)
		(stroke
			(width 1.016)
			(type default)
		)
		(layer "In8.Cu")
	)
	(gr_arc
		(start 6.500114 -70.79996)
		(mid 7.560682 -70.360658)
		(end 7.999984 -69.30009)
		(stroke
			(width 1.016)
			(type default)
		)
		(layer "In8.Cu")
	)
	(gr_line
		(start 6.500114 -30.80004)
		(end 1.500124 -30.80004)
		(stroke
			(width 1.016)
			(type default)
		)
		(layer "In8.Cu")
	)
	(gr_line
		(start 7.999984 -69.30009)
		(end 7.999984 -32.29991)
		(stroke
			(width 1.016)
			(type default)
		)
		(layer "In8.Cu")
	)
	(gr_arc
		(start 7.999984 -32.29991)
		(mid 7.560682 -31.239342)
		(end 6.500114 -30.80004)
		(stroke
			(width 1.016)
			(type default)
		)
		(layer "In8.Cu")
	)
	(gr_line
		(start 12.359894 -208.197196)
		(end 12.497054 -208.334356)
		(stroke
			(width 1.016)
			(type default)
		)
		(layer "In8.Cu")
	)
	(gr_arc
		(start 12.359894 -172.699934)
		(mid 11.774121 -171.285702)
		(end 10.359898 -170.699938)
		(stroke
			(width 1.016)
			(type default)
		)
		(layer "In8.Cu")
	)
	(gr_line
		(start 12.359894 -172.699934)
		(end 12.359894 -208.197196)
		(stroke
			(width 1.016)
			(type default)
		)
		(layer "In8.Cu")
	)
	(gr_line
		(start 12.418568 -203.257404)
		(end 187.31738 -203.257404)
		(stroke
			(width 0.508)
			(type default)
		)
		(layer "In8.Cu")
	)
	(gr_line
		(start 12.497054 -208.334356)
		(end 12.864084 -208.699608)
		(stroke
			(width 1.016)
			(type default)
		)
		(layer "In8.Cu")
	)
	(gr_line
		(start 12.581636 -204.561948)
		(end 12.774168 -204.75448)
		(stroke
			(width 1.016)
			(type default)
		)
		(layer "In8.Cu")
	)
	(gr_line
		(start 12.581636 -203.77277)
		(end 12.581636 -204.561948)
		(stroke
			(width 1.016)
			(type default)
		)
		(layer "In8.Cu")
	)
	(gr_line
		(start 12.61999 -203.811124)
		(end 12.581636 -203.77277)
		(stroke
			(width 1.016)
			(type default)
		)
		(layer "In8.Cu")
	)
	(gr_line
		(start 12.620244 -207.314292)
		(end 12.697206 -207.391254)
		(stroke
			(width 1.016)
			(type default)
		)
		(layer "In8.Cu")
	)
	(gr_line
		(start 12.620244 -206.582772)
		(end 12.620244 -207.314292)
		(stroke
			(width 1.016)
			(type default)
		)
		(layer "In8.Cu")
	)
	(gr_line
		(start 12.697206 -207.391254)
		(end 13.274294 -206.814166)
		(stroke
			(width 1.016)
			(type default)
		)
		(layer "In8.Cu")
	)
	(gr_line
		(start 12.697206 -207.391254)
		(end 187.081414 -207.391254)
		(stroke
			(width 1.016)
			(type default)
		)
		(layer "In8.Cu")
	)
	(gr_line
		(start 12.71651 -206.159608)
		(end 187.3123 -206.159608)
		(stroke
			(width 1.016)
			(type default)
		)
		(layer "In8.Cu")
	)
	(gr_line
		(start 12.71651 -205.35138)
		(end 12.71651 -206.159608)
		(stroke
			(width 1.016)
			(type default)
		)
		(layer "In8.Cu")
	)
	(gr_line
		(start 12.774168 -204.75448)
		(end 187.004198 -204.75448)
		(stroke
			(width 1.016)
			(type default)
		)
		(layer "In8.Cu")
	)
	(gr_line
		(start 12.774422 -205.293468)
		(end 12.71651 -205.35138)
		(stroke
			(width 1.016)
			(type default)
		)
		(layer "In8.Cu")
	)
	(gr_line
		(start 12.851638 -206.814166)
		(end 12.620244 -206.582772)
		(stroke
			(width 1.016)
			(type default)
		)
		(layer "In8.Cu")
	)
	(gr_line
		(start 13.005054 -205.5241)
		(end 12.774422 -205.293468)
		(stroke
			(width 1.016)
			(type default)
		)
		(layer "In8.Cu")
	)
	(gr_line
		(start 13.274294 -206.814166)
		(end 187.119768 -206.814166)
		(stroke
			(width 1.016)
			(type default)
		)
		(layer "In8.Cu")
	)
	(gr_line
		(start 13.54328 -208.237328)
		(end 12.697206 -207.391254)
		(stroke
			(width 1.016)
			(type default)
		)
		(layer "In8.Cu")
	)
	(gr_line
		(start 83.064604 -208.699608)
		(end 12.864084 -208.699608)
		(stroke
			(width 1.016)
			(type default)
		)
		(layer "In8.Cu")
	)
	(gr_line
		(start 83.064604 -208.699608)
		(end 83.54441 -208.222342)
		(stroke
			(width 1.016)
			(type default)
		)
		(layer "In8.Cu")
	)
	(gr_line
		(start 83.54441 -208.222342)
		(end 83.559904 -208.206848)
		(stroke
			(width 1.016)
			(type default)
		)
		(layer "In8.Cu")
	)
	(gr_line
		(start 83.559904 -208.206848)
		(end 83.559904 -201.250042)
		(stroke
			(width 1.016)
			(type default)
		)
		(layer "In8.Cu")
	)
	(gr_line
		(start 84.491322 -205.408784)
		(end 84.491322 -201.000868)
		(stroke
			(width 1.016)
			(type default)
		)
		(layer "In8.Cu")
	)
	(gr_line
		(start 84.491322 -201.000868)
		(end 84.626196 -201.135742)
		(stroke
			(width 1.016)
			(type default)
		)
		(layer "In8.Cu")
	)
	(gr_line
		(start 84.626196 -206.332582)
		(end 85.049868 -206.756254)
		(stroke
			(width 1.016)
			(type default)
		)
		(layer "In8.Cu")
	)
	(gr_line
		(start 84.626196 -201.135742)
		(end 84.626196 -206.332582)
		(stroke
			(width 1.016)
			(type default)
		)
		(layer "In8.Cu")
	)
	(gr_line
		(start 85.049868 -206.756254)
		(end 98.619564 -206.756254)
		(stroke
			(width 1.016)
			(type default)
		)
		(layer "In8.Cu")
	)
	(gr_line
		(start 85.460078 -208.196942)
		(end 85.464904 -208.201768)
		(stroke
			(width 1.016)
			(type default)
		)
		(layer "In8.Cu")
	)
	(gr_arc
		(start 85.460078 -201.250042)
		(mid 84.509991 -200.299828)
		(end 83.559904 -201.250042)
		(stroke
			(width 1.016)
			(type default)
		)
		(layer "In8.Cu")
	)
	(gr_line
		(start 85.460078 -201.250042)
		(end 85.460078 -208.196942)
		(stroke
			(width 1.016)
			(type default)
		)
		(layer "In8.Cu")
	)
	(gr_line
		(start 85.464904 -208.201768)
		(end 85.965284 -208.699608)
		(stroke
			(width 1.016)
			(type default)
		)
		(layer "In8.Cu")
	)
	(gr_line
		(start 85.742272 -206.659734)
		(end 84.491322 -205.408784)
		(stroke
			(width 1.016)
			(type default)
		)
		(layer "In8.Cu")
	)
	(gr_line
		(start 96.165924 -208.699608)
		(end 85.965284 -208.699608)
		(stroke
			(width 1.016)
			(type default)
		)
		(layer "In8.Cu")
	)
	(gr_line
		(start 96.165924 -208.699608)
		(end 96.659954 -208.205578)
		(stroke
			(width 1.016)
			(type default)
		)
		(layer "In8.Cu")
	)
	(gr_line
		(start 96.659954 -208.205578)
		(end 96.659954 -188.250068)
		(stroke
			(width 1.016)
			(type default)
		)
		(layer "In8.Cu")
	)
	(gr_line
		(start 97.387664 -203.946252)
		(end 97.387664 -187.277756)
		(stroke
			(width 1.016)
			(type default)
		)
		(layer "In8.Cu")
	)
	(gr_line
		(start 97.387664 -187.277756)
		(end 98.908362 -185.757058)
		(stroke
			(width 1.016)
			(type default)
		)
		(layer "In8.Cu")
	)
	(gr_line
		(start 97.79127 -203.310744)
		(end 101.409754 -203.310744)
		(stroke
			(width 1.27)
			(type default)
		)
		(layer "In8.Cu")
	)
	(gr_line
		(start 97.983802 -203.118212)
		(end 97.79127 -203.310744)
		(stroke
			(width 1.27)
			(type default)
		)
		(layer "In8.Cu")
	)
	(gr_line
		(start 97.983802 -187.681616)
		(end 97.983802 -203.118212)
		(stroke
			(width 1.27)
			(type default)
		)
		(layer "In8.Cu")
	)
	(gr_line
		(start 98.40722 -202.733148)
		(end 98.869246 -203.195174)
		(stroke
			(width 1.27)
			(type default)
		)
		(layer "In8.Cu")
	)
	(gr_line
		(start 98.40722 -188.412882)
		(end 98.40722 -202.733148)
		(stroke
			(width 1.27)
			(type default)
		)
		(layer "In8.Cu")
	)
	(gr_line
		(start 98.619564 -206.756254)
		(end 98.619564 -205.178152)
		(stroke
			(width 1.016)
			(type default)
		)
		(layer "In8.Cu")
	)
	(gr_line
		(start 98.619564 -205.178152)
		(end 97.387664 -203.946252)
		(stroke
			(width 1.016)
			(type default)
		)
		(layer "In8.Cu")
	)
	(gr_line
		(start 98.869246 -203.195174)
		(end 100.562918 -201.501502)
		(stroke
			(width 1.27)
			(type default)
		)
		(layer "In8.Cu")
	)
	(gr_line
		(start 98.908362 -185.757058)
		(end 100.794566 -185.757058)
		(stroke
			(width 1.016)
			(type default)
		)
		(layer "In8.Cu")
	)
	(gr_line
		(start 99.061778 -186.60364)
		(end 97.983802 -187.681616)
		(stroke
			(width 1.27)
			(type default)
		)
		(layer "In8.Cu")
	)
	(gr_line
		(start 99.331272 -202.232768)
		(end 100.408994 -201.155046)
		(stroke
			(width 1.27)
			(type default)
		)
		(layer "In8.Cu")
	)
	(gr_line
		(start 99.331272 -189.105794)
		(end 99.331272 -202.232768)
		(stroke
			(width 1.27)
			(type default)
		)
		(layer "In8.Cu")
	)
	(gr_line
		(start 99.562158 -187.257944)
		(end 98.40722 -188.412882)
		(stroke
			(width 1.27)
			(type default)
		)
		(layer "In8.Cu")
	)
	(gr_line
		(start 99.985576 -188.45149)
		(end 99.331272 -189.105794)
		(stroke
			(width 1.27)
			(type default)
		)
		(layer "In8.Cu")
	)
	(gr_line
		(start 100.332032 -187.257944)
		(end 99.562158 -187.257944)
		(stroke
			(width 1.27)
			(type default)
		)
		(layer "In8.Cu")
	)
	(gr_line
		(start 100.408994 -202.92568)
		(end 100.87102 -202.463654)
		(stroke
			(width 1.27)
			(type default)
		)
		(layer "In8.Cu")
	)
	(gr_line
		(start 100.408994 -201.655172)
		(end 100.408994 -202.92568)
		(stroke
			(width 1.27)
			(type default)
		)
		(layer "In8.Cu")
	)
	(gr_line
		(start 100.408994 -201.155046)
		(end 100.408994 -188.95187)
		(stroke
			(width 1.27)
			(type default)
		)
		(layer "In8.Cu")
	)
	(gr_line
		(start 100.562918 -201.501502)
		(end 100.562918 -201.501248)
		(stroke
			(width 1.27)
			(type default)
		)
		(layer "In8.Cu")
	)
	(gr_line
		(start 100.562918 -201.501248)
		(end 100.408994 -201.655172)
		(stroke
			(width 1.27)
			(type default)
		)
		(layer "In8.Cu")
	)
	(gr_line
		(start 100.601526 -188.45149)
		(end 99.985576 -188.45149)
		(stroke
			(width 1.27)
			(type default)
		)
		(layer "In8.Cu")
	)
	(gr_line
		(start 100.794566 -185.757058)
		(end 102.853236 -187.815728)
		(stroke
			(width 1.016)
			(type default)
		)
		(layer "In8.Cu")
	)
	(gr_line
		(start 100.87102 -202.463654)
		(end 100.87102 -188.720984)
		(stroke
			(width 1.27)
			(type default)
		)
		(layer "In8.Cu")
	)
	(gr_line
		(start 100.87102 -188.720984)
		(end 100.601526 -188.45149)
		(stroke
			(width 1.27)
			(type default)
		)
		(layer "In8.Cu")
	)
	(gr_line
		(start 100.947982 -186.60364)
		(end 99.061778 -186.60364)
		(stroke
			(width 1.27)
			(type default)
		)
		(layer "In8.Cu")
	)
	(gr_line
		(start 101.409754 -203.310744)
		(end 101.640894 -203.079604)
		(stroke
			(width 1.27)
			(type default)
		)
		(layer "In8.Cu")
	)
	(gr_line
		(start 101.640894 -203.079604)
		(end 101.640894 -188.566806)
		(stroke
			(width 1.27)
			(type default)
		)
		(layer "In8.Cu")
	)
	(gr_line
		(start 101.640894 -188.566806)
		(end 100.332032 -187.257944)
		(stroke
			(width 1.27)
			(type default)
		)
		(layer "In8.Cu")
	)
	(gr_line
		(start 102.064312 -203.233528)
		(end 102.064312 -187.71997)
		(stroke
			(width 1.27)
			(type default)
		)
		(layer "In8.Cu")
	)
	(gr_line
		(start 102.064312 -187.71997)
		(end 100.947982 -186.60364)
		(stroke
			(width 1.27)
			(type default)
		)
		(layer "In8.Cu")
	)
	(gr_line
		(start 102.333806 -203.503022)
		(end 102.064312 -203.233528)
		(stroke
			(width 1.27)
			(type default)
		)
		(layer "In8.Cu")
	)
	(gr_line
		(start 102.853236 -202.983592)
		(end 102.333806 -203.503022)
		(stroke
			(width 1.016)
			(type default)
		)
		(layer "In8.Cu")
	)
	(gr_line
		(start 102.853236 -187.815728)
		(end 102.853236 -202.983592)
		(stroke
			(width 1.016)
			(type default)
		)
		(layer "In8.Cu")
	)
	(gr_line
		(start 103.359966 -208.19745)
		(end 103.364284 -208.201768)
		(stroke
			(width 1.016)
			(type default)
		)
		(layer "In8.Cu")
	)
	(gr_arc
		(start 103.359966 -188.250068)
		(mid 100.00996 -184.900062)
		(end 96.659954 -188.250068)
		(stroke
			(width 1.016)
			(type default)
		)
		(layer "In8.Cu")
	)
	(gr_line
		(start 103.359966 -188.250068)
		(end 103.359966 -208.19745)
		(stroke
			(width 1.016)
			(type default)
		)
		(layer "In8.Cu")
	)
	(gr_line
		(start 103.364284 -208.201768)
		(end 103.864664 -208.699608)
		(stroke
			(width 1.016)
			(type default)
		)
		(layer "In8.Cu")
	)
	(gr_line
		(start 155.372308 -49.275238)
		(end 155.372308 -50.97526)
		(stroke
			(width 1.7018)
			(type default)
		)
		(layer "In8.Cu")
	)
	(gr_line
		(start 155.372308 -45.465238)
		(end 155.372308 -47.16526)
		(stroke
			(width 1.7018)
			(type default)
		)
		(layer "In8.Cu")
	)
	(gr_line
		(start 158.6992 -45.708062)
		(end 158.6992 -46.978062)
		(stroke
			(width 0.8128)
			(type default)
		)
		(layer "In8.Cu")
	)
	(gr_line
		(start 161.280348 -49.560734)
		(end 161.280348 -50.830734)
		(stroke
			(width 0.8128)
			(type default)
		)
		(layer "In8.Cu")
	)
	(gr_line
		(start 173.70425 -206.659734)
		(end 85.742272 -206.659734)
		(stroke
			(width 1.016)
			(type default)
		)
		(layer "In8.Cu")
	)
	(gr_line
		(start 174.065184 -208.699608)
		(end 103.864664 -208.699608)
		(stroke
			(width 1.016)
			(type default)
		)
		(layer "In8.Cu")
	)
	(gr_line
		(start 174.342552 -208.423764)
		(end 174.065184 -208.699608)
		(stroke
			(width 1.016)
			(type default)
		)
		(layer "In8.Cu")
	)
	(gr_line
		(start 174.559976 -208.20634)
		(end 174.342552 -208.423764)
		(stroke
			(width 1.016)
			(type default)
		)
		(layer "In8.Cu")
	)
	(gr_line
		(start 174.559976 -201.250042)
		(end 174.559976 -208.20634)
		(stroke
			(width 1.016)
			(type default)
		)
		(layer "In8.Cu")
	)
	(gr_line
		(start 175.494442 -204.869542)
		(end 173.70425 -206.659734)
		(stroke
			(width 1.016)
			(type default)
		)
		(layer "In8.Cu")
	)
	(gr_line
		(start 175.494442 -201.039476)
		(end 175.494442 -204.869542)
		(stroke
			(width 1.016)
			(type default)
		)
		(layer "In8.Cu")
	)
	(gr_line
		(start 175.53305 -205.543658)
		(end 175.53305 -201.000868)
		(stroke
			(width 1.016)
			(type default)
		)
		(layer "In8.Cu")
	)
	(gr_line
		(start 175.53305 -201.000868)
		(end 175.494442 -201.039476)
		(stroke
			(width 1.016)
			(type default)
		)
		(layer "In8.Cu")
	)
	(gr_line
		(start 175.879252 -205.88986)
		(end 175.53305 -205.543658)
		(stroke
			(width 1.016)
			(type default)
		)
		(layer "In8.Cu")
	)
	(gr_line
		(start 176.459896 -208.19618)
		(end 176.459896 -201.250042)
		(stroke
			(width 1.016)
			(type default)
		)
		(layer "In8.Cu")
	)
	(gr_arc
		(start 176.459896 -201.250042)
		(mid 175.509936 -200.300082)
		(end 174.559976 -201.250042)
		(stroke
			(width 1.016)
			(type default)
		)
		(layer "In8.Cu")
	)
	(gr_line
		(start 176.465484 -208.201768)
		(end 176.459896 -208.19618)
		(stroke
			(width 1.016)
			(type default)
		)
		(layer "In8.Cu")
	)
	(gr_line
		(start 176.965864 -208.699608)
		(end 176.465484 -208.201768)
		(stroke
			(width 1.016)
			(type default)
		)
		(layer "In8.Cu")
	)
	(gr_line
		(start 186.195462 -205.88986)
		(end 175.879252 -205.88986)
		(stroke
			(width 1.016)
			(type default)
		)
		(layer "In8.Cu")
	)
	(gr_line
		(start 187.004198 -204.75448)
		(end 187.524136 -204.234542)
		(stroke
			(width 1.016)
			(type default)
		)
		(layer "In8.Cu")
	)
	(gr_line
		(start 187.081414 -207.391254)
		(end 187.350908 -207.12176)
		(stroke
			(width 1.016)
			(type default)
		)
		(layer "In8.Cu")
	)
	(gr_line
		(start 187.119768 -206.814166)
		(end 12.851638 -206.814166)
		(stroke
			(width 1.016)
			(type default)
		)
		(layer "In8.Cu")
	)
	(gr_line
		(start 187.119768 -206.814166)
		(end 186.195462 -205.88986)
		(stroke
			(width 1.016)
			(type default)
		)
		(layer "In8.Cu")
	)
	(gr_line
		(start 187.163964 -208.699608)
		(end 176.965864 -208.699608)
		(stroke
			(width 1.016)
			(type default)
		)
		(layer "In8.Cu")
	)
	(gr_line
		(start 187.178188 -203.811124)
		(end 12.61999 -203.811124)
		(stroke
			(width 1.016)
			(type default)
		)
		(layer "In8.Cu")
	)
	(gr_line
		(start 187.196984 -205.5241)
		(end 13.005054 -205.5241)
		(stroke
			(width 1.016)
			(type default)
		)
		(layer "In8.Cu")
	)
	(gr_line
		(start 187.3123 -206.159608)
		(end 187.389262 -206.082646)
		(stroke
			(width 1.016)
			(type default)
		)
		(layer "In8.Cu")
	)
	(gr_line
		(start 187.31738 -203.257404)
		(end 187.524644 -203.464668)
		(stroke
			(width 0.508)
			(type default)
		)
		(layer "In8.Cu")
	)
	(gr_line
		(start 187.350908 -208.512664)
		(end 187.163964 -208.699608)
		(stroke
			(width 1.016)
			(type default)
		)
		(layer "In8.Cu")
	)
	(gr_line
		(start 187.350908 -207.12176)
		(end 187.350908 -208.512664)
		(stroke
			(width 1.016)
			(type default)
		)
		(layer "In8.Cu")
	)
	(gr_line
		(start 187.389262 -206.544672)
		(end 187.119768 -206.814166)
		(stroke
			(width 1.016)
			(type default)
		)
		(layer "In8.Cu")
	)
	(gr_line
		(start 187.389262 -206.082646)
		(end 187.389262 -206.544672)
		(stroke
			(width 1.016)
			(type default)
		)
		(layer "In8.Cu")
	)
	(gr_line
		(start 187.524136 -205.196948)
		(end 187.196984 -205.5241)
		(stroke
			(width 1.016)
			(type default)
		)
		(layer "In8.Cu")
	)
	(gr_line
		(start 187.524136 -204.234542)
		(end 187.524136 -205.196948)
		(stroke
			(width 1.016)
			(type default)
		)
		(layer "In8.Cu")
	)
	(gr_line
		(start 187.524644 -203.464668)
		(end 187.178188 -203.811124)
		(stroke
			(width 1.016)
			(type default)
		)
		(layer "In8.Cu")
	)
	(gr_line
		(start 187.62853 -208.237328)
		(end 13.54328 -208.237328)
		(stroke
			(width 1.016)
			(type default)
		)
		(layer "In8.Cu")
	)
	(gr_line
		(start 187.62853 -208.237328)
		(end 187.163964 -208.699608)
		(stroke
			(width 1.016)
			(type default)
		)
		(layer "In8.Cu")
	)
	(gr_line
		(start 187.660026 -208.205832)
		(end 187.62853 -208.237328)
		(stroke
			(width 1.016)
			(type default)
		)
		(layer "In8.Cu")
	)
	(gr_line
		(start 187.660026 -172.699934)
		(end 187.660026 -208.205832)
		(stroke
			(width 1.016)
			(type default)
		)
		(layer "In8.Cu")
	)
	(gr_arc
		(start 189.660022 -170.699938)
		(mid 188.245811 -171.285723)
		(end 187.660026 -172.699934)
		(stroke
			(width 1.016)
			(type default)
		)
		(layer "In8.Cu")
	)
	(gr_arc
		(start 196.699886 -72.650096)
		(mid 197.139352 -73.71068)
		(end 198.20001 -74.149966)
		(stroke
			(width 1.016)
			(type default)
		)
		(layer "In8.Cu")
	)
	(gr_line
		(start 196.699886 -33.64992)
		(end 196.699886 -72.650096)
		(stroke
			(width 1.016)
			(type default)
		)
		(layer "In8.Cu")
	)
	(gr_line
		(start 198.000112 -170.699938)
		(end 189.660022 -170.699938)
		(stroke
			(width 1.016)
			(type default)
		)
		(layer "In8.Cu")
	)
	(gr_arc
		(start 198.000112 -170.699938)
		(mid 199.41433 -170.114151)
		(end 200.000108 -168.699942)
		(stroke
			(width 1.016)
			(type default)
		)
		(layer "In8.Cu")
	)
	(gr_line
		(start 198.20001 -74.149966)
		(end 198.499984 -74.149966)
		(stroke
			(width 1.016)
			(type default)
		)
		(layer "In8.Cu")
	)
	(gr_arc
		(start 198.20001 -32.15005)
		(mid 197.139352 -32.589336)
		(end 196.699886 -33.64992)
		(stroke
			(width 1.016)
			(type default)
		)
		(layer "In8.Cu")
	)
	(gr_line
		(start 198.499984 -32.15005)
		(end 198.20001 -32.15005)
		(stroke
			(width 1.016)
			(type default)
		)
		(layer "In8.Cu")
	)
	(gr_arc
		(start 198.499984 -32.15005)
		(mid 199.560751 -31.710681)
		(end 200.000108 -30.649926)
		(stroke
			(width 1.016)
			(type default)
		)
		(layer "In8.Cu")
	)
	(gr_arc
		(start 200.000108 -75.65009)
		(mid 199.560727 -74.589354)
		(end 198.499984 -74.149966)
		(stroke
			(width 1.016)
			(type default)
		)
		(layer "In8.Cu")
	)
	(gr_line
		(start 200.000108 -75.65009)
		(end 200.000108 -168.699942)
		(stroke
			(width 1.016)
			(type default)
		)
		(layer "In8.Cu")
	)
	(gr_arc
		(start 200.000108 -1.999996)
		(mid 199.414322 -0.585784)
		(end 198.000112 0)
		(stroke
			(width 1.016)
			(type default)
		)
		(layer "In8.Cu")
	)
	(gr_line
		(start 200.000108 -1.999996)
		(end 200.000108 -30.649926)
		(stroke
			(width 1.016)
			(type default)
		)
		(layer "In8.Cu")
	)
	(gr_line
		(start 202.02398 -52.780946)
		(end 202.02398 -54.050946)
		(stroke
			(width 0.8128)
			(type default)
		)
		(layer "In8.Cu")
	)
	(gr_arc
		(start -12.032488 -191.641222)
		(mid -11.397488 -192.276222)
		(end -10.762488 -191.641222)
		(stroke
			(width 0.05)
			(type default)
		)
		(layer "Edge.Cuts")
	)
	(gr_arc
		(start -12.032488 -187.577222)
		(mid -11.397488 -188.212222)
		(end -10.762488 -187.577222)
		(stroke
			(width 0.05)
			(type default)
		)
		(layer "Edge.Cuts")
	)
	(gr_arc
		(start -12.032488 -63.127382)
		(mid -11.397488 -63.762382)
		(end -10.762488 -63.127382)
		(stroke
			(width 0.05)
			(type default)
		)
		(layer "Edge.Cuts")
	)
	(gr_arc
		(start -12.032488 -59.063382)
		(mid -11.397488 -59.698382)
		(end -10.762488 -59.063382)
		(stroke
			(width 0.05)
			(type default)
		)
		(layer "Edge.Cuts")
	)
	(gr_arc
		(start -12.032488 -35.868102)
		(mid -11.397488 -36.503102)
		(end -10.762488 -35.868102)
		(stroke
			(width 0.05)
			(type default)
		)
		(layer "Edge.Cuts")
	)
	(gr_arc
		(start -12.032488 -31.804102)
		(mid -11.397488 -32.439102)
		(end -10.762488 -31.804102)
		(stroke
			(width 0.05)
			(type default)
		)
		(layer "Edge.Cuts")
	)
	(gr_arc
		(start -11.397488 -192.276222)
		(mid -10.762488 -191.641222)
		(end -11.397488 -191.006222)
		(stroke
			(width 0.05)
			(type default)
		)
		(layer "Edge.Cuts")
	)
	(gr_circle
		(center -11.397488 -191.641222)
		(end -10.762488 -191.641222)
		(stroke
			(width 0.05)
			(type default)
		)
		(fill no)
		(layer "Edge.Cuts")
	)
	(gr_arc
		(start -11.397488 -191.006222)
		(mid -12.032488 -191.641222)
		(end -11.397488 -192.276222)
		(stroke
			(width 0.05)
			(type default)
		)
		(layer "Edge.Cuts")
	)
	(gr_arc
		(start -11.397488 -188.212222)
		(mid -10.762488 -187.577222)
		(end -11.397488 -186.942222)
		(stroke
			(width 0.05)
			(type default)
		)
		(layer "Edge.Cuts")
	)
	(gr_circle
		(center -11.397488 -187.577222)
		(end -10.762488 -187.577222)
		(stroke
			(width 0.05)
			(type default)
		)
		(fill no)
		(layer "Edge.Cuts")
	)
	(gr_arc
		(start -11.397488 -186.942222)
		(mid -12.032488 -187.577222)
		(end -11.397488 -188.212222)
		(stroke
			(width 0.05)
			(type default)
		)
		(layer "Edge.Cuts")
	)
	(gr_arc
		(start -11.397488 -63.762382)
		(mid -10.762488 -63.127382)
		(end -11.397488 -62.492382)
		(stroke
			(width 0.05)
			(type default)
		)
		(layer "Edge.Cuts")
	)
	(gr_circle
		(center -11.397488 -63.127382)
		(end -10.762488 -63.127382)
		(stroke
			(width 0.05)
			(type default)
		)
		(fill no)
		(layer "Edge.Cuts")
	)
	(gr_arc
		(start -11.397488 -62.492382)
		(mid -12.032488 -63.127382)
		(end -11.397488 -63.762382)
		(stroke
			(width 0.05)
			(type default)
		)
		(layer "Edge.Cuts")
	)
	(gr_arc
		(start -11.397488 -59.698382)
		(mid -10.762488 -59.063382)
		(end -11.397488 -58.428382)
		(stroke
			(width 0.05)
			(type default)
		)
		(layer "Edge.Cuts")
	)
	(gr_circle
		(center -11.397488 -59.063382)
		(end -10.762488 -59.063382)
		(stroke
			(width 0.05)
			(type default)
		)
		(fill no)
		(layer "Edge.Cuts")
	)
	(gr_arc
		(start -11.397488 -58.428382)
		(mid -12.032488 -59.063382)
		(end -11.397488 -59.698382)
		(stroke
			(width 0.05)
			(type default)
		)
		(layer "Edge.Cuts")
	)
	(gr_arc
		(start -11.397488 -36.503102)
		(mid -10.762488 -35.868102)
		(end -11.397488 -35.233102)
		(stroke
			(width 0.05)
			(type default)
		)
		(layer "Edge.Cuts")
	)
	(gr_circle
		(center -11.397488 -35.868102)
		(end -10.762488 -35.868102)
		(stroke
			(width 0.05)
			(type default)
		)
		(fill no)
		(layer "Edge.Cuts")
	)
	(gr_arc
		(start -11.397488 -35.233102)
		(mid -12.032488 -35.868102)
		(end -11.397488 -36.503102)
		(stroke
			(width 0.05)
			(type default)
		)
		(layer "Edge.Cuts")
	)
	(gr_arc
		(start -11.397488 -32.439102)
		(mid -10.762488 -31.804102)
		(end -11.397488 -31.169102)
		(stroke
			(width 0.05)
			(type default)
		)
		(layer "Edge.Cuts")
	)
	(gr_circle
		(center -11.397488 -31.804102)
		(end -10.762488 -31.804102)
		(stroke
			(width 0.05)
			(type default)
		)
		(fill no)
		(layer "Edge.Cuts")
	)
	(gr_arc
		(start -11.397488 -31.169102)
		(mid -12.032488 -31.804102)
		(end -11.397488 -32.439102)
		(stroke
			(width 0.05)
			(type default)
		)
		(layer "Edge.Cuts")
	)
	(gr_arc
		(start -10.762488 -191.641222)
		(mid -11.397488 -191.006222)
		(end -12.032488 -191.641222)
		(stroke
			(width 0.05)
			(type default)
		)
		(layer "Edge.Cuts")
	)
	(gr_arc
		(start -10.762488 -187.577222)
		(mid -11.397488 -186.942222)
		(end -12.032488 -187.577222)
		(stroke
			(width 0.05)
			(type default)
		)
		(layer "Edge.Cuts")
	)
	(gr_arc
		(start -10.762488 -63.127382)
		(mid -11.397488 -62.492382)
		(end -12.032488 -63.127382)
		(stroke
			(width 0.05)
			(type default)
		)
		(layer "Edge.Cuts")
	)
	(gr_arc
		(start -10.762488 -59.063382)
		(mid -11.397488 -58.428382)
		(end -12.032488 -59.063382)
		(stroke
			(width 0.05)
			(type default)
		)
		(layer "Edge.Cuts")
	)
	(gr_arc
		(start -10.762488 -35.868102)
		(mid -11.397488 -35.233102)
		(end -12.032488 -35.868102)
		(stroke
			(width 0.05)
			(type default)
		)
		(layer "Edge.Cuts")
	)
	(gr_arc
		(start -10.762488 -31.804102)
		(mid -11.397488 -31.169102)
		(end -12.032488 -31.804102)
		(stroke
			(width 0.05)
			(type default)
		)
		(layer "Edge.Cuts")
	)
	(gr_arc
		(start -7.460488 -191.641222)
		(mid -6.825488 -192.276222)
		(end -6.190488 -191.641222)
		(stroke
			(width 0.05)
			(type default)
		)
		(layer "Edge.Cuts")
	)
	(gr_arc
		(start -7.460488 -187.577222)
		(mid -6.825488 -188.212222)
		(end -6.190488 -187.577222)
		(stroke
			(width 0.05)
			(type default)
		)
		(layer "Edge.Cuts")
	)
	(gr_arc
		(start -7.460488 -63.127382)
		(mid -6.825488 -63.762382)
		(end -6.190488 -63.127382)
		(stroke
			(width 0.05)
			(type default)
		)
		(layer "Edge.Cuts")
	)
	(gr_arc
		(start -7.460488 -59.063382)
		(mid -6.825488 -59.698382)
		(end -6.190488 -59.063382)
		(stroke
			(width 0.05)
			(type default)
		)
		(layer "Edge.Cuts")
	)
	(gr_arc
		(start -7.460488 -35.868102)
		(mid -6.825488 -36.503102)
		(end -6.190488 -35.868102)
		(stroke
			(width 0.05)
			(type default)
		)
		(layer "Edge.Cuts")
	)
	(gr_arc
		(start -7.460488 -31.804102)
		(mid -6.825488 -32.439102)
		(end -6.190488 -31.804102)
		(stroke
			(width 0.05)
			(type default)
		)
		(layer "Edge.Cuts")
	)
	(gr_arc
		(start -6.825488 -192.276222)
		(mid -6.190488 -191.641222)
		(end -6.825488 -191.006222)
		(stroke
			(width 0.05)
			(type default)
		)
		(layer "Edge.Cuts")
	)
	(gr_circle
		(center -6.825488 -191.641222)
		(end -6.190488 -191.641222)
		(stroke
			(width 0.05)
			(type default)
		)
		(fill no)
		(layer "Edge.Cuts")
	)
	(gr_arc
		(start -6.825488 -191.006222)
		(mid -7.460488 -191.641222)
		(end -6.825488 -192.276222)
		(stroke
			(width 0.05)
			(type default)
		)
		(layer "Edge.Cuts")
	)
	(gr_arc
		(start -6.825488 -188.212222)
		(mid -6.190488 -187.577222)
		(end -6.825488 -186.942222)
		(stroke
			(width 0.05)
			(type default)
		)
		(layer "Edge.Cuts")
	)
	(gr_circle
		(center -6.825488 -187.577222)
		(end -6.190488 -187.577222)
		(stroke
			(width 0.05)
			(type default)
		)
		(fill no)
		(layer "Edge.Cuts")
	)
	(gr_arc
		(start -6.825488 -186.942222)
		(mid -7.460488 -187.577222)
		(end -6.825488 -188.212222)
		(stroke
			(width 0.05)
			(type default)
		)
		(layer "Edge.Cuts")
	)
	(gr_arc
		(start -6.825488 -63.762382)
		(mid -6.190488 -63.127382)
		(end -6.825488 -62.492382)
		(stroke
			(width 0.05)
			(type default)
		)
		(layer "Edge.Cuts")
	)
	(gr_circle
		(center -6.825488 -63.127382)
		(end -6.190488 -63.127382)
		(stroke
			(width 0.05)
			(type default)
		)
		(fill no)
		(layer "Edge.Cuts")
	)
	(gr_arc
		(start -6.825488 -62.492382)
		(mid -7.460488 -63.127382)
		(end -6.825488 -63.762382)
		(stroke
			(width 0.05)
			(type default)
		)
		(layer "Edge.Cuts")
	)
	(gr_arc
		(start -6.825488 -59.698382)
		(mid -6.190488 -59.063382)
		(end -6.825488 -58.428382)
		(stroke
			(width 0.05)
			(type default)
		)
		(layer "Edge.Cuts")
	)
	(gr_circle
		(center -6.825488 -59.063382)
		(end -6.190488 -59.063382)
		(stroke
			(width 0.05)
			(type default)
		)
		(fill no)
		(layer "Edge.Cuts")
	)
	(gr_arc
		(start -6.825488 -58.428382)
		(mid -7.460488 -59.063382)
		(end -6.825488 -59.698382)
		(stroke
			(width 0.05)
			(type default)
		)
		(layer "Edge.Cuts")
	)
	(gr_arc
		(start -6.825488 -36.503102)
		(mid -6.190488 -35.868102)
		(end -6.825488 -35.233102)
		(stroke
			(width 0.05)
			(type default)
		)
		(layer "Edge.Cuts")
	)
	(gr_circle
		(center -6.825488 -35.868102)
		(end -6.190488 -35.868102)
		(stroke
			(width 0.05)
			(type default)
		)
		(fill no)
		(layer "Edge.Cuts")
	)
	(gr_arc
		(start -6.825488 -35.233102)
		(mid -7.460488 -35.868102)
		(end -6.825488 -36.503102)
		(stroke
			(width 0.05)
			(type default)
		)
		(layer "Edge.Cuts")
	)
	(gr_arc
		(start -6.825488 -32.439102)
		(mid -6.190488 -31.804102)
		(end -6.825488 -31.169102)
		(stroke
			(width 0.05)
			(type default)
		)
		(layer "Edge.Cuts")
	)
	(gr_circle
		(center -6.825488 -31.804102)
		(end -6.190488 -31.804102)
		(stroke
			(width 0.05)
			(type default)
		)
		(fill no)
		(layer "Edge.Cuts")
	)
	(gr_arc
		(start -6.825488 -31.169102)
		(mid -7.460488 -31.804102)
		(end -6.825488 -32.439102)
		(stroke
			(width 0.05)
			(type default)
		)
		(layer "Edge.Cuts")
	)
	(gr_arc
		(start -6.190488 -191.641222)
		(mid -6.825488 -191.006222)
		(end -7.460488 -191.641222)
		(stroke
			(width 0.05)
			(type default)
		)
		(layer "Edge.Cuts")
	)
	(gr_arc
		(start -6.190488 -187.577222)
		(mid -6.825488 -186.942222)
		(end -7.460488 -187.577222)
		(stroke
			(width 0.05)
			(type default)
		)
		(layer "Edge.Cuts")
	)
	(gr_arc
		(start -6.190488 -63.127382)
		(mid -6.825488 -62.492382)
		(end -7.460488 -63.127382)
		(stroke
			(width 0.05)
			(type default)
		)
		(layer "Edge.Cuts")
	)
	(gr_arc
		(start -6.190488 -59.063382)
		(mid -6.825488 -58.428382)
		(end -7.460488 -59.063382)
		(stroke
			(width 0.05)
			(type default)
		)
		(layer "Edge.Cuts")
	)
	(gr_arc
		(start -6.190488 -35.868102)
		(mid -6.825488 -35.233102)
		(end -7.460488 -35.868102)
		(stroke
			(width 0.05)
			(type default)
		)
		(layer "Edge.Cuts")
	)
	(gr_arc
		(start -6.190488 -31.804102)
		(mid -6.825488 -31.169102)
		(end -7.460488 -31.804102)
		(stroke
			(width 0.05)
			(type default)
		)
		(layer "Edge.Cuts")
	)
	(gr_arc
		(start 0 -168.699942)
		(mid 0.585785 -170.114153)
		(end 1.999996 -170.699938)
		(stroke
			(width 0.05)
			(type default)
		)
		(layer "Edge.Cuts")
	)
	(gr_line
		(start 0 -72.300084)
		(end 0 -168.699942)
		(stroke
			(width 0.05)
			(type default)
		)
		(layer "Edge.Cuts")
	)
	(gr_line
		(start 0 -29.299916)
		(end 0 -1.999996)
		(stroke
			(width 0.05)
			(type default)
		)
		(layer "Edge.Cuts")
	)
	(gr_arc
		(start 0 -29.299916)
		(mid 0.439376 -30.360664)
		(end 1.500124 -30.80004)
		(stroke
			(width 0.05)
			(type default)
		)
		(layer "Edge.Cuts")
	)
	(gr_line
		(start 0 -1.999996)
		(end 0 -29.299916)
		(stroke
			(width 0.05)
			(type default)
		)
		(layer "Edge.Cuts")
	)
	(gr_arc
		(start 1.500124 -70.79996)
		(mid 0.439376 -71.239336)
		(end 0 -72.300084)
		(stroke
			(width 0.05)
			(type default)
		)
		(layer "Edge.Cuts")
	)
	(gr_line
		(start 1.500124 -70.79996)
		(end 6.500114 -70.79996)
		(stroke
			(width 0.05)
			(type default)
		)
		(layer "Edge.Cuts")
	)
	(gr_line
		(start 1.500124 -30.80004)
		(end 6.500114 -30.80004)
		(stroke
			(width 0.05)
			(type default)
		)
		(layer "Edge.Cuts")
	)
	(gr_line
		(start 1.999996 -170.699938)
		(end 10.359898 -170.699938)
		(stroke
			(width 0.05)
			(type default)
		)
		(layer "Edge.Cuts")
	)
	(gr_arc
		(start 1.999996 0)
		(mid 0.585785 -0.585785)
		(end 0 -1.999996)
		(stroke
			(width 0.05)
			(type default)
		)
		(layer "Edge.Cuts")
	)
	(gr_line
		(start 1.999996 0)
		(end 198.000112 0)
		(stroke
			(width 0.05)
			(type default)
		)
		(layer "Edge.Cuts")
	)
	(gr_line
		(start 6.500114 -70.79996)
		(end 1.500124 -70.79996)
		(stroke
			(width 0.05)
			(type default)
		)
		(layer "Edge.Cuts")
	)
	(gr_arc
		(start 6.500114 -70.79996)
		(mid 7.56068 -70.360657)
		(end 7.999984 -69.30009)
		(stroke
			(width 0.05)
			(type default)
		)
		(layer "Edge.Cuts")
	)
	(gr_line
		(start 6.500114 -30.80004)
		(end 1.500124 -30.80004)
		(stroke
			(width 0.05)
			(type default)
		)
		(layer "Edge.Cuts")
	)
	(gr_line
		(start 7.999984 -69.30009)
		(end 7.999984 -32.29991)
		(stroke
			(width 0.05)
			(type default)
		)
		(layer "Edge.Cuts")
	)
	(gr_arc
		(start 7.999984 -32.29991)
		(mid 7.560682 -31.239342)
		(end 6.500114 -30.80004)
		(stroke
			(width 0.05)
			(type default)
		)
		(layer "Edge.Cuts")
	)
	(gr_arc
		(start 7.999984 -32.29991)
		(mid 7.560687 -31.23933)
		(end 6.500114 -30.80004)
		(stroke
			(width 0.05)
			(type default)
		)
		(layer "Edge.Cuts")
	)
	(gr_line
		(start 7.999984 -32.29991)
		(end 7.999984 -69.30009)
		(stroke
			(width 0.05)
			(type default)
		)
		(layer "Edge.Cuts")
	)
	(gr_line
		(start 12.359894 -208.197196)
		(end 12.497054 -208.334356)
		(stroke
			(width 0.05)
			(type default)
		)
		(layer "Edge.Cuts")
	)
	(gr_arc
		(start 12.359894 -172.699934)
		(mid 11.774121 -171.285702)
		(end 10.359898 -170.699938)
		(stroke
			(width 0.05)
			(type default)
		)
		(layer "Edge.Cuts")
	)
	(gr_line
		(start 12.359894 -172.699934)
		(end 12.359894 -208.197196)
		(stroke
			(width 0.05)
			(type default)
		)
		(layer "Edge.Cuts")
	)
	(gr_line
		(start 12.497054 -208.334356)
		(end 12.864084 -208.699608)
		(stroke
			(width 0.05)
			(type default)
		)
		(layer "Edge.Cuts")
	)
	(gr_line
		(start 12.864084 -208.699608)
		(end 83.064604 -208.699608)
		(stroke
			(width 0.05)
			(type default)
		)
		(layer "Edge.Cuts")
	)
	(gr_arc
		(start 23.200106 -182.79999)
		(mid 25.000204 -184.600088)
		(end 26.800048 -182.79999)
		(stroke
			(width 0.05)
			(type default)
		)
		(layer "Edge.Cuts")
	)
	(gr_arc
		(start 23.200106 -181.322726)
		(mid 23.100684 -180.888072)
		(end 22.822154 -180.539898)
		(stroke
			(width 0.05)
			(type default)
		)
		(layer "Edge.Cuts")
	)
	(gr_line
		(start 23.200106 -181.322726)
		(end 23.200106 -182.79999)
		(stroke
			(width 0.05)
			(type default)
		)
		(layer "Edge.Cuts")
	)
	(gr_arc
		(start 23.200106 -26.800048)
		(mid 25.000204 -28.600146)
		(end 26.800048 -26.800048)
		(stroke
			(width 0.05)
			(type default)
		)
		(layer "Edge.Cuts")
	)
	(gr_arc
		(start 23.200106 -25.322784)
		(mid 23.100669 -24.888141)
		(end 22.822154 -24.539956)
		(stroke
			(width 0.05)
			(type default)
		)
		(layer "Edge.Cuts")
	)
	(gr_line
		(start 23.200106 -25.322784)
		(end 23.200106 -26.800048)
		(stroke
			(width 0.05)
			(type default)
		)
		(layer "Edge.Cuts")
	)
	(gr_line
		(start 26.800048 -182.79999)
		(end 26.800048 -181.322726)
		(stroke
			(width 0.05)
			(type default)
		)
		(layer "Edge.Cuts")
	)
	(gr_line
		(start 26.800048 -26.800048)
		(end 26.800048 -25.322784)
		(stroke
			(width 0.05)
			(type default)
		)
		(layer "Edge.Cuts")
	)
	(gr_arc
		(start 27.177746 -180.539898)
		(mid 24.99995 -174.300023)
		(end 22.822154 -180.539898)
		(stroke
			(width 0.05)
			(type default)
		)
		(layer "Edge.Cuts")
	)
	(gr_arc
		(start 27.177746 -180.539898)
		(mid 26.899422 -180.888142)
		(end 26.800048 -181.322726)
		(stroke
			(width 0.05)
			(type default)
		)
		(layer "Edge.Cuts")
	)
	(gr_arc
		(start 27.177746 -24.539956)
		(mid 24.99995 -18.300081)
		(end 22.822154 -24.539956)
		(stroke
			(width 0.05)
			(type default)
		)
		(layer "Edge.Cuts")
	)
	(gr_arc
		(start 27.177746 -24.539956)
		(mid 26.899442 -24.888204)
		(end 26.800048 -25.322784)
		(stroke
			(width 0.05)
			(type default)
		)
		(layer "Edge.Cuts")
	)
	(gr_line
		(start 83.064604 -208.699608)
		(end 12.864084 -208.699608)
		(stroke
			(width 0.05)
			(type default)
		)
		(layer "Edge.Cuts")
	)
	(gr_line
		(start 83.064604 -208.699608)
		(end 83.54441 -208.222342)
		(stroke
			(width 0.05)
			(type default)
		)
		(layer "Edge.Cuts")
	)
	(gr_line
		(start 83.54441 -208.222342)
		(end 83.559904 -208.206848)
		(stroke
			(width 0.05)
			(type default)
		)
		(layer "Edge.Cuts")
	)
	(gr_line
		(start 83.559904 -208.206848)
		(end 83.559904 -201.250042)
		(stroke
			(width 0.05)
			(type default)
		)
		(layer "Edge.Cuts")
	)
	(gr_line
		(start 85.460078 -208.196942)
		(end 85.464904 -208.201768)
		(stroke
			(width 0.05)
			(type default)
		)
		(layer "Edge.Cuts")
	)
	(gr_arc
		(start 85.460078 -201.250042)
		(mid 84.509991 -200.299828)
		(end 83.559904 -201.250042)
		(stroke
			(width 0.05)
			(type default)
		)
		(layer "Edge.Cuts")
	)
	(gr_line
		(start 85.460078 -201.250042)
		(end 85.460078 -208.196942)
		(stroke
			(width 0.05)
			(type default)
		)
		(layer "Edge.Cuts")
	)
	(gr_line
		(start 85.464904 -208.201768)
		(end 85.965284 -208.699608)
		(stroke
			(width 0.05)
			(type default)
		)
		(layer "Edge.Cuts")
	)
	(gr_line
		(start 85.965284 -208.699608)
		(end 96.165924 -208.699608)
		(stroke
			(width 0.05)
			(type default)
		)
		(layer "Edge.Cuts")
	)
	(gr_line
		(start 96.165924 -208.699608)
		(end 85.965284 -208.699608)
		(stroke
			(width 0.05)
			(type default)
		)
		(layer "Edge.Cuts")
	)
	(gr_line
		(start 96.165924 -208.699608)
		(end 96.659954 -208.205578)
		(stroke
			(width 0.05)
			(type default)
		)
		(layer "Edge.Cuts")
	)
	(gr_line
		(start 96.659954 -208.205578)
		(end 96.659954 -188.250068)
		(stroke
			(width 0.05)
			(type default)
		)
		(layer "Edge.Cuts")
	)
	(gr_line
		(start 103.359966 -208.19745)
		(end 103.364284 -208.201768)
		(stroke
			(width 0.05)
			(type default)
		)
		(layer "Edge.Cuts")
	)
	(gr_arc
		(start 103.359966 -188.250068)
		(mid 100.00996 -184.900062)
		(end 96.659954 -188.250068)
		(stroke
			(width 0.05)
			(type default)
		)
		(layer "Edge.Cuts")
	)
	(gr_line
		(start 103.359966 -188.250068)
		(end 103.359966 -208.19745)
		(stroke
			(width 0.05)
			(type default)
		)
		(layer "Edge.Cuts")
	)
	(gr_line
		(start 103.364284 -208.201768)
		(end 103.864664 -208.699608)
		(stroke
			(width 0.05)
			(type default)
		)
		(layer "Edge.Cuts")
	)
	(gr_line
		(start 103.864664 -208.699608)
		(end 174.065184 -208.699608)
		(stroke
			(width 0.05)
			(type default)
		)
		(layer "Edge.Cuts")
	)
	(gr_arc
		(start 173.099984 -182.749952)
		(mid 175.000158 -184.650126)
		(end 176.900078 -182.749952)
		(stroke
			(width 0.05)
			(type default)
		)
		(layer "Edge.Cuts")
	)
	(gr_arc
		(start 173.099984 -181.1909)
		(mid 173.006735 -180.769304)
		(end 172.744384 -180.42636)
		(stroke
			(width 0.05)
			(type default)
		)
		(layer "Edge.Cuts")
	)
	(gr_line
		(start 173.099984 -181.1909)
		(end 173.099984 -182.749952)
		(stroke
			(width 0.05)
			(type default)
		)
		(layer "Edge.Cuts")
	)
	(gr_arc
		(start 173.099984 -26.75001)
		(mid 175.000158 -28.650184)
		(end 176.900078 -26.75001)
		(stroke
			(width 0.05)
			(type default)
		)
		(layer "Edge.Cuts")
	)
	(gr_arc
		(start 173.099984 -25.190958)
		(mid 173.00679 -24.769222)
		(end 172.744384 -24.426164)
		(stroke
			(width 0.05)
			(type default)
		)
		(layer "Edge.Cuts")
	)
	(gr_line
		(start 173.099984 -25.190958)
		(end 173.099984 -26.75001)
		(stroke
			(width 0.05)
			(type default)
		)
		(layer "Edge.Cuts")
	)
	(gr_line
		(start 174.065184 -208.699608)
		(end 103.864664 -208.699608)
		(stroke
			(width 0.05)
			(type default)
		)
		(layer "Edge.Cuts")
	)
	(gr_line
		(start 174.065184 -208.699608)
		(end 174.342552 -208.423764)
		(stroke
			(width 0.05)
			(type default)
		)
		(layer "Edge.Cuts")
	)
	(gr_line
		(start 174.342552 -208.423764)
		(end 174.065184 -208.699608)
		(stroke
			(width 0.05)
			(type default)
		)
		(layer "Edge.Cuts")
	)
	(gr_line
		(start 174.342552 -208.423764)
		(end 174.559976 -208.20634)
		(stroke
			(width 0.05)
			(type default)
		)
		(layer "Edge.Cuts")
	)
	(gr_line
		(start 174.559976 -208.20634)
		(end 174.342552 -208.423764)
		(stroke
			(width 0.05)
			(type default)
		)
		(layer "Edge.Cuts")
	)
	(gr_line
		(start 174.559976 -208.20634)
		(end 174.559976 -201.250042)
		(stroke
			(width 0.05)
			(type default)
		)
		(layer "Edge.Cuts")
	)
	(gr_line
		(start 174.559976 -201.250042)
		(end 174.559976 -208.20634)
		(stroke
			(width 0.05)
			(type default)
		)
		(layer "Edge.Cuts")
	)
	(gr_line
		(start 176.459896 -208.19618)
		(end 176.459896 -201.250042)
		(stroke
			(width 0.05)
			(type default)
		)
		(layer "Edge.Cuts")
	)
	(gr_line
		(start 176.459896 -208.19618)
		(end 176.465484 -208.201768)
		(stroke
			(width 0.05)
			(type default)
		)
		(layer "Edge.Cuts")
	)
	(gr_arc
		(start 176.459896 -201.250042)
		(mid 175.509936 -200.300082)
		(end 174.559976 -201.250042)
		(stroke
			(width 0.05)
			(type default)
		)
		(layer "Edge.Cuts")
	)
	(gr_line
		(start 176.459896 -201.250042)
		(end 176.459896 -208.19618)
		(stroke
			(width 0.05)
			(type default)
		)
		(layer "Edge.Cuts")
	)
	(gr_line
		(start 176.465484 -208.201768)
		(end 176.459896 -208.19618)
		(stroke
			(width 0.05)
			(type default)
		)
		(layer "Edge.Cuts")
	)
	(gr_line
		(start 176.465484 -208.201768)
		(end 176.965864 -208.699608)
		(stroke
			(width 0.05)
			(type default)
		)
		(layer "Edge.Cuts")
	)
	(gr_line
		(start 176.900078 -182.749952)
		(end 176.900078 -181.1909)
		(stroke
			(width 0.05)
			(type default)
		)
		(layer "Edge.Cuts")
	)
	(gr_line
		(start 176.900078 -26.75001)
		(end 176.900078 -25.190958)
		(stroke
			(width 0.05)
			(type default)
		)
		(layer "Edge.Cuts")
	)
	(gr_line
		(start 176.965864 -208.699608)
		(end 176.465484 -208.201768)
		(stroke
			(width 0.05)
			(type default)
		)
		(layer "Edge.Cuts")
	)
	(gr_line
		(start 176.965864 -208.699608)
		(end 187.163964 -208.699608)
		(stroke
			(width 0.05)
			(type default)
		)
		(layer "Edge.Cuts")
	)
	(gr_arc
		(start 177.255678 -180.42636)
		(mid 175.000255 -174.249894)
		(end 172.744384 -180.42636)
		(stroke
			(width 0.05)
			(type default)
		)
		(layer "Edge.Cuts")
	)
	(gr_arc
		(start 177.255678 -180.42636)
		(mid 176.993296 -180.769291)
		(end 176.900078 -181.1909)
		(stroke
			(width 0.05)
			(type default)
		)
		(layer "Edge.Cuts")
	)
	(gr_arc
		(start 177.255678 -24.426164)
		(mid 175.000255 -18.250146)
		(end 172.744384 -24.426164)
		(stroke
			(width 0.05)
			(type default)
		)
		(layer "Edge.Cuts")
	)
	(gr_arc
		(start 177.255678 -24.426164)
		(mid 176.993325 -24.769252)
		(end 176.900078 -25.190958)
		(stroke
			(width 0.05)
			(type default)
		)
		(layer "Edge.Cuts")
	)
	(gr_line
		(start 187.163964 -208.699608)
		(end 176.965864 -208.699608)
		(stroke
			(width 0.05)
			(type default)
		)
		(layer "Edge.Cuts")
	)
	(gr_line
		(start 187.163964 -208.699608)
		(end 187.62853 -208.237328)
		(stroke
			(width 0.05)
			(type default)
		)
		(layer "Edge.Cuts")
	)
	(gr_line
		(start 187.62853 -208.237328)
		(end 187.163964 -208.699608)
		(stroke
			(width 0.05)
			(type default)
		)
		(layer "Edge.Cuts")
	)
	(gr_line
		(start 187.62853 -208.237328)
		(end 187.660026 -208.205832)
		(stroke
			(width 0.05)
			(type default)
		)
		(layer "Edge.Cuts")
	)
	(gr_line
		(start 187.660026 -208.205832)
		(end 187.62853 -208.237328)
		(stroke
			(width 0.05)
			(type default)
		)
		(layer "Edge.Cuts")
	)
	(gr_line
		(start 187.660026 -208.205832)
		(end 187.660026 -172.699934)
		(stroke
			(width 0.05)
			(type default)
		)
		(layer "Edge.Cuts")
	)
	(gr_line
		(start 187.660026 -172.699934)
		(end 187.660026 -208.205832)
		(stroke
			(width 0.05)
			(type default)
		)
		(layer "Edge.Cuts")
	)
	(gr_arc
		(start 189.660022 -170.699938)
		(mid 188.245811 -171.285723)
		(end 187.660026 -172.699934)
		(stroke
			(width 0.05)
			(type default)
		)
		(layer "Edge.Cuts")
	)
	(gr_arc
		(start 189.660022 -170.699938)
		(mid 188.245809 -171.285718)
		(end 187.660026 -172.699934)
		(stroke
			(width 0.05)
			(type default)
		)
		(layer "Edge.Cuts")
	)
	(gr_line
		(start 189.660022 -170.699938)
		(end 198.000112 -170.699938)
		(stroke
			(width 0.05)
			(type default)
		)
		(layer "Edge.Cuts")
	)
	(gr_line
		(start 196.699886 -72.650096)
		(end 196.699886 -33.64992)
		(stroke
			(width 0.05)
			(type default)
		)
		(layer "Edge.Cuts")
	)
	(gr_arc
		(start 196.699886 -72.650096)
		(mid 197.139352 -73.71068)
		(end 198.20001 -74.149966)
		(stroke
			(width 0.05)
			(type default)
		)
		(layer "Edge.Cuts")
	)
	(gr_arc
		(start 196.699886 -72.650096)
		(mid 197.139367 -73.710649)
		(end 198.20001 -74.149966)
		(stroke
			(width 0.05)
			(type default)
		)
		(layer "Edge.Cuts")
	)
	(gr_line
		(start 196.699886 -33.64992)
		(end 196.699886 -72.650096)
		(stroke
			(width 0.05)
			(type default)
		)
		(layer "Edge.Cuts")
	)
	(gr_line
		(start 198.000112 -170.699938)
		(end 189.660022 -170.699938)
		(stroke
			(width 0.05)
			(type default)
		)
		(layer "Edge.Cuts")
	)
	(gr_arc
		(start 198.000112 -170.699938)
		(mid 199.414323 -170.114153)
		(end 200.000108 -168.699942)
		(stroke
			(width 0.05)
			(type default)
		)
		(layer "Edge.Cuts")
	)
	(gr_arc
		(start 198.000112 -170.699938)
		(mid 199.41433 -170.114151)
		(end 200.000108 -168.699942)
		(stroke
			(width 0.05)
			(type default)
		)
		(layer "Edge.Cuts")
	)
	(gr_line
		(start 198.000112 0)
		(end 1.999996 0)
		(stroke
			(width 0.05)
			(type default)
		)
		(layer "Edge.Cuts")
	)
	(gr_line
		(start 198.20001 -74.149966)
		(end 198.499984 -74.149966)
		(stroke
			(width 0.05)
			(type default)
		)
		(layer "Edge.Cuts")
	)
	(gr_arc
		(start 198.20001 -32.15005)
		(mid 197.139336 -32.589331)
		(end 196.699886 -33.64992)
		(stroke
			(width 0.05)
			(type default)
		)
		(layer "Edge.Cuts")
	)
	(gr_arc
		(start 198.20001 -32.15005)
		(mid 197.139352 -32.589336)
		(end 196.699886 -33.64992)
		(stroke
			(width 0.05)
			(type default)
		)
		(layer "Edge.Cuts")
	)
	(gr_line
		(start 198.20001 -32.15005)
		(end 198.499984 -32.15005)
		(stroke
			(width 0.05)
			(type default)
		)
		(layer "Edge.Cuts")
	)
	(gr_line
		(start 198.499984 -74.149966)
		(end 198.20001 -74.149966)
		(stroke
			(width 0.05)
			(type default)
		)
		(layer "Edge.Cuts")
	)
	(gr_line
		(start 198.499984 -32.15005)
		(end 198.20001 -32.15005)
		(stroke
			(width 0.05)
			(type default)
		)
		(layer "Edge.Cuts")
	)
	(gr_arc
		(start 198.499984 -32.15005)
		(mid 199.560732 -31.710674)
		(end 200.000108 -30.649926)
		(stroke
			(width 0.05)
			(type default)
		)
		(layer "Edge.Cuts")
	)
	(gr_arc
		(start 198.499984 -32.15005)
		(mid 199.560751 -31.710681)
		(end 200.000108 -30.649926)
		(stroke
			(width 0.05)
			(type default)
		)
		(layer "Edge.Cuts")
	)
	(gr_line
		(start 200.000108 -168.699942)
		(end 200.000108 -75.65009)
		(stroke
			(width 0.05)
			(type default)
		)
		(layer "Edge.Cuts")
	)
	(gr_arc
		(start 200.000108 -75.65009)
		(mid 199.560727 -74.589354)
		(end 198.499984 -74.149966)
		(stroke
			(width 0.05)
			(type default)
		)
		(layer "Edge.Cuts")
	)
	(gr_arc
		(start 200.000108 -75.65009)
		(mid 199.560732 -74.589342)
		(end 198.499984 -74.149966)
		(stroke
			(width 0.05)
			(type default)
		)
		(layer "Edge.Cuts")
	)
	(gr_line
		(start 200.000108 -75.65009)
		(end 200.000108 -168.699942)
		(stroke
			(width 0.05)
			(type default)
		)
		(layer "Edge.Cuts")
	)
	(gr_line
		(start 200.000108 -30.649926)
		(end 200.000108 -1.999996)
		(stroke
			(width 0.05)
			(type default)
		)
		(layer "Edge.Cuts")
	)
	(gr_arc
		(start 200.000108 -1.999996)
		(mid 199.414323 -0.585785)
		(end 198.000112 0)
		(stroke
			(width 0.05)
			(type default)
		)
		(layer "Edge.Cuts")
	)
	(gr_line
		(start 200.000108 -1.999996)
		(end 200.000108 -30.649926)
		(stroke
			(width 0.05)
			(type default)
		)
		(layer "Edge.Cuts")
	)
	(segment
		(start 163.449 -188.48705)
		(end 162.9918 -188.94425)
		(width 0.1016)
		(layer "F.Cu")
		(net "UART_RI_RP5_L_N_R")
	)
	(segment
		(start 159.997648 -199.035162)
		(end 161.65576 -200.693274)
		(width 0.1016)
		(layer "F.Cu")
		(net "UART_RI_RP5_L_N_R")
	)
	(segment
		(start 161.65576 -202.135994)
		(end 161.01568 -202.776074)
		(width 0.1016)
		(layer "F.Cu")
		(net "UART_RI_RP5_L_N_R")
	)
	(segment
		(start 162.9918 -191.6684)
		(end 159.997648 -194.662552)
		(width 0.1016)
		(layer "F.Cu")
		(net "UART_RI_RP5_L_N_R")
	)
	(segment
		(start 162.9918 -188.94425)
		(end 162.9918 -191.6684)
		(width 0.1016)
		(layer "F.Cu")
		(net "UART_RI_RP5_L_N_R")
	)
	(segment
		(start 161.65576 -200.693274)
		(end 161.65576 -202.135994)
		(width 0.1016)
		(layer "F.Cu")
		(net "UART_RI_RP5_L_N_R")
	)
	(segment
		(start 159.997648 -195.3768)
		(end 159.997648 -199.035162)
		(width 0.1016)
		(layer "F.Cu")
		(net "UART_RI_RP5_L_N_R")
	)
	(segment
		(start 159.997648 -194.662552)
		(end 159.997648 -195.3768)
		(width 0.1016)
		(layer "F.Cu")
		(net "UART_RI_RP5_L_N_R")
	)
	(segment
		(start 161.01568 -202.776074)
		(end 161.01568 -205.199488)
		(width 0.1016)
		(layer "F.Cu")
		(net "UART_RI_RP5_L_N_R")
	)
	(via
		(at 159.997648 -195.3768)
		(size 0.508)
		(drill 0.254)
		(layers "F.Cu" "B.Cu")
		(net "UART_RI_RP5_L_N_R")
	)
	(segment
		(start 163.4236 -191.6176)
		(end 160.528 -194.5132)
		(width 0.1016)
		(layer "F.Cu")
		(net "UART_RI_RP6_L_N_R")
	)
	(segment
		(start 163.4236 -190.3476)
		(end 163.4236 -191.6176)
		(width 0.1016)
		(layer "F.Cu")
		(net "UART_RI_RP6_L_N_R")
	)
	(segment
		(start 164.211 -189.5602)
		(end 163.4236 -190.3476)
		(width 0.1016)
		(layer "F.Cu")
		(net "UART_RI_RP6_L_N_R")
	)
	(segment
		(start 160.528 -194.5132)
		(end 160.528 -196.9516)
		(width 0.1016)
		(layer "F.Cu")
		(net "UART_RI_RP6_L_N_R")
	)
	(via
		(at 164.211 -189.5602)
		(size 0.508)
		(drill 0.254)
		(layers "F.Cu" "B.Cu")
		(net "UART_RI_RP6_L_N_R")
	)
	(via
		(at 160.528 -196.9516)
		(size 0.508)
		(drill 0.254)
		(layers "F.Cu" "B.Cu")
		(net "UART_RI_RP6_L_N_R")
	)
	(segment
		(start 164.592 -189.1792)
		(end 164.592 -188.48705)
		(width 0.1016)
		(layer "B.Cu")
		(net "UART_RI_RP6_L_N_R")
	)
	(segment
		(start 161.163 -200.2536)
		(end 162.015678 -201.106278)
		(width 0.1016)
		(layer "B.Cu")
		(net "UART_RI_RP6_L_N_R")
	)
	(segment
		(start 160.528 -196.9516)
		(end 161.163 -197.5866)
		(width 0.1016)
		(layer "B.Cu")
		(net "UART_RI_RP6_L_N_R")
	)
	(segment
		(start 161.163 -197.5866)
		(end 161.163 -200.2536)
		(width 0.1016)
		(layer "B.Cu")
		(net "UART_RI_RP6_L_N_R")
	)
	(segment
		(start 164.211 -189.5602)
		(end 164.592 -189.1792)
		(width 0.1016)
		(layer "B.Cu")
		(net "UART_RI_RP6_L_N_R")
	)
	(segment
		(start 162.015678 -201.106278)
		(end 162.015678 -205.199488)
		(width 0.1016)
		(layer "B.Cu")
		(net "UART_RI_RP6_L_N_R")
	)
	(segment
		(start 37.014912 -205.199488)
		(end 37.014912 -200.424034)
		(width 0.1016)
		(layer "F.Cu")
		(net "UART_RI_P5_L_N_R")
	)
	(segment
		(start 37.014912 -200.424034)
		(end 36.576 -199.985122)
		(width 0.1016)
		(layer "F.Cu")
		(net "UART_RI_P5_L_N_R")
	)
	(segment
		(start 36.576 -198.6661)
		(end 36.97478 -198.26732)
		(width 0.1016)
		(layer "F.Cu")
		(net "UART_RI_P5_L_N_R")
	)
	(segment
		(start 36.576 -199.985122)
		(end 36.576 -198.6661)
		(width 0.1016)
		(layer "F.Cu")
		(net "UART_RI_P5_L_N_R")
	)
	(via
		(at 36.97478 -198.26732)
		(size 0.508)
		(drill 0.254)
		(layers "F.Cu" "B.Cu")
		(net "UART_RI_P5_L_N_R")
	)
	(segment
		(start 24.7904 -197.2818)
		(end 35.98926 -197.2818)
		(width 0.1016)
		(layer "B.Cu")
		(net "UART_RI_P5_L_N_R")
	)
	(segment
		(start 35.98926 -197.2818)
		(end 36.97478 -198.26732)
		(width 0.1016)
		(layer "B.Cu")
		(net "UART_RI_P5_L_N_R")
	)
	(segment
		(start 23.5966 -196.088)
		(end 24.7904 -197.2818)
		(width 0.1016)
		(layer "B.Cu")
		(net "UART_RI_P5_L_N_R")
	)
	(segment
		(start 33.03905 -188.7728)
		(end 33.03905 -192.79235)
		(width 0.1016)
		(layer "B.Cu")
		(net "UART_RI_P5_L_N_R")
	)
	(segment
		(start 24.46655 -193.49085)
		(end 23.5966 -194.3608)
		(width 0.1016)
		(layer "B.Cu")
		(net "UART_RI_P5_L_N_R")
	)
	(segment
		(start 33.03905 -192.79235)
		(end 32.34055 -193.49085)
		(width 0.1016)
		(layer "B.Cu")
		(net "UART_RI_P5_L_N_R")
	)
	(segment
		(start 32.34055 -193.49085)
		(end 24.46655 -193.49085)
		(width 0.1016)
		(layer "B.Cu")
		(net "UART_RI_P5_L_N_R")
	)
	(segment
		(start 23.5966 -194.3608)
		(end 23.5966 -196.088)
		(width 0.1016)
		(layer "B.Cu")
		(net "UART_RI_P5_L_N_R")
	)
	(via
		(at 33.5026 -193.2686)
		(size 0.6604)
		(drill 0.3302)
		(layers "F.Cu" "B.Cu")
		(net "UART_RI_P6_L_N_R")
	)
	(via
		(at 37.1221 -199.09028)
		(size 0.508)
		(drill 0.254)
		(layers "F.Cu" "B.Cu")
		(net "UART_RI_P6_L_N_R")
	)
	(segment
		(start 37.4904 -198.72198)
		(end 37.1221 -199.09028)
		(width 0.1016)
		(layer "B.Cu")
		(net "UART_RI_P6_L_N_R")
	)
	(segment
		(start 37.014912 -199.197468)
		(end 37.1221 -199.09028)
		(width 0.1016)
		(layer "B.Cu")
		(net "UART_RI_P6_L_N_R")
	)
	(segment
		(start 33.02 -193.7512)
		(end 24.5745 -193.7512)
		(width 0.1016)
		(layer "B.Cu")
		(net "UART_RI_P6_L_N_R")
	)
	(segment
		(start 23.85695 -195.98005)
		(end 24.8793 -197.0024)
		(width 0.1016)
		(layer "B.Cu")
		(net "UART_RI_P6_L_N_R")
	)
	(segment
		(start 37.4904 -197.9676)
		(end 37.4904 -198.72198)
		(width 0.1016)
		(layer "B.Cu")
		(net "UART_RI_P6_L_N_R")
	)
	(segment
		(start 24.8793 -197.0024)
		(end 36.5252 -197.0024)
		(width 0.1016)
		(layer "B.Cu")
		(net "UART_RI_P6_L_N_R")
	)
	(segment
		(start 36.5252 -197.0024)
		(end 37.4904 -197.9676)
		(width 0.1016)
		(layer "B.Cu")
		(net "UART_RI_P6_L_N_R")
	)
	(segment
		(start 33.5026 -188.19495)
		(end 33.5026 -193.2686)
		(width 0.1016)
		(layer "B.Cu")
		(net "UART_RI_P6_L_N_R")
	)
	(segment
		(start 37.014912 -205.199488)
		(end 37.014912 -199.197468)
		(width 0.1016)
		(layer "B.Cu")
		(net "UART_RI_P6_L_N_R")
	)
	(segment
		(start 33.03905 -187.7314)
		(end 33.5026 -188.19495)
		(width 0.1016)
		(layer "B.Cu")
		(net "UART_RI_P6_L_N_R")
	)
	(segment
		(start 33.5026 -193.2686)
		(end 33.02 -193.7512)
		(width 0.1016)
		(layer "B.Cu")
		(net "UART_RI_P6_L_N_R")
	)
	(segment
		(start 23.85695 -194.46875)
		(end 23.85695 -195.98005)
		(width 0.1016)
		(layer "B.Cu")
		(net "UART_RI_P6_L_N_R")
	)
	(segment
		(start 24.5745 -193.7512)
		(end 23.85695 -194.46875)
		(width 0.1016)
		(layer "B.Cu")
		(net "UART_RI_P6_L_N_R")
	)
	(segment
		(start 138.684 -48.768)
		(end 138.261598 -48.345598)
		(width 0.1016)
		(layer "F.Cu")
		(net "UART_DCD_P3_N")
	)
	(segment
		(start 138.261598 -48.345598)
		(end 138.261598 -47.199804)
		(width 0.1016)
		(layer "F.Cu")
		(net "UART_DCD_P3_N")
	)
	(via
		(at 138.684 -48.768)
		(size 0.508)
		(drill 0.254)
		(layers "F.Cu" "B.Cu")
		(net "UART_DCD_P3_N")
	)
	(segment
		(start 138.684 -48.768)
		(end 138.684 -47.352204)
		(width 0.1016)
		(layer "B.Cu")
		(net "UART_DCD_P3_N")
	)
	(segment
		(start 138.303 -51.03495)
		(end 138.303 -50.165)
		(width 0.1016)
		(layer "F.Cu")
		(net "UART_CTS_P3_N")
	)
	(segment
		(start 137.2616 -49.1236)
		(end 137.2616 -47.199804)
		(width 0.1016)
		(layer "F.Cu")
		(net "UART_CTS_P3_N")
	)
	(segment
		(start 138.303 -50.165)
		(end 137.2616 -49.1236)
		(width 0.1016)
		(layer "F.Cu")
		(net "UART_CTS_P3_N")
	)
	(via
		(at 138.303 -50.165)
		(size 0.508)
		(drill 0.254)
		(layers "F.Cu" "B.Cu")
		(net "UART_CTS_P3_N")
	)
	(segment
		(start 135.261604 -47.199804)
		(end 135.261604 -49.670208)
		(width 0.1016)
		(layer "F.Cu")
		(net "UART_DSR_P3_N")
	)
	(segment
		(start 135.261604 -49.670208)
		(end 135.502396 -49.911)
		(width 0.1016)
		(layer "F.Cu")
		(net "UART_DSR_P3_N")
	)
	(segment
		(start 135.502396 -49.911)
		(end 135.502396 -50.038)
		(width 0.1016)
		(layer "F.Cu")
		(net "UART_DSR_P3_N")
	)
	(segment
		(start 135.255 -50.285396)
		(end 135.255 -51.03495)
		(width 0.1016)
		(layer "F.Cu")
		(net "UART_DSR_P3_N")
	)
	(segment
		(start 135.502396 -50.038)
		(end 135.255 -50.285396)
		(width 0.1016)
		(layer "F.Cu")
		(net "UART_DSR_P3_N")
	)
	(via
		(at 135.502396 -49.911)
		(size 0.508)
		(drill 0.254)
		(layers "F.Cu" "B.Cu")
		(net "UART_DSR_P3_N")
	)
	(segment
		(start 137.025888 -169.411396)
		(end 137.11682 -169.502328)
		(width 0.1016)
		(layer "F.Cu")
		(net "UART_RI_P3_BUFFER_N")
	)
	(segment
		(start 137.025888 -163.358576)
		(end 137.025888 -169.411396)
		(width 0.1016)
		(layer "F.Cu")
		(net "UART_RI_P3_BUFFER_N")
	)
	(via
		(at 134.13867 -58.570876)
		(size 0.508)
		(drill 0.254)
		(layers "F.Cu" "B.Cu")
		(net "UART_RI_P3_BUFFER_N")
	)
	(via
		(at 137.11682 -169.502328)
		(size 0.508)
		(drill 0.254)
		(layers "F.Cu" "B.Cu")
		(net "UART_RI_P3_BUFFER_N")
	)
	(segment
		(start 129.77495 -59.03595)
		(end 130.175 -59.436)
		(width 0.1016)
		(layer "B.Cu")
		(net "UART_RI_P3_BUFFER_N")
	)
	(segment
		(start 130.556 -60.452)
		(end 133.731 -60.452)
		(width 0.1016)
		(layer "B.Cu")
		(net "UART_RI_P3_BUFFER_N")
	)
	(segment
		(start 128.92405 -59.436)
		(end 129.13995 -59.436)
		(width 0.1016)
		(layer "B.Cu")
		(net "UART_RI_P3_BUFFER_N")
	)
	(segment
		(start 129.54 -59.03595)
		(end 129.54 -58.801)
		(width 0.1016)
		(layer "B.Cu")
		(net "UART_RI_P3_BUFFER_N")
	)
	(segment
		(start 128.524 -59.83605)
		(end 128.92405 -59.436)
		(width 0.1016)
		(layer "B.Cu")
		(net "UART_RI_P3_BUFFER_N")
	)
	(segment
		(start 134.1374 -58.572146)
		(end 134.13867 -58.570876)
		(width 0.1016)
		(layer "B.Cu")
		(net "UART_RI_P3_BUFFER_N")
	)
	(segment
		(start 130.175 -60.071)
		(end 130.556 -60.452)
		(width 0.1016)
		(layer "B.Cu")
		(net "UART_RI_P3_BUFFER_N")
	)
	(segment
		(start 134.1374 -60.0456)
		(end 134.1374 -58.572146)
		(width 0.1016)
		(layer "B.Cu")
		(net "UART_RI_P3_BUFFER_N")
	)
	(segment
		(start 129.54 -58.801)
		(end 128.905 -58.166)
		(width 0.1016)
		(layer "B.Cu")
		(net "UART_RI_P3_BUFFER_N")
	)
	(segment
		(start 128.905 -58.166)
		(end 128.905 -54.282594)
		(width 0.1016)
		(layer "B.Cu")
		(net "UART_RI_P3_BUFFER_N")
	)
	(segment
		(start 129.54 -59.03595)
		(end 129.77495 -59.03595)
		(width 0.1016)
		(layer "B.Cu")
		(net "UART_RI_P3_BUFFER_N")
	)
	(segment
		(start 129.13995 -59.436)
		(end 129.54 -59.03595)
		(width 0.1016)
		(layer "B.Cu")
		(net "UART_RI_P3_BUFFER_N")
	)
	(segment
		(start 130.175 -59.436)
		(end 130.175 -60.071)
		(width 0.1016)
		(layer "B.Cu")
		(net "UART_RI_P3_BUFFER_N")
	)
	(segment
		(start 133.731 -60.452)
		(end 134.1374 -60.0456)
		(width 0.1016)
		(layer "B.Cu")
		(net "UART_RI_P3_BUFFER_N")
	)
	(segment
		(start 181.881018 -163.00577)
		(end 171.696126 -163.00577)
		(width 0.1143)
		(layer "In2.Cu")
		(net "UART_RI_P3_BUFFER_N")
	)
	(segment
		(start 164.74059 -165.483286)
		(end 156.807154 -165.483286)
		(width 0.1143)
		(layer "In2.Cu")
		(net "UART_RI_P3_BUFFER_N")
	)
	(segment
		(start 150.84425 -165.55593)
		(end 149.266402 -165.55593)
		(width 0.1143)
		(layer "In2.Cu")
		(net "UART_RI_P3_BUFFER_N")
	)
	(segment
		(start 145.11909 -166.468806)
		(end 142.620238 -166.468806)
		(width 0.1143)
		(layer "In2.Cu")
		(net "UART_RI_P3_BUFFER_N")
	)
	(segment
		(start 135.08228 -64.309244)
		(end 135.08228 -69.14134)
		(width 0.1143)
		(layer "In2.Cu")
		(net "UART_RI_P3_BUFFER_N")
	)
	(segment
		(start 137.74928 -71.80834)
		(end 137.74928 -74.064114)
		(width 0.1143)
		(layer "In2.Cu")
		(net "UART_RI_P3_BUFFER_N")
	)
	(segment
		(start 151.9936 -165.52164)
		(end 150.87854 -165.52164)
		(width 0.1143)
		(layer "In2.Cu")
		(net "UART_RI_P3_BUFFER_N")
	)
	(segment
		(start 176.423828 -85.118702)
		(end 178.53406 -85.118702)
		(width 0.1143)
		(layer "In2.Cu")
		(net "UART_RI_P3_BUFFER_N")
	)
	(segment
		(start 148.56333 -84.878164)
		(end 152.520396 -84.878164)
		(width 0.1143)
		(layer "In2.Cu")
		(net "UART_RI_P3_BUFFER_N")
	)
	(segment
		(start 135.08228 -69.14134)
		(end 137.74928 -71.80834)
		(width 0.1143)
		(layer "In2.Cu")
		(net "UART_RI_P3_BUFFER_N")
	)
	(segment
		(start 191.69507 -129.010664)
		(end 191.69507 -153.191718)
		(width 0.1143)
		(layer "In2.Cu")
		(net "UART_RI_P3_BUFFER_N")
	)
	(segment
		(start 191.69507 -153.191718)
		(end 181.881018 -163.00577)
		(width 0.1143)
		(layer "In2.Cu")
		(net "UART_RI_P3_BUFFER_N")
	)
	(segment
		(start 156.807154 -165.483286)
		(end 156.76372 -165.52672)
		(width 0.1143)
		(layer "In2.Cu")
		(net "UART_RI_P3_BUFFER_N")
	)
	(segment
		(start 152.520396 -84.878164)
		(end 152.559766 -84.838794)
		(width 0.1143)
		(layer "In2.Cu")
		(net "UART_RI_P3_BUFFER_N")
	)
	(segment
		(start 140.770102 -167.527224)
		(end 139.467844 -168.829482)
		(width 0.1143)
		(layer "In2.Cu")
		(net "UART_RI_P3_BUFFER_N")
	)
	(segment
		(start 148.88083 -165.170358)
		(end 146.417538 -165.170358)
		(width 0.1143)
		(layer "In2.Cu")
		(net "UART_RI_P3_BUFFER_N")
	)
	(segment
		(start 178.53406 -85.118702)
		(end 191.5668 -98.151442)
		(width 0.1143)
		(layer "In2.Cu")
		(net "UART_RI_P3_BUFFER_N")
	)
	(segment
		(start 176.14392 -84.838794)
		(end 176.423828 -85.118702)
		(width 0.1143)
		(layer "In2.Cu")
		(net "UART_RI_P3_BUFFER_N")
	)
	(segment
		(start 134.13867 -63.365634)
		(end 135.08228 -64.309244)
		(width 0.1143)
		(layer "In2.Cu")
		(net "UART_RI_P3_BUFFER_N")
	)
	(segment
		(start 165.251892 -164.971984)
		(end 164.74059 -165.483286)
		(width 0.1143)
		(layer "In2.Cu")
		(net "UART_RI_P3_BUFFER_N")
	)
	(segment
		(start 142.620238 -166.468806)
		(end 141.56182 -167.527224)
		(width 0.1143)
		(layer "In2.Cu")
		(net "UART_RI_P3_BUFFER_N")
	)
	(segment
		(start 150.87854 -165.52164)
		(end 150.84425 -165.55593)
		(width 0.1143)
		(layer "In2.Cu")
		(net "UART_RI_P3_BUFFER_N")
	)
	(segment
		(start 139.467844 -168.829482)
		(end 137.789666 -168.829482)
		(width 0.1143)
		(layer "In2.Cu")
		(net "UART_RI_P3_BUFFER_N")
	)
	(segment
		(start 169.729912 -164.971984)
		(end 165.251892 -164.971984)
		(width 0.1143)
		(layer "In2.Cu")
		(net "UART_RI_P3_BUFFER_N")
	)
	(segment
		(start 141.56182 -167.527224)
		(end 140.770102 -167.527224)
		(width 0.1143)
		(layer "In2.Cu")
		(net "UART_RI_P3_BUFFER_N")
	)
	(segment
		(start 191.5668 -98.151442)
		(end 191.5668 -121.4628)
		(width 0.1143)
		(layer "In2.Cu")
		(net "UART_RI_P3_BUFFER_N")
	)
	(segment
		(start 191.5668 -121.4628)
		(end 191.897 -121.793)
		(width 0.1143)
		(layer "In2.Cu")
		(net "UART_RI_P3_BUFFER_N")
	)
	(segment
		(start 146.417538 -165.170358)
		(end 145.11909 -166.468806)
		(width 0.1143)
		(layer "In2.Cu")
		(net "UART_RI_P3_BUFFER_N")
	)
	(segment
		(start 191.897 -121.793)
		(end 191.897 -128.808734)
		(width 0.1143)
		(layer "In2.Cu")
		(net "UART_RI_P3_BUFFER_N")
	)
	(segment
		(start 134.13867 -58.570876)
		(end 134.13867 -63.365634)
		(width 0.1143)
		(layer "In2.Cu")
		(net "UART_RI_P3_BUFFER_N")
	)
	(segment
		(start 137.789666 -168.829482)
		(end 137.11682 -169.502328)
		(width 0.1143)
		(layer "In2.Cu")
		(net "UART_RI_P3_BUFFER_N")
	)
	(segment
		(start 137.74928 -74.064114)
		(end 148.56333 -84.878164)
		(width 0.1143)
		(layer "In2.Cu")
		(net "UART_RI_P3_BUFFER_N")
	)
	(segment
		(start 149.266402 -165.55593)
		(end 148.88083 -165.170358)
		(width 0.1143)
		(layer "In2.Cu")
		(net "UART_RI_P3_BUFFER_N")
	)
	(segment
		(start 191.897 -128.808734)
		(end 191.69507 -129.010664)
		(width 0.1143)
		(layer "In2.Cu")
		(net "UART_RI_P3_BUFFER_N")
	)
	(segment
		(start 156.76372 -165.52672)
		(end 151.99868 -165.52672)
		(width 0.1143)
		(layer "In2.Cu")
		(net "UART_RI_P3_BUFFER_N")
	)
	(segment
		(start 152.559766 -84.838794)
		(end 176.14392 -84.838794)
		(width 0.1143)
		(layer "In2.Cu")
		(net "UART_RI_P3_BUFFER_N")
	)
	(segment
		(start 171.696126 -163.00577)
		(end 169.729912 -164.971984)
		(width 0.1143)
		(layer "In2.Cu")
		(net "UART_RI_P3_BUFFER_N")
	)
	(segment
		(start 151.99868 -165.52672)
		(end 151.9936 -165.52164)
		(width 0.1143)
		(layer "In2.Cu")
		(net "UART_RI_P3_BUFFER_N")
	)
	(segment
		(start 133.761734 -47.199804)
		(end 133.761734 -44.978066)
		(width 0.1016)
		(layer "F.Cu")
		(net "UART_DCD_P4_N")
	)
	(via
		(at 133.761734 -44.978066)
		(size 0.508)
		(drill 0.254)
		(layers "F.Cu" "B.Cu")
		(net "UART_DCD_P4_N")
	)
	(segment
		(start 133.761734 -44.978066)
		(end 132.969 -45.7708)
		(width 0.1016)
		(layer "B.Cu")
		(net "UART_DCD_P4_N")
	)
	(segment
		(start 132.969 -45.7708)
		(end 132.969 -46.88205)
		(width 0.1016)
		(layer "B.Cu")
		(net "UART_DCD_P4_N")
	)
	(segment
		(start 132.969 -46.88205)
		(end 133.4516 -47.36465)
		(width 0.1016)
		(layer "B.Cu")
		(net "UART_DCD_P4_N")
	)
	(segment
		(start 132.761736 -45.952664)
		(end 132.761736 -47.199804)
		(width 0.1016)
		(layer "F.Cu")
		(net "UART_CTS_P4_N")
	)
	(segment
		(start 131.0894 -45.2374)
		(end 131.804664 -45.952664)
		(width 0.1016)
		(layer "F.Cu")
		(net "UART_CTS_P4_N")
	)
	(segment
		(start 131.804664 -45.952664)
		(end 132.761736 -45.952664)
		(width 0.1016)
		(layer "F.Cu")
		(net "UART_CTS_P4_N")
	)
	(via
		(at 131.0894 -45.2374)
		(size 0.508)
		(drill 0.254)
		(layers "F.Cu" "B.Cu")
		(net "UART_CTS_P4_N")
	)
	(segment
		(start 131.28625 -45.4152)
		(end 131.10845 -45.2374)
		(width 0.1016)
		(layer "B.Cu")
		(net "UART_CTS_P4_N")
	)
	(segment
		(start 131.10845 -45.2374)
		(end 131.0894 -45.2374)
		(width 0.1016)
		(layer "B.Cu")
		(net "UART_CTS_P4_N")
	)
	(segment
		(start 131.28625 -46.3804)
		(end 131.28625 -45.4152)
		(width 0.1016)
		(layer "B.Cu")
		(net "UART_CTS_P4_N")
	)
	(segment
		(start 130.261614 -48.833786)
		(end 130.261614 -47.199804)
		(width 0.1016)
		(layer "F.Cu")
		(net "UART_DSR_P4_N")
	)
	(segment
		(start 129.8448 -49.53)
		(end 129.8448 -49.2506)
		(width 0.1016)
		(layer "F.Cu")
		(net "UART_DSR_P4_N")
	)
	(segment
		(start 130.0988 -50.45075)
		(end 130.0988 -49.784)
		(width 0.1016)
		(layer "F.Cu")
		(net "UART_DSR_P4_N")
	)
	(segment
		(start 130.0988 -49.784)
		(end 129.8448 -49.53)
		(width 0.1016)
		(layer "F.Cu")
		(net "UART_DSR_P4_N")
	)
	(segment
		(start 129.8448 -49.2506)
		(end 130.261614 -48.833786)
		(width 0.1016)
		(layer "F.Cu")
		(net "UART_DSR_P4_N")
	)
	(via
		(at 130.0988 -49.784)
		(size 0.508)
		(drill 0.254)
		(layers "F.Cu" "B.Cu")
		(net "UART_DSR_P4_N")
	)
	(segment
		(start 190.881 -88.011)
		(end 190.881 -94.2086)
		(width 0.1016)
		(layer "F.Cu")
		(net "SIO_JTAG_CPLD1_TDO")
	)
	(segment
		(start 161.29 -67.4116)
		(end 170.2816 -67.4116)
		(width 0.1016)
		(layer "F.Cu")
		(net "SIO_JTAG_CPLD1_TDO")
	)
	(segment
		(start 139.4714 -43.3324)
		(end 137.761726 -41.622726)
		(width 0.1016)
		(layer "F.Cu")
		(net "SIO_JTAG_CPLD1_TDO")
	)
	(segment
		(start 145.1864 -46.6344)
		(end 141.8844 -43.3324)
		(width 0.1016)
		(layer "F.Cu")
		(net "SIO_JTAG_CPLD1_TDO")
	)
	(segment
		(start 151.9428 -44.1198)
		(end 151.9428 -45.7708)
		(width 0.1016)
		(layer "F.Cu")
		(net "SIO_JTAG_CPLD1_TDO")
	)
	(segment
		(start 170.2816 -67.4116)
		(end 190.881 -88.011)
		(width 0.1016)
		(layer "F.Cu")
		(net "SIO_JTAG_CPLD1_TDO")
	)
	(segment
		(start 141.8844 -43.3324)
		(end 139.4714 -43.3324)
		(width 0.1016)
		(layer "F.Cu")
		(net "SIO_JTAG_CPLD1_TDO")
	)
	(segment
		(start 193.3194 -129.3368)
		(end 187.2234 -129.3368)
		(width 0.1016)
		(layer "F.Cu")
		(net "SIO_JTAG_CPLD1_TDO")
	)
	(segment
		(start 152.8572 -43.2054)
		(end 151.9428 -44.1198)
		(width 0.1016)
		(layer "F.Cu")
		(net "SIO_JTAG_CPLD1_TDO")
	)
	(segment
		(start 196.6976 -100.0252)
		(end 196.6976 -125.9586)
		(width 0.1016)
		(layer "F.Cu")
		(net "SIO_JTAG_CPLD1_TDO")
	)
	(segment
		(start 162.3568 -43.2054)
		(end 152.8572 -43.2054)
		(width 0.1016)
		(layer "F.Cu")
		(net "SIO_JTAG_CPLD1_TDO")
	)
	(segment
		(start 186.531758 -128.645158)
		(end 186.531758 -128.029716)
		(width 0.1016)
		(layer "F.Cu")
		(net "SIO_JTAG_CPLD1_TDO")
	)
	(segment
		(start 190.881 -94.2086)
		(end 196.6976 -100.0252)
		(width 0.1016)
		(layer "F.Cu")
		(net "SIO_JTAG_CPLD1_TDO")
	)
	(segment
		(start 151.0792 -46.6344)
		(end 145.1864 -46.6344)
		(width 0.1016)
		(layer "F.Cu")
		(net "SIO_JTAG_CPLD1_TDO")
	)
	(segment
		(start 151.9428 -45.7708)
		(end 151.0792 -46.6344)
		(width 0.1016)
		(layer "F.Cu")
		(net "SIO_JTAG_CPLD1_TDO")
	)
	(segment
		(start 187.2234 -129.3368)
		(end 186.531758 -128.645158)
		(width 0.1016)
		(layer "F.Cu")
		(net "SIO_JTAG_CPLD1_TDO")
	)
	(segment
		(start 196.6976 -125.9586)
		(end 193.3194 -129.3368)
		(width 0.1016)
		(layer "F.Cu")
		(net "SIO_JTAG_CPLD1_TDO")
	)
	(segment
		(start 186.531758 -128.029716)
		(end 186.531758 -127.0254)
		(width 0.1016)
		(layer "F.Cu")
		(net "SIO_JTAG_CPLD1_TDO")
	)
	(segment
		(start 137.761726 -41.622726)
		(end 137.761726 -30.079696)
		(width 0.1016)
		(layer "F.Cu")
		(net "SIO_JTAG_CPLD1_TDO")
	)
	(via
		(at 162.3568 -43.2054)
		(size 0.508)
		(drill 0.254)
		(layers "F.Cu" "B.Cu")
		(net "SIO_JTAG_CPLD1_TDO")
	)
	(via
		(at 161.29 -67.4116)
		(size 0.508)
		(drill 0.254)
		(layers "F.Cu" "B.Cu")
		(net "SIO_JTAG_CPLD1_TDO")
	)
	(segment
		(start 163.1442 -60.4012)
		(end 161.798 -61.7474)
		(width 0.1016)
		(layer "B.Cu")
		(net "SIO_JTAG_CPLD1_TDO")
	)
	(segment
		(start 163.1442 -43.9928)
		(end 163.1442 -60.4012)
		(width 0.1016)
		(layer "B.Cu")
		(net "SIO_JTAG_CPLD1_TDO")
	)
	(segment
		(start 161.798 -61.722)
		(end 161.29 -62.23)
		(width 0.1016)
		(layer "B.Cu")
		(net "SIO_JTAG_CPLD1_TDO")
	)
	(segment
		(start 162.3568 -43.2054)
		(end 163.1442 -43.9928)
		(width 0.1016)
		(layer "B.Cu")
		(net "SIO_JTAG_CPLD1_TDO")
	)
	(segment
		(start 161.29 -62.23)
		(end 161.29 -67.4116)
		(width 0.1016)
		(layer "B.Cu")
		(net "SIO_JTAG_CPLD1_TDO")
	)
	(segment
		(start 161.798 -61.7474)
		(end 161.798 -61.722)
		(width 0.1016)
		(layer "B.Cu")
		(net "SIO_JTAG_CPLD1_TDO")
	)
	(segment
		(start 190.5 -94.366588)
		(end 196.3166 -100.183188)
		(width 0.1016)
		(layer "F.Cu")
		(net "SIO_JTAG_CPLD1_TMS_R")
	)
	(segment
		(start 121.0056 -51.5874)
		(end 120.777 -51.816)
		(width 0.1016)
		(layer "F.Cu")
		(net "SIO_JTAG_CPLD1_TMS_R")
	)
	(segment
		(start 137.0838 -77.3176)
		(end 137.0838 -80.137)
		(width 0.1016)
		(layer "F.Cu")
		(net "SIO_JTAG_CPLD1_TMS_R")
	)
	(segment
		(start 190.5 -88.168988)
		(end 190.5 -94.366588)
		(width 0.1016)
		(layer "F.Cu")
		(net "SIO_JTAG_CPLD1_TMS_R")
	)
	(segment
		(start 123.5202 -63.2968)
		(end 123.5202 -66.929)
		(width 0.1016)
		(layer "F.Cu")
		(net "SIO_JTAG_CPLD1_TMS_R")
	)
	(segment
		(start 133.477 -71.9582)
		(end 133.477 -73.7108)
		(width 0.1016)
		(layer "F.Cu")
		(net "SIO_JTAG_CPLD1_TMS_R")
	)
	(segment
		(start 150.213568 -82.831686)
		(end 152.654 -80.391254)
		(width 0.1016)
		(layer "F.Cu")
		(net "SIO_JTAG_CPLD1_TMS_R")
	)
	(segment
		(start 129.9718 -68.453)
		(end 133.477 -71.9582)
		(width 0.1016)
		(layer "F.Cu")
		(net "SIO_JTAG_CPLD1_TMS_R")
	)
	(segment
		(start 123.5202 -66.929)
		(end 125.0442 -68.453)
		(width 0.1016)
		(layer "F.Cu")
		(net "SIO_JTAG_CPLD1_TMS_R")
	)
	(segment
		(start 139.778486 -82.831686)
		(end 150.213568 -82.831686)
		(width 0.1016)
		(layer "F.Cu")
		(net "SIO_JTAG_CPLD1_TMS_R")
	)
	(segment
		(start 170.758612 -68.4276)
		(end 190.5 -88.168988)
		(width 0.1016)
		(layer "F.Cu")
		(net "SIO_JTAG_CPLD1_TMS_R")
	)
	(segment
		(start 120.777 -60.5536)
		(end 123.5202 -63.2968)
		(width 0.1016)
		(layer "F.Cu")
		(net "SIO_JTAG_CPLD1_TMS_R")
	)
	(segment
		(start 125.0442 -68.453)
		(end 129.9718 -68.453)
		(width 0.1016)
		(layer "F.Cu")
		(net "SIO_JTAG_CPLD1_TMS_R")
	)
	(segment
		(start 119.462296 -33.889696)
		(end 122.451622 -33.889696)
		(width 0.1016)
		(layer "F.Cu")
		(net "SIO_JTAG_CPLD1_TMS_R")
	)
	(segment
		(start 152.654 -80.391254)
		(end 152.654 -74.5744)
		(width 0.1016)
		(layer "F.Cu")
		(net "SIO_JTAG_CPLD1_TMS_R")
	)
	(segment
		(start 120.777 -51.816)
		(end 120.777 -60.5536)
		(width 0.1016)
		(layer "F.Cu")
		(net "SIO_JTAG_CPLD1_TMS_R")
	)
	(segment
		(start 196.3166 -100.183188)
		(end 196.3166 -124.4346)
		(width 0.1016)
		(layer "F.Cu")
		(net "SIO_JTAG_CPLD1_TMS_R")
	)
	(segment
		(start 133.477 -73.7108)
		(end 137.0838 -77.3176)
		(width 0.1016)
		(layer "F.Cu")
		(net "SIO_JTAG_CPLD1_TMS_R")
	)
	(segment
		(start 196.3166 -124.4346)
		(end 193.4972 -127.254)
		(width 0.1016)
		(layer "F.Cu")
		(net "SIO_JTAG_CPLD1_TMS_R")
	)
	(segment
		(start 158.8008 -68.4276)
		(end 170.758612 -68.4276)
		(width 0.1016)
		(layer "F.Cu")
		(net "SIO_JTAG_CPLD1_TMS_R")
	)
	(segment
		(start 137.0838 -80.137)
		(end 139.778486 -82.831686)
		(width 0.1016)
		(layer "F.Cu")
		(net "SIO_JTAG_CPLD1_TMS_R")
	)
	(segment
		(start 152.654 -74.5744)
		(end 158.8008 -68.4276)
		(width 0.1016)
		(layer "F.Cu")
		(net "SIO_JTAG_CPLD1_TMS_R")
	)
	(segment
		(start 193.4972 -127.254)
		(end 189.24905 -127.254)
		(width 0.1016)
		(layer "F.Cu")
		(net "SIO_JTAG_CPLD1_TMS_R")
	)
	(via
		(at 119.462296 -33.889696)
		(size 0.508)
		(drill 0.254)
		(layers "F.Cu" "B.Cu")
		(net "SIO_JTAG_CPLD1_TMS_R")
	)
	(via
		(at 121.0056 -51.5874)
		(size 0.508)
		(drill 0.254)
		(layers "F.Cu" "B.Cu")
		(net "SIO_JTAG_CPLD1_TMS_R")
	)
	(segment
		(start 119.761 -37.084)
		(end 120.6754 -36.1696)
		(width 0.1016)
		(layer "B.Cu")
		(net "SIO_JTAG_CPLD1_TMS_R")
	)
	(segment
		(start 121.412 -51.9938)
		(end 121.0056 -51.5874)
		(width 0.1016)
		(layer "B.Cu")
		(net "SIO_JTAG_CPLD1_TMS_R")
	)
	(segment
		(start 120.9294 -39.751)
		(end 119.761 -38.5826)
		(width 0.1016)
		(layer "B.Cu")
		(net "SIO_JTAG_CPLD1_TMS_R")
	)
	(segment
		(start 120.9294 -40.132)
		(end 120.9294 -39.751)
		(width 0.1016)
		(layer "B.Cu")
		(net "SIO_JTAG_CPLD1_TMS_R")
	)
	(segment
		(start 119.6086 -41.9608)
		(end 119.9134 -41.656)
		(width 0.1016)
		(layer "B.Cu")
		(net "SIO_JTAG_CPLD1_TMS_R")
	)
	(segment
		(start 119.9134 -41.656)
		(end 119.9134 -41.148)
		(width 0.1016)
		(layer "B.Cu")
		(net "SIO_JTAG_CPLD1_TMS_R")
	)
	(segment
		(start 120.6754 -35.1028)
		(end 119.462296 -33.889696)
		(width 0.1016)
		(layer "B.Cu")
		(net "SIO_JTAG_CPLD1_TMS_R")
	)
	(segment
		(start 121.0056 -49.6824)
		(end 119.6086 -48.2854)
		(width 0.1016)
		(layer "B.Cu")
		(net "SIO_JTAG_CPLD1_TMS_R")
	)
	(segment
		(start 121.0056 -51.5874)
		(end 121.0056 -49.6824)
		(width 0.1016)
		(layer "B.Cu")
		(net "SIO_JTAG_CPLD1_TMS_R")
	)
	(segment
		(start 121.412 -52.55895)
		(end 121.412 -51.9938)
		(width 0.1016)
		(layer "B.Cu")
		(net "SIO_JTAG_CPLD1_TMS_R")
	)
	(segment
		(start 119.6086 -48.2854)
		(end 119.6086 -41.9608)
		(width 0.1016)
		(layer "B.Cu")
		(net "SIO_JTAG_CPLD1_TMS_R")
	)
	(segment
		(start 119.761 -38.5826)
		(end 119.761 -37.084)
		(width 0.1016)
		(layer "B.Cu")
		(net "SIO_JTAG_CPLD1_TMS_R")
	)
	(segment
		(start 119.9134 -41.148)
		(end 120.9294 -40.132)
		(width 0.1016)
		(layer "B.Cu")
		(net "SIO_JTAG_CPLD1_TMS_R")
	)
	(segment
		(start 120.6754 -36.1696)
		(end 120.6754 -35.1028)
		(width 0.1016)
		(layer "B.Cu")
		(net "SIO_JTAG_CPLD1_TMS_R")
	)
	(segment
		(start 189.484 -120.65)
		(end 190.98895 -120.65)
		(width 0.1016)
		(layer "F.Cu")
		(net "SIO_JTAG_CPLD1_TDI")
	)
	(segment
		(start 190.98895 -121.666)
		(end 190.98895 -120.65)
		(width 0.1016)
		(layer "F.Cu")
		(net "SIO_JTAG_CPLD1_TDI")
	)
	(segment
		(start 187.97905 -120.65)
		(end 189.484 -120.65)
		(width 0.1016)
		(layer "F.Cu")
		(net "SIO_JTAG_CPLD1_TDI")
	)
	(via
		(at 189.484 -120.65)
		(size 0.762)
		(drill 0.381)
		(layers "F.Cu" "B.Cu")
		(net "SIO_JTAG_CPLD1_TDI")
	)
	(segment
		(start 190.22695 -125.095)
		(end 190.22695 -124.079)
		(width 0.1016)
		(layer "F.Cu")
		(net "SIO_JTAG_CPLD1_TCK")
	)
	(segment
		(start 189.357 -125.095)
		(end 188.61405 -125.095)
		(width 0.1016)
		(layer "F.Cu")
		(net "SIO_JTAG_CPLD1_TCK")
	)
	(segment
		(start 190.22695 -125.095)
		(end 189.357 -125.095)
		(width 0.1016)
		(layer "F.Cu")
		(net "SIO_JTAG_CPLD1_TCK")
	)
	(via
		(at 189.357 -125.095)
		(size 0.508)
		(drill 0.254)
		(layers "F.Cu" "B.Cu")
		(net "SIO_JTAG_CPLD1_TCK")
	)
	(segment
		(start 136.271 -77.6986)
		(end 136.271 -80.722216)
		(width 0.1016)
		(layer "F.Cu")
		(net "SIO_JTAG_CPLD1_TDI_R")
	)
	(segment
		(start 139.368784 -83.82)
		(end 150.9014 -83.82)
		(width 0.1016)
		(layer "F.Cu")
		(net "SIO_JTAG_CPLD1_TDI_R")
	)
	(segment
		(start 193.6496 -99.7077)
		(end 193.6496 -120.8024)
		(width 0.1016)
		(layer "F.Cu")
		(net "SIO_JTAG_CPLD1_TDI_R")
	)
	(segment
		(start 169.7355 -69.596)
		(end 188.9506 -88.8111)
		(width 0.1016)
		(layer "F.Cu")
		(net "SIO_JTAG_CPLD1_TDI_R")
	)
	(segment
		(start 129.54 -69.2658)
		(end 132.6388 -72.3646)
		(width 0.1016)
		(layer "F.Cu")
		(net "SIO_JTAG_CPLD1_TDI_R")
	)
	(segment
		(start 118.4148 -52.6542)
		(end 119.7356 -53.975)
		(width 0.1016)
		(layer "F.Cu")
		(net "SIO_JTAG_CPLD1_TDI_R")
	)
	(segment
		(start 136.271 -80.722216)
		(end 139.368784 -83.82)
		(width 0.1016)
		(layer "F.Cu")
		(net "SIO_JTAG_CPLD1_TDI_R")
	)
	(segment
		(start 159.285178 -69.596)
		(end 169.7355 -69.596)
		(width 0.1016)
		(layer "F.Cu")
		(net "SIO_JTAG_CPLD1_TDI_R")
	)
	(segment
		(start 119.7356 -53.975)
		(end 119.7356 -61.3918)
		(width 0.1016)
		(layer "F.Cu")
		(net "SIO_JTAG_CPLD1_TDI_R")
	)
	(segment
		(start 132.6388 -72.3646)
		(end 132.6388 -74.0664)
		(width 0.1016)
		(layer "F.Cu")
		(net "SIO_JTAG_CPLD1_TDI_R")
	)
	(segment
		(start 120.868694 -34.889694)
		(end 122.451622 -34.889694)
		(width 0.1016)
		(layer "F.Cu")
		(net "SIO_JTAG_CPLD1_TDI_R")
	)
	(segment
		(start 188.9506 -88.8111)
		(end 188.9506 -95.0087)
		(width 0.1016)
		(layer "F.Cu")
		(net "SIO_JTAG_CPLD1_TDI_R")
	)
	(segment
		(start 118.9736 -34.4932)
		(end 120.4722 -34.4932)
		(width 0.1016)
		(layer "F.Cu")
		(net "SIO_JTAG_CPLD1_TDI_R")
	)
	(segment
		(start 153.8224 -75.058778)
		(end 159.285178 -69.596)
		(width 0.1016)
		(layer "F.Cu")
		(net "SIO_JTAG_CPLD1_TDI_R")
	)
	(segment
		(start 122.682 -64.3382)
		(end 122.682 -67.0814)
		(width 0.1016)
		(layer "F.Cu")
		(net "SIO_JTAG_CPLD1_TDI_R")
	)
	(segment
		(start 193.6496 -120.8024)
		(end 192.786 -121.666)
		(width 0.1016)
		(layer "F.Cu")
		(net "SIO_JTAG_CPLD1_TDI_R")
	)
	(segment
		(start 120.4722 -34.4932)
		(end 120.868694 -34.889694)
		(width 0.1016)
		(layer "F.Cu")
		(net "SIO_JTAG_CPLD1_TDI_R")
	)
	(segment
		(start 150.9014 -83.82)
		(end 153.8224 -80.899)
		(width 0.1016)
		(layer "F.Cu")
		(net "SIO_JTAG_CPLD1_TDI_R")
	)
	(segment
		(start 153.8224 -80.899)
		(end 153.8224 -75.058778)
		(width 0.1016)
		(layer "F.Cu")
		(net "SIO_JTAG_CPLD1_TDI_R")
	)
	(segment
		(start 132.6388 -74.0664)
		(end 136.271 -77.6986)
		(width 0.1016)
		(layer "F.Cu")
		(net "SIO_JTAG_CPLD1_TDI_R")
	)
	(segment
		(start 119.7356 -61.3918)
		(end 122.682 -64.3382)
		(width 0.1016)
		(layer "F.Cu")
		(net "SIO_JTAG_CPLD1_TDI_R")
	)
	(segment
		(start 122.682 -67.0814)
		(end 124.8664 -69.2658)
		(width 0.1016)
		(layer "F.Cu")
		(net "SIO_JTAG_CPLD1_TDI_R")
	)
	(segment
		(start 192.786 -121.666)
		(end 191.78905 -121.666)
		(width 0.1016)
		(layer "F.Cu")
		(net "SIO_JTAG_CPLD1_TDI_R")
	)
	(segment
		(start 124.8664 -69.2658)
		(end 129.54 -69.2658)
		(width 0.1016)
		(layer "F.Cu")
		(net "SIO_JTAG_CPLD1_TDI_R")
	)
	(segment
		(start 188.9506 -95.0087)
		(end 193.6496 -99.7077)
		(width 0.1016)
		(layer "F.Cu")
		(net "SIO_JTAG_CPLD1_TDI_R")
	)
	(via
		(at 118.4148 -52.6542)
		(size 0.508)
		(drill 0.254)
		(layers "F.Cu" "B.Cu")
		(net "SIO_JTAG_CPLD1_TDI_R")
	)
	(via
		(at 118.9736 -34.4932)
		(size 0.508)
		(drill 0.254)
		(layers "F.Cu" "B.Cu")
		(net "SIO_JTAG_CPLD1_TDI_R")
	)
	(segment
		(start 118.491 -50.43805)
		(end 116.586 -52.34305)
		(width 0.1016)
		(layer "B.Cu")
		(net "SIO_JTAG_CPLD1_TDI_R")
	)
	(segment
		(start 118.491 -34.9758)
		(end 118.491 -39.3446)
		(width 0.1016)
		(layer "B.Cu")
		(net "SIO_JTAG_CPLD1_TDI_R")
	)
	(segment
		(start 119.253 -40.1066)
		(end 119.253 -41.0464)
		(width 0.1016)
		(layer "B.Cu")
		(net "SIO_JTAG_CPLD1_TDI_R")
	)
	(segment
		(start 118.9736 -34.4932)
		(end 118.491 -34.9758)
		(width 0.1016)
		(layer "B.Cu")
		(net "SIO_JTAG_CPLD1_TDI_R")
	)
	(segment
		(start 118.491 -41.8084)
		(end 118.491 -50.43805)
		(width 0.1016)
		(layer "B.Cu")
		(net "SIO_JTAG_CPLD1_TDI_R")
	)
	(segment
		(start 118.10365 -52.34305)
		(end 118.4148 -52.6542)
		(width 0.1016)
		(layer "B.Cu")
		(net "SIO_JTAG_CPLD1_TDI_R")
	)
	(segment
		(start 119.253 -41.0464)
		(end 118.491 -41.8084)
		(width 0.1016)
		(layer "B.Cu")
		(net "SIO_JTAG_CPLD1_TDI_R")
	)
	(segment
		(start 116.586 -52.34305)
		(end 118.10365 -52.34305)
		(width 0.1016)
		(layer "B.Cu")
		(net "SIO_JTAG_CPLD1_TDI_R")
	)
	(segment
		(start 118.491 -39.3446)
		(end 119.253 -40.1066)
		(width 0.1016)
		(layer "B.Cu")
		(net "SIO_JTAG_CPLD1_TDI_R")
	)
	(segment
		(start 170.670728 -68.9864)
		(end 190.0428 -88.358472)
		(width 0.1016)
		(layer "F.Cu")
		(net "SIO_JTAG_CPLD1_TCK_R")
	)
	(segment
		(start 195.8594 -122.9868)
		(end 194.7672 -124.079)
		(width 0.1016)
		(layer "F.Cu")
		(net "SIO_JTAG_CPLD1_TCK_R")
	)
	(segment
		(start 194.7672 -124.079)
		(end 191.02705 -124.079)
		(width 0.1016)
		(layer "F.Cu")
		(net "SIO_JTAG_CPLD1_TCK_R")
	)
	(segment
		(start 150.5966 -83.3374)
		(end 153.2128 -80.7212)
		(width 0.1016)
		(layer "F.Cu")
		(net "SIO_JTAG_CPLD1_TCK_R")
	)
	(segment
		(start 125.041914 -68.933314)
		(end 129.820924 -68.933314)
		(width 0.1016)
		(layer "F.Cu")
		(net "SIO_JTAG_CPLD1_TCK_R")
	)
	(segment
		(start 132.407914 -71.498714)
		(end 132.971286 -72.062086)
		(width 0.1016)
		(layer "F.Cu")
		(net "SIO_JTAG_CPLD1_TCK_R")
	)
	(segment
		(start 139.568936 -83.3374)
		(end 150.5966 -83.3374)
		(width 0.1016)
		(layer "F.Cu")
		(net "SIO_JTAG_CPLD1_TCK_R")
	)
	(segment
		(start 120.2182 -51.7906)
		(end 120.2182 -61.1124)
		(width 0.1016)
		(layer "F.Cu")
		(net "SIO_JTAG_CPLD1_TCK_R")
	)
	(segment
		(start 195.8594 -100.372672)
		(end 195.8594 -122.9868)
		(width 0.1016)
		(layer "F.Cu")
		(net "SIO_JTAG_CPLD1_TCK_R")
	)
	(segment
		(start 153.2128 -80.7212)
		(end 153.2128 -74.806048)
		(width 0.1016)
		(layer "F.Cu")
		(net "SIO_JTAG_CPLD1_TCK_R")
	)
	(segment
		(start 153.2128 -74.806048)
		(end 159.032448 -68.9864)
		(width 0.1016)
		(layer "F.Cu")
		(net "SIO_JTAG_CPLD1_TCK_R")
	)
	(segment
		(start 136.6774 -80.445864)
		(end 139.568936 -83.3374)
		(width 0.1016)
		(layer "F.Cu")
		(net "SIO_JTAG_CPLD1_TCK_R")
	)
	(segment
		(start 132.971286 -73.81875)
		(end 136.6774 -77.524864)
		(width 0.1016)
		(layer "F.Cu")
		(net "SIO_JTAG_CPLD1_TCK_R")
	)
	(segment
		(start 159.032448 -68.9864)
		(end 170.670728 -68.9864)
		(width 0.1016)
		(layer "F.Cu")
		(net "SIO_JTAG_CPLD1_TCK_R")
	)
	(segment
		(start 122.451622 -35.38982)
		(end 120.43918 -35.38982)
		(width 0.1016)
		(layer "F.Cu")
		(net "SIO_JTAG_CPLD1_TCK_R")
	)
	(segment
		(start 119.7102 -51.2826)
		(end 120.2182 -51.7906)
		(width 0.1016)
		(layer "F.Cu")
		(net "SIO_JTAG_CPLD1_TCK_R")
	)
	(segment
		(start 120.43918 -35.38982)
		(end 120.1928 -35.6362)
		(width 0.1016)
		(layer "F.Cu")
		(net "SIO_JTAG_CPLD1_TCK_R")
	)
	(segment
		(start 190.0428 -94.556072)
		(end 195.8594 -100.372672)
		(width 0.1016)
		(layer "F.Cu")
		(net "SIO_JTAG_CPLD1_TCK_R")
	)
	(segment
		(start 129.820924 -68.933314)
		(end 132.386324 -71.498714)
		(width 0.1016)
		(layer "F.Cu")
		(net "SIO_JTAG_CPLD1_TCK_R")
	)
	(segment
		(start 123.1138 -67.0052)
		(end 125.041914 -68.933314)
		(width 0.1016)
		(layer "F.Cu")
		(net "SIO_JTAG_CPLD1_TCK_R")
	)
	(segment
		(start 136.6774 -77.524864)
		(end 136.6774 -80.445864)
		(width 0.1016)
		(layer "F.Cu")
		(net "SIO_JTAG_CPLD1_TCK_R")
	)
	(segment
		(start 132.386324 -71.498714)
		(end 132.407914 -71.498714)
		(width 0.1016)
		(layer "F.Cu")
		(net "SIO_JTAG_CPLD1_TCK_R")
	)
	(segment
		(start 120.2182 -61.1124)
		(end 123.1138 -64.008)
		(width 0.1016)
		(layer "F.Cu")
		(net "SIO_JTAG_CPLD1_TCK_R")
	)
	(segment
		(start 123.1138 -64.008)
		(end 123.1138 -67.0052)
		(width 0.1016)
		(layer "F.Cu")
		(net "SIO_JTAG_CPLD1_TCK_R")
	)
	(segment
		(start 190.0428 -88.358472)
		(end 190.0428 -94.556072)
		(width 0.1016)
		(layer "F.Cu")
		(net "SIO_JTAG_CPLD1_TCK_R")
	)
	(segment
		(start 132.971286 -72.062086)
		(end 132.971286 -73.81875)
		(width 0.1016)
		(layer "F.Cu")
		(net "SIO_JTAG_CPLD1_TCK_R")
	)
	(via
		(at 120.1928 -35.6362)
		(size 0.508)
		(drill 0.254)
		(layers "F.Cu" "B.Cu")
		(net "SIO_JTAG_CPLD1_TCK_R")
	)
	(via
		(at 119.7102 -51.2826)
		(size 0.508)
		(drill 0.254)
		(layers "F.Cu" "B.Cu")
		(net "SIO_JTAG_CPLD1_TCK_R")
	)
	(segment
		(start 119.1006 -41.91)
		(end 119.5832 -41.4274)
		(width 0.1016)
		(layer "B.Cu")
		(net "SIO_JTAG_CPLD1_TCK_R")
	)
	(segment
		(start 119.1006 -48.5648)
		(end 119.1006 -41.91)
		(width 0.1016)
		(layer "B.Cu")
		(net "SIO_JTAG_CPLD1_TCK_R")
	)
	(segment
		(start 119.5832 -39.7002)
		(end 119.126 -39.243)
		(width 0.1016)
		(layer "B.Cu")
		(net "SIO_JTAG_CPLD1_TCK_R")
	)
	(segment
		(start 119.126 -39.243)
		(end 119.126 -36.34105)
		(width 0.1016)
		(layer "B.Cu")
		(net "SIO_JTAG_CPLD1_TCK_R")
	)
	(segment
		(start 119.126 -36.34105)
		(end 119.48795 -36.34105)
		(width 0.1016)
		(layer "B.Cu")
		(net "SIO_JTAG_CPLD1_TCK_R")
	)
	(segment
		(start 119.7102 -49.1744)
		(end 119.1006 -48.5648)
		(width 0.1016)
		(layer "B.Cu")
		(net "SIO_JTAG_CPLD1_TCK_R")
	)
	(segment
		(start 119.7102 -51.2826)
		(end 119.7102 -49.1744)
		(width 0.1016)
		(layer "B.Cu")
		(net "SIO_JTAG_CPLD1_TCK_R")
	)
	(segment
		(start 119.5832 -41.4274)
		(end 119.5832 -39.7002)
		(width 0.1016)
		(layer "B.Cu")
		(net "SIO_JTAG_CPLD1_TCK_R")
	)
	(segment
		(start 119.48795 -36.34105)
		(end 120.1928 -35.6362)
		(width 0.1016)
		(layer "B.Cu")
		(net "SIO_JTAG_CPLD1_TCK_R")
	)
	(segment
		(start 186.58205 -125.984)
		(end 186.58205 -125.11405)
		(width 0.1016)
		(layer "F.Cu")
		(net "SIO_JTAG_CPLD1_TMS")
	)
	(segment
		(start 187.2234 -125.984)
		(end 186.58205 -125.984)
		(width 0.1016)
		(layer "F.Cu")
		(net "SIO_JTAG_CPLD1_TMS")
	)
	(segment
		(start 187.4266 -126.1872)
		(end 187.2234 -125.984)
		(width 0.1016)
		(layer "F.Cu")
		(net "SIO_JTAG_CPLD1_TMS")
	)
	(segment
		(start 188.44895 -126.1872)
		(end 187.4266 -126.1872)
		(width 0.1016)
		(layer "F.Cu")
		(net "SIO_JTAG_CPLD1_TMS")
	)
	(segment
		(start 188.44895 -127.254)
		(end 188.44895 -126.1872)
		(width 0.1016)
		(layer "F.Cu")
		(net "SIO_JTAG_CPLD1_TMS")
	)
	(via
		(at 186.58205 -125.11405)
		(size 0.508)
		(drill 0.254)
		(layers "F.Cu" "B.Cu")
		(net "SIO_JTAG_CPLD1_TMS")
	)
	(segment
		(start 133.261608 -48.14697)
		(end 133.261608 -47.199804)
		(width 0.1016)
		(layer "F.Cu")
		(net "UART_RI_P4_R_N")
	)
	(segment
		(start 133.223 -51.03495)
		(end 133.223 -50.565812)
		(width 0.1016)
		(layer "F.Cu")
		(net "UART_RI_P4_R_N")
	)
	(segment
		(start 133.223 -50.565812)
		(end 132.992622 -50.335434)
		(width 0.1016)
		(layer "F.Cu")
		(net "UART_RI_P4_R_N")
	)
	(segment
		(start 133.223 -51.03495)
		(end 132.6642 -51.59375)
		(width 0.1016)
		(layer "F.Cu")
		(net "UART_RI_P4_R_N")
	)
	(segment
		(start 132.992622 -50.335434)
		(end 132.992622 -48.415956)
		(width 0.1016)
		(layer "F.Cu")
		(net "UART_RI_P4_R_N")
	)
	(segment
		(start 132.6642 -51.59375)
		(end 132.6642 -52.8828)
		(width 0.1016)
		(layer "F.Cu")
		(net "UART_RI_P4_R_N")
	)
	(segment
		(start 132.6642 -52.8828)
		(end 132.5372 -53.0098)
		(width 0.1016)
		(layer "F.Cu")
		(net "UART_RI_P4_R_N")
	)
	(segment
		(start 132.992622 -48.415956)
		(end 133.261608 -48.14697)
		(width 0.1016)
		(layer "F.Cu")
		(net "UART_RI_P4_R_N")
	)
	(segment
		(start 132.5372 -53.0098)
		(end 132.5372 -53.72735)
		(width 0.1016)
		(layer "F.Cu")
		(net "UART_RI_P4_R_N")
	)
	(via
		(at 132.992622 -50.335434)
		(size 0.508)
		(drill 0.254)
		(layers "F.Cu" "B.Cu")
		(net "UART_RI_P4_R_N")
	)
	(segment
		(start 132.969 -48.3616)
		(end 132.4356 -47.8282)
		(width 0.1016)
		(layer "B.Cu")
		(net "UART_RI_P4_R_N")
	)
	(segment
		(start 132.992622 -50.335434)
		(end 132.969 -50.311812)
		(width 0.1016)
		(layer "B.Cu")
		(net "UART_RI_P4_R_N")
	)
	(segment
		(start 132.969 -50.311812)
		(end 132.969 -48.3616)
		(width 0.1016)
		(layer "B.Cu")
		(net "UART_RI_P4_R_N")
	)
	(segment
		(start 132.992622 -50.335434)
		(end 133.2992 -50.642012)
		(width 0.1016)
		(layer "B.Cu")
		(net "UART_RI_P4_R_N")
	)
	(segment
		(start 134.431786 -56.250586)
		(end 134.922006 -56.250586)
		(width 0.1016)
		(layer "B.Cu")
		(net "UART_RI_P4_R_N")
	)
	(segment
		(start 134.1374 -55.9562)
		(end 134.431786 -56.250586)
		(width 0.1016)
		(layer "B.Cu")
		(net "UART_RI_P4_R_N")
	)
	(segment
		(start 133.2992 -52.9082)
		(end 134.1374 -53.7464)
		(width 0.1016)
		(layer "B.Cu")
		(net "UART_RI_P4_R_N")
	)
	(segment
		(start 134.1374 -53.7464)
		(end 134.1374 -55.9562)
		(width 0.1016)
		(layer "B.Cu")
		(net "UART_RI_P4_R_N")
	)
	(segment
		(start 133.2992 -50.642012)
		(end 133.2992 -52.9082)
		(width 0.1016)
		(layer "B.Cu")
		(net "UART_RI_P4_R_N")
	)
	(segment
		(start 132.4356 -47.8282)
		(end 132.4356 -47.36465)
		(width 0.1016)
		(layer "B.Cu")
		(net "UART_RI_P4_R_N")
	)
	(segment
		(start 75.776836 -84.71281)
		(end 77.182218 -86.118192)
		(width 0.1016)
		(layer "F.Cu")
		(net "TP_CPU_NODE1_K62")
	)
	(segment
		(start 77.182218 -86.118192)
		(end 77.182218 -87.588598)
		(width 0.1016)
		(layer "F.Cu")
		(net "TP_CPU_NODE1_K62")
	)
	(segment
		(start 75.003406 -84.30514)
		(end 75.411076 -84.71281)
		(width 0.1016)
		(layer "F.Cu")
		(net "TP_CPU_NODE1_K62")
	)
	(segment
		(start 72.658478 -84.57057)
		(end 72.993758 -84.57057)
		(width 0.1016)
		(layer "F.Cu")
		(net "TP_CPU_NODE1_K62")
	)
	(segment
		(start 72.993758 -84.57057)
		(end 73.011538 -84.55279)
		(width 0.1016)
		(layer "F.Cu")
		(net "TP_CPU_NODE1_K62")
	)
	(segment
		(start 72.143112 -84.477352)
		(end 72.56526 -84.477352)
		(width 0.1016)
		(layer "F.Cu")
		(net "TP_CPU_NODE1_K62")
	)
	(segment
		(start 72.063864 -84.398104)
		(end 72.143112 -84.477352)
		(width 0.1016)
		(layer "F.Cu")
		(net "TP_CPU_NODE1_K62")
	)
	(segment
		(start 74.09053 -84.30514)
		(end 75.003406 -84.30514)
		(width 0.1016)
		(layer "F.Cu")
		(net "TP_CPU_NODE1_K62")
	)
	(segment
		(start 73.011538 -84.55279)
		(end 73.84288 -84.55279)
		(width 0.1016)
		(layer "F.Cu")
		(net "TP_CPU_NODE1_K62")
	)
	(segment
		(start 75.411076 -84.71281)
		(end 75.776836 -84.71281)
		(width 0.1016)
		(layer "F.Cu")
		(net "TP_CPU_NODE1_K62")
	)
	(segment
		(start 77.182218 -87.588598)
		(end 78.08214 -88.48852)
		(width 0.1016)
		(layer "F.Cu")
		(net "TP_CPU_NODE1_K62")
	)
	(segment
		(start 72.56526 -84.477352)
		(end 72.658478 -84.57057)
		(width 0.1016)
		(layer "F.Cu")
		(net "TP_CPU_NODE1_K62")
	)
	(segment
		(start 73.84288 -84.55279)
		(end 74.09053 -84.30514)
		(width 0.1016)
		(layer "F.Cu")
		(net "TP_CPU_NODE1_K62")
	)
	(via
		(at 78.08214 -88.48852)
		(size 0.508)
		(drill 0.254)
		(layers "F.Cu" "B.Cu")
		(net "TP_CPU_NODE1_K62")
	)
	(segment
		(start 88.77046 -14.655292)
		(end 89.004394 -14.421358)
		(width 0.1016)
		(layer "F.Cu")
		(net "N20512383")
	)
	(segment
		(start 88.77046 -15.404338)
		(end 88.77046 -14.655292)
		(width 0.1016)
		(layer "F.Cu")
		(net "N20512383")
	)
	(segment
		(start 89.004394 -14.421358)
		(end 89.004394 -11.91768)
		(width 0.1016)
		(layer "F.Cu")
		(net "N20512383")
	)
	(via
		(at 88.77046 -14.655292)
		(size 0.508)
		(drill 0.254)
		(layers "F.Cu" "B.Cu")
		(net "N20512383")
	)
	(segment
		(start 101.00437 -14.899894)
		(end 101.00437 -11.91768)
		(width 0.1016)
		(layer "F.Cu")
		(net "N20512395")
	)
	(segment
		(start 100.35032 -15.58544)
		(end 101.03866 -15.58544)
		(width 0.1016)
		(layer "F.Cu")
		(net "N20512395")
	)
	(segment
		(start 101.03866 -14.934184)
		(end 101.00437 -14.899894)
		(width 0.1016)
		(layer "F.Cu")
		(net "N20512395")
	)
	(segment
		(start 101.03866 -15.58544)
		(end 101.03866 -14.934184)
		(width 0.1016)
		(layer "F.Cu")
		(net "N20512395")
	)
	(via
		(at 101.03866 -15.58544)
		(size 0.508)
		(drill 0.254)
		(layers "F.Cu" "B.Cu")
		(net "N20512395")
	)
	(segment
		(start 93.004386 -13.824458)
		(end 93.2942 -14.114272)
		(width 0.1016)
		(layer "F.Cu")
		(net "LPC_CPU_TPM_LAD2")
	)
	(segment
		(start 93.993462 -15.449042)
		(end 93.390974 -15.449042)
		(width 0.1016)
		(layer "F.Cu")
		(net "LPC_CPU_TPM_LAD2")
	)
	(segment
		(start 93.390974 -15.449042)
		(end 93.2942 -15.352268)
		(width 0.1016)
		(layer "F.Cu")
		(net "LPC_CPU_TPM_LAD2")
	)
	(segment
		(start 93.004386 -11.91768)
		(end 93.004386 -13.824458)
		(width 0.1016)
		(layer "F.Cu")
		(net "LPC_CPU_TPM_LAD2")
	)
	(segment
		(start 93.2942 -14.114272)
		(end 93.2942 -15.352268)
		(width 0.1016)
		(layer "F.Cu")
		(net "LPC_CPU_TPM_LAD2")
	)
	(via
		(at 93.2942 -15.352268)
		(size 0.508)
		(drill 0.254)
		(layers "F.Cu" "B.Cu")
		(net "LPC_CPU_TPM_LAD2")
	)
	(segment
		(start 95.004382 -13.750798)
		(end 95.004382 -11.91768)
		(width 0.1016)
		(layer "F.Cu")
		(net "LPC_CPU_TPM_LAD1")
	)
	(segment
		(start 95.505524 -15.491714)
		(end 95.505524 -14.25194)
		(width 0.1016)
		(layer "F.Cu")
		(net "LPC_CPU_TPM_LAD1")
	)
	(segment
		(start 95.505524 -14.25194)
		(end 95.004382 -13.750798)
		(width 0.1016)
		(layer "F.Cu")
		(net "LPC_CPU_TPM_LAD1")
	)
	(segment
		(start 96.278954 -15.491714)
		(end 95.505524 -15.491714)
		(width 0.1016)
		(layer "F.Cu")
		(net "LPC_CPU_TPM_LAD1")
	)
	(via
		(at 95.505524 -15.491714)
		(size 0.508)
		(drill 0.254)
		(layers "F.Cu" "B.Cu")
		(net "LPC_CPU_TPM_LAD1")
	)
	(segment
		(start 97.35312 -14.189456)
		(end 97.35312 -15.22476)
		(width 0.1016)
		(layer "F.Cu")
		(net "LPC_CPU_TPM_LAD0")
	)
	(segment
		(start 97.35312 -15.22476)
		(end 97.669604 -15.541244)
		(width 0.1016)
		(layer "F.Cu")
		(net "LPC_CPU_TPM_LAD0")
	)
	(segment
		(start 97.004378 -13.840714)
		(end 97.35312 -14.189456)
		(width 0.1016)
		(layer "F.Cu")
		(net "LPC_CPU_TPM_LAD0")
	)
	(segment
		(start 97.669604 -15.541244)
		(end 98.297746 -15.541244)
		(width 0.1016)
		(layer "F.Cu")
		(net "LPC_CPU_TPM_LAD0")
	)
	(segment
		(start 97.004378 -11.91768)
		(end 97.004378 -13.840714)
		(width 0.1016)
		(layer "F.Cu")
		(net "LPC_CPU_TPM_LAD0")
	)
	(via
		(at 97.35312 -15.22476)
		(size 0.508)
		(drill 0.254)
		(layers "F.Cu" "B.Cu")
		(net "LPC_CPU_TPM_LAD0")
	)
	(segment
		(start 91.00439 -13.528548)
		(end 91.93022 -14.454378)
		(width 0.1016)
		(layer "F.Cu")
		(net "LPC_CPU_TPM_LAD3")
	)
	(segment
		(start 91.93022 -14.454378)
		(end 91.93022 -15.247874)
		(width 0.1016)
		(layer "F.Cu")
		(net "LPC_CPU_TPM_LAD3")
	)
	(segment
		(start 91.00439 -11.91768)
		(end 91.00439 -13.528548)
		(width 0.1016)
		(layer "F.Cu")
		(net "LPC_CPU_TPM_LAD3")
	)
	(segment
		(start 91.93022 -15.247874)
		(end 91.773756 -15.404338)
		(width 0.1016)
		(layer "F.Cu")
		(net "LPC_CPU_TPM_LAD3")
	)
	(segment
		(start 91.773756 -15.404338)
		(end 91.17076 -15.404338)
		(width 0.1016)
		(layer "F.Cu")
		(net "LPC_CPU_TPM_LAD3")
	)
	(via
		(at 91.93022 -15.247874)
		(size 0.508)
		(drill 0.254)
		(layers "F.Cu" "B.Cu")
		(net "LPC_CPU_TPM_LAD3")
	)
	(segment
		(start 5.19049 -142.550642)
		(end 5.19049 -143.493744)
		(width 0.1016)
		(layer "F.Cu")
		(net "UART_RI_P6_LS_N")
	)
	(segment
		(start 4.7371 -141.43355)
		(end 5.19049 -141.88694)
		(width 0.1016)
		(layer "F.Cu")
		(net "UART_RI_P6_LS_N")
	)
	(segment
		(start 5.69087 -140.043408)
		(end 5.6896 -140.043408)
		(width 0.1016)
		(layer "F.Cu")
		(net "UART_RI_P6_LS_N")
	)
	(segment
		(start 4.7371 -140.995908)
		(end 4.7371 -141.43355)
		(width 0.1016)
		(layer "F.Cu")
		(net "UART_RI_P6_LS_N")
	)
	(segment
		(start 5.6896 -140.043408)
		(end 4.7371 -140.995908)
		(width 0.1016)
		(layer "F.Cu")
		(net "UART_RI_P6_LS_N")
	)
	(segment
		(start 6.64083 -139.032234)
		(end 6.64083 -139.093448)
		(width 0.1016)
		(layer "F.Cu")
		(net "UART_RI_P6_LS_N")
	)
	(segment
		(start 6.64083 -139.093448)
		(end 5.69087 -140.043408)
		(width 0.1016)
		(layer "F.Cu")
		(net "UART_RI_P6_LS_N")
	)
	(segment
		(start 5.19049 -141.88694)
		(end 5.19049 -142.550642)
		(width 0.1016)
		(layer "F.Cu")
		(net "UART_RI_P6_LS_N")
	)
	(segment
		(start 5.19049 -143.493744)
		(end 5.99694 -144.300194)
		(width 0.1016)
		(layer "F.Cu")
		(net "UART_RI_P6_LS_N")
	)
	(via
		(at 124.47016 -158.02356)
		(size 0.508)
		(drill 0.254)
		(layers "F.Cu" "B.Cu")
		(net "UART_RI_P6_LS_N")
	)
	(via
		(at 5.99694 -144.300194)
		(size 0.508)
		(drill 0.254)
		(layers "F.Cu" "B.Cu")
		(net "UART_RI_P6_LS_N")
	)
	(via
		(at 45.19168 -187.782708)
		(size 0.508)
		(drill 0.254)
		(layers "F.Cu" "B.Cu")
		(net "UART_RI_P6_LS_N")
	)
	(via
		(at 24.73706 -194.67449)
		(size 0.508)
		(drill 0.254)
		(layers "F.Cu" "B.Cu")
		(net "UART_RI_P6_LS_N")
	)
	(segment
		(start 126.280926 -163.450016)
		(end 126.68504 -163.045902)
		(width 0.1016)
		(layer "B.Cu")
		(net "UART_RI_P6_LS_N")
	)
	(segment
		(start 126.68504 -163.045902)
		(end 127.589534 -163.045902)
		(width 0.1016)
		(layer "B.Cu")
		(net "UART_RI_P6_LS_N")
	)
	(segment
		(start 28.2194 -194.691)
		(end 28.2194 -194.69989)
		(width 0.1016)
		(layer "B.Cu")
		(net "UART_RI_P6_LS_N")
	)
	(segment
		(start 28.2194 -194.69989)
		(end 28.194 -194.67449)
		(width 0.1016)
		(layer "B.Cu")
		(net "UART_RI_P6_LS_N")
	)
	(segment
		(start 45.19168 -187.782708)
		(end 45.19168 -191.33312)
		(width 0.1016)
		(layer "B.Cu")
		(net "UART_RI_P6_LS_N")
	)
	(segment
		(start 45.19168 -191.33312)
		(end 41.8338 -194.691)
		(width 0.1016)
		(layer "B.Cu")
		(net "UART_RI_P6_LS_N")
	)
	(segment
		(start 124.47016 -159.254444)
		(end 123.83262 -159.891984)
		(width 0.1016)
		(layer "B.Cu")
		(net "UART_RI_P6_LS_N")
	)
	(segment
		(start 28.194 -194.67449)
		(end 24.73706 -194.67449)
		(width 0.1016)
		(layer "B.Cu")
		(net "UART_RI_P6_LS_N")
	)
	(segment
		(start 128.62306 -161.957766)
		(end 128.62306 -161.161984)
		(width 0.1016)
		(layer "B.Cu")
		(net "UART_RI_P6_LS_N")
	)
	(segment
		(start 128.62306 -161.161984)
		(end 129.78003 -160.005014)
		(width 0.1016)
		(layer "B.Cu")
		(net "UART_RI_P6_LS_N")
	)
	(segment
		(start 128.62306 -162.012376)
		(end 128.62306 -161.957766)
		(width 0.1016)
		(layer "B.Cu")
		(net "UART_RI_P6_LS_N")
	)
	(segment
		(start 124.294138 -163.045902)
		(end 124.76226 -163.045902)
		(width 0.1016)
		(layer "B.Cu")
		(net "UART_RI_P6_LS_N")
	)
	(segment
		(start 123.83262 -162.584384)
		(end 124.294138 -163.045902)
		(width 0.1016)
		(layer "B.Cu")
		(net "UART_RI_P6_LS_N")
	)
	(segment
		(start 41.8338 -194.691)
		(end 28.2194 -194.691)
		(width 0.1016)
		(layer "B.Cu")
		(net "UART_RI_P6_LS_N")
	)
	(segment
		(start 124.76226 -163.045902)
		(end 125.166374 -163.450016)
		(width 0.1016)
		(layer "B.Cu")
		(net "UART_RI_P6_LS_N")
	)
	(segment
		(start 124.47016 -158.02356)
		(end 124.47016 -159.254444)
		(width 0.1016)
		(layer "B.Cu")
		(net "UART_RI_P6_LS_N")
	)
	(segment
		(start 127.589534 -163.045902)
		(end 128.62306 -162.012376)
		(width 0.1016)
		(layer "B.Cu")
		(net "UART_RI_P6_LS_N")
	)
	(segment
		(start 123.83262 -159.891984)
		(end 123.83262 -162.584384)
		(width 0.1016)
		(layer "B.Cu")
		(net "UART_RI_P6_LS_N")
	)
	(segment
		(start 125.166374 -163.450016)
		(end 126.280926 -163.450016)
		(width 0.1016)
		(layer "B.Cu")
		(net "UART_RI_P6_LS_N")
	)
	(segment
		(start 129.78003 -160.005014)
		(end 130.183382 -160.005014)
		(width 0.1016)
		(layer "B.Cu")
		(net "UART_RI_P6_LS_N")
	)
	(segment
		(start 120.523508 -159.39897)
		(end 123.735084 -159.39897)
		(width 0.1143)
		(layer "In2.Cu")
		(net "UART_RI_P6_LS_N")
	)
	(segment
		(start 79.479648 -162.333178)
		(end 79.716376 -162.09645)
		(width 0.1143)
		(layer "In2.Cu")
		(net "UART_RI_P6_LS_N")
	)
	(segment
		(start 112.899698 -162.055302)
		(end 113.2332 -161.7218)
		(width 0.1143)
		(layer "In2.Cu")
		(net "UART_RI_P6_LS_N")
	)
	(segment
		(start 89.556082 -160.573212)
		(end 89.92108 -160.573212)
		(width 0.1143)
		(layer "In2.Cu")
		(net "UART_RI_P6_LS_N")
	)
	(segment
		(start 60.15482 -167.186864)
		(end 67.457574 -167.186864)
		(width 0.1143)
		(layer "In2.Cu")
		(net "UART_RI_P6_LS_N")
	)
	(segment
		(start 4.802124 -147.765516)
		(end 4.802124 -162.635692)
		(width 0.1143)
		(layer "In2.Cu")
		(net "UART_RI_P6_LS_N")
	)
	(segment
		(start 124.36348 -158.13024)
		(end 124.47016 -158.02356)
		(width 0.1143)
		(layer "In2.Cu")
		(net "UART_RI_P6_LS_N")
	)
	(segment
		(start 116.68633 -160.566608)
		(end 119.35587 -160.566608)
		(width 0.1143)
		(layer "In2.Cu")
		(net "UART_RI_P6_LS_N")
	)
	(segment
		(start 75.315826 -164.01796)
		(end 75.86726 -164.01796)
		(width 0.1143)
		(layer "In2.Cu")
		(net "UART_RI_P6_LS_N")
	)
	(segment
		(start 115.531138 -161.7218)
		(end 116.68633 -160.566608)
		(width 0.1143)
		(layer "In2.Cu")
		(net "UART_RI_P6_LS_N")
	)
	(segment
		(start 81.809844 -161.055304)
		(end 84.67852 -161.055304)
		(width 0.1143)
		(layer "In2.Cu")
		(net "UART_RI_P6_LS_N")
	)
	(segment
		(start 76.55052 -162.221164)
		(end 76.80706 -161.964624)
		(width 0.1143)
		(layer "In2.Cu")
		(net "UART_RI_P6_LS_N")
	)
	(segment
		(start 96.564196 -161.464752)
		(end 98.000058 -161.464752)
		(width 0.1143)
		(layer "In2.Cu")
		(net "UART_RI_P6_LS_N")
	)
	(segment
		(start 5.99694 -146.5707)
		(end 4.802124 -147.765516)
		(width 0.1143)
		(layer "In2.Cu")
		(net "UART_RI_P6_LS_N")
	)
	(segment
		(start 96.49968 -161.529268)
		(end 96.564196 -161.464752)
		(width 0.1143)
		(layer "In2.Cu")
		(net "UART_RI_P6_LS_N")
	)
	(segment
		(start 89.110312 -161.018982)
		(end 89.556082 -160.573212)
		(width 0.1143)
		(layer "In2.Cu")
		(net "UART_RI_P6_LS_N")
	)
	(segment
		(start 119.35587 -160.566608)
		(end 120.523508 -159.39897)
		(width 0.1143)
		(layer "In2.Cu")
		(net "UART_RI_P6_LS_N")
	)
	(segment
		(start 15.367 -171.104306)
		(end 15.367 -185.30443)
		(width 0.1143)
		(layer "In2.Cu")
		(net "UART_RI_P6_LS_N")
	)
	(segment
		(start 46.804072 -178.189636)
		(end 46.804072 -170.659044)
		(width 0.1143)
		(layer "In2.Cu")
		(net "UART_RI_P6_LS_N")
	)
	(segment
		(start 45.19168 -185.14822)
		(end 44.129452 -184.085992)
		(width 0.1143)
		(layer "In2.Cu")
		(net "UART_RI_P6_LS_N")
	)
	(segment
		(start 46.186598 -178.80711)
		(end 46.804072 -178.189636)
		(width 0.1143)
		(layer "In2.Cu")
		(net "UART_RI_P6_LS_N")
	)
	(segment
		(start 71.956676 -167.37711)
		(end 75.315826 -164.01796)
		(width 0.1143)
		(layer "In2.Cu")
		(net "UART_RI_P6_LS_N")
	)
	(segment
		(start 76.80706 -161.964624)
		(end 77.60208 -161.964624)
		(width 0.1143)
		(layer "In2.Cu")
		(net "UART_RI_P6_LS_N")
	)
	(segment
		(start 106.915204 -162.94989)
		(end 107.10926 -162.755834)
		(width 0.1143)
		(layer "In2.Cu")
		(net "UART_RI_P6_LS_N")
	)
	(segment
		(start 123.735084 -159.39897)
		(end 124.36348 -158.770574)
		(width 0.1143)
		(layer "In2.Cu")
		(net "UART_RI_P6_LS_N")
	)
	(segment
		(start 77.970634 -162.333178)
		(end 79.479648 -162.333178)
		(width 0.1143)
		(layer "In2.Cu")
		(net "UART_RI_P6_LS_N")
	)
	(segment
		(start 99.257612 -162.722306)
		(end 102.79126 -162.722306)
		(width 0.1143)
		(layer "In2.Cu")
		(net "UART_RI_P6_LS_N")
	)
	(segment
		(start 103.018844 -162.94989)
		(end 106.915204 -162.94989)
		(width 0.1143)
		(layer "In2.Cu")
		(net "UART_RI_P6_LS_N")
	)
	(segment
		(start 5.99694 -144.300194)
		(end 5.99694 -146.5707)
		(width 0.1143)
		(layer "In2.Cu")
		(net "UART_RI_P6_LS_N")
	)
	(segment
		(start 12.558522 -168.295828)
		(end 15.367 -171.104306)
		(width 0.1143)
		(layer "In2.Cu")
		(net "UART_RI_P6_LS_N")
	)
	(segment
		(start 76.55052 -163.3347)
		(end 76.55052 -162.221164)
		(width 0.1143)
		(layer "In2.Cu")
		(net "UART_RI_P6_LS_N")
	)
	(segment
		(start 89.92108 -160.573212)
		(end 90.585798 -161.23793)
		(width 0.1143)
		(layer "In2.Cu")
		(net "UART_RI_P6_LS_N")
	)
	(segment
		(start 79.716376 -162.09645)
		(end 80.768698 -162.09645)
		(width 0.1143)
		(layer "In2.Cu")
		(net "UART_RI_P6_LS_N")
	)
	(segment
		(start 67.64782 -167.37711)
		(end 71.956676 -167.37711)
		(width 0.1143)
		(layer "In2.Cu")
		(net "UART_RI_P6_LS_N")
	)
	(segment
		(start 94.298262 -161.23793)
		(end 94.5896 -161.529268)
		(width 0.1143)
		(layer "In2.Cu")
		(net "UART_RI_P6_LS_N")
	)
	(segment
		(start 84.714842 -161.018982)
		(end 89.110312 -161.018982)
		(width 0.1143)
		(layer "In2.Cu")
		(net "UART_RI_P6_LS_N")
	)
	(segment
		(start 80.768698 -162.09645)
		(end 81.809844 -161.055304)
		(width 0.1143)
		(layer "In2.Cu")
		(net "UART_RI_P6_LS_N")
	)
	(segment
		(start 4.802124 -162.635692)
		(end 10.46226 -168.295828)
		(width 0.1143)
		(layer "In2.Cu")
		(net "UART_RI_P6_LS_N")
	)
	(segment
		(start 90.585798 -161.23793)
		(end 94.298262 -161.23793)
		(width 0.1143)
		(layer "In2.Cu")
		(net "UART_RI_P6_LS_N")
	)
	(segment
		(start 44.129452 -182.331614)
		(end 46.186598 -180.274468)
		(width 0.1143)
		(layer "In2.Cu")
		(net "UART_RI_P6_LS_N")
	)
	(segment
		(start 107.87888 -162.755834)
		(end 108.579412 -162.055302)
		(width 0.1143)
		(layer "In2.Cu")
		(net "UART_RI_P6_LS_N")
	)
	(segment
		(start 46.186598 -180.274468)
		(end 46.186598 -178.80711)
		(width 0.1143)
		(layer "In2.Cu")
		(net "UART_RI_P6_LS_N")
	)
	(segment
		(start 75.86726 -164.01796)
		(end 76.55052 -163.3347)
		(width 0.1143)
		(layer "In2.Cu")
		(net "UART_RI_P6_LS_N")
	)
	(segment
		(start 46.804072 -170.659044)
		(end 50.724308 -166.738808)
		(width 0.1143)
		(layer "In2.Cu")
		(net "UART_RI_P6_LS_N")
	)
	(segment
		(start 107.10926 -162.755834)
		(end 107.87888 -162.755834)
		(width 0.1143)
		(layer "In2.Cu")
		(net "UART_RI_P6_LS_N")
	)
	(segment
		(start 59.706764 -166.738808)
		(end 60.15482 -167.186864)
		(width 0.1143)
		(layer "In2.Cu")
		(net "UART_RI_P6_LS_N")
	)
	(segment
		(start 15.367 -185.30443)
		(end 24.73706 -194.67449)
		(width 0.1143)
		(layer "In2.Cu")
		(net "UART_RI_P6_LS_N")
	)
	(segment
		(start 124.36348 -158.770574)
		(end 124.36348 -158.13024)
		(width 0.1143)
		(layer "In2.Cu")
		(net "UART_RI_P6_LS_N")
	)
	(segment
		(start 67.457574 -167.186864)
		(end 67.64782 -167.37711)
		(width 0.1143)
		(layer "In2.Cu")
		(net "UART_RI_P6_LS_N")
	)
	(segment
		(start 44.129452 -184.085992)
		(end 44.129452 -182.331614)
		(width 0.1143)
		(layer "In2.Cu")
		(net "UART_RI_P6_LS_N")
	)
	(segment
		(start 108.579412 -162.055302)
		(end 112.899698 -162.055302)
		(width 0.1143)
		(layer "In2.Cu")
		(net "UART_RI_P6_LS_N")
	)
	(segment
		(start 84.67852 -161.055304)
		(end 84.714842 -161.018982)
		(width 0.1143)
		(layer "In2.Cu")
		(net "UART_RI_P6_LS_N")
	)
	(segment
		(start 50.724308 -166.738808)
		(end 59.706764 -166.738808)
		(width 0.1143)
		(layer "In2.Cu")
		(net "UART_RI_P6_LS_N")
	)
	(segment
		(start 45.19168 -187.782708)
		(end 45.19168 -185.14822)
		(width 0.1143)
		(layer "In2.Cu")
		(net "UART_RI_P6_LS_N")
	)
	(segment
		(start 102.79126 -162.722306)
		(end 103.018844 -162.94989)
		(width 0.1143)
		(layer "In2.Cu")
		(net "UART_RI_P6_LS_N")
	)
	(segment
		(start 77.60208 -161.964624)
		(end 77.970634 -162.333178)
		(width 0.1143)
		(layer "In2.Cu")
		(net "UART_RI_P6_LS_N")
	)
	(segment
		(start 94.5896 -161.529268)
		(end 96.49968 -161.529268)
		(width 0.1143)
		(layer "In2.Cu")
		(net "UART_RI_P6_LS_N")
	)
	(segment
		(start 98.000058 -161.464752)
		(end 99.257612 -162.722306)
		(width 0.1143)
		(layer "In2.Cu")
		(net "UART_RI_P6_LS_N")
	)
	(segment
		(start 113.2332 -161.7218)
		(end 115.531138 -161.7218)
		(width 0.1143)
		(layer "In2.Cu")
		(net "UART_RI_P6_LS_N")
	)
	(segment
		(start 10.46226 -168.295828)
		(end 12.558522 -168.295828)
		(width 0.1143)
		(layer "In2.Cu")
		(net "UART_RI_P6_LS_N")
	)
	(segment
		(start 2.293112 -154.119834)
		(end 2.293112 -155.480766)
		(width 0.1016)
		(layer "F.Cu")
		(net "UART_RI_P5_LS_N")
	)
	(segment
		(start 2.253234 -159.043116)
		(end 2.797556 -159.587438)
		(width 0.1016)
		(layer "F.Cu")
		(net "UART_RI_P5_LS_N")
	)
	(segment
		(start 2.293112 -155.480766)
		(end 2.293112 -156.659072)
		(width 0.1016)
		(layer "F.Cu")
		(net "UART_RI_P5_LS_N")
	)
	(segment
		(start 4.19354 -159.587438)
		(end 3.6957 -159.587438)
		(width 0.1016)
		(layer "F.Cu")
		(net "UART_RI_P5_LS_N")
	)
	(segment
		(start 4.558792 -158.220156)
		(end 4.558792 -159.222186)
		(width 0.1016)
		(layer "F.Cu")
		(net "UART_RI_P5_LS_N")
	)
	(segment
		(start 2.49428 -153.918666)
		(end 2.293112 -154.119834)
		(width 0.1016)
		(layer "F.Cu")
		(net "UART_RI_P5_LS_N")
	)
	(segment
		(start 4.558792 -157.019752)
		(end 4.725162 -156.853382)
		(width 0.1016)
		(layer "F.Cu")
		(net "UART_RI_P5_LS_N")
	)
	(segment
		(start 2.797556 -159.587438)
		(end 3.6957 -159.587438)
		(width 0.1016)
		(layer "F.Cu")
		(net "UART_RI_P5_LS_N")
	)
	(segment
		(start 4.725162 -156.853382)
		(end 4.725162 -156.188156)
		(width 0.1016)
		(layer "F.Cu")
		(net "UART_RI_P5_LS_N")
	)
	(segment
		(start 4.558792 -158.220156)
		(end 4.558792 -157.019752)
		(width 0.1016)
		(layer "F.Cu")
		(net "UART_RI_P5_LS_N")
	)
	(segment
		(start 2.293112 -156.659072)
		(end 2.253234 -156.69895)
		(width 0.1016)
		(layer "F.Cu")
		(net "UART_RI_P5_LS_N")
	)
	(segment
		(start 4.558792 -159.222186)
		(end 4.19354 -159.587438)
		(width 0.1016)
		(layer "F.Cu")
		(net "UART_RI_P5_LS_N")
	)
	(segment
		(start 2.253234 -156.69895)
		(end 2.253234 -159.043116)
		(width 0.1016)
		(layer "F.Cu")
		(net "UART_RI_P5_LS_N")
	)
	(via
		(at 3.6957 -159.587438)
		(size 0.508)
		(drill 0.254)
		(layers "F.Cu" "B.Cu")
		(net "UART_RI_P5_LS_N")
	)
	(via
		(at 163.321746 -174.188374)
		(size 0.508)
		(drill 0.254)
		(layers "F.Cu" "B.Cu")
		(net "CPLD_UART_RI_P4_LS_N")
	)
	(via
		(at 164.43198 -169.835322)
		(size 0.6604)
		(drill 0.3302)
		(layers "F.Cu" "B.Cu")
		(net "CPLD_UART_RI_P4_LS_N")
	)
	(via
		(at 166.75227 -178.102514)
		(size 0.508)
		(drill 0.254)
		(layers "F.Cu" "B.Cu")
		(net "CPLD_UART_RI_P4_LS_N")
	)
	(segment
		(start 165.18382 -168.546272)
		(end 164.77488 -168.955212)
		(width 0.1016)
		(layer "B.Cu")
		(net "CPLD_UART_RI_P4_LS_N")
	)
	(segment
		(start 157.277308 -164.818314)
		(end 157.277308 -165.60038)
		(width 0.1016)
		(layer "B.Cu")
		(net "CPLD_UART_RI_P4_LS_N")
	)
	(segment
		(start 163.322 -174.188374)
		(end 163.7157 -173.794674)
		(width 0.1016)
		(layer "B.Cu")
		(net "CPLD_UART_RI_P4_LS_N")
	)
	(segment
		(start 165.67912 -168.053258)
		(end 165.67912 -167.042084)
		(width 0.1016)
		(layer "B.Cu")
		(net "CPLD_UART_RI_P4_LS_N")
	)
	(segment
		(start 165.67912 -167.042084)
		(end 163.196778 -164.559742)
		(width 0.1016)
		(layer "B.Cu")
		(net "CPLD_UART_RI_P4_LS_N")
	)
	(segment
		(start 165.186106 -168.546272)
		(end 165.67912 -168.053258)
		(width 0.1016)
		(layer "B.Cu")
		(net "CPLD_UART_RI_P4_LS_N")
	)
	(segment
		(start 163.7157 -170.551602)
		(end 164.43198 -169.835322)
		(width 0.1016)
		(layer "B.Cu")
		(net "CPLD_UART_RI_P4_LS_N")
	)
	(segment
		(start 163.7157 -173.794674)
		(end 163.7157 -170.551602)
		(width 0.1016)
		(layer "B.Cu")
		(net "CPLD_UART_RI_P4_LS_N")
	)
	(segment
		(start 163.321746 -174.188374)
		(end 163.322 -174.188374)
		(width 0.1016)
		(layer "B.Cu")
		(net "CPLD_UART_RI_P4_LS_N")
	)
	(segment
		(start 165.186106 -168.546272)
		(end 165.18382 -168.546272)
		(width 0.1016)
		(layer "B.Cu")
		(net "CPLD_UART_RI_P4_LS_N")
	)
	(segment
		(start 163.196778 -164.559742)
		(end 157.53588 -164.559742)
		(width 0.1016)
		(layer "B.Cu")
		(net "CPLD_UART_RI_P4_LS_N")
	)
	(segment
		(start 164.77488 -168.955212)
		(end 164.77488 -169.492422)
		(width 0.1016)
		(layer "B.Cu")
		(net "CPLD_UART_RI_P4_LS_N")
	)
	(segment
		(start 157.53588 -164.559742)
		(end 157.277308 -164.818314)
		(width 0.1016)
		(layer "B.Cu")
		(net "CPLD_UART_RI_P4_LS_N")
	)
	(segment
		(start 164.77488 -169.492422)
		(end 164.43198 -169.835322)
		(width 0.1016)
		(layer "B.Cu")
		(net "CPLD_UART_RI_P4_LS_N")
	)
	(segment
		(start 165.217602 -178.102514)
		(end 166.75227 -178.102514)
		(width 0.1016)
		(layer "B.Cu")
		(net "CPLD_UART_RI_P4_LS_N")
	)
	(segment
		(start 163.321746 -174.67199)
		(end 166.75227 -178.102514)
		(width 0.1143)
		(layer "In7.Cu")
		(net "CPLD_UART_RI_P4_LS_N")
	)
	(segment
		(start 163.321746 -174.188374)
		(end 163.321746 -174.67199)
		(width 0.1143)
		(layer "In7.Cu")
		(net "CPLD_UART_RI_P4_LS_N")
	)
	(segment
		(start 160.54832 -177.896774)
		(end 160.54832 -175.943006)
		(width 0.1016)
		(layer "F.Cu")
		(net "CPLD_UART_RI_P3_LS_N")
	)
	(segment
		(start 160.34258 -178.102514)
		(end 160.54832 -177.896774)
		(width 0.1016)
		(layer "F.Cu")
		(net "CPLD_UART_RI_P3_LS_N")
	)
	(segment
		(start 159.375602 -178.102514)
		(end 160.34258 -178.102514)
		(width 0.1016)
		(layer "F.Cu")
		(net "CPLD_UART_RI_P3_LS_N")
	)
	(segment
		(start 160.54832 -175.943006)
		(end 162.64382 -173.847506)
		(width 0.1016)
		(layer "F.Cu")
		(net "CPLD_UART_RI_P3_LS_N")
	)
	(via
		(at 162.64382 -173.847506)
		(size 0.508)
		(drill 0.254)
		(layers "F.Cu" "B.Cu")
		(net "CPLD_UART_RI_P3_LS_N")
	)
	(via
		(at 162.97402 -169.870882)
		(size 0.6604)
		(drill 0.3302)
		(layers "F.Cu" "B.Cu")
		(net "CPLD_UART_RI_P3_LS_N")
	)
	(segment
		(start 164.021008 -168.823894)
		(end 162.97402 -169.870882)
		(width 0.1016)
		(layer "B.Cu")
		(net "CPLD_UART_RI_P3_LS_N")
	)
	(segment
		(start 162.613594 -173.81728)
		(end 162.613594 -170.229276)
		(width 0.1016)
		(layer "B.Cu")
		(net "CPLD_UART_RI_P3_LS_N")
	)
	(segment
		(start 162.798252 -169.695114)
		(end 162.97402 -169.870882)
		(width 0.1016)
		(layer "B.Cu")
		(net "CPLD_UART_RI_P3_LS_N")
	)
	(segment
		(start 162.971988 -169.870882)
		(end 162.97402 -169.870882)
		(width 0.1016)
		(layer "B.Cu")
		(net "CPLD_UART_RI_P3_LS_N")
	)
	(segment
		(start 164.021008 -168.549574)
		(end 164.021008 -168.823894)
		(width 0.1016)
		(layer "B.Cu")
		(net "CPLD_UART_RI_P3_LS_N")
	)
	(segment
		(start 162.798252 -168.258998)
		(end 162.798252 -169.695114)
		(width 0.1016)
		(layer "B.Cu")
		(net "CPLD_UART_RI_P3_LS_N")
	)
	(segment
		(start 162.613594 -170.229276)
		(end 162.971988 -169.870882)
		(width 0.1016)
		(layer "B.Cu")
		(net "CPLD_UART_RI_P3_LS_N")
	)
	(segment
		(start 162.64382 -173.847506)
		(end 162.613594 -173.81728)
		(width 0.1016)
		(layer "B.Cu")
		(net "CPLD_UART_RI_P3_LS_N")
	)
	(segment
		(start 7.069582 -152.211024)
		(end 12.950698 -152.211024)
		(width 0.1016)
		(layer "F.Cu")
		(net "TACKOVER_EN")
	)
	(segment
		(start 12.950698 -152.211024)
		(end 13.125704 -152.38603)
		(width 0.1016)
		(layer "F.Cu")
		(net "TACKOVER_EN")
	)
	(segment
		(start 4.52628 -153.918666)
		(end 6.345428 -153.918666)
		(width 0.1016)
		(layer "F.Cu")
		(net "TACKOVER_EN")
	)
	(segment
		(start 13.125704 -152.38603)
		(end 17.43202 -152.38603)
		(width 0.1016)
		(layer "F.Cu")
		(net "TACKOVER_EN")
	)
	(segment
		(start 6.56082 -152.719786)
		(end 7.069582 -152.211024)
		(width 0.1016)
		(layer "F.Cu")
		(net "TACKOVER_EN")
	)
	(segment
		(start 6.56082 -153.703274)
		(end 6.56082 -152.719786)
		(width 0.1016)
		(layer "F.Cu")
		(net "TACKOVER_EN")
	)
	(segment
		(start 6.345428 -153.918666)
		(end 6.56082 -153.703274)
		(width 0.1016)
		(layer "F.Cu")
		(net "TACKOVER_EN")
	)
	(via
		(at 135.249666 -160.931352)
		(size 0.508)
		(drill 0.254)
		(layers "F.Cu" "B.Cu")
		(net "TACKOVER_EN")
	)
	(via
		(at 54.00929 -169.063416)
		(size 0.508)
		(drill 0.254)
		(layers "F.Cu" "B.Cu")
		(net "TACKOVER_EN")
	)
	(via
		(at 156.3878 -167.070278)
		(size 0.508)
		(drill 0.254)
		(layers "F.Cu" "B.Cu")
		(net "TACKOVER_EN")
	)
	(via
		(at 17.43202 -152.38603)
		(size 0.508)
		(drill 0.254)
		(layers "F.Cu" "B.Cu")
		(net "TACKOVER_EN")
	)
	(segment
		(start 126.465584 -158.909766)
		(end 128.18872 -158.909766)
		(width 0.1016)
		(layer "B.Cu")
		(net "TACKOVER_EN")
	)
	(segment
		(start 133.29412 -163.3855)
		(end 133.29412 -162.153092)
		(width 0.1016)
		(layer "B.Cu")
		(net "TACKOVER_EN")
	)
	(segment
		(start 160.122616 -168.258998)
		(end 160.766252 -168.258998)
		(width 0.1016)
		(layer "B.Cu")
		(net "TACKOVER_EN")
	)
	(segment
		(start 133.890766 -157.891734)
		(end 135.249666 -159.250634)
		(width 0.1016)
		(layer "B.Cu")
		(net "TACKOVER_EN")
	)
	(segment
		(start 126.1491 -159.58566)
		(end 126.1491 -159.22625)
		(width 0.1016)
		(layer "B.Cu")
		(net "TACKOVER_EN")
	)
	(segment
		(start 135.249666 -159.250634)
		(end 135.249666 -160.931352)
		(width 0.1016)
		(layer "B.Cu")
		(net "TACKOVER_EN")
	)
	(segment
		(start 126.59106 -160.02762)
		(end 126.1491 -159.58566)
		(width 0.1016)
		(layer "B.Cu")
		(net "TACKOVER_EN")
	)
	(segment
		(start 133.197346 -163.482274)
		(end 133.29412 -163.3855)
		(width 0.1016)
		(layer "B.Cu")
		(net "TACKOVER_EN")
	)
	(segment
		(start 128.18872 -158.909766)
		(end 128.197864 -158.91891)
		(width 0.1016)
		(layer "B.Cu")
		(net "TACKOVER_EN")
	)
	(segment
		(start 159.309308 -165.60038)
		(end 158.343092 -166.566596)
		(width 0.1016)
		(layer "B.Cu")
		(net "TACKOVER_EN")
	)
	(segment
		(start 159.34182 -165.632892)
		(end 159.34182 -167.478202)
		(width 0.1016)
		(layer "B.Cu")
		(net "TACKOVER_EN")
	)
	(segment
		(start 135.249666 -162.276282)
		(end 135.249666 -160.931352)
		(width 0.1016)
		(layer "B.Cu")
		(net "TACKOVER_EN")
	)
	(segment
		(start 133.294628 -162.153092)
		(end 133.928612 -162.153092)
		(width 0.1016)
		(layer "B.Cu")
		(net "TACKOVER_EN")
	)
	(segment
		(start 159.309308 -165.60038)
		(end 159.34182 -165.632892)
		(width 0.1016)
		(layer "B.Cu")
		(net "TACKOVER_EN")
	)
	(segment
		(start 126.59106 -161.957766)
		(end 126.59106 -160.02762)
		(width 0.1016)
		(layer "B.Cu")
		(net "TACKOVER_EN")
	)
	(segment
		(start 130.181096 -157.891734)
		(end 133.890766 -157.891734)
		(width 0.1016)
		(layer "B.Cu")
		(net "TACKOVER_EN")
	)
	(segment
		(start 134.289546 -162.514026)
		(end 135.011922 -162.514026)
		(width 0.1016)
		(layer "B.Cu")
		(net "TACKOVER_EN")
	)
	(segment
		(start 128.197864 -158.91891)
		(end 129.15392 -158.91891)
		(width 0.1016)
		(layer "B.Cu")
		(net "TACKOVER_EN")
	)
	(segment
		(start 135.011922 -162.514026)
		(end 135.249666 -162.276282)
		(width 0.1016)
		(layer "B.Cu")
		(net "TACKOVER_EN")
	)
	(segment
		(start 126.1491 -159.22625)
		(end 126.465584 -158.909766)
		(width 0.1016)
		(layer "B.Cu")
		(net "TACKOVER_EN")
	)
	(segment
		(start 133.928612 -162.153092)
		(end 134.289546 -162.514026)
		(width 0.1016)
		(layer "B.Cu")
		(net "TACKOVER_EN")
	)
	(segment
		(start 156.891482 -166.566596)
		(end 156.3878 -167.070278)
		(width 0.1016)
		(layer "B.Cu")
		(net "TACKOVER_EN")
	)
	(segment
		(start 129.15392 -158.91891)
		(end 130.181096 -157.891734)
		(width 0.1016)
		(layer "B.Cu")
		(net "TACKOVER_EN")
	)
	(segment
		(start 133.29412 -162.153092)
		(end 133.294628 -162.153092)
		(width 0.1016)
		(layer "B.Cu")
		(net "TACKOVER_EN")
	)
	(segment
		(start 159.34182 -167.478202)
		(end 160.122616 -168.258998)
		(width 0.1016)
		(layer "B.Cu")
		(net "TACKOVER_EN")
	)
	(segment
		(start 158.343092 -166.566596)
		(end 156.891482 -166.566596)
		(width 0.1016)
		(layer "B.Cu")
		(net "TACKOVER_EN")
	)
	(segment
		(start 133.197346 -163.884356)
		(end 133.197346 -163.482274)
		(width 0.1016)
		(layer "B.Cu")
		(net "TACKOVER_EN")
	)
	(segment
		(start 17.763744 -152.054306)
		(end 19.3167 -152.054306)
		(width 0.1143)
		(layer "In6.Cu")
		(net "TACKOVER_EN")
	)
	(segment
		(start 42.80535 -170.143424)
		(end 43.178476 -169.770298)
		(width 0.1143)
		(layer "In6.Cu")
		(net "TACKOVER_EN")
	)
	(segment
		(start 43.178476 -169.770298)
		(end 53.302408 -169.770298)
		(width 0.1143)
		(layer "In6.Cu")
		(net "TACKOVER_EN")
	)
	(segment
		(start 41.821354 -169.522648)
		(end 42.44213 -170.143424)
		(width 0.1143)
		(layer "In6.Cu")
		(net "TACKOVER_EN")
	)
	(segment
		(start 39.575994 -169.522648)
		(end 41.821354 -169.522648)
		(width 0.1143)
		(layer "In6.Cu")
		(net "TACKOVER_EN")
	)
	(segment
		(start 33.39338 -167.866314)
		(end 37.167058 -167.866314)
		(width 0.1143)
		(layer "In6.Cu")
		(net "TACKOVER_EN")
	)
	(segment
		(start 20.1041 -166.099744)
		(end 22.70379 -168.699434)
		(width 0.1143)
		(layer "In6.Cu")
		(net "TACKOVER_EN")
	)
	(segment
		(start 17.43202 -152.38603)
		(end 17.763744 -152.054306)
		(width 0.1143)
		(layer "In6.Cu")
		(net "TACKOVER_EN")
	)
	(segment
		(start 20.1041 -152.841706)
		(end 20.1041 -166.099744)
		(width 0.1143)
		(layer "In6.Cu")
		(net "TACKOVER_EN")
	)
	(segment
		(start 37.167058 -167.866314)
		(end 38.271958 -168.971214)
		(width 0.1143)
		(layer "In6.Cu")
		(net "TACKOVER_EN")
	)
	(segment
		(start 42.44213 -170.143424)
		(end 42.80535 -170.143424)
		(width 0.1143)
		(layer "In6.Cu")
		(net "TACKOVER_EN")
	)
	(segment
		(start 39.02456 -168.971214)
		(end 39.575994 -169.522648)
		(width 0.1143)
		(layer "In6.Cu")
		(net "TACKOVER_EN")
	)
	(segment
		(start 53.302408 -169.770298)
		(end 54.00929 -169.063416)
		(width 0.1143)
		(layer "In6.Cu")
		(net "TACKOVER_EN")
	)
	(segment
		(start 38.271958 -168.971214)
		(end 39.02456 -168.971214)
		(width 0.1143)
		(layer "In6.Cu")
		(net "TACKOVER_EN")
	)
	(segment
		(start 22.70379 -168.699434)
		(end 32.56026 -168.699434)
		(width 0.1143)
		(layer "In6.Cu")
		(net "TACKOVER_EN")
	)
	(segment
		(start 32.56026 -168.699434)
		(end 33.39338 -167.866314)
		(width 0.1143)
		(layer "In6.Cu")
		(net "TACKOVER_EN")
	)
	(segment
		(start 19.3167 -152.054306)
		(end 20.1041 -152.841706)
		(width 0.1143)
		(layer "In6.Cu")
		(net "TACKOVER_EN")
	)
	(segment
		(start 155.513278 -167.171878)
		(end 156.2862 -167.171878)
		(width 0.1143)
		(layer "In7.Cu")
		(net "TACKOVER_EN")
	)
	(segment
		(start 80.588612 -160.294066)
		(end 90.291158 -160.294066)
		(width 0.1143)
		(layer "In7.Cu")
		(net "TACKOVER_EN")
	)
	(segment
		(start 90.291158 -160.294066)
		(end 90.65006 -160.652968)
		(width 0.1143)
		(layer "In7.Cu")
		(net "TACKOVER_EN")
	)
	(segment
		(start 111.960406 -161.106866)
		(end 112.544606 -161.691066)
		(width 0.1143)
		(layer "In7.Cu")
		(net "TACKOVER_EN")
	)
	(segment
		(start 125.633734 -158.6738)
		(end 127.0762 -158.6738)
		(width 0.1143)
		(layer "In7.Cu")
		(net "TACKOVER_EN")
	)
	(segment
		(start 97.563432 -161.39922)
		(end 102.502716 -161.39922)
		(width 0.1143)
		(layer "In7.Cu")
		(net "TACKOVER_EN")
	)
	(segment
		(start 127.2794 -158.877)
		(end 130.4798 -158.877)
		(width 0.1143)
		(layer "In7.Cu")
		(net "TACKOVER_EN")
	)
	(segment
		(start 149.7076 -161.3662)
		(end 155.513278 -167.171878)
		(width 0.1143)
		(layer "In7.Cu")
		(net "TACKOVER_EN")
	)
	(segment
		(start 127.0762 -158.6738)
		(end 127.2794 -158.877)
		(width 0.1143)
		(layer "In7.Cu")
		(net "TACKOVER_EN")
	)
	(segment
		(start 54.591966 -168.48074)
		(end 63.789814 -168.48074)
		(width 0.1143)
		(layer "In7.Cu")
		(net "TACKOVER_EN")
	)
	(segment
		(start 138.9888 -161.3662)
		(end 149.7076 -161.3662)
		(width 0.1143)
		(layer "In7.Cu")
		(net "TACKOVER_EN")
	)
	(segment
		(start 104.088438 -161.106866)
		(end 111.960406 -161.106866)
		(width 0.1143)
		(layer "In7.Cu")
		(net "TACKOVER_EN")
	)
	(segment
		(start 132.187696 -160.584896)
		(end 134.90321 -160.584896)
		(width 0.1143)
		(layer "In7.Cu")
		(net "TACKOVER_EN")
	)
	(segment
		(start 135.249666 -160.931352)
		(end 136.202674 -161.88436)
		(width 0.1143)
		(layer "In7.Cu")
		(net "TACKOVER_EN")
	)
	(segment
		(start 123.348496 -160.959038)
		(end 125.633734 -158.6738)
		(width 0.1143)
		(layer "In7.Cu")
		(net "TACKOVER_EN")
	)
	(segment
		(start 67.66179 -164.608764)
		(end 70.978522 -164.608764)
		(width 0.1143)
		(layer "In7.Cu")
		(net "TACKOVER_EN")
	)
	(segment
		(start 96.81718 -160.652968)
		(end 97.563432 -161.39922)
		(width 0.1143)
		(layer "In7.Cu")
		(net "TACKOVER_EN")
	)
	(segment
		(start 134.90321 -160.584896)
		(end 135.249666 -160.931352)
		(width 0.1143)
		(layer "In7.Cu")
		(net "TACKOVER_EN")
	)
	(segment
		(start 80.34528 -160.537398)
		(end 80.588612 -160.294066)
		(width 0.1143)
		(layer "In7.Cu")
		(net "TACKOVER_EN")
	)
	(segment
		(start 70.978522 -164.608764)
		(end 75.049888 -160.537398)
		(width 0.1143)
		(layer "In7.Cu")
		(net "TACKOVER_EN")
	)
	(segment
		(start 118.53545 -160.959038)
		(end 123.348496 -160.959038)
		(width 0.1143)
		(layer "In7.Cu")
		(net "TACKOVER_EN")
	)
	(segment
		(start 102.502716 -161.39922)
		(end 102.6922 -161.588704)
		(width 0.1143)
		(layer "In7.Cu")
		(net "TACKOVER_EN")
	)
	(segment
		(start 54.00929 -169.063416)
		(end 54.591966 -168.48074)
		(width 0.1143)
		(layer "In7.Cu")
		(net "TACKOVER_EN")
	)
	(segment
		(start 130.4798 -158.877)
		(end 132.187696 -160.584896)
		(width 0.1143)
		(layer "In7.Cu")
		(net "TACKOVER_EN")
	)
	(segment
		(start 103.6066 -161.588704)
		(end 104.088438 -161.106866)
		(width 0.1143)
		(layer "In7.Cu")
		(net "TACKOVER_EN")
	)
	(segment
		(start 156.2862 -167.171878)
		(end 156.3878 -167.070278)
		(width 0.1143)
		(layer "In7.Cu")
		(net "TACKOVER_EN")
	)
	(segment
		(start 90.65006 -160.652968)
		(end 96.81718 -160.652968)
		(width 0.1143)
		(layer "In7.Cu")
		(net "TACKOVER_EN")
	)
	(segment
		(start 117.803422 -161.691066)
		(end 118.53545 -160.959038)
		(width 0.1143)
		(layer "In7.Cu")
		(net "TACKOVER_EN")
	)
	(segment
		(start 63.789814 -168.48074)
		(end 67.66179 -164.608764)
		(width 0.1143)
		(layer "In7.Cu")
		(net "TACKOVER_EN")
	)
	(segment
		(start 138.47064 -161.88436)
		(end 138.9888 -161.3662)
		(width 0.1143)
		(layer "In7.Cu")
		(net "TACKOVER_EN")
	)
	(segment
		(start 75.049888 -160.537398)
		(end 80.34528 -160.537398)
		(width 0.1143)
		(layer "In7.Cu")
		(net "TACKOVER_EN")
	)
	(segment
		(start 102.6922 -161.588704)
		(end 103.6066 -161.588704)
		(width 0.1143)
		(layer "In7.Cu")
		(net "TACKOVER_EN")
	)
	(segment
		(start 136.202674 -161.88436)
		(end 138.47064 -161.88436)
		(width 0.1143)
		(layer "In7.Cu")
		(net "TACKOVER_EN")
	)
	(segment
		(start 112.544606 -161.691066)
		(end 117.803422 -161.691066)
		(width 0.1143)
		(layer "In7.Cu")
		(net "TACKOVER_EN")
	)
	(segment
		(start 17.48282 -54.817518)
		(end 17.645634 -54.654704)
		(width 0.1016)
		(layer "F.Cu")
		(net "CRT_B_L")
	)
	(segment
		(start 16.825468 -54.036722)
		(end 16.825468 -54.160166)
		(width 0.1016)
		(layer "F.Cu")
		(net "CRT_B_L")
	)
	(segment
		(start 18.226532 -54.659784)
		(end 18.231612 -54.654704)
		(width 0.1016)
		(layer "F.Cu")
		(net "CRT_B_L")
	)
	(segment
		(start 17.645634 -54.654704)
		(end 18.231612 -54.654704)
		(width 0.1016)
		(layer "F.Cu")
		(net "CRT_B_L")
	)
	(segment
		(start 18.226532 -55.604156)
		(end 18.226532 -54.659784)
		(width 0.1016)
		(layer "F.Cu")
		(net "CRT_B_L")
	)
	(segment
		(start 16.825468 -54.160166)
		(end 17.48282 -54.817518)
		(width 0.1016)
		(layer "F.Cu")
		(net "CRT_B_L")
	)
	(via
		(at 17.48282 -54.817518)
		(size 0.508)
		(drill 0.254)
		(layers "F.Cu" "B.Cu")
		(net "CRT_B_L")
	)
	(segment
		(start 18.26006 -43.989244)
		(end 18.37944 -43.869864)
		(width 0.1016)
		(layer "F.Cu")
		(net "CRT_R_L")
	)
	(segment
		(start 17.96923 -43.989244)
		(end 18.26006 -43.989244)
		(width 0.1016)
		(layer "F.Cu")
		(net "CRT_R_L")
	)
	(segment
		(start 18.549366 -43.869864)
		(end 18.57756 -43.84167)
		(width 0.1016)
		(layer "F.Cu")
		(net "CRT_R_L")
	)
	(segment
		(start 17.375632 -44.671234)
		(end 17.44726 -44.599606)
		(width 0.1016)
		(layer "F.Cu")
		(net "CRT_R_L")
	)
	(segment
		(start 18.57756 -43.84167)
		(end 18.98523 -43.84167)
		(width 0.1016)
		(layer "F.Cu")
		(net "CRT_R_L")
	)
	(segment
		(start 16.686784 -44.671234)
		(end 17.375632 -44.671234)
		(width 0.1016)
		(layer "F.Cu")
		(net "CRT_R_L")
	)
	(segment
		(start 17.96923 -43.989244)
		(end 17.96923 -44.13123)
		(width 0.1016)
		(layer "F.Cu")
		(net "CRT_R_L")
	)
	(segment
		(start 17.96923 -44.13123)
		(end 17.500854 -44.599606)
		(width 0.1016)
		(layer "F.Cu")
		(net "CRT_R_L")
	)
	(segment
		(start 17.500854 -44.599606)
		(end 17.44726 -44.599606)
		(width 0.1016)
		(layer "F.Cu")
		(net "CRT_R_L")
	)
	(segment
		(start 18.37944 -43.869864)
		(end 18.549366 -43.869864)
		(width 0.1016)
		(layer "F.Cu")
		(net "CRT_R_L")
	)
	(via
		(at 17.44726 -44.599606)
		(size 0.508)
		(drill 0.254)
		(layers "F.Cu" "B.Cu")
		(net "CRT_R_L")
	)
	(segment
		(start 16.90878 -48.255682)
		(end 16.705326 -48.052228)
		(width 0.1016)
		(layer "F.Cu")
		(net "CRT_G_L")
	)
	(segment
		(start 16.718534 -49.0601)
		(end 16.718534 -49.21631)
		(width 0.1016)
		(layer "F.Cu")
		(net "CRT_G_L")
	)
	(segment
		(start 17.64919 -47.992284)
		(end 17.172178 -47.992284)
		(width 0.1016)
		(layer "F.Cu")
		(net "CRT_G_L")
	)
	(segment
		(start 16.705326 -48.052228)
		(end 16.208502 -48.052228)
		(width 0.1016)
		(layer "F.Cu")
		(net "CRT_G_L")
	)
	(segment
		(start 16.208502 -48.052228)
		(end 16.208502 -48.550068)
		(width 0.1016)
		(layer "F.Cu")
		(net "CRT_G_L")
	)
	(segment
		(start 16.208502 -48.550068)
		(end 16.718534 -49.0601)
		(width 0.1016)
		(layer "F.Cu")
		(net "CRT_G_L")
	)
	(segment
		(start 17.172178 -47.992284)
		(end 16.90878 -48.255682)
		(width 0.1016)
		(layer "F.Cu")
		(net "CRT_G_L")
	)
	(via
		(at 16.90878 -48.255682)
		(size 0.508)
		(drill 0.254)
		(layers "F.Cu" "B.Cu")
		(net "CRT_G_L")
	)
	(segment
		(start 5.2451 -138.745722)
		(end 5.226812 -138.745722)
		(width 0.1016)
		(layer "F.Cu")
		(net "UART_CTS_P6_N")
	)
	(segment
		(start 5.226812 -138.745722)
		(end 3.890518 -140.082016)
		(width 0.1016)
		(layer "F.Cu")
		(net "UART_CTS_P6_N")
	)
	(segment
		(start 3.890518 -140.082016)
		(end 3.890518 -142.550642)
		(width 0.1016)
		(layer "F.Cu")
		(net "UART_CTS_P6_N")
	)
	(segment
		(start 138.261598 -29.087572)
		(end 138.261598 -30.079696)
		(width 0.1016)
		(layer "F.Cu")
		(net "UART_CTS_P6_N")
	)
	(segment
		(start 137.8458 -28.671774)
		(end 138.261598 -29.087572)
		(width 0.1016)
		(layer "F.Cu")
		(net "UART_CTS_P6_N")
	)
	(via
		(at 5.2451 -138.745722)
		(size 0.508)
		(drill 0.254)
		(layers "F.Cu" "B.Cu")
		(net "UART_CTS_P6_N")
	)
	(via
		(at 137.8458 -28.671774)
		(size 0.508)
		(drill 0.254)
		(layers "F.Cu" "B.Cu")
		(net "UART_CTS_P6_N")
	)
	(segment
		(start 40.506396 -19.032728)
		(end 53.415184 -19.032728)
		(width 0.1143)
		(layer "In2.Cu")
		(net "UART_CTS_P6_N")
	)
	(segment
		(start 87.72398 -11.428476)
		(end 90.513916 -11.428476)
		(width 0.1143)
		(layer "In2.Cu")
		(net "UART_CTS_P6_N")
	)
	(segment
		(start 87.463376 -11.685778)
		(end 87.51824 -11.631422)
		(width 0.1143)
		(layer "In2.Cu")
		(net "UART_CTS_P6_N")
	)
	(segment
		(start 22.2504 -81.8134)
		(end 22.2504 -66.613278)
		(width 0.1143)
		(layer "In2.Cu")
		(net "UART_CTS_P6_N")
	)
	(segment
		(start 20.59178 -63.938912)
		(end 20.59178 -59.724798)
		(width 0.1143)
		(layer "In2.Cu")
		(net "UART_CTS_P6_N")
	)
	(segment
		(start 21.80082 -65.147952)
		(end 20.59178 -63.938912)
		(width 0.1143)
		(layer "In2.Cu")
		(net "UART_CTS_P6_N")
	)
	(segment
		(start 39.948866 -19.590258)
		(end 40.506396 -19.032728)
		(width 0.1143)
		(layer "In2.Cu")
		(net "UART_CTS_P6_N")
	)
	(segment
		(start 67.65544 -14.526514)
		(end 80.169512 -14.526514)
		(width 0.1143)
		(layer "In2.Cu")
		(net "UART_CTS_P6_N")
	)
	(segment
		(start 36.823396 -21.236178)
		(end 37.112448 -20.79879)
		(width 0.1143)
		(layer "In2.Cu")
		(net "UART_CTS_P6_N")
	)
	(segment
		(start 87.51824 -11.631422)
		(end 87.72398 -11.428476)
		(width 0.1143)
		(layer "In2.Cu")
		(net "UART_CTS_P6_N")
	)
	(segment
		(start 22.4536 -55.943246)
		(end 23.63216 -52.625498)
		(width 0.1143)
		(layer "In2.Cu")
		(net "UART_CTS_P6_N")
	)
	(segment
		(start 53.415184 -19.032728)
		(end 56.146446 -16.301466)
		(width 0.1143)
		(layer "In2.Cu")
		(net "UART_CTS_P6_N")
	)
	(segment
		(start 118.658386 -13.0683)
		(end 119.433848 -13.843762)
		(width 0.1143)
		(layer "In2.Cu")
		(net "UART_CTS_P6_N")
	)
	(segment
		(start 87.463122 -11.685778)
		(end 87.463376 -11.685778)
		(width 0.1143)
		(layer "In2.Cu")
		(net "UART_CTS_P6_N")
	)
	(segment
		(start 23.63216 -42.159174)
		(end 26.95194 -38.839394)
		(width 0.1143)
		(layer "In2.Cu")
		(net "UART_CTS_P6_N")
	)
	(segment
		(start 87.348822 -11.798808)
		(end 87.463122 -11.685778)
		(width 0.1143)
		(layer "In2.Cu")
		(net "UART_CTS_P6_N")
	)
	(segment
		(start 17.5133 -86.5505)
		(end 22.2504 -81.8134)
		(width 0.1143)
		(layer "In2.Cu")
		(net "UART_CTS_P6_N")
	)
	(segment
		(start 63.92672 -16.597122)
		(end 64.609472 -16.597122)
		(width 0.1143)
		(layer "In2.Cu")
		(net "UART_CTS_P6_N")
	)
	(segment
		(start 23.63216 -52.625498)
		(end 23.63216 -42.159174)
		(width 0.1143)
		(layer "In2.Cu")
		(net "UART_CTS_P6_N")
	)
	(segment
		(start 26.95194 -38.839394)
		(end 26.95194 -34.998406)
		(width 0.1143)
		(layer "In2.Cu")
		(net "UART_CTS_P6_N")
	)
	(segment
		(start 133.91134 -25.522936)
		(end 137.060178 -28.671774)
		(width 0.1143)
		(layer "In2.Cu")
		(net "UART_CTS_P6_N")
	)
	(segment
		(start 20.59178 -59.724798)
		(end 21.209 -59.107578)
		(width 0.1143)
		(layer "In2.Cu")
		(net "UART_CTS_P6_N")
	)
	(segment
		(start 26.95194 -34.998406)
		(end 35.18916 -26.761186)
		(width 0.1143)
		(layer "In2.Cu")
		(net "UART_CTS_P6_N")
	)
	(segment
		(start 37.112448 -20.79879)
		(end 37.113464 -20.79752)
		(width 0.1143)
		(layer "In2.Cu")
		(net "UART_CTS_P6_N")
	)
	(segment
		(start 112.87252 -13.0683)
		(end 118.658386 -13.0683)
		(width 0.1143)
		(layer "In2.Cu")
		(net "UART_CTS_P6_N")
	)
	(segment
		(start 35.18916 -23.70709)
		(end 36.823396 -21.236178)
		(width 0.1143)
		(layer "In2.Cu")
		(net "UART_CTS_P6_N")
	)
	(segment
		(start 123.931172 -13.843762)
		(end 133.91134 -23.82393)
		(width 0.1143)
		(layer "In2.Cu")
		(net "UART_CTS_P6_N")
	)
	(segment
		(start 133.91134 -23.82393)
		(end 133.91134 -25.522936)
		(width 0.1143)
		(layer "In2.Cu")
		(net "UART_CTS_P6_N")
	)
	(segment
		(start 56.146446 -16.301466)
		(end 63.631064 -16.301466)
		(width 0.1143)
		(layer "In2.Cu")
		(net "UART_CTS_P6_N")
	)
	(segment
		(start 5.2451 -138.745722)
		(end 5.2451 -102.69474)
		(width 0.1143)
		(layer "In2.Cu")
		(net "UART_CTS_P6_N")
	)
	(segment
		(start 21.80082 -66.163698)
		(end 21.80082 -65.147952)
		(width 0.1143)
		(layer "In2.Cu")
		(net "UART_CTS_P6_N")
	)
	(segment
		(start 111.606076 -11.801856)
		(end 112.87252 -13.0683)
		(width 0.1143)
		(layer "In2.Cu")
		(net "UART_CTS_P6_N")
	)
	(segment
		(start 80.169512 -14.526514)
		(end 87.348822 -11.798808)
		(width 0.1143)
		(layer "In2.Cu")
		(net "UART_CTS_P6_N")
	)
	(segment
		(start 17.5133 -91.799156)
		(end 17.5133 -86.5505)
		(width 0.1143)
		(layer "In2.Cu")
		(net "UART_CTS_P6_N")
	)
	(segment
		(start 37.118798 -20.789646)
		(end 38.318186 -19.590258)
		(width 0.1143)
		(layer "In2.Cu")
		(net "UART_CTS_P6_N")
	)
	(segment
		(start 65.09004 -16.116554)
		(end 66.0654 -16.116554)
		(width 0.1143)
		(layer "In2.Cu")
		(net "UART_CTS_P6_N")
	)
	(segment
		(start 35.18916 -26.761186)
		(end 35.18916 -23.70709)
		(width 0.1143)
		(layer "In2.Cu")
		(net "UART_CTS_P6_N")
	)
	(segment
		(start 21.209 -57.187846)
		(end 22.4536 -55.943246)
		(width 0.1143)
		(layer "In2.Cu")
		(net "UART_CTS_P6_N")
	)
	(segment
		(start 64.609472 -16.597122)
		(end 65.09004 -16.116554)
		(width 0.1143)
		(layer "In2.Cu")
		(net "UART_CTS_P6_N")
	)
	(segment
		(start 90.513916 -11.428476)
		(end 90.887296 -11.801856)
		(width 0.1143)
		(layer "In2.Cu")
		(net "UART_CTS_P6_N")
	)
	(segment
		(start 37.113464 -20.79752)
		(end 37.118798 -20.789646)
		(width 0.1143)
		(layer "In2.Cu")
		(net "UART_CTS_P6_N")
	)
	(segment
		(start 119.433848 -13.843762)
		(end 123.931172 -13.843762)
		(width 0.1143)
		(layer "In2.Cu")
		(net "UART_CTS_P6_N")
	)
	(segment
		(start 63.631064 -16.301466)
		(end 63.92672 -16.597122)
		(width 0.1143)
		(layer "In2.Cu")
		(net "UART_CTS_P6_N")
	)
	(segment
		(start 5.2451 -102.69474)
		(end 12.383516 -95.556324)
		(width 0.1143)
		(layer "In2.Cu")
		(net "UART_CTS_P6_N")
	)
	(segment
		(start 12.383516 -95.556324)
		(end 13.756132 -95.556324)
		(width 0.1143)
		(layer "In2.Cu")
		(net "UART_CTS_P6_N")
	)
	(segment
		(start 22.2504 -66.613278)
		(end 21.80082 -66.163698)
		(width 0.1143)
		(layer "In2.Cu")
		(net "UART_CTS_P6_N")
	)
	(segment
		(start 38.318186 -19.590258)
		(end 39.948866 -19.590258)
		(width 0.1143)
		(layer "In2.Cu")
		(net "UART_CTS_P6_N")
	)
	(segment
		(start 13.756132 -95.556324)
		(end 17.5133 -91.799156)
		(width 0.1143)
		(layer "In2.Cu")
		(net "UART_CTS_P6_N")
	)
	(segment
		(start 137.060178 -28.671774)
		(end 137.8458 -28.671774)
		(width 0.1143)
		(layer "In2.Cu")
		(net "UART_CTS_P6_N")
	)
	(segment
		(start 90.887296 -11.801856)
		(end 111.606076 -11.801856)
		(width 0.1143)
		(layer "In2.Cu")
		(net "UART_CTS_P6_N")
	)
	(segment
		(start 21.209 -59.107578)
		(end 21.209 -57.187846)
		(width 0.1143)
		(layer "In2.Cu")
		(net "UART_CTS_P6_N")
	)
	(segment
		(start 66.0654 -16.116554)
		(end 67.65544 -14.526514)
		(width 0.1143)
		(layer "In2.Cu")
		(net "UART_CTS_P6_N")
	)
	(segment
		(start 4.32816 -141.638528)
		(end 4.540504 -141.850872)
		(width 0.1016)
		(layer "F.Cu")
		(net "UART_DSR_P6_N")
	)
	(segment
		(start 4.32816 -140.90269)
		(end 4.32816 -141.638528)
		(width 0.1016)
		(layer "F.Cu")
		(net "UART_DSR_P6_N")
	)
	(segment
		(start 4.540504 -141.850872)
		(end 4.540504 -142.550642)
		(width 0.1016)
		(layer "F.Cu")
		(net "UART_DSR_P6_N")
	)
	(segment
		(start 140.0683 -26.212292)
		(end 140.069316 -26.212292)
		(width 0.1016)
		(layer "F.Cu")
		(net "UART_DSR_P6_N")
	)
	(segment
		(start 139.761722 -28.761944)
		(end 139.82446 -28.699206)
		(width 0.1016)
		(layer "F.Cu")
		(net "UART_DSR_P6_N")
	)
	(segment
		(start 139.82446 -28.699206)
		(end 140.0683 -28.455366)
		(width 0.1016)
		(layer "F.Cu")
		(net "UART_DSR_P6_N")
	)
	(segment
		(start 140.0683 -28.455366)
		(end 140.0683 -26.212292)
		(width 0.1016)
		(layer "F.Cu")
		(net "UART_DSR_P6_N")
	)
	(segment
		(start 139.761722 -30.079696)
		(end 139.761722 -28.761944)
		(width 0.1016)
		(layer "F.Cu")
		(net "UART_DSR_P6_N")
	)
	(segment
		(start 4.9403 -139.775438)
		(end 4.32816 -140.90269)
		(width 0.1016)
		(layer "F.Cu")
		(net "UART_DSR_P6_N")
	)
	(via
		(at 4.9403 -139.775438)
		(size 0.508)
		(drill 0.254)
		(layers "F.Cu" "B.Cu")
		(net "UART_DSR_P6_N")
	)
	(via
		(at 139.82446 -28.699206)
		(size 0.508)
		(drill 0.254)
		(layers "F.Cu" "B.Cu")
		(net "UART_DSR_P6_N")
	)
	(segment
		(start 134.80542 -26.010108)
		(end 136.924034 -28.128722)
		(width 0.1143)
		(layer "In2.Cu")
		(net "UART_DSR_P6_N")
	)
	(segment
		(start 87.396574 -11.374882)
		(end 87.397082 -11.374882)
		(width 0.1143)
		(layer "In2.Cu")
		(net "UART_DSR_P6_N")
	)
	(segment
		(start 20.30476 -59.584844)
		(end 20.92452 -58.965084)
		(width 0.1143)
		(layer "In2.Cu")
		(net "UART_DSR_P6_N")
	)
	(segment
		(start 66.224912 -15.578582)
		(end 67.54368 -14.259814)
		(width 0.1143)
		(layer "In2.Cu")
		(net "UART_DSR_P6_N")
	)
	(segment
		(start 39.55415 -18.577052)
		(end 53.349144 -18.577052)
		(width 0.1143)
		(layer "In2.Cu")
		(net "UART_DSR_P6_N")
	)
	(segment
		(start 90.7669 -11.161776)
		(end 91.14028 -11.535156)
		(width 0.1143)
		(layer "In2.Cu")
		(net "UART_DSR_P6_N")
	)
	(segment
		(start 67.54368 -14.259814)
		(end 79.893414 -14.259814)
		(width 0.1143)
		(layer "In2.Cu")
		(net "UART_DSR_P6_N")
	)
	(segment
		(start 19.63674 -61.480954)
		(end 19.63674 -60.181744)
		(width 0.1143)
		(layer "In2.Cu")
		(net "UART_DSR_P6_N")
	)
	(segment
		(start 22.42439 -54.401466)
		(end 22.42439 -45.03674)
		(width 0.1143)
		(layer "In2.Cu")
		(net "UART_DSR_P6_N")
	)
	(segment
		(start 36.89604 -20.641564)
		(end 36.89858 -20.638516)
		(width 0.1143)
		(layer "In2.Cu")
		(net "UART_DSR_P6_N")
	)
	(segment
		(start 111.95558 -11.535156)
		(end 113.0935 -12.673076)
		(width 0.1143)
		(layer "In2.Cu")
		(net "UART_DSR_P6_N")
	)
	(segment
		(start 124.082302 -13.577062)
		(end 134.80542 -24.30018)
		(width 0.1143)
		(layer "In2.Cu")
		(net "UART_DSR_P6_N")
	)
	(segment
		(start 20.92452 -58.965084)
		(end 20.92452 -55.87873)
		(width 0.1143)
		(layer "In2.Cu")
		(net "UART_DSR_P6_N")
	)
	(segment
		(start 22.42439 -45.03674)
		(end 23.10638 -44.35475)
		(width 0.1143)
		(layer "In2.Cu")
		(net "UART_DSR_P6_N")
	)
	(segment
		(start 36.906962 -20.624292)
		(end 38.207696 -19.323558)
		(width 0.1143)
		(layer "In2.Cu")
		(net "UART_DSR_P6_N")
	)
	(segment
		(start 26.53538 -38.754812)
		(end 26.53538 -34.98215)
		(width 0.1143)
		(layer "In2.Cu")
		(net "UART_DSR_P6_N")
	)
	(segment
		(start 63.66764 -15.947136)
		(end 64.036194 -15.578582)
		(width 0.1143)
		(layer "In2.Cu")
		(net "UART_DSR_P6_N")
	)
	(segment
		(start 136.924034 -28.128722)
		(end 138.077702 -28.128722)
		(width 0.1143)
		(layer "In2.Cu")
		(net "UART_DSR_P6_N")
	)
	(segment
		(start 17.16532 -91.768422)
		(end 17.16532 -86.275672)
		(width 0.1143)
		(layer "In2.Cu")
		(net "UART_DSR_P6_N")
	)
	(segment
		(start 4.9403 -139.775438)
		(end 4.79806 -139.633198)
		(width 0.1143)
		(layer "In2.Cu")
		(net "UART_DSR_P6_N")
	)
	(segment
		(start 20.92452 -55.87873)
		(end 21.630894 -55.172356)
		(width 0.1143)
		(layer "In2.Cu")
		(net "UART_DSR_P6_N")
	)
	(segment
		(start 119.617744 -13.577062)
		(end 124.082302 -13.577062)
		(width 0.1143)
		(layer "In2.Cu")
		(net "UART_DSR_P6_N")
	)
	(segment
		(start 4.79806 -139.633198)
		(end 4.79806 -102.76459)
		(width 0.1143)
		(layer "In2.Cu")
		(net "UART_DSR_P6_N")
	)
	(segment
		(start 12.273026 -95.289624)
		(end 13.644118 -95.289624)
		(width 0.1143)
		(layer "In2.Cu")
		(net "UART_DSR_P6_N")
	)
	(segment
		(start 13.644118 -95.289624)
		(end 17.16532 -91.768422)
		(width 0.1143)
		(layer "In2.Cu")
		(net "UART_DSR_P6_N")
	)
	(segment
		(start 91.14028 -11.535156)
		(end 111.95558 -11.535156)
		(width 0.1143)
		(layer "In2.Cu")
		(net "UART_DSR_P6_N")
	)
	(segment
		(start 55.97906 -15.947136)
		(end 63.66764 -15.947136)
		(width 0.1143)
		(layer "In2.Cu")
		(net "UART_DSR_P6_N")
	)
	(segment
		(start 79.893414 -14.259814)
		(end 87.34044 -11.430254)
		(width 0.1143)
		(layer "In2.Cu")
		(net "UART_DSR_P6_N")
	)
	(segment
		(start 20.2057 -62.049914)
		(end 19.63674 -61.480954)
		(width 0.1143)
		(layer "In2.Cu")
		(net "UART_DSR_P6_N")
	)
	(segment
		(start 87.61222 -11.161776)
		(end 90.7669 -11.161776)
		(width 0.1143)
		(layer "In2.Cu")
		(net "UART_DSR_P6_N")
	)
	(segment
		(start 53.349144 -18.577052)
		(end 55.97906 -15.947136)
		(width 0.1143)
		(layer "In2.Cu")
		(net "UART_DSR_P6_N")
	)
	(segment
		(start 21.21154 -66.443606)
		(end 21.21154 -65.136014)
		(width 0.1143)
		(layer "In2.Cu")
		(net "UART_DSR_P6_N")
	)
	(segment
		(start 23.10638 -44.35475)
		(end 23.10638 -42.183812)
		(width 0.1143)
		(layer "In2.Cu")
		(net "UART_DSR_P6_N")
	)
	(segment
		(start 64.036194 -15.578582)
		(end 66.224912 -15.578582)
		(width 0.1143)
		(layer "In2.Cu")
		(net "UART_DSR_P6_N")
	)
	(segment
		(start 38.207696 -19.323558)
		(end 38.807644 -19.323558)
		(width 0.1143)
		(layer "In2.Cu")
		(net "UART_DSR_P6_N")
	)
	(segment
		(start 36.89858 -20.638516)
		(end 36.906962 -20.624292)
		(width 0.1143)
		(layer "In2.Cu")
		(net "UART_DSR_P6_N")
	)
	(segment
		(start 21.6535 -55.172356)
		(end 22.42439 -54.401466)
		(width 0.1143)
		(layer "In2.Cu")
		(net "UART_DSR_P6_N")
	)
	(segment
		(start 113.0935 -12.673076)
		(end 118.713758 -12.673076)
		(width 0.1143)
		(layer "In2.Cu")
		(net "UART_DSR_P6_N")
	)
	(segment
		(start 138.648186 -28.699206)
		(end 139.82446 -28.699206)
		(width 0.1143)
		(layer "In2.Cu")
		(net "UART_DSR_P6_N")
	)
	(segment
		(start 19.63674 -60.181744)
		(end 20.23364 -59.584844)
		(width 0.1143)
		(layer "In2.Cu")
		(net "UART_DSR_P6_N")
	)
	(segment
		(start 34.79038 -26.72715)
		(end 34.79038 -23.826724)
		(width 0.1143)
		(layer "In2.Cu")
		(net "UART_DSR_P6_N")
	)
	(segment
		(start 87.398606 -11.373358)
		(end 87.61222 -11.161776)
		(width 0.1143)
		(layer "In2.Cu")
		(net "UART_DSR_P6_N")
	)
	(segment
		(start 26.53538 -34.98215)
		(end 34.79038 -26.72715)
		(width 0.1143)
		(layer "In2.Cu")
		(net "UART_DSR_P6_N")
	)
	(segment
		(start 21.630894 -55.172356)
		(end 21.6535 -55.172356)
		(width 0.1143)
		(layer "In2.Cu")
		(net "UART_DSR_P6_N")
	)
	(segment
		(start 21.21154 -65.136014)
		(end 20.2057 -64.130174)
		(width 0.1143)
		(layer "In2.Cu")
		(net "UART_DSR_P6_N")
	)
	(segment
		(start 36.59886 -21.089112)
		(end 36.89604 -20.641564)
		(width 0.1143)
		(layer "In2.Cu")
		(net "UART_DSR_P6_N")
	)
	(segment
		(start 21.78685 -81.654142)
		(end 21.78685 -67.018916)
		(width 0.1143)
		(layer "In2.Cu")
		(net "UART_DSR_P6_N")
	)
	(segment
		(start 20.23364 -59.584844)
		(end 20.30476 -59.584844)
		(width 0.1143)
		(layer "In2.Cu")
		(net "UART_DSR_P6_N")
	)
	(segment
		(start 134.80542 -24.30018)
		(end 134.80542 -26.010108)
		(width 0.1143)
		(layer "In2.Cu")
		(net "UART_DSR_P6_N")
	)
	(segment
		(start 23.10638 -42.183812)
		(end 26.53538 -38.754812)
		(width 0.1143)
		(layer "In2.Cu")
		(net "UART_DSR_P6_N")
	)
	(segment
		(start 4.79806 -102.76459)
		(end 12.273026 -95.289624)
		(width 0.1143)
		(layer "In2.Cu")
		(net "UART_DSR_P6_N")
	)
	(segment
		(start 21.78685 -67.018916)
		(end 21.21154 -66.443606)
		(width 0.1143)
		(layer "In2.Cu")
		(net "UART_DSR_P6_N")
	)
	(segment
		(start 118.713758 -12.673076)
		(end 119.617744 -13.577062)
		(width 0.1143)
		(layer "In2.Cu")
		(net "UART_DSR_P6_N")
	)
	(segment
		(start 20.2057 -64.130174)
		(end 20.2057 -62.049914)
		(width 0.1143)
		(layer "In2.Cu")
		(net "UART_DSR_P6_N")
	)
	(segment
		(start 87.34044 -11.430254)
		(end 87.396574 -11.374882)
		(width 0.1143)
		(layer "In2.Cu")
		(net "UART_DSR_P6_N")
	)
	(segment
		(start 38.807644 -19.323558)
		(end 39.55415 -18.577052)
		(width 0.1143)
		(layer "In2.Cu")
		(net "UART_DSR_P6_N")
	)
	(segment
		(start 17.16532 -86.275672)
		(end 21.78685 -81.654142)
		(width 0.1143)
		(layer "In2.Cu")
		(net "UART_DSR_P6_N")
	)
	(segment
		(start 34.79038 -23.826724)
		(end 36.59886 -21.089112)
		(width 0.1143)
		(layer "In2.Cu")
		(net "UART_DSR_P6_N")
	)
	(segment
		(start 138.077702 -28.128722)
		(end 138.648186 -28.699206)
		(width 0.1143)
		(layer "In2.Cu")
		(net "UART_DSR_P6_N")
	)
	(segment
		(start 87.397082 -11.374882)
		(end 87.398606 -11.373358)
		(width 0.1143)
		(layer "In2.Cu")
		(net "UART_DSR_P6_N")
	)
	(segment
		(start 3.908806 -158.220156)
		(end 3.898646 -158.209996)
		(width 0.1016)
		(layer "F.Cu")
		(net "UART_DSR_P5_N")
	)
	(segment
		(start 3.898646 -158.209996)
		(end 3.898646 -155.992068)
		(width 0.1016)
		(layer "F.Cu")
		(net "UART_DSR_P5_N")
	)
	(segment
		(start 125.76175 -44.6913)
		(end 125.76175 -47.199804)
		(width 0.1016)
		(layer "F.Cu")
		(net "UART_DSR_P5_N")
	)
	(segment
		(start 125.52934 -44.45889)
		(end 125.76175 -44.6913)
		(width 0.1016)
		(layer "F.Cu")
		(net "UART_DSR_P5_N")
	)
	(via
		(at 32.96412 -23.51532)
		(size 0.508)
		(drill 0.254)
		(layers "F.Cu" "B.Cu")
		(net "UART_DSR_P5_N")
	)
	(via
		(at 3.898646 -155.992068)
		(size 0.508)
		(drill 0.254)
		(layers "F.Cu" "B.Cu")
		(net "UART_DSR_P5_N")
	)
	(via
		(at 125.52934 -44.45889)
		(size 0.508)
		(drill 0.254)
		(layers "F.Cu" "B.Cu")
		(net "UART_DSR_P5_N")
	)
	(segment
		(start 19.533362 -52.131722)
		(end 19.71294 -51.243992)
		(width 0.1143)
		(layer "In2.Cu")
		(net "UART_DSR_P5_N")
	)
	(segment
		(start 19.71294 -51.243992)
		(end 19.71294 -48.597312)
		(width 0.1143)
		(layer "In2.Cu")
		(net "UART_DSR_P5_N")
	)
	(segment
		(start 20.10664 -46.919134)
		(end 20.11426 -46.886368)
		(width 0.1143)
		(layer "In2.Cu")
		(net "UART_DSR_P5_N")
	)
	(segment
		(start 17.40916 -67.774312)
		(end 17.40916 -57.265062)
		(width 0.1143)
		(layer "In2.Cu")
		(net "UART_DSR_P5_N")
	)
	(segment
		(start 3.57886 -154.688286)
		(end 2.98958 -152.68956)
		(width 0.1143)
		(layer "In2.Cu")
		(net "UART_DSR_P5_N")
	)
	(segment
		(start 15.28318 -85.04047)
		(end 16.114522 -76.035408)
		(width 0.1143)
		(layer "In2.Cu")
		(net "UART_DSR_P5_N")
	)
	(segment
		(start 17.40916 -57.265062)
		(end 17.42186 -57.169304)
		(width 0.1143)
		(layer "In2.Cu")
		(net "UART_DSR_P5_N")
	)
	(segment
		(start 20.11426 -43.699938)
		(end 20.20062 -43.445938)
		(width 0.1143)
		(layer "In2.Cu")
		(net "UART_DSR_P5_N")
	)
	(segment
		(start 17.42186 -57.169304)
		(end 18.55089 -54.581552)
		(width 0.1143)
		(layer "In2.Cu")
		(net "UART_DSR_P5_N")
	)
	(segment
		(start 15.28318 -89.761568)
		(end 15.28318 -85.04047)
		(width 0.1143)
		(layer "In2.Cu")
		(net "UART_DSR_P5_N")
	)
	(segment
		(start 16.73352 -72.081136)
		(end 16.736568 -72.060816)
		(width 0.1143)
		(layer "In2.Cu")
		(net "UART_DSR_P5_N")
	)
	(segment
		(start 19.713702 -48.595026)
		(end 19.75104 -48.436276)
		(width 0.1143)
		(layer "In2.Cu")
		(net "UART_DSR_P5_N")
	)
	(segment
		(start 32.01162 -26.967688)
		(end 33.03397 -25.14219)
		(width 0.1143)
		(layer "In2.Cu")
		(net "UART_DSR_P5_N")
	)
	(segment
		(start 19.75104 -48.436276)
		(end 19.75104 -48.434752)
		(width 0.1143)
		(layer "In2.Cu")
		(net "UART_DSR_P5_N")
	)
	(segment
		(start 16.736568 -72.060816)
		(end 17.40916 -67.774312)
		(width 0.1143)
		(layer "In2.Cu")
		(net "UART_DSR_P5_N")
	)
	(segment
		(start 20.11426 -46.886368)
		(end 20.11426 -43.699938)
		(width 0.1143)
		(layer "In2.Cu")
		(net "UART_DSR_P5_N")
	)
	(segment
		(start 24.7396 -38.076632)
		(end 24.7396 -34.239708)
		(width 0.1143)
		(layer "In2.Cu")
		(net "UART_DSR_P5_N")
	)
	(segment
		(start 33.03397 -25.14219)
		(end 33.03397 -23.58517)
		(width 0.1143)
		(layer "In2.Cu")
		(net "UART_DSR_P5_N")
	)
	(segment
		(start 18.55089 -54.581552)
		(end 19.533362 -52.131722)
		(width 0.1143)
		(layer "In2.Cu")
		(net "UART_DSR_P5_N")
	)
	(segment
		(start 3.57886 -155.316174)
		(end 3.57886 -154.688286)
		(width 0.1143)
		(layer "In2.Cu")
		(net "UART_DSR_P5_N")
	)
	(segment
		(start 3.898646 -155.992068)
		(end 3.57886 -155.316174)
		(width 0.1143)
		(layer "In2.Cu")
		(net "UART_DSR_P5_N")
	)
	(segment
		(start 24.7396 -34.239708)
		(end 32.01162 -26.967688)
		(width 0.1143)
		(layer "In2.Cu")
		(net "UART_DSR_P5_N")
	)
	(segment
		(start 19.71294 -48.597312)
		(end 19.713702 -48.595026)
		(width 0.1143)
		(layer "In2.Cu")
		(net "UART_DSR_P5_N")
	)
	(segment
		(start 2.98958 -102.055168)
		(end 15.28318 -89.761568)
		(width 0.1143)
		(layer "In2.Cu")
		(net "UART_DSR_P5_N")
	)
	(segment
		(start 19.75104 -48.434752)
		(end 20.10664 -46.919134)
		(width 0.1143)
		(layer "In2.Cu")
		(net "UART_DSR_P5_N")
	)
	(segment
		(start 16.114522 -76.035408)
		(end 16.73352 -72.081136)
		(width 0.1143)
		(layer "In2.Cu")
		(net "UART_DSR_P5_N")
	)
	(segment
		(start 20.20062 -43.445938)
		(end 21.309076 -41.507156)
		(width 0.1143)
		(layer "In2.Cu")
		(net "UART_DSR_P5_N")
	)
	(segment
		(start 2.98958 -152.68956)
		(end 2.98958 -102.055168)
		(width 0.1143)
		(layer "In2.Cu")
		(net "UART_DSR_P5_N")
	)
	(segment
		(start 21.309076 -41.507156)
		(end 24.7396 -38.076632)
		(width 0.1143)
		(layer "In2.Cu")
		(net "UART_DSR_P5_N")
	)
	(segment
		(start 33.03397 -23.58517)
		(end 32.96412 -23.51532)
		(width 0.1143)
		(layer "In2.Cu")
		(net "UART_DSR_P5_N")
	)
	(segment
		(start 104.88676 -20.804124)
		(end 40.88003 -20.804124)
		(width 0.1143)
		(layer "In6.Cu")
		(net "UART_DSR_P5_N")
	)
	(segment
		(start 39.865554 -21.812504)
		(end 39.53256 -21.962618)
		(width 0.1143)
		(layer "In6.Cu")
		(net "UART_DSR_P5_N")
	)
	(segment
		(start 121.912634 -39.63543)
		(end 120.533414 -38.25621)
		(width 0.1143)
		(layer "In6.Cu")
		(net "UART_DSR_P5_N")
	)
	(segment
		(start 111.737394 -31.570676)
		(end 111.53902 -31.157926)
		(width 0.1143)
		(layer "In6.Cu")
		(net "UART_DSR_P5_N")
	)
	(segment
		(start 39.53256 -21.962618)
		(end 38.85438 -22.268434)
		(width 0.1143)
		(layer "In6.Cu")
		(net "UART_DSR_P5_N")
	)
	(segment
		(start 124.46254 -43.568366)
		(end 124.04344 -43.568366)
		(width 0.1143)
		(layer "In6.Cu")
		(net "UART_DSR_P5_N")
	)
	(segment
		(start 40.88003 -20.804124)
		(end 39.87165 -21.812504)
		(width 0.1143)
		(layer "In6.Cu")
		(net "UART_DSR_P5_N")
	)
	(segment
		(start 112.625632 -32.458914)
		(end 111.737394 -31.570676)
		(width 0.1143)
		(layer "In6.Cu")
		(net "UART_DSR_P5_N")
	)
	(segment
		(start 122.367548 -41.892474)
		(end 122.182636 -41.226232)
		(width 0.1143)
		(layer "In6.Cu")
		(net "UART_DSR_P5_N")
	)
	(segment
		(start 125.076458 -44.006008)
		(end 124.8664 -43.890438)
		(width 0.1143)
		(layer "In6.Cu")
		(net "UART_DSR_P5_N")
	)
	(segment
		(start 120.533414 -38.25621)
		(end 120.491504 -38.25621)
		(width 0.1143)
		(layer "In6.Cu")
		(net "UART_DSR_P5_N")
	)
	(segment
		(start 111.53902 -30.422342)
		(end 108.52658 -24.443944)
		(width 0.1143)
		(layer "In6.Cu")
		(net "UART_DSR_P5_N")
	)
	(segment
		(start 124.8664 -43.890438)
		(end 124.46254 -43.568366)
		(width 0.1143)
		(layer "In6.Cu")
		(net "UART_DSR_P5_N")
	)
	(segment
		(start 118.11889 -36.635436)
		(end 112.625632 -32.458914)
		(width 0.1143)
		(layer "In6.Cu")
		(net "UART_DSR_P5_N")
	)
	(segment
		(start 36.444428 -22.483826)
		(end 35.51047 -23.417784)
		(width 0.1143)
		(layer "In6.Cu")
		(net "UART_DSR_P5_N")
	)
	(segment
		(start 39.87165 -21.812504)
		(end 39.865554 -21.812504)
		(width 0.1143)
		(layer "In6.Cu")
		(net "UART_DSR_P5_N")
	)
	(segment
		(start 124.04344 -43.568366)
		(end 122.367548 -41.892474)
		(width 0.1143)
		(layer "In6.Cu")
		(net "UART_DSR_P5_N")
	)
	(segment
		(start 35.51047 -23.417784)
		(end 33.061656 -23.417784)
		(width 0.1143)
		(layer "In6.Cu")
		(net "UART_DSR_P5_N")
	)
	(segment
		(start 120.491504 -38.25621)
		(end 118.11889 -36.635436)
		(width 0.1143)
		(layer "In6.Cu")
		(net "UART_DSR_P5_N")
	)
	(segment
		(start 38.37686 -22.483826)
		(end 36.444428 -22.483826)
		(width 0.1143)
		(layer "In6.Cu")
		(net "UART_DSR_P5_N")
	)
	(segment
		(start 125.52934 -44.45889)
		(end 125.076458 -44.006008)
		(width 0.1143)
		(layer "In6.Cu")
		(net "UART_DSR_P5_N")
	)
	(segment
		(start 122.182636 -41.226232)
		(end 121.912634 -39.63543)
		(width 0.1143)
		(layer "In6.Cu")
		(net "UART_DSR_P5_N")
	)
	(segment
		(start 33.061656 -23.417784)
		(end 32.96412 -23.51532)
		(width 0.1143)
		(layer "In6.Cu")
		(net "UART_DSR_P5_N")
	)
	(segment
		(start 111.53902 -31.157926)
		(end 111.53902 -30.422342)
		(width 0.1143)
		(layer "In6.Cu")
		(net "UART_DSR_P5_N")
	)
	(segment
		(start 108.52658 -24.443944)
		(end 104.88676 -20.804124)
		(width 0.1143)
		(layer "In6.Cu")
		(net "UART_DSR_P5_N")
	)
	(segment
		(start 38.85438 -22.268434)
		(end 38.37686 -22.483826)
		(width 0.1143)
		(layer "In6.Cu")
		(net "UART_DSR_P5_N")
	)
	(segment
		(start 127.761746 -47.199804)
		(end 127.761746 -45.857414)
		(width 0.1016)
		(layer "F.Cu")
		(net "UART_CTS_P5_N")
	)
	(segment
		(start 127.761746 -47.199804)
		(end 127.761746 -49.985422)
		(width 0.1016)
		(layer "F.Cu")
		(net "UART_CTS_P5_N")
	)
	(segment
		(start 128.029208 -50.252884)
		(end 128.029208 -51.345084)
		(width 0.1016)
		(layer "F.Cu")
		(net "UART_CTS_P5_N")
	)
	(segment
		(start 3.04292 -156.960824)
		(end 3.25882 -157.176724)
		(width 0.1016)
		(layer "F.Cu")
		(net "UART_CTS_P5_N")
	)
	(segment
		(start 3.25882 -157.176724)
		(end 3.25882 -158.220156)
		(width 0.1016)
		(layer "F.Cu")
		(net "UART_CTS_P5_N")
	)
	(segment
		(start 127.761746 -49.985422)
		(end 128.029208 -50.252884)
		(width 0.1016)
		(layer "F.Cu")
		(net "UART_CTS_P5_N")
	)
	(via
		(at 3.04292 -156.960824)
		(size 0.508)
		(drill 0.254)
		(layers "F.Cu" "B.Cu")
		(net "UART_CTS_P5_N")
	)
	(via
		(at 127.761746 -45.857414)
		(size 0.508)
		(drill 0.254)
		(layers "F.Cu" "B.Cu")
		(net "UART_CTS_P5_N")
	)
	(via
		(at 32.59582 -24.98344)
		(size 0.508)
		(drill 0.254)
		(layers "F.Cu" "B.Cu")
		(net "UART_CTS_P5_N")
	)
	(segment
		(start 24.4729 -33.977834)
		(end 31.471108 -26.979626)
		(width 0.1143)
		(layer "In2.Cu")
		(net "UART_CTS_P5_N")
	)
	(segment
		(start 19.95424 -43.335702)
		(end 21.1709 -41.210484)
		(width 0.1143)
		(layer "In2.Cu")
		(net "UART_CTS_P5_N")
	)
	(segment
		(start 19.46529 -48.476154)
		(end 19.581622 -47.979838)
		(width 0.1143)
		(layer "In2.Cu")
		(net "UART_CTS_P5_N")
	)
	(segment
		(start 2.69494 -153.197052)
		(end 2.69367 -153.195782)
		(width 0.1143)
		(layer "In2.Cu")
		(net "UART_CTS_P5_N")
	)
	(segment
		(start 3.72618 -98.270314)
		(end 4.072636 -98.61677)
		(width 0.1143)
		(layer "In2.Cu")
		(net "UART_CTS_P5_N")
	)
	(segment
		(start 2.69367 -150.057612)
		(end 2.69494 -150.056342)
		(width 0.1143)
		(layer "In2.Cu")
		(net "UART_CTS_P5_N")
	)
	(segment
		(start 3.36169 -98.270314)
		(end 3.72618 -98.270314)
		(width 0.1143)
		(layer "In2.Cu")
		(net "UART_CTS_P5_N")
	)
	(segment
		(start 15.121636 -80.627474)
		(end 15.71117 -76.871068)
		(width 0.1143)
		(layer "In2.Cu")
		(net "UART_CTS_P5_N")
	)
	(segment
		(start 17.14246 -57.155842)
		(end 17.16278 -57.095898)
		(width 0.1143)
		(layer "In2.Cu")
		(net "UART_CTS_P5_N")
	)
	(segment
		(start 3.04292 -155.496006)
		(end 2.69494 -153.197052)
		(width 0.1143)
		(layer "In2.Cu")
		(net "UART_CTS_P5_N")
	)
	(segment
		(start 15.07744 -80.908398)
		(end 15.07744 -80.908144)
		(width 0.1143)
		(layer "In2.Cu")
		(net "UART_CTS_P5_N")
	)
	(segment
		(start 2.69367 -153.195782)
		(end 2.69367 -150.057612)
		(width 0.1143)
		(layer "In2.Cu")
		(net "UART_CTS_P5_N")
	)
	(segment
		(start 2.69494 -100.595938)
		(end 3.093974 -98.53803)
		(width 0.1143)
		(layer "In2.Cu")
		(net "UART_CTS_P5_N")
	)
	(segment
		(start 19.30654 -49.10836)
		(end 19.30654 -49.084738)
		(width 0.1143)
		(layer "In2.Cu")
		(net "UART_CTS_P5_N")
	)
	(segment
		(start 3.093974 -98.53803)
		(end 3.36169 -98.270314)
		(width 0.1143)
		(layer "In2.Cu")
		(net "UART_CTS_P5_N")
	)
	(segment
		(start 31.471108 -26.979626)
		(end 32.59582 -24.98344)
		(width 0.1143)
		(layer "In2.Cu")
		(net "UART_CTS_P5_N")
	)
	(segment
		(start 24.4729 -37.908484)
		(end 24.4729 -33.977834)
		(width 0.1143)
		(layer "In2.Cu")
		(net "UART_CTS_P5_N")
	)
	(segment
		(start 19.331178 -49.059846)
		(end 19.44624 -48.566832)
		(width 0.1143)
		(layer "In2.Cu")
		(net "UART_CTS_P5_N")
	)
	(segment
		(start 15.01648 -89.640664)
		(end 15.01648 -81.296764)
		(width 0.1143)
		(layer "In2.Cu")
		(net "UART_CTS_P5_N")
	)
	(segment
		(start 16.4719 -72.02551)
		(end 17.14246 -67.753484)
		(width 0.1143)
		(layer "In2.Cu")
		(net "UART_CTS_P5_N")
	)
	(segment
		(start 18.32356 -52.094892)
		(end 18.48739 -51.3461)
		(width 0.1143)
		(layer "In2.Cu")
		(net "UART_CTS_P5_N")
	)
	(segment
		(start 2.69494 -150.056342)
		(end 2.69494 -100.595938)
		(width 0.1143)
		(layer "In2.Cu")
		(net "UART_CTS_P5_N")
	)
	(segment
		(start 19.44624 -48.558958)
		(end 19.46529 -48.476154)
		(width 0.1143)
		(layer "In2.Cu")
		(net "UART_CTS_P5_N")
	)
	(segment
		(start 15.01648 -81.296764)
		(end 15.07744 -80.908398)
		(width 0.1143)
		(layer "In2.Cu")
		(net "UART_CTS_P5_N")
	)
	(segment
		(start 19.581622 -47.979838)
		(end 19.84756 -44.484036)
		(width 0.1143)
		(layer "In2.Cu")
		(net "UART_CTS_P5_N")
	)
	(segment
		(start 18.48739 -51.3461)
		(end 19.30654 -49.10836)
		(width 0.1143)
		(layer "In2.Cu")
		(net "UART_CTS_P5_N")
	)
	(segment
		(start 19.84756 -43.655742)
		(end 19.95424 -43.335702)
		(width 0.1143)
		(layer "In2.Cu")
		(net "UART_CTS_P5_N")
	)
	(segment
		(start 16.451834 -72.154034)
		(end 16.451834 -72.152002)
		(width 0.1143)
		(layer "In2.Cu")
		(net "UART_CTS_P5_N")
	)
	(segment
		(start 17.92859 -55.338218)
		(end 18.086578 -54.626002)
		(width 0.1143)
		(layer "In2.Cu")
		(net "UART_CTS_P5_N")
	)
	(segment
		(start 19.30654 -49.084738)
		(end 19.331178 -49.059846)
		(width 0.1143)
		(layer "In2.Cu")
		(net "UART_CTS_P5_N")
	)
	(segment
		(start 17.14246 -67.753484)
		(end 17.14246 -57.155842)
		(width 0.1143)
		(layer "In2.Cu")
		(net "UART_CTS_P5_N")
	)
	(segment
		(start 17.16278 -57.095898)
		(end 17.92859 -55.338218)
		(width 0.1143)
		(layer "In2.Cu")
		(net "UART_CTS_P5_N")
	)
	(segment
		(start 3.04292 -156.960824)
		(end 3.04292 -155.496006)
		(width 0.1143)
		(layer "In2.Cu")
		(net "UART_CTS_P5_N")
	)
	(segment
		(start 16.451834 -72.152002)
		(end 16.4719 -72.02551)
		(width 0.1143)
		(layer "In2.Cu")
		(net "UART_CTS_P5_N")
	)
	(segment
		(start 18.086578 -54.626002)
		(end 18.32356 -52.228496)
		(width 0.1143)
		(layer "In2.Cu")
		(net "UART_CTS_P5_N")
	)
	(segment
		(start 15.07744 -80.908144)
		(end 15.121636 -80.627474)
		(width 0.1143)
		(layer "In2.Cu")
		(net "UART_CTS_P5_N")
	)
	(segment
		(start 4.072636 -98.61677)
		(end 6.040374 -98.61677)
		(width 0.1143)
		(layer "In2.Cu")
		(net "UART_CTS_P5_N")
	)
	(segment
		(start 15.711424 -76.870814)
		(end 16.451834 -72.154034)
		(width 0.1143)
		(layer "In2.Cu")
		(net "UART_CTS_P5_N")
	)
	(segment
		(start 19.84756 -44.484036)
		(end 19.84756 -43.655742)
		(width 0.1143)
		(layer "In2.Cu")
		(net "UART_CTS_P5_N")
	)
	(segment
		(start 6.040374 -98.61677)
		(end 15.01648 -89.640664)
		(width 0.1143)
		(layer "In2.Cu")
		(net "UART_CTS_P5_N")
	)
	(segment
		(start 21.1709 -41.210484)
		(end 24.4729 -37.908484)
		(width 0.1143)
		(layer "In2.Cu")
		(net "UART_CTS_P5_N")
	)
	(segment
		(start 18.32356 -52.228496)
		(end 18.32356 -52.094892)
		(width 0.1143)
		(layer "In2.Cu")
		(net "UART_CTS_P5_N")
	)
	(segment
		(start 15.71117 -76.871068)
		(end 15.711424 -76.870814)
		(width 0.1143)
		(layer "In2.Cu")
		(net "UART_CTS_P5_N")
	)
	(segment
		(start 19.44624 -48.566832)
		(end 19.44624 -48.558958)
		(width 0.1143)
		(layer "In2.Cu")
		(net "UART_CTS_P5_N")
	)
	(segment
		(start 123.522486 -44.693586)
		(end 121.10466 -41.81983)
		(width 0.1143)
		(layer "In6.Cu")
		(net "UART_CTS_P5_N")
	)
	(segment
		(start 104.33304 -21.540724)
		(end 41.520872 -21.540724)
		(width 0.1143)
		(layer "In6.Cu")
		(net "UART_CTS_P5_N")
	)
	(segment
		(start 41.520872 -21.540724)
		(end 39.610792 -23.450804)
		(width 0.1143)
		(layer "In6.Cu")
		(net "UART_CTS_P5_N")
	)
	(segment
		(start 107.76966 -26.686764)
		(end 107.76966 -24.977344)
		(width 0.1143)
		(layer "In6.Cu")
		(net "UART_CTS_P5_N")
	)
	(segment
		(start 107.76966 -24.977344)
		(end 104.33304 -21.540724)
		(width 0.1143)
		(layer "In6.Cu")
		(net "UART_CTS_P5_N")
	)
	(segment
		(start 110.80242 -30.672278)
		(end 107.76966 -26.686764)
		(width 0.1143)
		(layer "In6.Cu")
		(net "UART_CTS_P5_N")
	)
	(segment
		(start 112.975136 -34.016188)
		(end 110.80242 -31.843472)
		(width 0.1143)
		(layer "In6.Cu")
		(net "UART_CTS_P5_N")
	)
	(segment
		(start 126.337314 -46.107604)
		(end 124.46 -45.463714)
		(width 0.1143)
		(layer "In6.Cu")
		(net "UART_CTS_P5_N")
	)
	(segment
		(start 121.10466 -41.81983)
		(end 121.10466 -39.958772)
		(width 0.1143)
		(layer "In6.Cu")
		(net "UART_CTS_P5_N")
	)
	(segment
		(start 127.198628 -46.107604)
		(end 126.337314 -46.107604)
		(width 0.1143)
		(layer "In6.Cu")
		(net "UART_CTS_P5_N")
	)
	(segment
		(start 39.610792 -23.450804)
		(end 36.632896 -23.450804)
		(width 0.1143)
		(layer "In6.Cu")
		(net "UART_CTS_P5_N")
	)
	(segment
		(start 36.632896 -23.450804)
		(end 36.015168 -24.068532)
		(width 0.1143)
		(layer "In6.Cu")
		(net "UART_CTS_P5_N")
	)
	(segment
		(start 127.761746 -45.857414)
		(end 127.198628 -46.107604)
		(width 0.1143)
		(layer "In6.Cu")
		(net "UART_CTS_P5_N")
	)
	(segment
		(start 119.87403 -38.728142)
		(end 112.975136 -34.016188)
		(width 0.1143)
		(layer "In6.Cu")
		(net "UART_CTS_P5_N")
	)
	(segment
		(start 110.80242 -31.843472)
		(end 110.80242 -30.672278)
		(width 0.1143)
		(layer "In6.Cu")
		(net "UART_CTS_P5_N")
	)
	(segment
		(start 36.015168 -24.068532)
		(end 32.59582 -24.98344)
		(width 0.1143)
		(layer "In6.Cu")
		(net "UART_CTS_P5_N")
	)
	(segment
		(start 124.46 -45.463714)
		(end 123.522486 -44.693586)
		(width 0.1143)
		(layer "In6.Cu")
		(net "UART_CTS_P5_N")
	)
	(segment
		(start 121.10466 -39.958772)
		(end 119.87403 -38.728142)
		(width 0.1143)
		(layer "In6.Cu")
		(net "UART_CTS_P5_N")
	)
	(segment
		(start 9.500362 -160.923986)
		(end 11.91006 -160.923986)
		(width 0.1016)
		(layer "F.Cu")
		(net "UART_CTS_P5_L_N")
	)
	(segment
		(start 7.15899 -163.265358)
		(end 9.500362 -160.923986)
		(width 0.1016)
		(layer "F.Cu")
		(net "UART_CTS_P5_L_N")
	)
	(segment
		(start 37.9603 -198.228966)
		(end 37.61486 -198.574406)
		(width 0.1016)
		(layer "F.Cu")
		(net "UART_CTS_P5_L_N")
	)
	(segment
		(start 7.15899 -164.062156)
		(end 7.15899 -163.265358)
		(width 0.1016)
		(layer "F.Cu")
		(net "UART_CTS_P5_L_N")
	)
	(segment
		(start 11.91006 -160.923986)
		(end 11.91006 -160.925256)
		(width 0.1016)
		(layer "F.Cu")
		(net "UART_CTS_P5_L_N")
	)
	(segment
		(start 38.01491 -200.49109)
		(end 38.01491 -205.199488)
		(width 0.1016)
		(layer "F.Cu")
		(net "UART_CTS_P5_L_N")
	)
	(segment
		(start 37.61486 -198.574406)
		(end 37.61486 -200.09104)
		(width 0.1016)
		(layer "F.Cu")
		(net "UART_CTS_P5_L_N")
	)
	(segment
		(start 37.61486 -200.09104)
		(end 38.01491 -200.49109)
		(width 0.1016)
		(layer "F.Cu")
		(net "UART_CTS_P5_L_N")
	)
	(via
		(at 11.91006 -160.925256)
		(size 0.508)
		(drill 0.254)
		(layers "F.Cu" "B.Cu")
		(net "UART_CTS_P5_L_N")
	)
	(via
		(at 37.9603 -198.228966)
		(size 0.508)
		(drill 0.254)
		(layers "F.Cu" "B.Cu")
		(net "UART_CTS_P5_L_N")
	)
	(segment
		(start 37.9603 -198.228966)
		(end 37.9603 -197.704202)
		(width 0.1143)
		(layer "In2.Cu")
		(net "UART_CTS_P5_L_N")
	)
	(segment
		(start 13.081254 -160.925256)
		(end 11.91006 -160.925256)
		(width 0.1143)
		(layer "In2.Cu")
		(net "UART_CTS_P5_L_N")
	)
	(segment
		(start 28.485338 -181.158134)
		(end 29.434536 -180.208936)
		(width 0.1143)
		(layer "In2.Cu")
		(net "UART_CTS_P5_L_N")
	)
	(segment
		(start 28.485338 -189.37605)
		(end 28.485338 -181.158134)
		(width 0.1143)
		(layer "In2.Cu")
		(net "UART_CTS_P5_L_N")
	)
	(segment
		(start 14.632178 -162.47618)
		(end 13.081254 -160.925256)
		(width 0.1143)
		(layer "In2.Cu")
		(net "UART_CTS_P5_L_N")
	)
	(segment
		(start 15.946882 -162.47618)
		(end 14.632178 -162.47618)
		(width 0.1143)
		(layer "In2.Cu")
		(net "UART_CTS_P5_L_N")
	)
	(segment
		(start 29.434536 -175.963834)
		(end 15.946882 -162.47618)
		(width 0.1143)
		(layer "In2.Cu")
		(net "UART_CTS_P5_L_N")
	)
	(segment
		(start 29.434536 -180.208936)
		(end 29.434536 -175.963834)
		(width 0.1143)
		(layer "In2.Cu")
		(net "UART_CTS_P5_L_N")
	)
	(segment
		(start 31.334202 -191.078104)
		(end 30.187392 -191.078104)
		(width 0.1143)
		(layer "In2.Cu")
		(net "UART_CTS_P5_L_N")
	)
	(segment
		(start 37.9603 -197.704202)
		(end 31.334202 -191.078104)
		(width 0.1143)
		(layer "In2.Cu")
		(net "UART_CTS_P5_L_N")
	)
	(segment
		(start 30.187392 -191.078104)
		(end 28.485338 -189.37605)
		(width 0.1143)
		(layer "In2.Cu")
		(net "UART_CTS_P5_L_N")
	)
	(segment
		(start 8.802116 -145.849848)
		(end 12.60348 -145.849848)
		(width 0.1016)
		(layer "F.Cu")
		(net "UART_CTS_P6_L_N")
	)
	(segment
		(start 7.790688 -146.861276)
		(end 8.802116 -145.849848)
		(width 0.1016)
		(layer "F.Cu")
		(net "UART_CTS_P6_L_N")
	)
	(segment
		(start 7.790688 -148.392642)
		(end 7.790688 -146.861276)
		(width 0.1016)
		(layer "F.Cu")
		(net "UART_CTS_P6_L_N")
	)
	(via
		(at 12.60348 -145.849848)
		(size 0.508)
		(drill 0.254)
		(layers "F.Cu" "B.Cu")
		(net "UART_CTS_P6_L_N")
	)
	(via
		(at 38.05174 -199.099932)
		(size 0.508)
		(drill 0.254)
		(layers "F.Cu" "B.Cu")
		(net "UART_CTS_P6_L_N")
	)
	(segment
		(start 38.01491 -205.199488)
		(end 38.01491 -199.136762)
		(width 0.1016)
		(layer "B.Cu")
		(net "UART_CTS_P6_L_N")
	)
	(segment
		(start 38.01491 -199.136762)
		(end 38.05174 -199.099932)
		(width 0.1016)
		(layer "B.Cu")
		(net "UART_CTS_P6_L_N")
	)
	(segment
		(start 12.946126 -160.410652)
		(end 14.744954 -162.20948)
		(width 0.1143)
		(layer "In2.Cu")
		(net "UART_CTS_P6_L_N")
	)
	(segment
		(start 29.701236 -175.853344)
		(end 29.701236 -180.564536)
		(width 0.1143)
		(layer "In2.Cu")
		(net "UART_CTS_P6_L_N")
	)
	(segment
		(start 38.4048 -198.746872)
		(end 38.05174 -199.099932)
		(width 0.1143)
		(layer "In2.Cu")
		(net "UART_CTS_P6_L_N")
	)
	(segment
		(start 28.752038 -189.26556)
		(end 30.297882 -190.811404)
		(width 0.1143)
		(layer "In2.Cu")
		(net "UART_CTS_P6_L_N")
	)
	(segment
		(start 38.4048 -197.607428)
		(end 38.4048 -198.746872)
		(width 0.1143)
		(layer "In2.Cu")
		(net "UART_CTS_P6_L_N")
	)
	(segment
		(start 30.297882 -190.811404)
		(end 31.608776 -190.811404)
		(width 0.1143)
		(layer "In2.Cu")
		(net "UART_CTS_P6_L_N")
	)
	(segment
		(start 28.752038 -181.513734)
		(end 28.752038 -189.26556)
		(width 0.1143)
		(layer "In2.Cu")
		(net "UART_CTS_P6_L_N")
	)
	(segment
		(start 13.05687 -155.062682)
		(end 11.62177 -156.497782)
		(width 0.1143)
		(layer "In2.Cu")
		(net "UART_CTS_P6_L_N")
	)
	(segment
		(start 31.608776 -190.811404)
		(end 38.4048 -197.607428)
		(width 0.1143)
		(layer "In2.Cu")
		(net "UART_CTS_P6_L_N")
	)
	(segment
		(start 12.579096 -160.410652)
		(end 12.946126 -160.410652)
		(width 0.1143)
		(layer "In2.Cu")
		(net "UART_CTS_P6_L_N")
	)
	(segment
		(start 12.60348 -145.849848)
		(end 13.05687 -146.303238)
		(width 0.1143)
		(layer "In2.Cu")
		(net "UART_CTS_P6_L_N")
	)
	(segment
		(start 11.62177 -159.453326)
		(end 12.579096 -160.410652)
		(width 0.1143)
		(layer "In2.Cu")
		(net "UART_CTS_P6_L_N")
	)
	(segment
		(start 29.701236 -180.564536)
		(end 28.752038 -181.513734)
		(width 0.1143)
		(layer "In2.Cu")
		(net "UART_CTS_P6_L_N")
	)
	(segment
		(start 11.62177 -156.497782)
		(end 11.62177 -159.453326)
		(width 0.1143)
		(layer "In2.Cu")
		(net "UART_CTS_P6_L_N")
	)
	(segment
		(start 13.05687 -146.303238)
		(end 13.05687 -155.062682)
		(width 0.1143)
		(layer "In2.Cu")
		(net "UART_CTS_P6_L_N")
	)
	(segment
		(start 16.057372 -162.20948)
		(end 29.701236 -175.853344)
		(width 0.1143)
		(layer "In2.Cu")
		(net "UART_CTS_P6_L_N")
	)
	(segment
		(start 14.744954 -162.20948)
		(end 16.057372 -162.20948)
		(width 0.1143)
		(layer "In2.Cu")
		(net "UART_CTS_P6_L_N")
	)
	(segment
		(start 13.810996 -147.338796)
		(end 14.49578 -147.338796)
		(width 0.1016)
		(layer "F.Cu")
		(net "UART_DSR_P6_L_N")
	)
	(segment
		(start 9.283954 -146.287236)
		(end 12.759436 -146.287236)
		(width 0.1016)
		(layer "F.Cu")
		(net "UART_DSR_P6_L_N")
	)
	(segment
		(start 8.440674 -147.130516)
		(end 9.283954 -146.287236)
		(width 0.1016)
		(layer "F.Cu")
		(net "UART_DSR_P6_L_N")
	)
	(segment
		(start 8.440674 -148.392642)
		(end 8.440674 -147.130516)
		(width 0.1016)
		(layer "F.Cu")
		(net "UART_DSR_P6_L_N")
	)
	(segment
		(start 12.759436 -146.287236)
		(end 13.810996 -147.338796)
		(width 0.1016)
		(layer "F.Cu")
		(net "UART_DSR_P6_L_N")
	)
	(via
		(at 14.49578 -147.338796)
		(size 0.508)
		(drill 0.254)
		(layers "F.Cu" "B.Cu")
		(net "UART_DSR_P6_L_N")
	)
	(via
		(at 42.5069 -197.630796)
		(size 0.508)
		(drill 0.254)
		(layers "F.Cu" "B.Cu")
		(net "UART_DSR_P6_L_N")
	)
	(segment
		(start 42.014902 -199.766428)
		(end 42.014902 -205.199488)
		(width 0.1016)
		(layer "B.Cu")
		(net "UART_DSR_P6_L_N")
	)
	(segment
		(start 42.5069 -197.630796)
		(end 42.5069 -199.27443)
		(width 0.1016)
		(layer "B.Cu")
		(net "UART_DSR_P6_L_N")
	)
	(segment
		(start 42.5069 -199.27443)
		(end 42.014902 -199.766428)
		(width 0.1016)
		(layer "B.Cu")
		(net "UART_DSR_P6_L_N")
	)
	(segment
		(start 22.55266 -155.194)
		(end 22.55266 -164.682932)
		(width 0.1143)
		(layer "In2.Cu")
		(net "UART_DSR_P6_L_N")
	)
	(segment
		(start 33.619186 -188.079634)
		(end 34.53384 -188.079634)
		(width 0.1143)
		(layer "In2.Cu")
		(net "UART_DSR_P6_L_N")
	)
	(segment
		(start 32.70377 -183.61914)
		(end 32.70377 -187.164218)
		(width 0.1143)
		(layer "In2.Cu")
		(net "UART_DSR_P6_L_N")
	)
	(segment
		(start 35.78098 -190.728854)
		(end 42.5069 -197.454774)
		(width 0.1143)
		(layer "In2.Cu")
		(net "UART_DSR_P6_L_N")
	)
	(segment
		(start 32.70377 -187.164218)
		(end 33.619186 -188.079634)
		(width 0.1143)
		(layer "In2.Cu")
		(net "UART_DSR_P6_L_N")
	)
	(segment
		(start 22.55266 -164.682932)
		(end 32.81172 -174.941992)
		(width 0.1143)
		(layer "In2.Cu")
		(net "UART_DSR_P6_L_N")
	)
	(segment
		(start 42.5069 -197.454774)
		(end 42.5069 -197.630796)
		(width 0.1143)
		(layer "In2.Cu")
		(net "UART_DSR_P6_L_N")
	)
	(segment
		(start 35.78098 -189.326774)
		(end 35.78098 -190.728854)
		(width 0.1143)
		(layer "In2.Cu")
		(net "UART_DSR_P6_L_N")
	)
	(segment
		(start 34.53384 -188.079634)
		(end 35.78098 -189.326774)
		(width 0.1143)
		(layer "In2.Cu")
		(net "UART_DSR_P6_L_N")
	)
	(segment
		(start 32.86633 -183.45658)
		(end 32.70377 -183.61914)
		(width 0.1143)
		(layer "In2.Cu")
		(net "UART_DSR_P6_L_N")
	)
	(segment
		(start 14.49578 -147.338796)
		(end 14.697456 -147.338796)
		(width 0.1143)
		(layer "In2.Cu")
		(net "UART_DSR_P6_L_N")
	)
	(segment
		(start 32.81172 -174.941992)
		(end 32.81172 -182.730902)
		(width 0.1143)
		(layer "In2.Cu")
		(net "UART_DSR_P6_L_N")
	)
	(segment
		(start 32.86633 -182.785512)
		(end 32.86633 -183.45658)
		(width 0.1143)
		(layer "In2.Cu")
		(net "UART_DSR_P6_L_N")
	)
	(segment
		(start 32.81172 -182.730902)
		(end 32.86633 -182.785512)
		(width 0.1143)
		(layer "In2.Cu")
		(net "UART_DSR_P6_L_N")
	)
	(segment
		(start 14.697456 -147.338796)
		(end 22.55266 -155.194)
		(width 0.1143)
		(layer "In2.Cu")
		(net "UART_DSR_P6_L_N")
	)
	(segment
		(start 7.808976 -163.276534)
		(end 9.445752 -161.639758)
		(width 0.1016)
		(layer "F.Cu")
		(net "UART_DSR_P5_L_N")
	)
	(segment
		(start 14.755114 -160.452816)
		(end 15.12062 -160.452816)
		(width 0.1016)
		(layer "F.Cu")
		(net "UART_DSR_P5_L_N")
	)
	(segment
		(start 12.437364 -161.120328)
		(end 14.087602 -161.120328)
		(width 0.1016)
		(layer "F.Cu")
		(net "UART_DSR_P5_L_N")
	)
	(segment
		(start 11.917934 -161.639758)
		(end 12.437364 -161.120328)
		(width 0.1016)
		(layer "F.Cu")
		(net "UART_DSR_P5_L_N")
	)
	(segment
		(start 7.808976 -164.062156)
		(end 7.808976 -163.276534)
		(width 0.1016)
		(layer "F.Cu")
		(net "UART_DSR_P5_L_N")
	)
	(segment
		(start 14.087602 -161.120328)
		(end 14.755114 -160.452816)
		(width 0.1016)
		(layer "F.Cu")
		(net "UART_DSR_P5_L_N")
	)
	(segment
		(start 43.14444 -198.649844)
		(end 42.014902 -199.779382)
		(width 0.1016)
		(layer "F.Cu")
		(net "UART_DSR_P5_L_N")
	)
	(segment
		(start 9.445752 -161.639758)
		(end 11.917934 -161.639758)
		(width 0.1016)
		(layer "F.Cu")
		(net "UART_DSR_P5_L_N")
	)
	(segment
		(start 42.014902 -199.779382)
		(end 42.014902 -205.199488)
		(width 0.1016)
		(layer "F.Cu")
		(net "UART_DSR_P5_L_N")
	)
	(via
		(at 15.12062 -160.452816)
		(size 0.508)
		(drill 0.254)
		(layers "F.Cu" "B.Cu")
		(net "UART_DSR_P5_L_N")
	)
	(via
		(at 43.14444 -198.649844)
		(size 0.508)
		(drill 0.254)
		(layers "F.Cu" "B.Cu")
		(net "UART_DSR_P5_L_N")
	)
	(segment
		(start 43.14444 -198.649844)
		(end 42.925746 -198.868538)
		(width 0.1143)
		(layer "In2.Cu")
		(net "UART_DSR_P5_L_N")
	)
	(segment
		(start 30.380178 -188.953648)
		(end 30.123638 -188.697108)
		(width 0.1143)
		(layer "In2.Cu")
		(net "UART_DSR_P5_L_N")
	)
	(segment
		(start 40.557958 -198.492364)
		(end 40.27932 -198.213726)
		(width 0.1143)
		(layer "In2.Cu")
		(net "UART_DSR_P5_L_N")
	)
	(segment
		(start 40.27932 -197.513448)
		(end 31.71952 -188.953648)
		(width 0.1143)
		(layer "In2.Cu")
		(net "UART_DSR_P5_L_N")
	)
	(segment
		(start 16.503142 -160.715198)
		(end 15.383002 -160.715198)
		(width 0.1143)
		(layer "In2.Cu")
		(net "UART_DSR_P5_L_N")
	)
	(segment
		(start 31.71952 -188.953648)
		(end 30.380178 -188.953648)
		(width 0.1143)
		(layer "In2.Cu")
		(net "UART_DSR_P5_L_N")
	)
	(segment
		(start 42.925746 -198.868538)
		(end 41.63441 -198.868538)
		(width 0.1143)
		(layer "In2.Cu")
		(net "UART_DSR_P5_L_N")
	)
	(segment
		(start 41.258236 -198.492364)
		(end 40.557958 -198.492364)
		(width 0.1143)
		(layer "In2.Cu")
		(net "UART_DSR_P5_L_N")
	)
	(segment
		(start 15.383002 -160.715198)
		(end 15.12062 -160.452816)
		(width 0.1143)
		(layer "In2.Cu")
		(net "UART_DSR_P5_L_N")
	)
	(segment
		(start 30.123638 -187.356242)
		(end 30.93466 -186.54522)
		(width 0.1143)
		(layer "In2.Cu")
		(net "UART_DSR_P5_L_N")
	)
	(segment
		(start 30.93466 -182.65394)
		(end 31.072836 -182.515764)
		(width 0.1143)
		(layer "In2.Cu")
		(net "UART_DSR_P5_L_N")
	)
	(segment
		(start 31.072836 -175.284892)
		(end 16.503142 -160.715198)
		(width 0.1143)
		(layer "In2.Cu")
		(net "UART_DSR_P5_L_N")
	)
	(segment
		(start 30.123638 -188.697108)
		(end 30.123638 -187.356242)
		(width 0.1143)
		(layer "In2.Cu")
		(net "UART_DSR_P5_L_N")
	)
	(segment
		(start 30.93466 -186.54522)
		(end 30.93466 -182.65394)
		(width 0.1143)
		(layer "In2.Cu")
		(net "UART_DSR_P5_L_N")
	)
	(segment
		(start 40.27932 -198.213726)
		(end 40.27932 -197.513448)
		(width 0.1143)
		(layer "In2.Cu")
		(net "UART_DSR_P5_L_N")
	)
	(segment
		(start 31.072836 -182.515764)
		(end 31.072836 -175.284892)
		(width 0.1143)
		(layer "In2.Cu")
		(net "UART_DSR_P5_L_N")
	)
	(segment
		(start 41.63441 -198.868538)
		(end 41.258236 -198.492364)
		(width 0.1143)
		(layer "In2.Cu")
		(net "UART_DSR_P5_L_N")
	)
	(segment
		(start 162.015678 -205.199488)
		(end 162.015678 -199.380856)
		(width 0.1016)
		(layer "F.Cu")
		(net "UART_CTS_RP5_L_N")
	)
	(segment
		(start 162.015678 -199.380856)
		(end 160.53562 -197.900798)
		(width 0.1016)
		(layer "F.Cu")
		(net "UART_CTS_RP5_L_N")
	)
	(via
		(at 160.53562 -197.900798)
		(size 0.508)
		(drill 0.254)
		(layers "F.Cu" "B.Cu")
		(net "UART_CTS_RP5_L_N")
	)
	(segment
		(start 160.406588 -198.02983)
		(end 160.53562 -197.900798)
		(width 0.1016)
		(layer "B.Cu")
		(net "UART_CTS_RP5_L_N")
	)
	(segment
		(start 160.406588 -198.841614)
		(end 160.406588 -198.02983)
		(width 0.1016)
		(layer "B.Cu")
		(net "UART_CTS_RP5_L_N")
	)
	(segment
		(start 165.661848 -199.8218)
		(end 165.661848 -200.360788)
		(width 0.1016)
		(layer "F.Cu")
		(net "UART_DSR_RP5_L")
	)
	(segment
		(start 166.01567 -200.71461)
		(end 166.01567 -205.199488)
		(width 0.1016)
		(layer "F.Cu")
		(net "UART_DSR_RP5_L")
	)
	(segment
		(start 165.661848 -200.360788)
		(end 166.01567 -200.71461)
		(width 0.1016)
		(layer "F.Cu")
		(net "UART_DSR_RP5_L")
	)
	(via
		(at 165.661848 -199.8218)
		(size 0.508)
		(drill 0.254)
		(layers "F.Cu" "B.Cu")
		(net "UART_DSR_RP5_L")
	)
	(segment
		(start 165.661848 -199.27697)
		(end 165.420548 -199.03567)
		(width 0.1016)
		(layer "B.Cu")
		(net "UART_DSR_RP5_L")
	)
	(segment
		(start 165.661848 -199.8218)
		(end 165.661848 -199.27697)
		(width 0.1016)
		(layer "B.Cu")
		(net "UART_DSR_RP5_L")
	)
	(via
		(at 161.64306 -196.95033)
		(size 0.508)
		(drill 0.254)
		(layers "F.Cu" "B.Cu")
		(net "UART_CTS_RP6_L")
	)
	(segment
		(start 161.64306 -196.95033)
		(end 161.64306 -200.221088)
		(width 0.1016)
		(layer "B.Cu")
		(net "UART_CTS_RP6_L")
	)
	(segment
		(start 161.64306 -200.221088)
		(end 163.015676 -201.593704)
		(width 0.1016)
		(layer "B.Cu")
		(net "UART_CTS_RP6_L")
	)
	(segment
		(start 161.458148 -196.09943)
		(end 161.458148 -196.765418)
		(width 0.1016)
		(layer "B.Cu")
		(net "UART_CTS_RP6_L")
	)
	(segment
		(start 163.015676 -201.593704)
		(end 163.015676 -205.199488)
		(width 0.1016)
		(layer "B.Cu")
		(net "UART_CTS_RP6_L")
	)
	(segment
		(start 161.458148 -196.765418)
		(end 161.64306 -196.95033)
		(width 0.1016)
		(layer "B.Cu")
		(net "UART_CTS_RP6_L")
	)
	(via
		(at 166.88054 -199.653906)
		(size 0.508)
		(drill 0.254)
		(layers "F.Cu" "B.Cu")
		(net "UART_DSR_RP6_L_N")
	)
	(segment
		(start 166.88054 -199.653906)
		(end 166.88054 -200.990708)
		(width 0.1016)
		(layer "B.Cu")
		(net "UART_DSR_RP6_L_N")
	)
	(segment
		(start 167.015668 -201.125836)
		(end 167.015668 -205.199488)
		(width 0.1016)
		(layer "B.Cu")
		(net "UART_DSR_RP6_L_N")
	)
	(segment
		(start 166.88054 -200.990708)
		(end 167.015668 -201.125836)
		(width 0.1016)
		(layer "B.Cu")
		(net "UART_DSR_RP6_L_N")
	)
	(segment
		(start 167.000428 -199.534018)
		(end 166.88054 -199.653906)
		(width 0.1016)
		(layer "B.Cu")
		(net "UART_DSR_RP6_L_N")
	)
	(segment
		(start 167.000428 -198.83247)
		(end 167.000428 -199.534018)
		(width 0.1016)
		(layer "B.Cu")
		(net "UART_DSR_RP6_L_N")
	)
	(segment
		(start 114.76736 -169.371518)
		(end 113.898426 -169.371518)
		(width 0.1016)
		(layer "F.Cu")
		(net "I2C_PSU2_SCL_MOS")
	)
	(segment
		(start 113.898426 -169.371518)
		(end 113.255044 -170.0149)
		(width 0.1016)
		(layer "F.Cu")
		(net "I2C_PSU2_SCL_MOS")
	)
	(segment
		(start 108.790994 -161.703258)
		(end 108.790994 -162.73272)
		(width 0.1016)
		(layer "F.Cu")
		(net "I2C_PSU2_SCL_MOS")
	)
	(segment
		(start 112.27181 -169.577512)
		(end 112.709198 -170.0149)
		(width 0.1016)
		(layer "F.Cu")
		(net "I2C_PSU2_SCL_MOS")
	)
	(segment
		(start 110.408974 -161.411158)
		(end 109.083094 -161.411158)
		(width 0.1016)
		(layer "F.Cu")
		(net "I2C_PSU2_SCL_MOS")
	)
	(segment
		(start 109.083094 -161.411158)
		(end 108.790994 -161.703258)
		(width 0.1016)
		(layer "F.Cu")
		(net "I2C_PSU2_SCL_MOS")
	)
	(segment
		(start 113.255044 -170.0149)
		(end 112.892332 -170.0149)
		(width 0.1016)
		(layer "F.Cu")
		(net "I2C_PSU2_SCL_MOS")
	)
	(segment
		(start 110.408974 -163.230306)
		(end 110.408974 -161.411158)
		(width 0.1016)
		(layer "F.Cu")
		(net "I2C_PSU2_SCL_MOS")
	)
	(segment
		(start 112.709198 -170.0149)
		(end 112.892332 -170.0149)
		(width 0.1016)
		(layer "F.Cu")
		(net "I2C_PSU2_SCL_MOS")
	)
	(via
		(at 110.408974 -163.230306)
		(size 0.508)
		(drill 0.254)
		(layers "F.Cu" "B.Cu")
		(net "I2C_PSU2_SCL_MOS")
	)
	(via
		(at 112.892332 -170.0149)
		(size 0.508)
		(drill 0.254)
		(layers "F.Cu" "B.Cu")
		(net "I2C_PSU2_SCL_MOS")
	)
	(segment
		(start 110.782608 -166.08298)
		(end 109.33557 -164.635942)
		(width 0.1143)
		(layer "In6.Cu")
		(net "I2C_PSU2_SCL_MOS")
	)
	(segment
		(start 111.2901 -166.454582)
		(end 110.918498 -166.08298)
		(width 0.1143)
		(layer "In6.Cu")
		(net "I2C_PSU2_SCL_MOS")
	)
	(segment
		(start 110.918498 -166.08298)
		(end 110.782608 -166.08298)
		(width 0.1143)
		(layer "In6.Cu")
		(net "I2C_PSU2_SCL_MOS")
	)
	(segment
		(start 111.2901 -168.412668)
		(end 111.2901 -166.454582)
		(width 0.1143)
		(layer "In6.Cu")
		(net "I2C_PSU2_SCL_MOS")
	)
	(segment
		(start 110.213648 -163.230306)
		(end 110.408974 -163.230306)
		(width 0.1143)
		(layer "In6.Cu")
		(net "I2C_PSU2_SCL_MOS")
	)
	(segment
		(start 112.892332 -170.0149)
		(end 111.2901 -168.412668)
		(width 0.1143)
		(layer "In6.Cu")
		(net "I2C_PSU2_SCL_MOS")
	)
	(segment
		(start 109.33557 -164.635942)
		(end 109.33557 -164.108384)
		(width 0.1143)
		(layer "In6.Cu")
		(net "I2C_PSU2_SCL_MOS")
	)
	(segment
		(start 109.33557 -164.108384)
		(end 110.213648 -163.230306)
		(width 0.1143)
		(layer "In6.Cu")
		(net "I2C_PSU2_SCL_MOS")
	)
	(segment
		(start 114.76736 -168.721532)
		(end 114.024664 -168.721532)
		(width 0.1016)
		(layer "F.Cu")
		(net "I2C_PSU2_SDA_MOS")
	)
	(segment
		(start 121.096786 -159.725614)
		(end 120.98528 -159.83712)
		(width 0.1016)
		(layer "F.Cu")
		(net "I2C_PSU2_SDA_MOS")
	)
	(segment
		(start 121.877328 -159.725614)
		(end 121.096786 -159.725614)
		(width 0.1016)
		(layer "F.Cu")
		(net "I2C_PSU2_SDA_MOS")
	)
	(segment
		(start 120.98528 -159.83712)
		(end 120.922034 -159.900366)
		(width 0.1016)
		(layer "F.Cu")
		(net "I2C_PSU2_SDA_MOS")
	)
	(segment
		(start 113.15446 -167.851328)
		(end 113.09858 -167.851328)
		(width 0.1016)
		(layer "F.Cu")
		(net "I2C_PSU2_SDA_MOS")
	)
	(segment
		(start 120.922034 -159.900366)
		(end 120.252744 -159.900366)
		(width 0.1016)
		(layer "F.Cu")
		(net "I2C_PSU2_SDA_MOS")
	)
	(segment
		(start 119.238776 -160.00476)
		(end 120.14835 -160.00476)
		(width 0.1016)
		(layer "F.Cu")
		(net "I2C_PSU2_SDA_MOS")
	)
	(segment
		(start 114.024664 -168.721532)
		(end 113.15446 -167.851328)
		(width 0.1016)
		(layer "F.Cu")
		(net "I2C_PSU2_SDA_MOS")
	)
	(segment
		(start 120.14835 -160.00476)
		(end 120.252744 -159.900366)
		(width 0.1016)
		(layer "F.Cu")
		(net "I2C_PSU2_SDA_MOS")
	)
	(via
		(at 120.98528 -159.83712)
		(size 0.508)
		(drill 0.254)
		(layers "F.Cu" "B.Cu")
		(net "I2C_PSU2_SDA_MOS")
	)
	(via
		(at 113.09858 -167.851328)
		(size 0.508)
		(drill 0.254)
		(layers "F.Cu" "B.Cu")
		(net "I2C_PSU2_SDA_MOS")
	)
	(segment
		(start 117.352064 -161.964624)
		(end 117.13464 -161.7472)
		(width 0.1143)
		(layer "In6.Cu")
		(net "I2C_PSU2_SDA_MOS")
	)
	(segment
		(start 112.2172 -166.715186)
		(end 113.09858 -167.596566)
		(width 0.1143)
		(layer "In6.Cu")
		(net "I2C_PSU2_SDA_MOS")
	)
	(segment
		(start 119.62384 -162.266376)
		(end 119.365776 -162.52444)
		(width 0.1143)
		(layer "In6.Cu")
		(net "I2C_PSU2_SDA_MOS")
	)
	(segment
		(start 118.890542 -162.52444)
		(end 118.330726 -161.964624)
		(width 0.1143)
		(layer "In6.Cu")
		(net "I2C_PSU2_SDA_MOS")
	)
	(segment
		(start 119.365776 -162.52444)
		(end 118.890542 -162.52444)
		(width 0.1143)
		(layer "In6.Cu")
		(net "I2C_PSU2_SDA_MOS")
	)
	(segment
		(start 120.98528 -159.83712)
		(end 119.62384 -161.19856)
		(width 0.1143)
		(layer "In6.Cu")
		(net "I2C_PSU2_SDA_MOS")
	)
	(segment
		(start 117.13464 -161.7472)
		(end 113.2078 -161.7472)
		(width 0.1143)
		(layer "In6.Cu")
		(net "I2C_PSU2_SDA_MOS")
	)
	(segment
		(start 119.62384 -161.19856)
		(end 119.62384 -162.266376)
		(width 0.1143)
		(layer "In6.Cu")
		(net "I2C_PSU2_SDA_MOS")
	)
	(segment
		(start 118.330726 -161.964624)
		(end 117.352064 -161.964624)
		(width 0.1143)
		(layer "In6.Cu")
		(net "I2C_PSU2_SDA_MOS")
	)
	(segment
		(start 113.2078 -161.7472)
		(end 112.2172 -162.7378)
		(width 0.1143)
		(layer "In6.Cu")
		(net "I2C_PSU2_SDA_MOS")
	)
	(segment
		(start 112.2172 -162.7378)
		(end 112.2172 -166.715186)
		(width 0.1143)
		(layer "In6.Cu")
		(net "I2C_PSU2_SDA_MOS")
	)
	(segment
		(start 113.09858 -167.596566)
		(end 113.09858 -167.851328)
		(width 0.1143)
		(layer "In6.Cu")
		(net "I2C_PSU2_SDA_MOS")
	)
	(segment
		(start 116.54028 -171.230798)
		(end 115.981226 -170.671744)
		(width 0.1016)
		(layer "F.Cu")
		(net "I2C_PSU1_SDA_MOS")
	)
	(segment
		(start 122.762772 -156.592016)
		(end 123.38939 -156.592016)
		(width 0.1016)
		(layer "F.Cu")
		(net "I2C_PSU1_SDA_MOS")
	)
	(segment
		(start 123.579128 -158.282132)
		(end 123.20524 -158.65602)
		(width 0.1016)
		(layer "F.Cu")
		(net "I2C_PSU1_SDA_MOS")
	)
	(segment
		(start 123.20524 -159.792162)
		(end 122.330972 -160.66643)
		(width 0.1016)
		(layer "F.Cu")
		(net "I2C_PSU1_SDA_MOS")
	)
	(segment
		(start 121.830592 -155.659328)
		(end 121.830592 -155.659836)
		(width 0.1016)
		(layer "F.Cu")
		(net "I2C_PSU1_SDA_MOS")
	)
	(segment
		(start 112.27181 -170.593512)
		(end 113.721388 -170.593512)
		(width 0.1016)
		(layer "F.Cu")
		(net "I2C_PSU1_SDA_MOS")
	)
	(segment
		(start 123.579128 -156.781754)
		(end 123.579128 -158.282132)
		(width 0.1016)
		(layer "F.Cu")
		(net "I2C_PSU1_SDA_MOS")
	)
	(segment
		(start 121.589038 -160.66643)
		(end 120.85828 -161.397188)
		(width 0.1016)
		(layer "F.Cu")
		(net "I2C_PSU1_SDA_MOS")
	)
	(segment
		(start 122.330972 -160.66643)
		(end 121.589038 -160.66643)
		(width 0.1016)
		(layer "F.Cu")
		(net "I2C_PSU1_SDA_MOS")
	)
	(segment
		(start 120.620536 -154.449272)
		(end 121.830592 -155.659328)
		(width 0.1016)
		(layer "F.Cu")
		(net "I2C_PSU1_SDA_MOS")
	)
	(segment
		(start 115.981226 -170.671744)
		(end 114.76736 -170.671744)
		(width 0.1016)
		(layer "F.Cu")
		(net "I2C_PSU1_SDA_MOS")
	)
	(segment
		(start 123.20524 -158.65602)
		(end 123.20524 -159.792162)
		(width 0.1016)
		(layer "F.Cu")
		(net "I2C_PSU1_SDA_MOS")
	)
	(segment
		(start 121.830592 -155.659836)
		(end 122.762772 -156.592016)
		(width 0.1016)
		(layer "F.Cu")
		(net "I2C_PSU1_SDA_MOS")
	)
	(segment
		(start 113.79962 -170.671744)
		(end 114.76736 -170.671744)
		(width 0.1016)
		(layer "F.Cu")
		(net "I2C_PSU1_SDA_MOS")
	)
	(segment
		(start 123.38939 -156.592016)
		(end 123.579128 -156.781754)
		(width 0.1016)
		(layer "F.Cu")
		(net "I2C_PSU1_SDA_MOS")
	)
	(segment
		(start 113.721388 -170.593512)
		(end 113.79962 -170.671744)
		(width 0.1016)
		(layer "F.Cu")
		(net "I2C_PSU1_SDA_MOS")
	)
	(segment
		(start 120.620536 -154.298904)
		(end 120.620536 -154.449272)
		(width 0.1016)
		(layer "F.Cu")
		(net "I2C_PSU1_SDA_MOS")
	)
	(via
		(at 120.85828 -161.397188)
		(size 0.508)
		(drill 0.254)
		(layers "F.Cu" "B.Cu")
		(net "I2C_PSU1_SDA_MOS")
	)
	(via
		(at 116.54028 -171.230798)
		(size 0.508)
		(drill 0.254)
		(layers "F.Cu" "B.Cu")
		(net "I2C_PSU1_SDA_MOS")
	)
	(segment
		(start 114.8461 -166.20363)
		(end 112.903 -164.26053)
		(width 0.1143)
		(layer "In6.Cu")
		(net "I2C_PSU1_SDA_MOS")
	)
	(segment
		(start 116.621814 -163.24072)
		(end 117.005862 -163.624768)
		(width 0.1143)
		(layer "In6.Cu")
		(net "I2C_PSU1_SDA_MOS")
	)
	(segment
		(start 117.005862 -163.624768)
		(end 118.86438 -163.624768)
		(width 0.1143)
		(layer "In6.Cu")
		(net "I2C_PSU1_SDA_MOS")
	)
	(segment
		(start 114.8461 -169.536618)
		(end 114.8461 -166.20363)
		(width 0.1143)
		(layer "In6.Cu")
		(net "I2C_PSU1_SDA_MOS")
	)
	(segment
		(start 119.002556 -163.486592)
		(end 119.301768 -163.486592)
		(width 0.1143)
		(layer "In6.Cu")
		(net "I2C_PSU1_SDA_MOS")
	)
	(segment
		(start 120.85828 -161.93008)
		(end 120.85828 -161.397188)
		(width 0.1143)
		(layer "In6.Cu")
		(net "I2C_PSU1_SDA_MOS")
	)
	(segment
		(start 112.903 -163.57981)
		(end 113.24209 -163.24072)
		(width 0.1143)
		(layer "In6.Cu")
		(net "I2C_PSU1_SDA_MOS")
	)
	(segment
		(start 119.301768 -163.486592)
		(end 120.85828 -161.93008)
		(width 0.1143)
		(layer "In6.Cu")
		(net "I2C_PSU1_SDA_MOS")
	)
	(segment
		(start 112.903 -164.26053)
		(end 112.903 -163.57981)
		(width 0.1143)
		(layer "In6.Cu")
		(net "I2C_PSU1_SDA_MOS")
	)
	(segment
		(start 113.24209 -163.24072)
		(end 116.621814 -163.24072)
		(width 0.1143)
		(layer "In6.Cu")
		(net "I2C_PSU1_SDA_MOS")
	)
	(segment
		(start 118.86438 -163.624768)
		(end 119.002556 -163.486592)
		(width 0.1143)
		(layer "In6.Cu")
		(net "I2C_PSU1_SDA_MOS")
	)
	(segment
		(start 116.54028 -171.230798)
		(end 114.8461 -169.536618)
		(width 0.1143)
		(layer "In6.Cu")
		(net "I2C_PSU1_SDA_MOS")
	)
	(segment
		(start 123.648724 -161.238184)
		(end 124.56922 -161.238184)
		(width 0.1016)
		(layer "F.Cu")
		(net "I2C_PSU1_SCL_MOS")
	)
	(segment
		(start 125.547628 -159.724344)
		(end 125.547628 -160.259776)
		(width 0.1016)
		(layer "F.Cu")
		(net "I2C_PSU1_SCL_MOS")
	)
	(segment
		(start 114.76736 -171.32173)
		(end 113.815368 -171.32173)
		(width 0.1016)
		(layer "F.Cu")
		(net "I2C_PSU1_SCL_MOS")
	)
	(segment
		(start 124.56922 -161.238184)
		(end 124.618242 -161.189162)
		(width 0.1016)
		(layer "F.Cu")
		(net "I2C_PSU1_SCL_MOS")
	)
	(segment
		(start 126.261876 -159.724344)
		(end 125.547628 -159.724344)
		(width 0.1016)
		(layer "F.Cu")
		(net "I2C_PSU1_SCL_MOS")
	)
	(segment
		(start 113.815368 -171.32173)
		(end 113.578894 -171.085256)
		(width 0.1016)
		(layer "F.Cu")
		(net "I2C_PSU1_SCL_MOS")
	)
	(segment
		(start 125.547628 -160.259776)
		(end 124.618242 -161.189162)
		(width 0.1016)
		(layer "F.Cu")
		(net "I2C_PSU1_SCL_MOS")
	)
	(segment
		(start 126.5809 -159.40532)
		(end 126.261876 -159.724344)
		(width 0.1016)
		(layer "F.Cu")
		(net "I2C_PSU1_SCL_MOS")
	)
	(via
		(at 113.578894 -171.085256)
		(size 0.508)
		(drill 0.254)
		(layers "F.Cu" "B.Cu")
		(net "I2C_PSU1_SCL_MOS")
	)
	(via
		(at 126.5809 -159.40532)
		(size 0.508)
		(drill 0.254)
		(layers "F.Cu" "B.Cu")
		(net "I2C_PSU1_SCL_MOS")
	)
	(segment
		(start 120.35536 -161.280348)
		(end 120.35536 -162.05581)
		(width 0.1143)
		(layer "In6.Cu")
		(net "I2C_PSU1_SCL_MOS")
	)
	(segment
		(start 117.343428 -162.97402)
		(end 113.1316 -162.97402)
		(width 0.1143)
		(layer "In6.Cu")
		(net "I2C_PSU1_SCL_MOS")
	)
	(segment
		(start 114.02949 -165.76421)
		(end 114.02949 -169.127932)
		(width 0.1143)
		(layer "In6.Cu")
		(net "I2C_PSU1_SCL_MOS")
	)
	(segment
		(start 121.702068 -159.93364)
		(end 120.35536 -161.280348)
		(width 0.1143)
		(layer "In6.Cu")
		(net "I2C_PSU1_SCL_MOS")
	)
	(segment
		(start 120.35536 -162.05581)
		(end 119.513604 -162.897566)
		(width 0.1143)
		(layer "In6.Cu")
		(net "I2C_PSU1_SCL_MOS")
	)
	(segment
		(start 112.5982 -163.50742)
		(end 112.5982 -164.33292)
		(width 0.1143)
		(layer "In6.Cu")
		(net "I2C_PSU1_SCL_MOS")
	)
	(segment
		(start 114.02949 -169.127932)
		(end 113.578894 -169.578528)
		(width 0.1143)
		(layer "In6.Cu")
		(net "I2C_PSU1_SCL_MOS")
	)
	(segment
		(start 112.5982 -164.33292)
		(end 114.02949 -165.76421)
		(width 0.1143)
		(layer "In6.Cu")
		(net "I2C_PSU1_SCL_MOS")
	)
	(segment
		(start 117.727476 -163.358068)
		(end 117.343428 -162.97402)
		(width 0.1143)
		(layer "In6.Cu")
		(net "I2C_PSU1_SCL_MOS")
	)
	(segment
		(start 113.1316 -162.97402)
		(end 112.5982 -163.50742)
		(width 0.1143)
		(layer "In6.Cu")
		(net "I2C_PSU1_SCL_MOS")
	)
	(segment
		(start 119.513604 -162.897566)
		(end 119.104918 -162.897566)
		(width 0.1143)
		(layer "In6.Cu")
		(net "I2C_PSU1_SCL_MOS")
	)
	(segment
		(start 119.104918 -162.897566)
		(end 118.644416 -163.358068)
		(width 0.1143)
		(layer "In6.Cu")
		(net "I2C_PSU1_SCL_MOS")
	)
	(segment
		(start 118.644416 -163.358068)
		(end 117.727476 -163.358068)
		(width 0.1143)
		(layer "In6.Cu")
		(net "I2C_PSU1_SCL_MOS")
	)
	(segment
		(start 126.05258 -159.93364)
		(end 121.702068 -159.93364)
		(width 0.1143)
		(layer "In6.Cu")
		(net "I2C_PSU1_SCL_MOS")
	)
	(segment
		(start 126.5809 -159.40532)
		(end 126.05258 -159.93364)
		(width 0.1143)
		(layer "In6.Cu")
		(net "I2C_PSU1_SCL_MOS")
	)
	(segment
		(start 113.578894 -169.578528)
		(end 113.578894 -171.085256)
		(width 0.1143)
		(layer "In6.Cu")
		(net "I2C_PSU1_SCL_MOS")
	)
	(segment
		(start 131.80568 -156.308298)
		(end 132.489702 -156.308298)
		(width 0.1016)
		(layer "F.Cu")
		(net "PMBUS3_EN")
	)
	(segment
		(start 132.658612 -156.477208)
		(end 132.489702 -156.308298)
		(width 0.1016)
		(layer "F.Cu")
		(net "PMBUS3_EN")
	)
	(segment
		(start 131.12242 -156.991558)
		(end 131.80568 -156.308298)
		(width 0.1016)
		(layer "F.Cu")
		(net "PMBUS3_EN")
	)
	(segment
		(start 132.658612 -157.68193)
		(end 132.658612 -156.477208)
		(width 0.1016)
		(layer "F.Cu")
		(net "PMBUS3_EN")
	)
	(segment
		(start 131.12242 -159.759396)
		(end 131.12242 -156.991558)
		(width 0.1016)
		(layer "F.Cu")
		(net "PMBUS3_EN")
	)
	(segment
		(start 131.124452 -159.759396)
		(end 131.12242 -159.759396)
		(width 0.1016)
		(layer "F.Cu")
		(net "PMBUS3_EN")
	)
	(via
		(at 131.80568 -156.308298)
		(size 0.508)
		(drill 0.254)
		(layers "F.Cu" "B.Cu")
		(net "PMBUS3_EN")
	)
	(segment
		(start 113.183416 -159.77743)
		(end 112.320578 -159.77743)
		(width 0.1016)
		(layer "F.Cu")
		(net "PMBUS2_EN")
	)
	(segment
		(start 111.922306 -159.379158)
		(end 112.320578 -159.77743)
		(width 0.1016)
		(layer "F.Cu")
		(net "PMBUS2_EN")
	)
	(segment
		(start 110.408974 -159.379158)
		(end 111.922306 -159.379158)
		(width 0.1016)
		(layer "F.Cu")
		(net "PMBUS2_EN")
	)
	(segment
		(start 123.909328 -159.725614)
		(end 123.909328 -158.604966)
		(width 0.1016)
		(layer "F.Cu")
		(net "PMBUS2_EN")
	)
	(via
		(at 123.909328 -158.604966)
		(size 0.508)
		(drill 0.254)
		(layers "F.Cu" "B.Cu")
		(net "PMBUS2_EN")
	)
	(via
		(at 113.183416 -159.77743)
		(size 0.508)
		(drill 0.254)
		(layers "F.Cu" "B.Cu")
		(net "PMBUS2_EN")
	)
	(segment
		(start 120.151398 -159.03067)
		(end 119.404638 -159.77743)
		(width 0.1143)
		(layer "In2.Cu")
		(net "PMBUS2_EN")
	)
	(segment
		(start 119.404638 -159.77743)
		(end 113.183416 -159.77743)
		(width 0.1143)
		(layer "In2.Cu")
		(net "PMBUS2_EN")
	)
	(segment
		(start 123.909328 -158.604966)
		(end 123.483624 -159.03067)
		(width 0.1143)
		(layer "In2.Cu")
		(net "PMBUS2_EN")
	)
	(segment
		(start 123.483624 -159.03067)
		(end 120.151398 -159.03067)
		(width 0.1143)
		(layer "In2.Cu")
		(net "PMBUS2_EN")
	)
	(segment
		(start 127.193802 -156.352494)
		(end 127.52832 -156.687012)
		(width 0.1016)
		(layer "F.Cu")
		(net "PMBUS1_EN")
	)
	(segment
		(start 123.862592 -155.659328)
		(end 125.66396 -155.659328)
		(width 0.1016)
		(layer "F.Cu")
		(net "PMBUS1_EN")
	)
	(segment
		(start 127.579628 -159.724344)
		(end 127.57912 -159.723836)
		(width 0.1016)
		(layer "F.Cu")
		(net "PMBUS1_EN")
	)
	(segment
		(start 127.57912 -159.723836)
		(end 127.57912 -158.292546)
		(width 0.1016)
		(layer "F.Cu")
		(net "PMBUS1_EN")
	)
	(segment
		(start 127.193802 -155.853892)
		(end 127.193802 -156.352494)
		(width 0.1016)
		(layer "F.Cu")
		(net "PMBUS1_EN")
	)
	(segment
		(start 127.52832 -156.687012)
		(end 127.52832 -158.241746)
		(width 0.1016)
		(layer "F.Cu")
		(net "PMBUS1_EN")
	)
	(segment
		(start 125.858524 -155.853892)
		(end 127.193802 -155.853892)
		(width 0.1016)
		(layer "F.Cu")
		(net "PMBUS1_EN")
	)
	(segment
		(start 125.66396 -155.659328)
		(end 125.858524 -155.853892)
		(width 0.1016)
		(layer "F.Cu")
		(net "PMBUS1_EN")
	)
	(segment
		(start 127.57912 -158.292546)
		(end 127.52832 -158.241746)
		(width 0.1016)
		(layer "F.Cu")
		(net "PMBUS1_EN")
	)
	(via
		(at 127.52832 -158.241746)
		(size 0.508)
		(drill 0.254)
		(layers "F.Cu" "B.Cu")
		(net "PMBUS1_EN")
	)
	(segment
		(start 98.4631 -181.722268)
		(end 98.705924 -181.965092)
		(width 0.1016)
		(layer "F.Cu")
		(net "ATTENTION_LED_N")
	)
	(segment
		(start 98.4631 -181.722268)
		(end 98.4631 -180.142134)
		(width 0.1016)
		(layer "F.Cu")
		(net "ATTENTION_LED_N")
	)
	(segment
		(start 98.4631 -180.142134)
		(end 98.861372 -179.743862)
		(width 0.1016)
		(layer "F.Cu")
		(net "ATTENTION_LED_N")
	)
	(segment
		(start 98.705924 -181.965092)
		(end 99.531678 -181.965092)
		(width 0.1016)
		(layer "F.Cu")
		(net "ATTENTION_LED_N")
	)
	(segment
		(start 98.861372 -179.743862)
		(end 98.861372 -178.728116)
		(width 0.1016)
		(layer "F.Cu")
		(net "ATTENTION_LED_N")
	)
	(segment
		(start 98.861372 -178.728116)
		(end 99.3013 -178.288188)
		(width 0.1016)
		(layer "F.Cu")
		(net "ATTENTION_LED_N")
	)
	(via
		(at 94.57944 -179.010564)
		(size 0.6604)
		(drill 0.3302)
		(layers "F.Cu" "B.Cu")
		(net "ATTENTION_LED_N")
	)
	(via
		(at 99.3013 -178.288188)
		(size 0.508)
		(drill 0.254)
		(layers "F.Cu" "B.Cu")
		(net "ATTENTION_LED_N")
	)
	(segment
		(start 95.210376 -179.010564)
		(end 94.57944 -179.010564)
		(width 0.1016)
		(layer "B.Cu")
		(net "ATTENTION_LED_N")
	)
	(segment
		(start 98.744786 -178.844702)
		(end 97.52076 -178.844702)
		(width 0.1016)
		(layer "B.Cu")
		(net "ATTENTION_LED_N")
	)
	(segment
		(start 95.376238 -178.844702)
		(end 95.210376 -179.010564)
		(width 0.1016)
		(layer "B.Cu")
		(net "ATTENTION_LED_N")
	)
	(segment
		(start 97.52076 -178.844702)
		(end 95.376238 -178.844702)
		(width 0.1016)
		(layer "B.Cu")
		(net "ATTENTION_LED_N")
	)
	(segment
		(start 99.3013 -178.288188)
		(end 98.744786 -178.844702)
		(width 0.1016)
		(layer "B.Cu")
		(net "ATTENTION_LED_N")
	)
	(segment
		(start 100.29952 -180.715158)
		(end 100.29952 -180.972968)
		(width 0.1016)
		(layer "F.Cu")
		(net "ATTENTION_LED_R")
	)
	(segment
		(start 101.291644 -181.965092)
		(end 101.431598 -181.965092)
		(width 0.1016)
		(layer "F.Cu")
		(net "ATTENTION_LED_R")
	)
	(segment
		(start 100.29952 -180.972968)
		(end 101.291644 -181.965092)
		(width 0.1016)
		(layer "F.Cu")
		(net "ATTENTION_LED_R")
	)
	(segment
		(start 100.28936 -180.704998)
		(end 100.29952 -180.715158)
		(width 0.1016)
		(layer "F.Cu")
		(net "ATTENTION_LED_R")
	)
	(via
		(at 182.8292 -6.32968)
		(size 0.508)
		(drill 0.254)
		(layers "F.Cu" "B.Cu")
		(net "ATTENTION_LED_R")
	)
	(via
		(at 100.28936 -180.704998)
		(size 0.508)
		(drill 0.254)
		(layers "F.Cu" "B.Cu")
		(net "ATTENTION_LED_R")
	)
	(via
		(at 194.46494 -91.743276)
		(size 0.508)
		(drill 0.254)
		(layers "F.Cu" "B.Cu")
		(net "ATTENTION_LED_R")
	)
	(segment
		(start 108.561632 -181.563772)
		(end 101.148134 -181.563772)
		(width 0.1143)
		(layer "In2.Cu")
		(net "ATTENTION_LED_R")
	)
	(segment
		(start 194.28206 -154.608276)
		(end 183.176164 -165.714172)
		(width 0.1143)
		(layer "In2.Cu")
		(net "ATTENTION_LED_R")
	)
	(segment
		(start 116.540788 -182.664608)
		(end 112.969548 -182.664608)
		(width 0.1143)
		(layer "In2.Cu")
		(net "ATTENTION_LED_R")
	)
	(segment
		(start 151.943562 -188.304932)
		(end 120.396 -188.304932)
		(width 0.1143)
		(layer "In2.Cu")
		(net "ATTENTION_LED_R")
	)
	(segment
		(start 120.396 -188.304932)
		(end 119.18061 -187.089542)
		(width 0.1143)
		(layer "In2.Cu")
		(net "ATTENTION_LED_R")
	)
	(segment
		(start 154.214576 -185.932826)
		(end 153.20518 -186.942222)
		(width 0.1143)
		(layer "In2.Cu")
		(net "ATTENTION_LED_R")
	)
	(segment
		(start 167.7416 -170.4086)
		(end 167.7416 -182.175912)
		(width 0.1143)
		(layer "In2.Cu")
		(net "ATTENTION_LED_R")
	)
	(segment
		(start 181.842664 -1.326642)
		(end 21.842984 -1.326642)
		(width 0.1143)
		(layer "In2.Cu")
		(net "ATTENTION_LED_R")
	)
	(segment
		(start 119.18061 -185.71591)
		(end 117.76964 -184.30494)
		(width 0.1143)
		(layer "In2.Cu")
		(net "ATTENTION_LED_R")
	)
	(segment
		(start 117.76964 -184.30494)
		(end 117.76964 -183.89346)
		(width 0.1143)
		(layer "In2.Cu")
		(net "ATTENTION_LED_R")
	)
	(segment
		(start 194.691 -140.625576)
		(end 194.28206 -141.034516)
		(width 0.1143)
		(layer "In2.Cu")
		(net "ATTENTION_LED_R")
	)
	(segment
		(start 21.842984 -1.326642)
		(end 18.72996 -4.439666)
		(width 0.1143)
		(layer "In2.Cu")
		(net "ATTENTION_LED_R")
	)
	(segment
		(start 163.961572 -185.95594)
		(end 161.29254 -185.95594)
		(width 0.1143)
		(layer "In2.Cu")
		(net "ATTENTION_LED_R")
	)
	(segment
		(start 194.46494 -92.99194)
		(end 194.691 -93.218)
		(width 0.1143)
		(layer "In2.Cu")
		(net "ATTENTION_LED_R")
	)
	(segment
		(start 182.8292 -2.313178)
		(end 181.842664 -1.326642)
		(width 0.1143)
		(layer "In2.Cu")
		(net "ATTENTION_LED_R")
	)
	(segment
		(start 168.9354 -168.4782)
		(end 168.9354 -169.2148)
		(width 0.1143)
		(layer "In2.Cu")
		(net "ATTENTION_LED_R")
	)
	(segment
		(start 194.691 -93.218)
		(end 194.691 -140.625576)
		(width 0.1143)
		(layer "In2.Cu")
		(net "ATTENTION_LED_R")
	)
	(segment
		(start 183.176164 -165.714172)
		(end 172.436028 -165.714172)
		(width 0.1143)
		(layer "In2.Cu")
		(net "ATTENTION_LED_R")
	)
	(segment
		(start 112.969548 -182.664608)
		(end 112.377728 -182.072788)
		(width 0.1143)
		(layer "In2.Cu")
		(net "ATTENTION_LED_R")
	)
	(segment
		(start 172.436028 -165.714172)
		(end 170.5737 -167.5765)
		(width 0.1143)
		(layer "In2.Cu")
		(net "ATTENTION_LED_R")
	)
	(segment
		(start 153.20518 -186.942222)
		(end 153.20518 -187.043314)
		(width 0.1143)
		(layer "In2.Cu")
		(net "ATTENTION_LED_R")
	)
	(segment
		(start 170.5737 -167.5765)
		(end 169.8371 -167.5765)
		(width 0.1143)
		(layer "In2.Cu")
		(net "ATTENTION_LED_R")
	)
	(segment
		(start 117.76964 -183.89346)
		(end 116.540788 -182.664608)
		(width 0.1143)
		(layer "In2.Cu")
		(net "ATTENTION_LED_R")
	)
	(segment
		(start 169.8371 -167.5765)
		(end 168.9354 -168.4782)
		(width 0.1143)
		(layer "In2.Cu")
		(net "ATTENTION_LED_R")
	)
	(segment
		(start 182.8292 -6.32968)
		(end 182.8292 -2.313178)
		(width 0.1143)
		(layer "In2.Cu")
		(net "ATTENTION_LED_R")
	)
	(segment
		(start 194.46494 -91.743276)
		(end 194.46494 -92.99194)
		(width 0.1143)
		(layer "In2.Cu")
		(net "ATTENTION_LED_R")
	)
	(segment
		(start 161.29254 -185.95594)
		(end 161.269426 -185.932826)
		(width 0.1143)
		(layer "In2.Cu")
		(net "ATTENTION_LED_R")
	)
	(segment
		(start 153.20518 -187.043314)
		(end 151.943562 -188.304932)
		(width 0.1143)
		(layer "In2.Cu")
		(net "ATTENTION_LED_R")
	)
	(segment
		(start 161.269426 -185.932826)
		(end 154.214576 -185.932826)
		(width 0.1143)
		(layer "In2.Cu")
		(net "ATTENTION_LED_R")
	)
	(segment
		(start 18.72996 -4.439666)
		(end 18.72996 -5.259832)
		(width 0.1143)
		(layer "In2.Cu")
		(net "ATTENTION_LED_R")
	)
	(segment
		(start 109.070648 -182.072788)
		(end 108.561632 -181.563772)
		(width 0.1143)
		(layer "In2.Cu")
		(net "ATTENTION_LED_R")
	)
	(segment
		(start 194.28206 -141.034516)
		(end 194.28206 -154.608276)
		(width 0.1143)
		(layer "In2.Cu")
		(net "ATTENTION_LED_R")
	)
	(segment
		(start 119.18061 -187.089542)
		(end 119.18061 -185.71591)
		(width 0.1143)
		(layer "In2.Cu")
		(net "ATTENTION_LED_R")
	)
	(segment
		(start 168.9354 -169.2148)
		(end 167.7416 -170.4086)
		(width 0.1143)
		(layer "In2.Cu")
		(net "ATTENTION_LED_R")
	)
	(segment
		(start 167.7416 -182.175912)
		(end 163.961572 -185.95594)
		(width 0.1143)
		(layer "In2.Cu")
		(net "ATTENTION_LED_R")
	)
	(segment
		(start 101.148134 -181.563772)
		(end 100.28936 -180.704998)
		(width 0.1143)
		(layer "In2.Cu")
		(net "ATTENTION_LED_R")
	)
	(segment
		(start 112.377728 -182.072788)
		(end 109.070648 -182.072788)
		(width 0.1143)
		(layer "In2.Cu")
		(net "ATTENTION_LED_R")
	)
	(segment
		(start 194.81165 -91.396566)
		(end 194.81165 -83.80349)
		(width 0.1143)
		(layer "In6.Cu")
		(net "ATTENTION_LED_R")
	)
	(segment
		(start 194.81165 -83.80349)
		(end 192.072514 -81.064354)
		(width 0.1143)
		(layer "In6.Cu")
		(net "ATTENTION_LED_R")
	)
	(segment
		(start 177.335688 -52.818538)
		(end 177.67935 -52.474876)
		(width 0.1143)
		(layer "In6.Cu")
		(net "ATTENTION_LED_R")
	)
	(segment
		(start 180.56987 -13.382752)
		(end 180.327554 -13.140436)
		(width 0.1143)
		(layer "In6.Cu")
		(net "ATTENTION_LED_R")
	)
	(segment
		(start 194.46494 -91.743276)
		(end 194.81165 -91.396566)
		(width 0.1143)
		(layer "In6.Cu")
		(net "ATTENTION_LED_R")
	)
	(segment
		(start 192.072514 -81.064354)
		(end 189.01537 -81.064354)
		(width 0.1143)
		(layer "In6.Cu")
		(net "ATTENTION_LED_R")
	)
	(segment
		(start 177.335688 -69.384672)
		(end 177.335688 -52.818538)
		(width 0.1143)
		(layer "In6.Cu")
		(net "ATTENTION_LED_R")
	)
	(segment
		(start 177.67935 -52.474876)
		(end 177.67935 -52.111656)
		(width 0.1143)
		(layer "In6.Cu")
		(net "ATTENTION_LED_R")
	)
	(segment
		(start 176.62525 -46.233334)
		(end 176.62525 -33.519618)
		(width 0.1143)
		(layer "In6.Cu")
		(net "ATTENTION_LED_R")
	)
	(segment
		(start 180.327554 -8.831326)
		(end 182.8292 -6.32968)
		(width 0.1143)
		(layer "In6.Cu")
		(net "ATTENTION_LED_R")
	)
	(segment
		(start 180.327554 -13.140436)
		(end 180.327554 -8.831326)
		(width 0.1143)
		(layer "In6.Cu")
		(net "ATTENTION_LED_R")
	)
	(segment
		(start 177.67935 -52.111656)
		(end 176.7078 -51.140106)
		(width 0.1143)
		(layer "In6.Cu")
		(net "ATTENTION_LED_R")
	)
	(segment
		(start 176.7078 -46.315884)
		(end 176.62525 -46.233334)
		(width 0.1143)
		(layer "In6.Cu")
		(net "ATTENTION_LED_R")
	)
	(segment
		(start 176.7078 -51.140106)
		(end 176.7078 -46.315884)
		(width 0.1143)
		(layer "In6.Cu")
		(net "ATTENTION_LED_R")
	)
	(segment
		(start 180.56987 -29.574998)
		(end 180.56987 -13.382752)
		(width 0.1143)
		(layer "In6.Cu")
		(net "ATTENTION_LED_R")
	)
	(segment
		(start 176.62525 -33.519618)
		(end 180.56987 -29.574998)
		(width 0.1143)
		(layer "In6.Cu")
		(net "ATTENTION_LED_R")
	)
	(segment
		(start 189.01537 -81.064354)
		(end 177.335688 -69.384672)
		(width 0.1143)
		(layer "In6.Cu")
		(net "ATTENTION_LED_R")
	)
	(segment
		(start 121.374154 -168.721532)
		(end 120.60936 -168.721532)
		(width 0.1016)
		(layer "F.Cu")
		(net "I2C_PSU3_SCL_MOS")
	)
	(segment
		(start 128.769872 -161.689034)
		(end 128.917954 -161.540952)
		(width 0.1016)
		(layer "F.Cu")
		(net "I2C_PSU3_SCL_MOS")
	)
	(segment
		(start 128.117854 -161.93262)
		(end 128.36144 -161.689034)
		(width 0.1016)
		(layer "F.Cu")
		(net "I2C_PSU3_SCL_MOS")
	)
	(segment
		(start 128.917954 -159.933894)
		(end 128.917954 -161.243772)
		(width 0.1016)
		(layer "F.Cu")
		(net "I2C_PSU3_SCL_MOS")
	)
	(segment
		(start 128.117854 -162.25012)
		(end 128.117854 -161.93262)
		(width 0.1016)
		(layer "F.Cu")
		(net "I2C_PSU3_SCL_MOS")
	)
	(segment
		(start 128.89992 -163.026852)
		(end 128.566672 -162.693604)
		(width 0.1016)
		(layer "F.Cu")
		(net "I2C_PSU3_SCL_MOS")
	)
	(segment
		(start 123.1138 -167.73017)
		(end 122.365516 -167.73017)
		(width 0.1016)
		(layer "F.Cu")
		(net "I2C_PSU3_SCL_MOS")
	)
	(segment
		(start 128.117854 -162.251644)
		(end 128.117854 -162.25012)
		(width 0.1016)
		(layer "F.Cu")
		(net "I2C_PSU3_SCL_MOS")
	)
	(segment
		(start 128.566672 -162.693604)
		(end 128.559814 -162.693604)
		(width 0.1016)
		(layer "F.Cu")
		(net "I2C_PSU3_SCL_MOS")
	)
	(segment
		(start 128.917954 -161.540952)
		(end 128.917954 -161.243772)
		(width 0.1016)
		(layer "F.Cu")
		(net "I2C_PSU3_SCL_MOS")
	)
	(segment
		(start 127.53594 -163.637722)
		(end 128.64719 -163.637722)
		(width 0.1016)
		(layer "F.Cu")
		(net "I2C_PSU3_SCL_MOS")
	)
	(segment
		(start 128.64719 -163.637722)
		(end 128.89992 -163.384992)
		(width 0.1016)
		(layer "F.Cu")
		(net "I2C_PSU3_SCL_MOS")
	)
	(segment
		(start 122.365516 -167.73017)
		(end 121.374154 -168.721532)
		(width 0.1016)
		(layer "F.Cu")
		(net "I2C_PSU3_SCL_MOS")
	)
	(segment
		(start 128.89992 -163.384992)
		(end 128.89992 -163.026852)
		(width 0.1016)
		(layer "F.Cu")
		(net "I2C_PSU3_SCL_MOS")
	)
	(segment
		(start 128.36144 -161.689034)
		(end 128.769872 -161.689034)
		(width 0.1016)
		(layer "F.Cu")
		(net "I2C_PSU3_SCL_MOS")
	)
	(segment
		(start 128.559814 -162.693604)
		(end 128.117854 -162.251644)
		(width 0.1016)
		(layer "F.Cu")
		(net "I2C_PSU3_SCL_MOS")
	)
	(segment
		(start 127.49276 -163.594542)
		(end 127.53594 -163.637722)
		(width 0.1016)
		(layer "F.Cu")
		(net "I2C_PSU3_SCL_MOS")
	)
	(segment
		(start 129.092452 -159.759396)
		(end 128.917954 -159.933894)
		(width 0.1016)
		(layer "F.Cu")
		(net "I2C_PSU3_SCL_MOS")
	)
	(via
		(at 127.49276 -163.594542)
		(size 0.508)
		(drill 0.254)
		(layers "F.Cu" "B.Cu")
		(net "I2C_PSU3_SCL_MOS")
	)
	(via
		(at 123.1138 -167.73017)
		(size 0.508)
		(drill 0.254)
		(layers "F.Cu" "B.Cu")
		(net "I2C_PSU3_SCL_MOS")
	)
	(segment
		(start 124.86767 -164.799264)
		(end 125.434852 -164.799264)
		(width 0.1016)
		(layer "B.Cu")
		(net "I2C_PSU3_SCL_MOS")
	)
	(segment
		(start 126.63932 -163.594542)
		(end 127.49276 -163.594542)
		(width 0.1016)
		(layer "B.Cu")
		(net "I2C_PSU3_SCL_MOS")
	)
	(segment
		(start 124.01804 -165.648894)
		(end 124.86767 -164.799264)
		(width 0.1016)
		(layer "B.Cu")
		(net "I2C_PSU3_SCL_MOS")
	)
	(segment
		(start 125.434852 -164.799264)
		(end 126.63932 -163.594542)
		(width 0.1016)
		(layer "B.Cu")
		(net "I2C_PSU3_SCL_MOS")
	)
	(segment
		(start 123.1138 -167.73017)
		(end 124.01804 -166.82593)
		(width 0.1016)
		(layer "B.Cu")
		(net "I2C_PSU3_SCL_MOS")
	)
	(segment
		(start 124.01804 -166.82593)
		(end 124.01804 -165.648894)
		(width 0.1016)
		(layer "B.Cu")
		(net "I2C_PSU3_SCL_MOS")
	)
	(segment
		(start 133.9342 -157.68193)
		(end 133.6802 -157.93593)
		(width 0.1016)
		(layer "F.Cu")
		(net "I2C_PSU3_SDA_MOS")
	)
	(segment
		(start 125.16358 -168.93286)
		(end 122.040396 -168.93286)
		(width 0.1016)
		(layer "F.Cu")
		(net "I2C_PSU3_SDA_MOS")
	)
	(segment
		(start 134.690612 -157.68193)
		(end 133.9342 -157.68193)
		(width 0.1016)
		(layer "F.Cu")
		(net "I2C_PSU3_SDA_MOS")
	)
	(segment
		(start 134.834884 -157.537658)
		(end 134.690612 -157.68193)
		(width 0.1016)
		(layer "F.Cu")
		(net "I2C_PSU3_SDA_MOS")
	)
	(segment
		(start 122.040396 -168.93286)
		(end 121.601738 -169.371518)
		(width 0.1016)
		(layer "F.Cu")
		(net "I2C_PSU3_SDA_MOS")
	)
	(segment
		(start 133.6802 -157.93593)
		(end 133.6802 -158.399734)
		(width 0.1016)
		(layer "F.Cu")
		(net "I2C_PSU3_SDA_MOS")
	)
	(segment
		(start 121.601738 -169.371518)
		(end 120.60936 -169.371518)
		(width 0.1016)
		(layer "F.Cu")
		(net "I2C_PSU3_SDA_MOS")
	)
	(segment
		(start 136.050274 -158.553658)
		(end 136.050274 -157.537658)
		(width 0.1016)
		(layer "F.Cu")
		(net "I2C_PSU3_SDA_MOS")
	)
	(segment
		(start 136.050274 -157.537658)
		(end 134.834884 -157.537658)
		(width 0.1016)
		(layer "F.Cu")
		(net "I2C_PSU3_SDA_MOS")
	)
	(via
		(at 125.16358 -168.93286)
		(size 0.508)
		(drill 0.254)
		(layers "F.Cu" "B.Cu")
		(net "I2C_PSU3_SDA_MOS")
	)
	(via
		(at 133.6802 -158.399734)
		(size 0.508)
		(drill 0.254)
		(layers "F.Cu" "B.Cu")
		(net "I2C_PSU3_SDA_MOS")
	)
	(segment
		(start 133.08076 -160.886648)
		(end 133.08076 -158.999174)
		(width 0.1016)
		(layer "B.Cu")
		(net "I2C_PSU3_SDA_MOS")
	)
	(segment
		(start 126.17323 -166.7891)
		(end 127.021844 -166.7891)
		(width 0.1016)
		(layer "B.Cu")
		(net "I2C_PSU3_SDA_MOS")
	)
	(segment
		(start 133.08076 -158.999174)
		(end 133.6802 -158.399734)
		(width 0.1016)
		(layer "B.Cu")
		(net "I2C_PSU3_SDA_MOS")
	)
	(segment
		(start 131.43484 -162.532568)
		(end 133.08076 -160.886648)
		(width 0.1016)
		(layer "B.Cu")
		(net "I2C_PSU3_SDA_MOS")
	)
	(segment
		(start 127.021844 -166.7891)
		(end 129.514092 -164.296852)
		(width 0.1016)
		(layer "B.Cu")
		(net "I2C_PSU3_SDA_MOS")
	)
	(segment
		(start 125.16358 -168.93286)
		(end 125.16358 -167.79875)
		(width 0.1016)
		(layer "B.Cu")
		(net "I2C_PSU3_SDA_MOS")
	)
	(segment
		(start 131.43484 -162.756596)
		(end 131.43484 -162.532568)
		(width 0.1016)
		(layer "B.Cu")
		(net "I2C_PSU3_SDA_MOS")
	)
	(segment
		(start 129.514092 -164.296852)
		(end 129.894584 -164.296852)
		(width 0.1016)
		(layer "B.Cu")
		(net "I2C_PSU3_SDA_MOS")
	)
	(segment
		(start 129.894584 -164.296852)
		(end 131.43484 -162.756596)
		(width 0.1016)
		(layer "B.Cu")
		(net "I2C_PSU3_SDA_MOS")
	)
	(segment
		(start 125.16358 -167.79875)
		(end 126.17323 -166.7891)
		(width 0.1016)
		(layer "B.Cu")
		(net "I2C_PSU3_SDA_MOS")
	)
	(segment
		(start 164.015674 -200.10501)
		(end 164.015674 -205.199488)
		(width 0.1016)
		(layer "F.Cu")
		(net "UART_TX_RP5_L")
	)
	(segment
		(start 162.13074 -196.532246)
		(end 162.13074 -198.220076)
		(width 0.1016)
		(layer "F.Cu")
		(net "UART_TX_RP5_L")
	)
	(segment
		(start 164.26307 -194.399662)
		(end 164.01034 -194.652392)
		(width 0.1016)
		(layer "F.Cu")
		(net "UART_TX_RP5_L")
	)
	(segment
		(start 165.0619 -193.116454)
		(end 165.0619 -193.632582)
		(width 0.1016)
		(layer "F.Cu")
		(net "UART_TX_RP5_L")
	)
	(segment
		(start 165.3286 -189.5856)
		(end 165.3286 -187.154312)
		(width 0.1016)
		(layer "F.Cu")
		(net "UART_TX_RP5_L")
	)
	(segment
		(start 164.25672 -191.772286)
		(end 164.3126 -191.828166)
		(width 0.1016)
		(layer "F.Cu")
		(net "UART_TX_RP5_L")
	)
	(segment
		(start 164.25672 -190.65748)
		(end 165.3286 -189.5856)
		(width 0.1016)
		(layer "F.Cu")
		(net "UART_TX_RP5_L")
	)
	(segment
		(start 162.61334 -184.439052)
		(end 162.61334 -179.205636)
		(width 0.1016)
		(layer "F.Cu")
		(net "UART_TX_RP5_L")
	)
	(segment
		(start 165.3286 -187.154312)
		(end 162.61334 -184.439052)
		(width 0.1016)
		(layer "F.Cu")
		(net "UART_TX_RP5_L")
	)
	(segment
		(start 164.01034 -194.652392)
		(end 162.13074 -196.532246)
		(width 0.1016)
		(layer "F.Cu")
		(net "UART_TX_RP5_L")
	)
	(segment
		(start 164.25672 -191.772286)
		(end 164.25672 -190.65748)
		(width 0.1016)
		(layer "F.Cu")
		(net "UART_TX_RP5_L")
	)
	(segment
		(start 164.29482 -194.399662)
		(end 164.26307 -194.399662)
		(width 0.1016)
		(layer "F.Cu")
		(net "UART_TX_RP5_L")
	)
	(segment
		(start 165.0619 -193.632582)
		(end 164.29482 -194.399662)
		(width 0.1016)
		(layer "F.Cu")
		(net "UART_TX_RP5_L")
	)
	(segment
		(start 164.3126 -192.367154)
		(end 165.0619 -193.116454)
		(width 0.1016)
		(layer "F.Cu")
		(net "UART_TX_RP5_L")
	)
	(segment
		(start 162.13074 -198.220076)
		(end 164.015674 -200.10501)
		(width 0.1016)
		(layer "F.Cu")
		(net "UART_TX_RP5_L")
	)
	(segment
		(start 164.366448 -177.452528)
		(end 165.217602 -177.452528)
		(width 0.1016)
		(layer "F.Cu")
		(net "UART_TX_RP5_L")
	)
	(segment
		(start 162.61334 -179.205636)
		(end 164.366448 -177.452528)
		(width 0.1016)
		(layer "F.Cu")
		(net "UART_TX_RP5_L")
	)
	(segment
		(start 164.3126 -191.828166)
		(end 164.3126 -192.367154)
		(width 0.1016)
		(layer "F.Cu")
		(net "UART_TX_RP5_L")
	)
	(via
		(at 164.25672 -191.772286)
		(size 0.508)
		(drill 0.254)
		(layers "F.Cu" "B.Cu")
		(net "UART_TX_RP5_L")
	)
	(segment
		(start 177.7492 -193.7512)
		(end 180.3654 -191.135)
		(width 0.381)
		(layer "F.Cu")
		(net "POWER_SW1_PWR_CTR_12V_R")
	)
	(segment
		(start 182.1434 -191.135)
		(end 182.753 -190.5254)
		(width 0.381)
		(layer "F.Cu")
		(net "POWER_SW1_PWR_CTR_12V_R")
	)
	(segment
		(start 182.753 -190.5254)
		(end 182.753 -189.738)
		(width 0.381)
		(layer "F.Cu")
		(net "POWER_SW1_PWR_CTR_12V_R")
	)
	(segment
		(start 176.6062 -196.723)
		(end 177.7492 -195.58)
		(width 0.381)
		(layer "F.Cu")
		(net "POWER_SW1_PWR_CTR_12V_R")
	)
	(segment
		(start 175.1838 -196.723)
		(end 176.6062 -196.723)
		(width 0.381)
		(layer "F.Cu")
		(net "POWER_SW1_PWR_CTR_12V_R")
	)
	(segment
		(start 180.3654 -191.135)
		(end 182.1434 -191.135)
		(width 0.381)
		(layer "F.Cu")
		(net "POWER_SW1_PWR_CTR_12V_R")
	)
	(segment
		(start 177.7492 -195.58)
		(end 177.7492 -193.7512)
		(width 0.381)
		(layer "F.Cu")
		(net "POWER_SW1_PWR_CTR_12V_R")
	)
	(via
		(at 175.1838 -196.723)
		(size 0.508)
		(drill 0.254)
		(layers "F.Cu" "B.Cu")
		(net "POWER_SW1_PWR_CTR_12V_R")
	)
	(segment
		(start 180.213 -192.024)
		(end 180.213 -188.86805)
		(width 0.381)
		(layer "B.Cu")
		(net "POWER_SW1_PWR_CTR_12V_R")
	)
	(segment
		(start 177.0126 -205.199488)
		(end 177.015648 -205.199488)
		(width 0.381)
		(layer "B.Cu")
		(net "POWER_SW1_PWR_CTR_12V_R")
	)
	(segment
		(start 175.1838 -196.723)
		(end 177.0126 -198.5518)
		(width 0.381)
		(layer "B.Cu")
		(net "POWER_SW1_PWR_CTR_12V_R")
	)
	(segment
		(start 175.514 -196.723)
		(end 180.213 -192.024)
		(width 0.381)
		(layer "B.Cu")
		(net "POWER_SW1_PWR_CTR_12V_R")
	)
	(segment
		(start 175.1838 -196.723)
		(end 175.514 -196.723)
		(width 0.381)
		(layer "B.Cu")
		(net "POWER_SW1_PWR_CTR_12V_R")
	)
	(segment
		(start 177.0126 -198.5518)
		(end 177.0126 -205.199488)
		(width 0.381)
		(layer "B.Cu")
		(net "POWER_SW1_PWR_CTR_12V_R")
	)
	(segment
		(start 9.09066 -148.392642)
		(end 9.09066 -147.399756)
		(width 0.1016)
		(layer "F.Cu")
		(net "UART_RI_P6_L_N")
	)
	(segment
		(start 12.06119 -146.688556)
		(end 12.61872 -147.246086)
		(width 0.1016)
		(layer "F.Cu")
		(net "UART_RI_P6_L_N")
	)
	(segment
		(start 9.09066 -147.399756)
		(end 9.80186 -146.688556)
		(width 0.1016)
		(layer "F.Cu")
		(net "UART_RI_P6_L_N")
	)
	(segment
		(start 9.80186 -146.688556)
		(end 12.06119 -146.688556)
		(width 0.1016)
		(layer "F.Cu")
		(net "UART_RI_P6_L_N")
	)
	(via
		(at 30.4546 -191.521334)
		(size 0.508)
		(drill 0.254)
		(layers "F.Cu" "B.Cu")
		(net "UART_RI_P6_L_N")
	)
	(via
		(at 12.61872 -147.246086)
		(size 0.508)
		(drill 0.254)
		(layers "F.Cu" "B.Cu")
		(net "UART_RI_P6_L_N")
	)
	(segment
		(start 31.8262 -188.14415)
		(end 32.23895 -187.7314)
		(width 0.1016)
		(layer "B.Cu")
		(net "UART_RI_P6_L_N")
	)
	(segment
		(start 30.4546 -191.516)
		(end 31.8262 -190.1444)
		(width 0.1016)
		(layer "B.Cu")
		(net "UART_RI_P6_L_N")
	)
	(segment
		(start 30.4546 -191.521334)
		(end 30.4546 -191.516)
		(width 0.1016)
		(layer "B.Cu")
		(net "UART_RI_P6_L_N")
	)
	(segment
		(start 31.8262 -190.1444)
		(end 31.8262 -188.14415)
		(width 0.1016)
		(layer "B.Cu")
		(net "UART_RI_P6_L_N")
	)
	(segment
		(start 12.92606 -161.33318)
		(end 12.5603 -161.33318)
		(width 0.1143)
		(layer "In2.Cu")
		(net "UART_RI_P6_L_N")
	)
	(segment
		(start 12.530074 -161.363406)
		(end 11.72845 -161.363406)
		(width 0.1143)
		(layer "In2.Cu")
		(net "UART_RI_P6_L_N")
	)
	(segment
		(start 30.109668 -191.521334)
		(end 28.117038 -189.528704)
		(width 0.1143)
		(layer "In2.Cu")
		(net "UART_RI_P6_L_N")
	)
	(segment
		(start 12.517628 -155.03398)
		(end 12.517628 -147.347178)
		(width 0.1143)
		(layer "In2.Cu")
		(net "UART_RI_P6_L_N")
	)
	(segment
		(start 28.117038 -189.528704)
		(end 28.117038 -180.649118)
		(width 0.1143)
		(layer "In2.Cu")
		(net "UART_RI_P6_L_N")
	)
	(segment
		(start 12.517628 -147.347178)
		(end 12.61872 -147.246086)
		(width 0.1143)
		(layer "In2.Cu")
		(net "UART_RI_P6_L_N")
	)
	(segment
		(start 28.117038 -180.649118)
		(end 29.066236 -179.69992)
		(width 0.1143)
		(layer "In2.Cu")
		(net "UART_RI_P6_L_N")
	)
	(segment
		(start 15.794228 -162.84448)
		(end 14.43736 -162.84448)
		(width 0.1143)
		(layer "In2.Cu")
		(net "UART_RI_P6_L_N")
	)
	(segment
		(start 12.5603 -161.33318)
		(end 12.530074 -161.363406)
		(width 0.1143)
		(layer "In2.Cu")
		(net "UART_RI_P6_L_N")
	)
	(segment
		(start 11.25347 -160.888426)
		(end 11.25347 -156.298138)
		(width 0.1143)
		(layer "In2.Cu")
		(net "UART_RI_P6_L_N")
	)
	(segment
		(start 11.25347 -156.298138)
		(end 12.517628 -155.03398)
		(width 0.1143)
		(layer "In2.Cu")
		(net "UART_RI_P6_L_N")
	)
	(segment
		(start 29.066236 -179.69992)
		(end 29.066236 -176.116488)
		(width 0.1143)
		(layer "In2.Cu")
		(net "UART_RI_P6_L_N")
	)
	(segment
		(start 11.72845 -161.363406)
		(end 11.25347 -160.888426)
		(width 0.1143)
		(layer "In2.Cu")
		(net "UART_RI_P6_L_N")
	)
	(segment
		(start 29.066236 -176.116488)
		(end 15.794228 -162.84448)
		(width 0.1143)
		(layer "In2.Cu")
		(net "UART_RI_P6_L_N")
	)
	(segment
		(start 14.43736 -162.84448)
		(end 12.92606 -161.33318)
		(width 0.1143)
		(layer "In2.Cu")
		(net "UART_RI_P6_L_N")
	)
	(segment
		(start 30.4546 -191.521334)
		(end 30.109668 -191.521334)
		(width 0.1143)
		(layer "In2.Cu")
		(net "UART_RI_P6_L_N")
	)
	(segment
		(start 163.449 -186.6138)
		(end 163.449 -187.68695)
		(width 0.1016)
		(layer "F.Cu")
		(net "UART_RI_RP5_L_N")
	)
	(segment
		(start 163.322 -186.379104)
		(end 163.322 -186.4868)
		(width 0.1016)
		(layer "F.Cu")
		(net "UART_RI_RP5_L_N")
	)
	(segment
		(start 162.00374 -185.060844)
		(end 163.322 -186.379104)
		(width 0.1016)
		(layer "F.Cu")
		(net "UART_RI_RP5_L_N")
	)
	(segment
		(start 162.00374 -176.75352)
		(end 162.00374 -185.060844)
		(width 0.1016)
		(layer "F.Cu")
		(net "UART_RI_RP5_L_N")
	)
	(segment
		(start 164.554916 -174.202344)
		(end 162.00374 -176.75352)
		(width 0.1016)
		(layer "F.Cu")
		(net "UART_RI_RP5_L_N")
	)
	(segment
		(start 165.217602 -174.202344)
		(end 164.554916 -174.202344)
		(width 0.1016)
		(layer "F.Cu")
		(net "UART_RI_RP5_L_N")
	)
	(segment
		(start 163.322 -186.4868)
		(end 163.449 -186.6138)
		(width 0.1016)
		(layer "F.Cu")
		(net "UART_RI_RP5_L_N")
	)
	(via
		(at 163.322 -186.4868)
		(size 0.762)
		(drill 0.381)
		(layers "F.Cu" "B.Cu")
		(net "UART_RI_RP5_L_N")
	)
	(segment
		(start 165.217602 -176.802542)
		(end 164.483034 -176.802542)
		(width 0.1016)
		(layer "F.Cu")
		(net "UART_RTS_RP5_L_N")
	)
	(segment
		(start 162.30854 -178.977036)
		(end 162.30854 -184.60974)
		(width 0.1016)
		(layer "F.Cu")
		(net "UART_RTS_RP5_L_N")
	)
	(segment
		(start 167.015668 -205.199488)
		(end 167.015668 -201.29881)
		(width 0.1016)
		(layer "F.Cu")
		(net "UART_RTS_RP5_L_N")
	)
	(segment
		(start 164.473128 -194.86245)
		(end 164.44214 -194.831462)
		(width 0.1016)
		(layer "F.Cu")
		(net "UART_RTS_RP5_L_N")
	)
	(segment
		(start 162.30854 -184.60974)
		(end 165.0238 -187.325)
		(width 0.1016)
		(layer "F.Cu")
		(net "UART_RTS_RP5_L_N")
	)
	(segment
		(start 164.17798 -192.834768)
		(end 164.17798 -192.850008)
		(width 0.1016)
		(layer "F.Cu")
		(net "UART_RTS_RP5_L_N")
	)
	(segment
		(start 163.82492 -190.60668)
		(end 163.82492 -192.481708)
		(width 0.1016)
		(layer "F.Cu")
		(net "UART_RTS_RP5_L_N")
	)
	(segment
		(start 164.483034 -176.802542)
		(end 162.30854 -178.977036)
		(width 0.1016)
		(layer "F.Cu")
		(net "UART_RTS_RP5_L_N")
	)
	(segment
		(start 165.0238 -189.4078)
		(end 163.82492 -190.60668)
		(width 0.1016)
		(layer "F.Cu")
		(net "UART_RTS_RP5_L_N")
	)
	(segment
		(start 166.429436 -196.329554)
		(end 164.962332 -194.86245)
		(width 0.1016)
		(layer "F.Cu")
		(net "UART_RTS_RP5_L_N")
	)
	(segment
		(start 166.429436 -200.712578)
		(end 166.429436 -196.329554)
		(width 0.1016)
		(layer "F.Cu")
		(net "UART_RTS_RP5_L_N")
	)
	(segment
		(start 167.015668 -201.29881)
		(end 166.429436 -200.712578)
		(width 0.1016)
		(layer "F.Cu")
		(net "UART_RTS_RP5_L_N")
	)
	(segment
		(start 164.962332 -194.86245)
		(end 164.473128 -194.86245)
		(width 0.1016)
		(layer "F.Cu")
		(net "UART_RTS_RP5_L_N")
	)
	(segment
		(start 165.0238 -187.325)
		(end 165.0238 -189.4078)
		(width 0.1016)
		(layer "F.Cu")
		(net "UART_RTS_RP5_L_N")
	)
	(segment
		(start 163.82492 -192.481708)
		(end 164.17798 -192.834768)
		(width 0.1016)
		(layer "F.Cu")
		(net "UART_RTS_RP5_L_N")
	)
	(via
		(at 164.44214 -194.831462)
		(size 0.508)
		(drill 0.254)
		(layers "F.Cu" "B.Cu")
		(net "UART_RTS_RP5_L_N")
	)
	(via
		(at 164.17798 -192.850008)
		(size 0.508)
		(drill 0.254)
		(layers "F.Cu" "B.Cu")
		(net "UART_RTS_RP5_L_N")
	)
	(segment
		(start 164.1221 -194.511422)
		(end 164.44214 -194.831462)
		(width 0.1016)
		(layer "B.Cu")
		(net "UART_RTS_RP5_L_N")
	)
	(segment
		(start 164.17798 -192.850008)
		(end 164.17798 -193.084704)
		(width 0.1016)
		(layer "B.Cu")
		(net "UART_RTS_RP5_L_N")
	)
	(segment
		(start 164.1221 -193.140584)
		(end 164.1221 -194.511422)
		(width 0.1016)
		(layer "B.Cu")
		(net "UART_RTS_RP5_L_N")
	)
	(segment
		(start 164.17798 -193.084704)
		(end 164.1221 -193.140584)
		(width 0.1016)
		(layer "B.Cu")
		(net "UART_RTS_RP5_L_N")
	)
	(segment
		(start 178.660044 -168.705784)
		(end 178.660044 -167.992044)
		(width 0.10414)
		(layer "F.Cu")
		(net "LAN2_P3_P")
	)
	(segment
		(start 178.660044 -170.122596)
		(end 179.077874 -169.704766)
		(width 0.10414)
		(layer "F.Cu")
		(net "LAN2_P3_P")
	)
	(segment
		(start 179.077874 -169.704766)
		(end 179.077874 -169.123614)
		(width 0.10414)
		(layer "F.Cu")
		(net "LAN2_P3_P")
	)
	(segment
		(start 179.077874 -169.123614)
		(end 178.660044 -168.705784)
		(width 0.10414)
		(layer "F.Cu")
		(net "LAN2_P3_P")
	)
	(via
		(at 178.660044 -170.122596)
		(size 0.508)
		(drill 0.254)
		(layers "F.Cu" "B.Cu")
		(net "LAN2_P3_P")
	)
	(segment
		(start 184.00776 -196.708522)
		(end 184.16524 -195.176394)
		(width 0.10414)
		(layer "B.Cu")
		(net "LAN2_P3_P")
	)
	(segment
		(start 180.401468 -168.884346)
		(end 179.507896 -168.884346)
		(width 0.10414)
		(layer "B.Cu")
		(net "LAN2_P3_P")
	)
	(segment
		(start 184.16524 -195.176394)
		(end 184.16524 -173.470824)
		(width 0.10414)
		(layer "B.Cu")
		(net "LAN2_P3_P")
	)
	(segment
		(start 185.015632 -202.942698)
		(end 184.732676 -202.659742)
		(width 0.10414)
		(layer "B.Cu")
		(net "LAN2_P3_P")
	)
	(segment
		(start 182.11038 -169.577258)
		(end 180.401468 -168.884346)
		(width 0.10414)
		(layer "B.Cu")
		(net "LAN2_P3_P")
	)
	(segment
		(start 184.732676 -202.659742)
		(end 184.732676 -200.355962)
		(width 0.10414)
		(layer "B.Cu")
		(net "LAN2_P3_P")
	)
	(segment
		(start 184.732676 -200.355962)
		(end 184.00776 -197.750176)
		(width 0.10414)
		(layer "B.Cu")
		(net "LAN2_P3_P")
	)
	(segment
		(start 185.015632 -205.199488)
		(end 185.015632 -202.942698)
		(width 0.10414)
		(layer "B.Cu")
		(net "LAN2_P3_P")
	)
	(segment
		(start 179.077874 -169.314368)
		(end 179.077874 -169.704766)
		(width 0.10414)
		(layer "B.Cu")
		(net "LAN2_P3_P")
	)
	(segment
		(start 184.16524 -173.470824)
		(end 183.254396 -170.721528)
		(width 0.10414)
		(layer "B.Cu")
		(net "LAN2_P3_P")
	)
	(segment
		(start 183.254396 -170.721528)
		(end 182.11038 -169.577258)
		(width 0.10414)
		(layer "B.Cu")
		(net "LAN2_P3_P")
	)
	(segment
		(start 179.077874 -169.704766)
		(end 178.660044 -170.122596)
		(width 0.10414)
		(layer "B.Cu")
		(net "LAN2_P3_P")
	)
	(segment
		(start 184.00776 -197.750176)
		(end 184.00776 -196.708522)
		(width 0.10414)
		(layer "B.Cu")
		(net "LAN2_P3_P")
	)
	(segment
		(start 179.507896 -168.884346)
		(end 179.077874 -169.314368)
		(width 0.10414)
		(layer "B.Cu")
		(net "LAN2_P3_P")
	)
	(segment
		(start 117.33149 -157.447742)
		(end 117.33149 -158.541212)
		(width 0.1016)
		(layer "F.Cu")
		(net "POWER_SW3_PWR_CTR_N")
	)
	(segment
		(start 117.33149 -158.541212)
		(end 116.76126 -159.111442)
		(width 0.1016)
		(layer "F.Cu")
		(net "POWER_SW3_PWR_CTR_N")
	)
	(via
		(at 101.78542 -183.376316)
		(size 0.508)
		(drill 0.254)
		(layers "F.Cu" "B.Cu")
		(net "POWER_SW3_PWR_CTR_N")
	)
	(via
		(at 116.76126 -159.111442)
		(size 0.508)
		(drill 0.254)
		(layers "F.Cu" "B.Cu")
		(net "POWER_SW3_PWR_CTR_N")
	)
	(via
		(at 101.24948 -178.158394)
		(size 0.508)
		(drill 0.254)
		(layers "F.Cu" "B.Cu")
		(net "POWER_SW3_PWR_CTR_N")
	)
	(segment
		(start 108.0008 -174.296832)
		(end 108.0008 -171.463462)
		(width 0.1016)
		(layer "B.Cu")
		(net "POWER_SW3_PWR_CTR_N")
	)
	(segment
		(start 103.36276 -177.54473)
		(end 104.068118 -177.54473)
		(width 0.1016)
		(layer "B.Cu")
		(net "POWER_SW3_PWR_CTR_N")
	)
	(segment
		(start 122.07494 -167.212264)
		(end 122.98172 -166.305484)
		(width 0.1016)
		(layer "B.Cu")
		(net "POWER_SW3_PWR_CTR_N")
	)
	(segment
		(start 101.78542 -183.376316)
		(end 101.78542 -183.162702)
		(width 0.1016)
		(layer "B.Cu")
		(net "POWER_SW3_PWR_CTR_N")
	)
	(segment
		(start 122.98172 -163.38931)
		(end 121.809002 -162.216592)
		(width 0.1016)
		(layer "B.Cu")
		(net "POWER_SW3_PWR_CTR_N")
	)
	(segment
		(start 107.215432 -175.857154)
		(end 107.64901 -175.857154)
		(width 0.1016)
		(layer "B.Cu")
		(net "POWER_SW3_PWR_CTR_N")
	)
	(segment
		(start 122.98172 -166.305484)
		(end 122.98172 -163.38931)
		(width 0.1016)
		(layer "B.Cu")
		(net "POWER_SW3_PWR_CTR_N")
	)
	(segment
		(start 121.809002 -162.216592)
		(end 120.618758 -162.216592)
		(width 0.1016)
		(layer "B.Cu")
		(net "POWER_SW3_PWR_CTR_N")
	)
	(segment
		(start 108.0008 -171.463462)
		(end 112.044734 -167.419528)
		(width 0.1016)
		(layer "B.Cu")
		(net "POWER_SW3_PWR_CTR_N")
	)
	(segment
		(start 105.0544 -176.558448)
		(end 106.105706 -176.558448)
		(width 0.1016)
		(layer "B.Cu")
		(net "POWER_SW3_PWR_CTR_N")
	)
	(segment
		(start 120.618758 -162.216592)
		(end 117.513608 -159.111442)
		(width 0.1016)
		(layer "B.Cu")
		(net "POWER_SW3_PWR_CTR_N")
	)
	(segment
		(start 101.78542 -183.162702)
		(end 101.458522 -182.835804)
		(width 0.1016)
		(layer "B.Cu")
		(net "POWER_SW3_PWR_CTR_N")
	)
	(segment
		(start 112.044734 -167.419528)
		(end 113.27765 -167.419528)
		(width 0.1016)
		(layer "B.Cu")
		(net "POWER_SW3_PWR_CTR_N")
	)
	(segment
		(start 107.64901 -175.857154)
		(end 108.425742 -175.080422)
		(width 0.1016)
		(layer "B.Cu")
		(net "POWER_SW3_PWR_CTR_N")
	)
	(segment
		(start 119.786908 -170.541696)
		(end 122.07494 -168.253664)
		(width 0.1016)
		(layer "B.Cu")
		(net "POWER_SW3_PWR_CTR_N")
	)
	(segment
		(start 101.863144 -177.54473)
		(end 101.24948 -178.158394)
		(width 0.1016)
		(layer "B.Cu")
		(net "POWER_SW3_PWR_CTR_N")
	)
	(segment
		(start 122.07494 -168.253664)
		(end 122.07494 -167.212264)
		(width 0.1016)
		(layer "B.Cu")
		(net "POWER_SW3_PWR_CTR_N")
	)
	(segment
		(start 113.27765 -167.419528)
		(end 116.399818 -170.541696)
		(width 0.1016)
		(layer "B.Cu")
		(net "POWER_SW3_PWR_CTR_N")
	)
	(segment
		(start 106.105706 -176.558448)
		(end 106.819192 -175.844962)
		(width 0.1016)
		(layer "B.Cu")
		(net "POWER_SW3_PWR_CTR_N")
	)
	(segment
		(start 106.819192 -175.844962)
		(end 107.20324 -175.844962)
		(width 0.1016)
		(layer "B.Cu")
		(net "POWER_SW3_PWR_CTR_N")
	)
	(segment
		(start 101.458522 -182.835804)
		(end 101.458522 -181.928516)
		(width 0.1016)
		(layer "B.Cu")
		(net "POWER_SW3_PWR_CTR_N")
	)
	(segment
		(start 117.513608 -159.111442)
		(end 116.76126 -159.111442)
		(width 0.1016)
		(layer "B.Cu")
		(net "POWER_SW3_PWR_CTR_N")
	)
	(segment
		(start 108.425742 -174.721774)
		(end 108.0008 -174.296832)
		(width 0.1016)
		(layer "B.Cu")
		(net "POWER_SW3_PWR_CTR_N")
	)
	(segment
		(start 104.068118 -177.54473)
		(end 105.0544 -176.558448)
		(width 0.1016)
		(layer "B.Cu")
		(net "POWER_SW3_PWR_CTR_N")
	)
	(segment
		(start 103.36276 -177.54473)
		(end 101.863144 -177.54473)
		(width 0.1016)
		(layer "B.Cu")
		(net "POWER_SW3_PWR_CTR_N")
	)
	(segment
		(start 108.425742 -175.080422)
		(end 108.425742 -174.721774)
		(width 0.1016)
		(layer "B.Cu")
		(net "POWER_SW3_PWR_CTR_N")
	)
	(segment
		(start 116.399818 -170.541696)
		(end 119.786908 -170.541696)
		(width 0.1016)
		(layer "B.Cu")
		(net "POWER_SW3_PWR_CTR_N")
	)
	(segment
		(start 107.20324 -175.844962)
		(end 107.215432 -175.857154)
		(width 0.1016)
		(layer "B.Cu")
		(net "POWER_SW3_PWR_CTR_N")
	)
	(segment
		(start 101.24948 -182.840376)
		(end 101.24948 -178.158394)
		(width 0.1143)
		(layer "In7.Cu")
		(net "POWER_SW3_PWR_CTR_N")
	)
	(segment
		(start 101.78542 -183.376316)
		(end 101.24948 -182.840376)
		(width 0.1143)
		(layer "In7.Cu")
		(net "POWER_SW3_PWR_CTR_N")
	)
	(segment
		(start 23.101554 -101.47808)
		(end 22.69236 -101.068886)
		(width 0.1016)
		(layer "F.Cu")
		(net "FRU_SYS_A2")
	)
	(segment
		(start 20.343876 -101.069902)
		(end 21.14423 -101.069902)
		(width 0.1016)
		(layer "F.Cu")
		(net "FRU_SYS_A2")
	)
	(segment
		(start 22.69236 -101.068886)
		(end 21.14423 -101.068886)
		(width 0.1016)
		(layer "F.Cu")
		(net "FRU_SYS_A2")
	)
	(segment
		(start 23.101554 -102.709472)
		(end 23.101554 -101.47808)
		(width 0.1016)
		(layer "F.Cu")
		(net "FRU_SYS_A2")
	)
	(segment
		(start 20.343876 -100.039678)
		(end 20.343876 -101.069902)
		(width 0.1016)
		(layer "F.Cu")
		(net "FRU_SYS_A2")
	)
	(segment
		(start 21.14423 -101.068886)
		(end 21.14423 -101.069902)
		(width 0.1016)
		(layer "F.Cu")
		(net "FRU_SYS_A2")
	)
	(via
		(at 21.14423 -101.069902)
		(size 0.508)
		(drill 0.254)
		(layers "F.Cu" "B.Cu")
		(net "FRU_SYS_A2")
	)
	(segment
		(start 21.66747 -98.963734)
		(end 21.103336 -98.963734)
		(width 0.1016)
		(layer "F.Cu")
		(net "FRU_SYS_A1")
	)
	(segment
		(start 20.338796 -97.973388)
		(end 20.338796 -98.963734)
		(width 0.1016)
		(layer "F.Cu")
		(net "FRU_SYS_A1")
	)
	(segment
		(start 20.338796 -98.963734)
		(end 21.103336 -98.963734)
		(width 0.1016)
		(layer "F.Cu")
		(net "FRU_SYS_A1")
	)
	(segment
		(start 24.371554 -101.667818)
		(end 21.66747 -98.963734)
		(width 0.1016)
		(layer "F.Cu")
		(net "FRU_SYS_A1")
	)
	(segment
		(start 24.371554 -102.709472)
		(end 24.371554 -101.667818)
		(width 0.1016)
		(layer "F.Cu")
		(net "FRU_SYS_A1")
	)
	(via
		(at 21.103336 -98.963734)
		(size 0.508)
		(drill 0.254)
		(layers "F.Cu" "B.Cu")
		(net "FRU_SYS_A1")
	)
	(segment
		(start 119.487696 -151.666956)
		(end 119.35206 -151.53132)
		(width 0.1016)
		(layer "F.Cu")
		(net "N52998343")
	)
	(segment
		(start 119.35206 -151.53132)
		(end 119.01678 -151.19604)
		(width 0.1016)
		(layer "F.Cu")
		(net "N52998343")
	)
	(segment
		(start 121.516394 -151.666956)
		(end 120.496838 -151.666956)
		(width 0.1016)
		(layer "F.Cu")
		(net "N52998343")
	)
	(segment
		(start 120.496838 -151.666956)
		(end 119.487696 -151.666956)
		(width 0.1016)
		(layer "F.Cu")
		(net "N52998343")
	)
	(segment
		(start 119.01678 -151.19604)
		(end 118.15191 -151.19604)
		(width 0.1016)
		(layer "F.Cu")
		(net "N52998343")
	)
	(via
		(at 119.35206 -151.53132)
		(size 0.508)
		(drill 0.254)
		(layers "F.Cu" "B.Cu")
		(net "N52998343")
	)
	(segment
		(start 11.058906 -158.220156)
		(end 11.058906 -157.680406)
		(width 0.1016)
		(layer "F.Cu")
		(net "N54258513")
	)
	(segment
		(start 12.26058 -154.53741)
		(end 12.26058 -156.478732)
		(width 0.1016)
		(layer "F.Cu")
		(net "N54258513")
	)
	(segment
		(start 11.058906 -157.680406)
		(end 12.05992 -156.679392)
		(width 0.1016)
		(layer "F.Cu")
		(net "N54258513")
	)
	(segment
		(start 12.26058 -156.478732)
		(end 12.05992 -156.679392)
		(width 0.1016)
		(layer "F.Cu")
		(net "N54258513")
	)
	(via
		(at 12.05992 -156.679392)
		(size 0.508)
		(drill 0.254)
		(layers "F.Cu" "B.Cu")
		(net "N54258513")
	)
	(segment
		(start 121.5644 -149.675088)
		(end 121.608088 -149.675088)
		(width 0.1016)
		(layer "F.Cu")
		(net "N52998345")
	)
	(segment
		(start 122.26036 -150.32736)
		(end 122.26036 -150.697184)
		(width 0.1016)
		(layer "F.Cu")
		(net "N52998345")
	)
	(segment
		(start 122.090688 -150.866856)
		(end 121.516394 -150.866856)
		(width 0.1016)
		(layer "F.Cu")
		(net "N52998345")
	)
	(segment
		(start 121.608088 -149.675088)
		(end 122.26036 -150.32736)
		(width 0.1016)
		(layer "F.Cu")
		(net "N52998345")
	)
	(segment
		(start 122.26036 -150.697184)
		(end 122.090688 -150.866856)
		(width 0.1016)
		(layer "F.Cu")
		(net "N52998345")
	)
	(via
		(at 122.26036 -150.697184)
		(size 0.508)
		(drill 0.254)
		(layers "F.Cu" "B.Cu")
		(net "N52998345")
	)
	(segment
		(start 10.40892 -166.751762)
		(end 10.40892 -166.724584)
		(width 0.1016)
		(layer "F.Cu")
		(net "N54258525")
	)
	(segment
		(start 10.240518 -166.920164)
		(end 10.40892 -166.751762)
		(width 0.1016)
		(layer "F.Cu")
		(net "N54258525")
	)
	(segment
		(start 10.40892 -164.062156)
		(end 10.40892 -166.724584)
		(width 0.1016)
		(layer "F.Cu")
		(net "N54258525")
	)
	(segment
		(start 10.240518 -167.373554)
		(end 10.240518 -166.920164)
		(width 0.1016)
		(layer "F.Cu")
		(net "N54258525")
	)
	(via
		(at 10.40892 -166.724584)
		(size 0.508)
		(drill 0.254)
		(layers "F.Cu" "B.Cu")
		(net "N54258525")
	)
	(segment
		(start 119.66448 -149.422358)
		(end 119.05996 -148.817838)
		(width 0.1016)
		(layer "F.Cu")
		(net "N52998325")
	)
	(segment
		(start 118.635018 -149.24278)
		(end 117.822218 -149.24278)
		(width 0.1016)
		(layer "F.Cu")
		(net "N52998325")
	)
	(segment
		(start 119.05996 -148.817838)
		(end 118.635018 -149.24278)
		(width 0.1016)
		(layer "F.Cu")
		(net "N52998325")
	)
	(segment
		(start 119.66448 -149.675088)
		(end 119.66448 -149.422358)
		(width 0.1016)
		(layer "F.Cu")
		(net "N52998325")
	)
	(via
		(at 119.05996 -148.817838)
		(size 0.508)
		(drill 0.254)
		(layers "F.Cu" "B.Cu")
		(net "N52998325")
	)
	(segment
		(start 165.2778 -186.5884)
		(end 165.6334 -186.944)
		(width 0.1016)
		(layer "F.Cu")
		(net "UART_DTR_RP5_L_N")
	)
	(segment
		(start 165.2778 -186.601862)
		(end 165.2778 -186.5884)
		(width 0.1016)
		(layer "F.Cu")
		(net "UART_DTR_RP5_L_N")
	)
	(segment
		(start 162.91814 -179.597558)
		(end 162.91814 -184.242202)
		(width 0.1016)
		(layer "F.Cu")
		(net "UART_DTR_RP5_L_N")
	)
	(segment
		(start 165.2778 -190.0682)
		(end 165.2778 -192.1256)
		(width 0.1016)
		(layer "F.Cu")
		(net "UART_DTR_RP5_L_N")
	)
	(segment
		(start 165.6334 -186.944)
		(end 165.6334 -189.7126)
		(width 0.1016)
		(layer "F.Cu")
		(net "UART_DTR_RP5_L_N")
	)
	(segment
		(start 161.21126 -197.731888)
		(end 161.21126 -194.561968)
		(width 0.1016)
		(layer "F.Cu")
		(net "UART_DTR_RP5_L_N")
	)
	(segment
		(start 165.2778 -192.1256)
		(end 165.00856 -192.39484)
		(width 0.1016)
		(layer "F.Cu")
		(net "UART_DTR_RP5_L_N")
	)
	(segment
		(start 161.21126 -194.561968)
		(end 162.17138 -193.601848)
		(width 0.1016)
		(layer "F.Cu")
		(net "UART_DTR_RP5_L_N")
	)
	(segment
		(start 165.6334 -189.7126)
		(end 165.2778 -190.0682)
		(width 0.1016)
		(layer "F.Cu")
		(net "UART_DTR_RP5_L_N")
	)
	(segment
		(start 163.015676 -205.199488)
		(end 163.015676 -199.536304)
		(width 0.1016)
		(layer "F.Cu")
		(net "UART_DTR_RP5_L_N")
	)
	(segment
		(start 165.00856 -192.39484)
		(end 165.00856 -192.411858)
		(width 0.1016)
		(layer "F.Cu")
		(net "UART_DTR_RP5_L_N")
	)
	(segment
		(start 164.413184 -178.102514)
		(end 162.91814 -179.597558)
		(width 0.1016)
		(layer "F.Cu")
		(net "UART_DTR_RP5_L_N")
	)
	(segment
		(start 163.015676 -199.536304)
		(end 161.21126 -197.731888)
		(width 0.1016)
		(layer "F.Cu")
		(net "UART_DTR_RP5_L_N")
	)
	(segment
		(start 165.217602 -178.102514)
		(end 164.413184 -178.102514)
		(width 0.1016)
		(layer "F.Cu")
		(net "UART_DTR_RP5_L_N")
	)
	(segment
		(start 162.91814 -184.242202)
		(end 165.2778 -186.601862)
		(width 0.1016)
		(layer "F.Cu")
		(net "UART_DTR_RP5_L_N")
	)
	(via
		(at 162.17138 -193.601848)
		(size 0.508)
		(drill 0.254)
		(layers "F.Cu" "B.Cu")
		(net "UART_DTR_RP5_L_N")
	)
	(via
		(at 165.00856 -192.411858)
		(size 0.508)
		(drill 0.254)
		(layers "F.Cu" "B.Cu")
		(net "UART_DTR_RP5_L_N")
	)
	(segment
		(start 162.17138 -193.601848)
		(end 163.36137 -192.411858)
		(width 0.1143)
		(layer "In7.Cu")
		(net "UART_DTR_RP5_L_N")
	)
	(segment
		(start 163.36137 -192.411858)
		(end 165.00856 -192.411858)
		(width 0.1143)
		(layer "In7.Cu")
		(net "UART_DTR_RP5_L_N")
	)
	(segment
		(start 8.19658 -155.070302)
		(end 7.808976 -155.457906)
		(width 0.1016)
		(layer "F.Cu")
		(net "N54258474")
	)
	(segment
		(start 7.808976 -158.220156)
		(end 7.808976 -156.946092)
		(width 0.1016)
		(layer "F.Cu")
		(net "N54258474")
	)
	(segment
		(start 8.19658 -154.53741)
		(end 8.19658 -155.070302)
		(width 0.1016)
		(layer "F.Cu")
		(net "N54258474")
	)
	(segment
		(start 7.808976 -155.457906)
		(end 7.808976 -156.946092)
		(width 0.1016)
		(layer "F.Cu")
		(net "N54258474")
	)
	(via
		(at 7.808976 -156.946092)
		(size 0.508)
		(drill 0.254)
		(layers "F.Cu" "B.Cu")
		(net "N54258474")
	)
	(segment
		(start 119.16791 -153.43124)
		(end 119.16791 -154.645106)
		(width 0.1016)
		(layer "F.Cu")
		(net "N52998261")
	)
	(segment
		(start 117.491764 -155.754578)
		(end 117.41658 -155.679394)
		(width 0.1016)
		(layer "F.Cu")
		(net "N52998261")
	)
	(segment
		(start 117.41658 -155.679394)
		(end 116.949728 -155.212542)
		(width 0.1016)
		(layer "F.Cu")
		(net "N52998261")
	)
	(segment
		(start 119.16791 -154.645106)
		(end 118.577868 -155.235148)
		(width 0.1016)
		(layer "F.Cu")
		(net "N52998261")
	)
	(segment
		(start 118.577868 -155.235148)
		(end 118.577868 -155.754578)
		(width 0.1016)
		(layer "F.Cu")
		(net "N52998261")
	)
	(segment
		(start 118.707662 -155.884372)
		(end 118.577868 -155.754578)
		(width 0.1016)
		(layer "F.Cu")
		(net "N52998261")
	)
	(segment
		(start 116.949728 -155.212542)
		(end 116.31549 -155.212542)
		(width 0.1016)
		(layer "F.Cu")
		(net "N52998261")
	)
	(segment
		(start 118.577868 -155.754578)
		(end 117.491764 -155.754578)
		(width 0.1016)
		(layer "F.Cu")
		(net "N52998261")
	)
	(segment
		(start 118.707662 -156.94152)
		(end 118.707662 -155.884372)
		(width 0.1016)
		(layer "F.Cu")
		(net "N52998261")
	)
	(via
		(at 117.41658 -155.679394)
		(size 0.508)
		(drill 0.254)
		(layers "F.Cu" "B.Cu")
		(net "N52998261")
	)
	(segment
		(start 11.058906 -164.062156)
		(end 11.058906 -165.081712)
		(width 0.1016)
		(layer "F.Cu")
		(net "N54258523")
	)
	(segment
		(start 11.040618 -167.373554)
		(end 11.040618 -165.659308)
		(width 0.1016)
		(layer "F.Cu")
		(net "N54258523")
	)
	(segment
		(start 11.058906 -165.081712)
		(end 11.33856 -165.361366)
		(width 0.1016)
		(layer "F.Cu")
		(net "N54258523")
	)
	(segment
		(start 11.040618 -165.659308)
		(end 11.33856 -165.361366)
		(width 0.1016)
		(layer "F.Cu")
		(net "N54258523")
	)
	(via
		(at 11.33856 -165.361366)
		(size 0.508)
		(drill 0.254)
		(layers "F.Cu" "B.Cu")
		(net "N54258523")
	)
	(segment
		(start 7.18058 -154.53741)
		(end 7.15899 -154.559)
		(width 0.1016)
		(layer "F.Cu")
		(net "N54258476")
	)
	(segment
		(start 7.15899 -154.559)
		(end 7.15899 -155.470352)
		(width 0.1016)
		(layer "F.Cu")
		(net "N54258476")
	)
	(segment
		(start 7.15899 -158.220156)
		(end 7.15899 -155.470352)
		(width 0.1016)
		(layer "F.Cu")
		(net "N54258476")
	)
	(via
		(at 7.15899 -155.470352)
		(size 0.508)
		(drill 0.254)
		(layers "F.Cu" "B.Cu")
		(net "N54258476")
	)
	(via
		(at 163.60394 -196.369432)
		(size 0.6604)
		(drill 0.3302)
		(layers "F.Cu" "B.Cu")
		(net "UART_TX_RP6_L")
	)
	(segment
		(start 163.0172 -187.01258)
		(end 163.32962 -187.325)
		(width 0.1016)
		(layer "B.Cu")
		(net "UART_TX_RP6_L")
	)
	(segment
		(start 159.375602 -177.452528)
		(end 160.964626 -177.452528)
		(width 0.1016)
		(layer "B.Cu")
		(net "UART_TX_RP6_L")
	)
	(segment
		(start 161.79038 -184.304432)
		(end 162.39998 -184.914032)
		(width 0.1016)
		(layer "B.Cu")
		(net "UART_TX_RP6_L")
	)
	(segment
		(start 163.60394 -195.586604)
		(end 163.60394 -196.369432)
		(width 0.1016)
		(layer "B.Cu")
		(net "UART_TX_RP6_L")
	)
	(segment
		(start 163.60394 -196.369432)
		(end 163.60394 -200.474834)
		(width 0.1016)
		(layer "B.Cu")
		(net "UART_TX_RP6_L")
	)
	(segment
		(start 161.47796 -183.021986)
		(end 161.79038 -183.334406)
		(width 0.1016)
		(layer "B.Cu")
		(net "UART_TX_RP6_L")
	)
	(segment
		(start 161.79038 -183.334406)
		(end 161.79038 -184.304432)
		(width 0.1016)
		(layer "B.Cu")
		(net "UART_TX_RP6_L")
	)
	(segment
		(start 162.39998 -184.914032)
		(end 162.39998 -185.71718)
		(width 0.1016)
		(layer "B.Cu")
		(net "UART_TX_RP6_L")
	)
	(segment
		(start 165.015672 -201.886566)
		(end 165.015672 -205.199488)
		(width 0.1016)
		(layer "B.Cu")
		(net "UART_TX_RP6_L")
	)
	(segment
		(start 161.47796 -177.965862)
		(end 161.47796 -183.021986)
		(width 0.1016)
		(layer "B.Cu")
		(net "UART_TX_RP6_L")
	)
	(segment
		(start 163.32962 -195.312284)
		(end 163.60394 -195.586604)
		(width 0.1016)
		(layer "B.Cu")
		(net "UART_TX_RP6_L")
	)
	(segment
		(start 160.964626 -177.452528)
		(end 161.47796 -177.965862)
		(width 0.1016)
		(layer "B.Cu")
		(net "UART_TX_RP6_L")
	)
	(segment
		(start 163.32962 -187.325)
		(end 163.32962 -195.312284)
		(width 0.1016)
		(layer "B.Cu")
		(net "UART_TX_RP6_L")
	)
	(segment
		(start 163.60394 -200.474834)
		(end 165.015672 -201.886566)
		(width 0.1016)
		(layer "B.Cu")
		(net "UART_TX_RP6_L")
	)
	(segment
		(start 163.0172 -186.3344)
		(end 163.0172 -187.01258)
		(width 0.1016)
		(layer "B.Cu")
		(net "UART_TX_RP6_L")
	)
	(segment
		(start 162.39998 -185.71718)
		(end 163.0172 -186.3344)
		(width 0.1016)
		(layer "B.Cu")
		(net "UART_TX_RP6_L")
	)
	(segment
		(start 11.24458 -154.53741)
		(end 11.24458 -155.236418)
		(width 0.1016)
		(layer "F.Cu")
		(net "N54258535")
	)
	(segment
		(start 10.40892 -156.963618)
		(end 10.9093 -156.463238)
		(width 0.1016)
		(layer "F.Cu")
		(net "N54258535")
	)
	(segment
		(start 10.40892 -158.220156)
		(end 10.40892 -156.963618)
		(width 0.1016)
		(layer "F.Cu")
		(net "N54258535")
	)
	(segment
		(start 11.24458 -155.236418)
		(end 10.9093 -155.571698)
		(width 0.1016)
		(layer "F.Cu")
		(net "N54258535")
	)
	(segment
		(start 10.9093 -156.463238)
		(end 10.9093 -155.571698)
		(width 0.1016)
		(layer "F.Cu")
		(net "N54258535")
	)
	(via
		(at 10.9093 -155.571698)
		(size 0.508)
		(drill 0.254)
		(layers "F.Cu" "B.Cu")
		(net "N54258535")
	)
	(segment
		(start 9.63168 -166.307008)
		(end 9.63168 -165.564312)
		(width 0.1016)
		(layer "F.Cu")
		(net "N54258537")
	)
	(segment
		(start 9.758934 -164.062156)
		(end 9.758934 -165.437058)
		(width 0.1016)
		(layer "F.Cu")
		(net "N54258537")
	)
	(segment
		(start 9.758934 -165.437058)
		(end 9.63168 -165.564312)
		(width 0.1016)
		(layer "F.Cu")
		(net "N54258537")
	)
	(segment
		(start 9.13384 -166.804848)
		(end 9.63168 -166.307008)
		(width 0.1016)
		(layer "F.Cu")
		(net "N54258537")
	)
	(segment
		(start 9.13384 -167.373554)
		(end 9.13384 -166.804848)
		(width 0.1016)
		(layer "F.Cu")
		(net "N54258537")
	)
	(via
		(at 9.63168 -165.564312)
		(size 0.508)
		(drill 0.254)
		(layers "F.Cu" "B.Cu")
		(net "N54258537")
	)
	(segment
		(start 8.259572 -145.418048)
		(end 6.490462 -147.187158)
		(width 0.1016)
		(layer "F.Cu")
		(net "UART_RTS_P6_L_N")
	)
	(segment
		(start 12.886944 -145.521172)
		(end 12.78382 -145.418048)
		(width 0.1016)
		(layer "F.Cu")
		(net "UART_RTS_P6_L_N")
	)
	(segment
		(start 6.490462 -147.187158)
		(end 6.490462 -148.392642)
		(width 0.1016)
		(layer "F.Cu")
		(net "UART_RTS_P6_L_N")
	)
	(segment
		(start 14.65834 -145.521172)
		(end 12.886944 -145.521172)
		(width 0.1016)
		(layer "F.Cu")
		(net "UART_RTS_P6_L_N")
	)
	(segment
		(start 12.78382 -145.418048)
		(end 8.259572 -145.418048)
		(width 0.1016)
		(layer "F.Cu")
		(net "UART_RTS_P6_L_N")
	)
	(via
		(at 14.65834 -145.521172)
		(size 0.508)
		(drill 0.254)
		(layers "F.Cu" "B.Cu")
		(net "UART_RTS_P6_L_N")
	)
	(via
		(at 43.8404 -198.1581)
		(size 0.508)
		(drill 0.254)
		(layers "F.Cu" "B.Cu")
		(net "UART_RTS_P6_L_N")
	)
	(segment
		(start 43.0149 -205.199488)
		(end 43.0149 -200.176384)
		(width 0.1016)
		(layer "B.Cu")
		(net "UART_RTS_P6_L_N")
	)
	(segment
		(start 43.8404 -199.350884)
		(end 43.8404 -198.1581)
		(width 0.1016)
		(layer "B.Cu")
		(net "UART_RTS_P6_L_N")
	)
	(segment
		(start 43.0149 -200.176384)
		(end 43.8404 -199.350884)
		(width 0.1016)
		(layer "B.Cu")
		(net "UART_RTS_P6_L_N")
	)
	(segment
		(start 33.358328 -176.278032)
		(end 33.201102 -176.435258)
		(width 0.1143)
		(layer "In2.Cu")
		(net "UART_RTS_P6_L_N")
	)
	(segment
		(start 33.201102 -179.184554)
		(end 33.23463 -179.218082)
		(width 0.1143)
		(layer "In2.Cu")
		(net "UART_RTS_P6_L_N")
	)
	(segment
		(start 36.226496 -189.952884)
		(end 43.8404 -197.566788)
		(width 0.1143)
		(layer "In2.Cu")
		(net "UART_RTS_P6_L_N")
	)
	(segment
		(start 33.23463 -183.623204)
		(end 33.07207 -183.785764)
		(width 0.1143)
		(layer "In2.Cu")
		(net "UART_RTS_P6_L_N")
	)
	(segment
		(start 33.07207 -183.785764)
		(end 33.07207 -186.717432)
		(width 0.1143)
		(layer "In2.Cu")
		(net "UART_RTS_P6_L_N")
	)
	(segment
		(start 33.07207 -186.717432)
		(end 33.50387 -187.149232)
		(width 0.1143)
		(layer "In2.Cu")
		(net "UART_RTS_P6_L_N")
	)
	(segment
		(start 22.92096 -164.179758)
		(end 32.536638 -173.795436)
		(width 0.1143)
		(layer "In2.Cu")
		(net "UART_RTS_P6_L_N")
	)
	(segment
		(start 33.50387 -187.149232)
		(end 35.00755 -187.149232)
		(width 0.1143)
		(layer "In2.Cu")
		(net "UART_RTS_P6_L_N")
	)
	(segment
		(start 33.358328 -174.24908)
		(end 33.358328 -176.278032)
		(width 0.1143)
		(layer "In2.Cu")
		(net "UART_RTS_P6_L_N")
	)
	(segment
		(start 32.904684 -173.795436)
		(end 33.358328 -174.24908)
		(width 0.1143)
		(layer "In2.Cu")
		(net "UART_RTS_P6_L_N")
	)
	(segment
		(start 33.23463 -179.218082)
		(end 33.23463 -183.623204)
		(width 0.1143)
		(layer "In2.Cu")
		(net "UART_RTS_P6_L_N")
	)
	(segment
		(start 32.536638 -173.795436)
		(end 32.904684 -173.795436)
		(width 0.1143)
		(layer "In2.Cu")
		(net "UART_RTS_P6_L_N")
	)
	(segment
		(start 14.65834 -145.521172)
		(end 22.92096 -153.783792)
		(width 0.1143)
		(layer "In2.Cu")
		(net "UART_RTS_P6_L_N")
	)
	(segment
		(start 35.00755 -187.149232)
		(end 36.226496 -188.368178)
		(width 0.1143)
		(layer "In2.Cu")
		(net "UART_RTS_P6_L_N")
	)
	(segment
		(start 43.8404 -197.566788)
		(end 43.8404 -198.1581)
		(width 0.1143)
		(layer "In2.Cu")
		(net "UART_RTS_P6_L_N")
	)
	(segment
		(start 22.92096 -153.783792)
		(end 22.92096 -164.179758)
		(width 0.1143)
		(layer "In2.Cu")
		(net "UART_RTS_P6_L_N")
	)
	(segment
		(start 33.201102 -176.435258)
		(end 33.201102 -179.184554)
		(width 0.1143)
		(layer "In2.Cu")
		(net "UART_RTS_P6_L_N")
	)
	(segment
		(start 36.226496 -188.368178)
		(end 36.226496 -189.952884)
		(width 0.1143)
		(layer "In2.Cu")
		(net "UART_RTS_P6_L_N")
	)
	(segment
		(start 90.56116 -127.449072)
		(end 89.54897 -126.436882)
		(width 0.1016)
		(layer "F.Cu")
		(net "CLK_33M_PORT80")
	)
	(segment
		(start 134.85876 -107.970574)
		(end 134.85876 -107.240578)
		(width 0.1016)
		(layer "F.Cu")
		(net "CLK_33M_PORT80")
	)
	(segment
		(start 89.54897 -126.436882)
		(end 88.486996 -126.436882)
		(width 0.1016)
		(layer "F.Cu")
		(net "CLK_33M_PORT80")
	)
	(segment
		(start 95.64116 -126.58979)
		(end 95.56369 -126.66726)
		(width 0.1016)
		(layer "F.Cu")
		(net "CLK_33M_PORT80")
	)
	(segment
		(start 93.322648 -127.449072)
		(end 90.56116 -127.449072)
		(width 0.1016)
		(layer "F.Cu")
		(net "CLK_33M_PORT80")
	)
	(segment
		(start 94.10446 -126.66726)
		(end 93.322648 -127.449072)
		(width 0.1016)
		(layer "F.Cu")
		(net "CLK_33M_PORT80")
	)
	(segment
		(start 87.866474 -125.81636)
		(end 87.866474 -125.19152)
		(width 0.1016)
		(layer "F.Cu")
		(net "CLK_33M_PORT80")
	)
	(segment
		(start 88.486996 -126.436882)
		(end 87.866474 -125.81636)
		(width 0.1016)
		(layer "F.Cu")
		(net "CLK_33M_PORT80")
	)
	(segment
		(start 95.56369 -126.66726)
		(end 94.10446 -126.66726)
		(width 0.1016)
		(layer "F.Cu")
		(net "CLK_33M_PORT80")
	)
	(via
		(at 134.85876 -107.240578)
		(size 0.508)
		(drill 0.254)
		(layers "F.Cu" "B.Cu")
		(net "CLK_33M_PORT80")
	)
	(via
		(at 95.64116 -126.58979)
		(size 0.508)
		(drill 0.254)
		(layers "F.Cu" "B.Cu")
		(net "CLK_33M_PORT80")
	)
	(via
		(at 96.24314 -109.441996)
		(size 0.508)
		(drill 0.254)
		(layers "F.Cu" "B.Cu")
		(net "CLK_33M_PORT80")
	)
	(segment
		(start 96.24314 -109.441996)
		(end 95.61449 -110.070646)
		(width 0.1143)
		(layer "In2.Cu")
		(net "CLK_33M_PORT80")
	)
	(segment
		(start 95.391986 -118.569486)
		(end 95.391986 -120.420892)
		(width 0.1143)
		(layer "In2.Cu")
		(net "CLK_33M_PORT80")
	)
	(segment
		(start 94.85884 -117.673374)
		(end 94.85884 -118.03634)
		(width 0.1143)
		(layer "In2.Cu")
		(net "CLK_33M_PORT80")
	)
	(segment
		(start 95.61449 -116.917724)
		(end 94.85884 -117.673374)
		(width 0.1143)
		(layer "In2.Cu")
		(net "CLK_33M_PORT80")
	)
	(segment
		(start 95.56496 -126.51359)
		(end 95.64116 -126.58979)
		(width 0.1143)
		(layer "In2.Cu")
		(net "CLK_33M_PORT80")
	)
	(segment
		(start 95.61449 -110.070646)
		(end 95.61449 -116.917724)
		(width 0.1143)
		(layer "In2.Cu")
		(net "CLK_33M_PORT80")
	)
	(segment
		(start 95.391986 -120.420892)
		(end 95.56496 -120.593866)
		(width 0.1143)
		(layer "In2.Cu")
		(net "CLK_33M_PORT80")
	)
	(segment
		(start 94.85884 -118.03634)
		(end 95.391986 -118.569486)
		(width 0.1143)
		(layer "In2.Cu")
		(net "CLK_33M_PORT80")
	)
	(segment
		(start 95.56496 -120.593866)
		(end 95.56496 -126.51359)
		(width 0.1143)
		(layer "In2.Cu")
		(net "CLK_33M_PORT80")
	)
	(segment
		(start 132.015738 -104.71277)
		(end 134.543546 -107.240578)
		(width 0.1143)
		(layer "In6.Cu")
		(net "CLK_33M_PORT80")
	)
	(segment
		(start 96.338644 -109.441996)
		(end 98.808032 -106.972608)
		(width 0.1143)
		(layer "In6.Cu")
		(net "CLK_33M_PORT80")
	)
	(segment
		(start 119.208804 -106.972608)
		(end 121.468642 -104.71277)
		(width 0.1143)
		(layer "In6.Cu")
		(net "CLK_33M_PORT80")
	)
	(segment
		(start 134.543546 -107.240578)
		(end 134.85876 -107.240578)
		(width 0.1143)
		(layer "In6.Cu")
		(net "CLK_33M_PORT80")
	)
	(segment
		(start 96.24314 -109.441996)
		(end 96.338644 -109.441996)
		(width 0.1143)
		(layer "In6.Cu")
		(net "CLK_33M_PORT80")
	)
	(segment
		(start 121.468642 -104.71277)
		(end 132.015738 -104.71277)
		(width 0.1143)
		(layer "In6.Cu")
		(net "CLK_33M_PORT80")
	)
	(segment
		(start 98.808032 -106.972608)
		(end 119.208804 -106.972608)
		(width 0.1143)
		(layer "In6.Cu")
		(net "CLK_33M_PORT80")
	)
	(segment
		(start 12.26058 -153.199846)
		(end 11.703558 -152.642824)
		(width 0.1016)
		(layer "F.Cu")
		(net "N54258515")
	)
	(segment
		(start 11.703558 -152.642824)
		(end 9.99998 -152.642824)
		(width 0.1016)
		(layer "F.Cu")
		(net "N54258515")
	)
	(segment
		(start 8.84936 -153.491946)
		(end 9.698482 -152.642824)
		(width 0.1016)
		(layer "F.Cu")
		(net "N54258515")
	)
	(segment
		(start 8.84936 -156.01188)
		(end 8.84936 -153.491946)
		(width 0.1016)
		(layer "F.Cu")
		(net "N54258515")
	)
	(segment
		(start 8.458962 -158.220156)
		(end 8.458962 -156.402278)
		(width 0.1016)
		(layer "F.Cu")
		(net "N54258515")
	)
	(segment
		(start 8.458962 -156.402278)
		(end 8.84936 -156.01188)
		(width 0.1016)
		(layer "F.Cu")
		(net "N54258515")
	)
	(segment
		(start 12.26058 -153.73731)
		(end 12.26058 -153.199846)
		(width 0.1016)
		(layer "F.Cu")
		(net "N54258515")
	)
	(segment
		(start 9.698482 -152.642824)
		(end 9.99998 -152.642824)
		(width 0.1016)
		(layer "F.Cu")
		(net "N54258515")
	)
	(via
		(at 9.99998 -152.642824)
		(size 0.508)
		(drill 0.254)
		(layers "F.Cu" "B.Cu")
		(net "N54258515")
	)
	(segment
		(start 15.54607 -159.73298)
		(end 15.952724 -159.326326)
		(width 0.10414)
		(layer "F.Cu")
		(net "LAN1_P2_N")
	)
	(segment
		(start 15.952724 -159.326326)
		(end 16.264636 -159.326326)
		(width 0.10414)
		(layer "F.Cu")
		(net "LAN1_P2_N")
	)
	(segment
		(start 16.264636 -159.326326)
		(end 16.682466 -159.744156)
		(width 0.10414)
		(layer "F.Cu")
		(net "LAN1_P2_N")
	)
	(segment
		(start 16.682466 -159.744156)
		(end 17.396206 -159.744156)
		(width 0.10414)
		(layer "F.Cu")
		(net "LAN1_P2_N")
	)
	(via
		(at 15.54607 -159.73298)
		(size 0.508)
		(drill 0.254)
		(layers "F.Cu" "B.Cu")
		(net "LAN1_P2_N")
	)
	(segment
		(start 18.955766 -194.532504)
		(end 18.55724 -192.272412)
		(width 0.10414)
		(layer "B.Cu")
		(net "LAN1_P2_N")
	)
	(segment
		(start 18.55724 -192.272412)
		(end 16.38808 -183.237886)
		(width 0.10414)
		(layer "B.Cu")
		(net "LAN1_P2_N")
	)
	(segment
		(start 16.976344 -163.175188)
		(end 16.837152 -163.024566)
		(width 0.10414)
		(layer "B.Cu")
		(net "LAN1_P2_N")
	)
	(segment
		(start 16.660622 -166.785798)
		(end 16.674084 -166.473124)
		(width 0.10414)
		(layer "B.Cu")
		(net "LAN1_P2_N")
	)
	(segment
		(start 16.816324 -166.9542)
		(end 16.660622 -166.785798)
		(width 0.10414)
		(layer "B.Cu")
		(net "LAN1_P2_N")
	)
	(segment
		(start 16.700754 -165.837362)
		(end 16.714216 -165.524688)
		(width 0.10414)
		(layer "B.Cu")
		(net "LAN1_P2_N")
	)
	(segment
		(start 16.88973 -161.796984)
		(end 17.041114 -161.657792)
		(width 0.10414)
		(layer "B.Cu")
		(net "LAN1_P2_N")
	)
	(segment
		(start 16.850614 -162.711892)
		(end 17.001998 -162.5727)
		(width 0.10414)
		(layer "B.Cu")
		(net "LAN1_P2_N")
	)
	(segment
		(start 16.937482 -164.090096)
		(end 16.798036 -163.939474)
		(width 0.10414)
		(layer "B.Cu")
		(net "LAN1_P2_N")
	)
	(segment
		(start 16.876268 -162.109658)
		(end 16.88973 -161.796984)
		(width 0.10414)
		(layer "B.Cu")
		(net "LAN1_P2_N")
	)
	(segment
		(start 16.798036 -163.939474)
		(end 16.811498 -163.6268)
		(width 0.10414)
		(layer "B.Cu")
		(net "LAN1_P2_N")
	)
	(segment
		(start 16.674084 -166.473124)
		(end 16.842994 -166.318438)
		(width 0.10414)
		(layer "B.Cu")
		(net "LAN1_P2_N")
	)
	(segment
		(start 19.29765 -199.804274)
		(end 19.285458 -197.762622)
		(width 0.10414)
		(layer "B.Cu")
		(net "LAN1_P2_N")
	)
	(segment
		(start 17.041114 -161.657792)
		(end 17.066768 -161.057336)
		(width 0.10414)
		(layer "B.Cu")
		(net "LAN1_P2_N")
	)
	(segment
		(start 16.714216 -165.524688)
		(end 16.883126 -165.370002)
		(width 0.10414)
		(layer "B.Cu")
		(net "LAN1_P2_N")
	)
	(segment
		(start 16.811498 -163.6268)
		(end 16.962882 -163.487608)
		(width 0.10414)
		(layer "B.Cu")
		(net "LAN1_P2_N")
	)
	(segment
		(start 16.962882 -163.487608)
		(end 16.976344 -163.175188)
		(width 0.10414)
		(layer "B.Cu")
		(net "LAN1_P2_N")
	)
	(segment
		(start 16.866362 -159.996378)
		(end 16.185134 -159.31515)
		(width 0.10414)
		(layer "B.Cu")
		(net "LAN1_P2_N")
	)
	(segment
		(start 16.776192 -167.902636)
		(end 16.802862 -167.266874)
		(width 0.10414)
		(layer "B.Cu")
		(net "LAN1_P2_N")
	)
	(segment
		(start 17.066768 -161.057336)
		(end 16.866362 -159.996378)
		(width 0.10414)
		(layer "B.Cu")
		(net "LAN1_P2_N")
	)
	(segment
		(start 19.29765 -202.659742)
		(end 19.29765 -199.804274)
		(width 0.10414)
		(layer "B.Cu")
		(net "LAN1_P2_N")
	)
	(segment
		(start 17.01546 -162.26028)
		(end 16.876268 -162.109658)
		(width 0.10414)
		(layer "B.Cu")
		(net "LAN1_P2_N")
	)
	(segment
		(start 16.837152 -163.024566)
		(end 16.850614 -162.711892)
		(width 0.10414)
		(layer "B.Cu")
		(net "LAN1_P2_N")
	)
	(segment
		(start 15.9639 -159.31515)
		(end 15.54607 -159.73298)
		(width 0.10414)
		(layer "B.Cu")
		(net "LAN1_P2_N")
	)
	(segment
		(start 16.802862 -167.266874)
		(end 16.816324 -166.9542)
		(width 0.10414)
		(layer "B.Cu")
		(net "LAN1_P2_N")
	)
	(segment
		(start 16.883126 -165.370002)
		(end 16.937482 -164.090096)
		(width 0.10414)
		(layer "B.Cu")
		(net "LAN1_P2_N")
	)
	(segment
		(start 16.185134 -159.31515)
		(end 15.9639 -159.31515)
		(width 0.10414)
		(layer "B.Cu")
		(net "LAN1_P2_N")
	)
	(segment
		(start 16.856456 -166.005764)
		(end 16.700754 -165.837362)
		(width 0.10414)
		(layer "B.Cu")
		(net "LAN1_P2_N")
	)
	(segment
		(start 16.38808 -177.285904)
		(end 16.387572 -177.123344)
		(width 0.10414)
		(layer "B.Cu")
		(net "LAN1_P2_N")
	)
	(segment
		(start 16.842994 -166.318438)
		(end 16.856456 -166.005764)
		(width 0.10414)
		(layer "B.Cu")
		(net "LAN1_P2_N")
	)
	(segment
		(start 16.387572 -177.123344)
		(end 16.776192 -167.902636)
		(width 0.10414)
		(layer "B.Cu")
		(net "LAN1_P2_N")
	)
	(segment
		(start 16.38808 -183.237886)
		(end 16.38808 -177.285904)
		(width 0.10414)
		(layer "B.Cu")
		(net "LAN1_P2_N")
	)
	(segment
		(start 19.014948 -202.942444)
		(end 19.29765 -202.659742)
		(width 0.10414)
		(layer "B.Cu")
		(net "LAN1_P2_N")
	)
	(segment
		(start 19.014948 -205.199488)
		(end 19.014948 -202.942444)
		(width 0.10414)
		(layer "B.Cu")
		(net "LAN1_P2_N")
	)
	(segment
		(start 17.001998 -162.5727)
		(end 17.01546 -162.26028)
		(width 0.10414)
		(layer "B.Cu")
		(net "LAN1_P2_N")
	)
	(segment
		(start 19.285458 -197.762622)
		(end 18.955766 -194.532504)
		(width 0.10414)
		(layer "B.Cu")
		(net "LAN1_P2_N")
	)
	(segment
		(start 113.90884 -158.99384)
		(end 113.82629 -158.91129)
		(width 0.1016)
		(layer "F.Cu")
		(net "POWER_SW2_PWR_CTR_N")
	)
	(segment
		(start 113.82629 -158.91129)
		(end 113.82629 -157.447742)
		(width 0.1016)
		(layer "F.Cu")
		(net "POWER_SW2_PWR_CTR_N")
	)
	(via
		(at 113.90884 -158.99384)
		(size 0.508)
		(drill 0.254)
		(layers "F.Cu" "B.Cu")
		(net "POWER_SW2_PWR_CTR_N")
	)
	(segment
		(start 118.431564 -158.251906)
		(end 123.23572 -163.056062)
		(width 0.1016)
		(layer "B.Cu")
		(net "POWER_SW2_PWR_CTR_N")
	)
	(segment
		(start 108.2548 -174.184056)
		(end 108.94314 -174.872396)
		(width 0.1016)
		(layer "B.Cu")
		(net "POWER_SW2_PWR_CTR_N")
	)
	(segment
		(start 104.64546 -178.590194)
		(end 104.249982 -178.194716)
		(width 0.1016)
		(layer "B.Cu")
		(net "POWER_SW2_PWR_CTR_N")
	)
	(segment
		(start 119.892318 -170.795696)
		(end 116.15928 -170.795696)
		(width 0.1016)
		(layer "B.Cu")
		(net "POWER_SW2_PWR_CTR_N")
	)
	(segment
		(start 113.90884 -158.99384)
		(end 114.650774 -158.251906)
		(width 0.1016)
		(layer "B.Cu")
		(net "POWER_SW2_PWR_CTR_N")
	)
	(segment
		(start 108.2548 -171.568872)
		(end 108.2548 -174.184056)
		(width 0.1016)
		(layer "B.Cu")
		(net "POWER_SW2_PWR_CTR_N")
	)
	(segment
		(start 122.32894 -167.340788)
		(end 122.32894 -168.35882)
		(width 0.1016)
		(layer "B.Cu")
		(net "POWER_SW2_PWR_CTR_N")
	)
	(segment
		(start 108.055918 -177.412142)
		(end 107.97032 -177.412142)
		(width 0.1016)
		(layer "B.Cu")
		(net "POWER_SW2_PWR_CTR_N")
	)
	(segment
		(start 111.38535 -168.438322)
		(end 108.2548 -171.568872)
		(width 0.1016)
		(layer "B.Cu")
		(net "POWER_SW2_PWR_CTR_N")
	)
	(segment
		(start 113.801906 -168.438322)
		(end 111.38535 -168.438322)
		(width 0.1016)
		(layer "B.Cu")
		(net "POWER_SW2_PWR_CTR_N")
	)
	(segment
		(start 106.130852 -178.590194)
		(end 104.64546 -178.590194)
		(width 0.1016)
		(layer "B.Cu")
		(net "POWER_SW2_PWR_CTR_N")
	)
	(segment
		(start 108.94314 -176.52492)
		(end 108.055918 -177.412142)
		(width 0.1016)
		(layer "B.Cu")
		(net "POWER_SW2_PWR_CTR_N")
	)
	(segment
		(start 123.23572 -166.434008)
		(end 122.32894 -167.340788)
		(width 0.1016)
		(layer "B.Cu")
		(net "POWER_SW2_PWR_CTR_N")
	)
	(segment
		(start 108.94314 -174.872396)
		(end 108.94314 -176.52492)
		(width 0.1016)
		(layer "B.Cu")
		(net "POWER_SW2_PWR_CTR_N")
	)
	(segment
		(start 122.22353 -168.464484)
		(end 119.892318 -170.795696)
		(width 0.1016)
		(layer "B.Cu")
		(net "POWER_SW2_PWR_CTR_N")
	)
	(segment
		(start 114.650774 -158.251906)
		(end 118.431564 -158.251906)
		(width 0.1016)
		(layer "B.Cu")
		(net "POWER_SW2_PWR_CTR_N")
	)
	(segment
		(start 107.97032 -177.412142)
		(end 107.414822 -177.96764)
		(width 0.1016)
		(layer "B.Cu")
		(net "POWER_SW2_PWR_CTR_N")
	)
	(segment
		(start 123.23572 -163.056062)
		(end 123.23572 -166.434008)
		(width 0.1016)
		(layer "B.Cu")
		(net "POWER_SW2_PWR_CTR_N")
	)
	(segment
		(start 107.414822 -177.96764)
		(end 106.753406 -177.96764)
		(width 0.1016)
		(layer "B.Cu")
		(net "POWER_SW2_PWR_CTR_N")
	)
	(segment
		(start 106.753406 -177.96764)
		(end 106.130852 -178.590194)
		(width 0.1016)
		(layer "B.Cu")
		(net "POWER_SW2_PWR_CTR_N")
	)
	(segment
		(start 122.32894 -168.35882)
		(end 122.22353 -168.464484)
		(width 0.1016)
		(layer "B.Cu")
		(net "POWER_SW2_PWR_CTR_N")
	)
	(segment
		(start 104.249982 -178.194716)
		(end 103.36276 -178.194716)
		(width 0.1016)
		(layer "B.Cu")
		(net "POWER_SW2_PWR_CTR_N")
	)
	(segment
		(start 116.15928 -170.795696)
		(end 113.801906 -168.438322)
		(width 0.1016)
		(layer "B.Cu")
		(net "POWER_SW2_PWR_CTR_N")
	)
	(via
		(at 159.09036 -169.888662)
		(size 0.6604)
		(drill 0.3302)
		(layers "F.Cu" "B.Cu")
		(net "N54365827")
	)
	(segment
		(start 155.930346 -169.890948)
		(end 157.108398 -169.890948)
		(width 0.1016)
		(layer "B.Cu")
		(net "N54365827")
	)
	(segment
		(start 155.403296 -169.363898)
		(end 155.930346 -169.890948)
		(width 0.1016)
		(layer "B.Cu")
		(net "N54365827")
	)
	(segment
		(start 154.77363 -169.363898)
		(end 155.403296 -169.363898)
		(width 0.1016)
		(layer "B.Cu")
		(net "N54365827")
	)
	(segment
		(start 159.375602 -170.173904)
		(end 159.09036 -169.888662)
		(width 0.1016)
		(layer "B.Cu")
		(net "N54365827")
	)
	(segment
		(start 157.108398 -169.890948)
		(end 157.272482 -169.726864)
		(width 0.1016)
		(layer "B.Cu")
		(net "N54365827")
	)
	(segment
		(start 158.928562 -169.726864)
		(end 159.09036 -169.888662)
		(width 0.1016)
		(layer "B.Cu")
		(net "N54365827")
	)
	(segment
		(start 157.272482 -169.726864)
		(end 158.928562 -169.726864)
		(width 0.1016)
		(layer "B.Cu")
		(net "N54365827")
	)
	(segment
		(start 159.375602 -171.6024)
		(end 159.375602 -170.173904)
		(width 0.1016)
		(layer "B.Cu")
		(net "N54365827")
	)
	(via
		(at 156.471874 -171.487846)
		(size 0.6604)
		(drill 0.3302)
		(layers "F.Cu" "B.Cu")
		(net "N54365829")
	)
	(segment
		(start 156.007816 -171.104052)
		(end 156.08808 -171.104052)
		(width 0.1016)
		(layer "B.Cu")
		(net "N54365829")
	)
	(segment
		(start 155.06954 -170.163998)
		(end 155.19146 -170.285918)
		(width 0.1016)
		(layer "B.Cu")
		(net "N54365829")
	)
	(segment
		(start 157.791658 -171.639738)
		(end 156.623766 -171.639738)
		(width 0.1016)
		(layer "B.Cu")
		(net "N54365829")
	)
	(segment
		(start 156.08808 -171.104052)
		(end 156.471874 -171.487846)
		(width 0.1016)
		(layer "B.Cu")
		(net "N54365829")
	)
	(segment
		(start 155.19146 -170.287696)
		(end 156.007816 -171.104052)
		(width 0.1016)
		(layer "B.Cu")
		(net "N54365829")
	)
	(segment
		(start 154.77363 -170.163998)
		(end 155.06954 -170.163998)
		(width 0.1016)
		(layer "B.Cu")
		(net "N54365829")
	)
	(segment
		(start 155.19146 -170.285918)
		(end 155.19146 -170.287696)
		(width 0.1016)
		(layer "B.Cu")
		(net "N54365829")
	)
	(segment
		(start 158.404306 -172.252386)
		(end 157.791658 -171.639738)
		(width 0.1016)
		(layer "B.Cu")
		(net "N54365829")
	)
	(segment
		(start 159.375602 -172.252386)
		(end 158.404306 -172.252386)
		(width 0.1016)
		(layer "B.Cu")
		(net "N54365829")
	)
	(segment
		(start 156.623766 -171.639738)
		(end 156.471874 -171.487846)
		(width 0.1016)
		(layer "B.Cu")
		(net "N54365829")
	)
	(segment
		(start 186.06516 -166.072566)
		(end 183.34228 -166.072566)
		(width 0.1016)
		(layer "F.Cu")
		(net "LAN2_P4_R")
	)
	(segment
		(start 182.470044 -166.944802)
		(end 182.470044 -167.992044)
		(width 0.1016)
		(layer "F.Cu")
		(net "LAN2_P4_R")
	)
	(segment
		(start 187.36945 -166.072566)
		(end 186.06516 -166.072566)
		(width 0.1016)
		(layer "F.Cu")
		(net "LAN2_P4_R")
	)
	(segment
		(start 183.34228 -166.072566)
		(end 182.470044 -166.944802)
		(width 0.1016)
		(layer "F.Cu")
		(net "LAN2_P4_R")
	)
	(via
		(at 186.06516 -166.072566)
		(size 0.508)
		(drill 0.254)
		(layers "F.Cu" "B.Cu")
		(net "LAN2_P4_R")
	)
	(segment
		(start 80.44815 -105.59415)
		(end 81.156556 -104.885744)
		(width 0.1016)
		(layer "F.Cu")
		(net "CONSOLE_SELECT_N")
	)
	(segment
		(start 66.17589 -82.333846)
		(end 66.38417 -82.333846)
		(width 0.1016)
		(layer "F.Cu")
		(net "CONSOLE_SELECT_N")
	)
	(segment
		(start 17.993868 -36.838128)
		(end 18.44167 -36.390326)
		(width 0.1016)
		(layer "F.Cu")
		(net "CONSOLE_SELECT_N")
	)
	(segment
		(start 18.44167 -36.390326)
		(end 19.52752 -36.390326)
		(width 0.1016)
		(layer "F.Cu")
		(net "CONSOLE_SELECT_N")
	)
	(segment
		(start 36.84778 -99.244912)
		(end 42.2275 -104.624632)
		(width 0.1016)
		(layer "F.Cu")
		(net "CONSOLE_SELECT_N")
	)
	(segment
		(start 32.0802 -99.153726)
		(end 32.171386 -99.244912)
		(width 0.1016)
		(layer "F.Cu")
		(net "CONSOLE_SELECT_N")
	)
	(segment
		(start 66.38417 -82.333846)
		(end 66.7258 -82.675476)
		(width 0.1016)
		(layer "F.Cu")
		(net "CONSOLE_SELECT_N")
	)
	(segment
		(start 17.229074 -36.838128)
		(end 17.993868 -36.838128)
		(width 0.1016)
		(layer "F.Cu")
		(net "CONSOLE_SELECT_N")
	)
	(segment
		(start 82.290158 -104.885744)
		(end 82.53476 -105.130346)
		(width 0.1016)
		(layer "F.Cu")
		(net "CONSOLE_SELECT_N")
	)
	(segment
		(start 77.800962 -104.624632)
		(end 78.77048 -105.59415)
		(width 0.1016)
		(layer "F.Cu")
		(net "CONSOLE_SELECT_N")
	)
	(segment
		(start 42.2275 -104.624632)
		(end 77.800962 -104.624632)
		(width 0.1016)
		(layer "F.Cu")
		(net "CONSOLE_SELECT_N")
	)
	(segment
		(start 78.77048 -105.59415)
		(end 80.44815 -105.59415)
		(width 0.1016)
		(layer "F.Cu")
		(net "CONSOLE_SELECT_N")
	)
	(segment
		(start 32.171386 -99.244912)
		(end 36.84778 -99.244912)
		(width 0.1016)
		(layer "F.Cu")
		(net "CONSOLE_SELECT_N")
	)
	(segment
		(start 81.156556 -104.885744)
		(end 82.290158 -104.885744)
		(width 0.1016)
		(layer "F.Cu")
		(net "CONSOLE_SELECT_N")
	)
	(via
		(at 82.53476 -105.130346)
		(size 0.508)
		(drill 0.254)
		(layers "F.Cu" "B.Cu")
		(net "CONSOLE_SELECT_N")
	)
	(via
		(at 19.52752 -32.138112)
		(size 0.508)
		(drill 0.254)
		(layers "F.Cu" "B.Cu")
		(net "CONSOLE_SELECT_N")
	)
	(via
		(at 32.0802 -99.153726)
		(size 0.508)
		(drill 0.254)
		(layers "F.Cu" "B.Cu")
		(net "CONSOLE_SELECT_N")
	)
	(via
		(at 66.7258 -82.675476)
		(size 0.508)
		(drill 0.254)
		(layers "F.Cu" "B.Cu")
		(net "CONSOLE_SELECT_N")
	)
	(segment
		(start 19.52752 -36.390326)
		(end 19.52752 -32.138112)
		(width 0.1016)
		(layer "B.Cu")
		(net "CONSOLE_SELECT_N")
	)
	(segment
		(start 72.359266 -84.583778)
		(end 71.816722 -84.041234)
		(width 0.1143)
		(layer "In2.Cu")
		(net "CONSOLE_SELECT_N")
	)
	(segment
		(start 82.718402 -92.503498)
		(end 80.399128 -92.503498)
		(width 0.1143)
		(layer "In2.Cu")
		(net "CONSOLE_SELECT_N")
	)
	(segment
		(start 78.08214 -90.002106)
		(end 72.663812 -84.583778)
		(width 0.1143)
		(layer "In2.Cu")
		(net "CONSOLE_SELECT_N")
	)
	(segment
		(start 82.53476 -105.130346)
		(end 83.580478 -104.084628)
		(width 0.1143)
		(layer "In2.Cu")
		(net "CONSOLE_SELECT_N")
	)
	(segment
		(start 71.816722 -84.041234)
		(end 70.58152 -84.041234)
		(width 0.1143)
		(layer "In2.Cu")
		(net "CONSOLE_SELECT_N")
	)
	(segment
		(start 72.663812 -84.583778)
		(end 72.359266 -84.583778)
		(width 0.1143)
		(layer "In2.Cu")
		(net "CONSOLE_SELECT_N")
	)
	(segment
		(start 70.58152 -84.041234)
		(end 69.880734 -83.340448)
		(width 0.1143)
		(layer "In2.Cu")
		(net "CONSOLE_SELECT_N")
	)
	(segment
		(start 78.08214 -90.18651)
		(end 78.08214 -90.002106)
		(width 0.1143)
		(layer "In2.Cu")
		(net "CONSOLE_SELECT_N")
	)
	(segment
		(start 69.880734 -83.340448)
		(end 67.219576 -83.340448)
		(width 0.1143)
		(layer "In2.Cu")
		(net "CONSOLE_SELECT_N")
	)
	(segment
		(start 83.580478 -104.084628)
		(end 83.580478 -93.365574)
		(width 0.1143)
		(layer "In2.Cu")
		(net "CONSOLE_SELECT_N")
	)
	(segment
		(start 66.97726 -83.098132)
		(end 66.97726 -82.926936)
		(width 0.1143)
		(layer "In2.Cu")
		(net "CONSOLE_SELECT_N")
	)
	(segment
		(start 66.97726 -82.926936)
		(end 66.7258 -82.675476)
		(width 0.1143)
		(layer "In2.Cu")
		(net "CONSOLE_SELECT_N")
	)
	(segment
		(start 83.580478 -93.365574)
		(end 82.718402 -92.503498)
		(width 0.1143)
		(layer "In2.Cu")
		(net "CONSOLE_SELECT_N")
	)
	(segment
		(start 67.219576 -83.340448)
		(end 66.97726 -83.098132)
		(width 0.1143)
		(layer "In2.Cu")
		(net "CONSOLE_SELECT_N")
	)
	(segment
		(start 80.399128 -92.503498)
		(end 78.08214 -90.18651)
		(width 0.1143)
		(layer "In2.Cu")
		(net "CONSOLE_SELECT_N")
	)
	(segment
		(start 30.52318 -82.92592)
		(end 29.85262 -82.25536)
		(width 0.1143)
		(layer "In6.Cu")
		(net "CONSOLE_SELECT_N")
	)
	(segment
		(start 30.60065 -42.211752)
		(end 20.52701 -32.138112)
		(width 0.1143)
		(layer "In6.Cu")
		(net "CONSOLE_SELECT_N")
	)
	(segment
		(start 29.85262 -70.106794)
		(end 30.60065 -69.358764)
		(width 0.1143)
		(layer "In6.Cu")
		(net "CONSOLE_SELECT_N")
	)
	(segment
		(start 31.24073 -99.153726)
		(end 30.52318 -98.436176)
		(width 0.1143)
		(layer "In6.Cu")
		(net "CONSOLE_SELECT_N")
	)
	(segment
		(start 32.0802 -99.153726)
		(end 31.24073 -99.153726)
		(width 0.1143)
		(layer "In6.Cu")
		(net "CONSOLE_SELECT_N")
	)
	(segment
		(start 20.52701 -32.138112)
		(end 19.52752 -32.138112)
		(width 0.1143)
		(layer "In6.Cu")
		(net "CONSOLE_SELECT_N")
	)
	(segment
		(start 30.52318 -98.436176)
		(end 30.52318 -82.92592)
		(width 0.1143)
		(layer "In6.Cu")
		(net "CONSOLE_SELECT_N")
	)
	(segment
		(start 29.85262 -82.25536)
		(end 29.85262 -70.106794)
		(width 0.1143)
		(layer "In6.Cu")
		(net "CONSOLE_SELECT_N")
	)
	(segment
		(start 30.60065 -69.358764)
		(end 30.60065 -42.211752)
		(width 0.1143)
		(layer "In6.Cu")
		(net "CONSOLE_SELECT_N")
	)
	(segment
		(start 168.87698 -169.233596)
		(end 167.634412 -169.233596)
		(width 0.1016)
		(layer "F.Cu")
		(net "N54365611")
	)
	(segment
		(start 165.217602 -171.6024)
		(end 165.217602 -170.49369)
		(width 0.1016)
		(layer "F.Cu")
		(net "N54365611")
	)
	(segment
		(start 165.217602 -170.49369)
		(end 166.477696 -169.233596)
		(width 0.1016)
		(layer "F.Cu")
		(net "N54365611")
	)
	(segment
		(start 166.477696 -169.233596)
		(end 167.634412 -169.233596)
		(width 0.1016)
		(layer "F.Cu")
		(net "N54365611")
	)
	(via
		(at 167.634412 -169.233596)
		(size 0.508)
		(drill 0.254)
		(layers "F.Cu" "B.Cu")
		(net "N54365611")
	)
	(segment
		(start 176.156874 -164.382958)
		(end 173.580044 -166.959788)
		(width 0.1016)
		(layer "F.Cu")
		(net "LAN2_P1_R")
	)
	(segment
		(start 184.86882 -163.024566)
		(end 184.86882 -163.026598)
		(width 0.1016)
		(layer "F.Cu")
		(net "LAN2_P1_R")
	)
	(segment
		(start 173.580044 -166.959788)
		(end 173.580044 -167.992044)
		(width 0.1016)
		(layer "F.Cu")
		(net "LAN2_P1_R")
	)
	(segment
		(start 187.36945 -163.024566)
		(end 184.86882 -163.024566)
		(width 0.1016)
		(layer "F.Cu")
		(net "LAN2_P1_R")
	)
	(segment
		(start 181.286912 -164.382958)
		(end 176.156874 -164.382958)
		(width 0.1016)
		(layer "F.Cu")
		(net "LAN2_P1_R")
	)
	(segment
		(start 182.643272 -163.026598)
		(end 181.286912 -164.382958)
		(width 0.1016)
		(layer "F.Cu")
		(net "LAN2_P1_R")
	)
	(segment
		(start 184.86882 -163.026598)
		(end 182.643272 -163.026598)
		(width 0.1016)
		(layer "F.Cu")
		(net "LAN2_P1_R")
	)
	(via
		(at 184.86882 -163.024566)
		(size 0.508)
		(drill 0.254)
		(layers "F.Cu" "B.Cu")
		(net "LAN2_P1_R")
	)
	(segment
		(start 159.375602 -171.6024)
		(end 159.375602 -170.449748)
		(width 0.1016)
		(layer "F.Cu")
		(net "N54365601")
	)
	(segment
		(start 158.308802 -169.382948)
		(end 156.44876 -169.382948)
		(width 0.1016)
		(layer "F.Cu")
		(net "N54365601")
	)
	(segment
		(start 154.252168 -172.2755)
		(end 154.2161 -172.239432)
		(width 0.1016)
		(layer "F.Cu")
		(net "N54365601")
	)
	(segment
		(start 154.2161 -171.21124)
		(end 156.044392 -169.382948)
		(width 0.1016)
		(layer "F.Cu")
		(net "N54365601")
	)
	(segment
		(start 159.375602 -170.449748)
		(end 158.308802 -169.382948)
		(width 0.1016)
		(layer "F.Cu")
		(net "N54365601")
	)
	(segment
		(start 154.2161 -172.239432)
		(end 154.2161 -171.21124)
		(width 0.1016)
		(layer "F.Cu")
		(net "N54365601")
	)
	(segment
		(start 156.044392 -169.382948)
		(end 156.44876 -169.382948)
		(width 0.1016)
		(layer "F.Cu")
		(net "N54365601")
	)
	(via
		(at 156.44876 -169.382948)
		(size 0.508)
		(drill 0.254)
		(layers "F.Cu" "B.Cu")
		(net "N54365601")
	)
	(segment
		(start 186.23534 -164.040566)
		(end 182.78094 -164.040566)
		(width 0.1016)
		(layer "F.Cu")
		(net "LAN2_P2_R")
	)
	(segment
		(start 182.78094 -164.040566)
		(end 181.335934 -165.485572)
		(width 0.1016)
		(layer "F.Cu")
		(net "LAN2_P2_R")
	)
	(segment
		(start 176.62144 -165.485572)
		(end 174.850044 -167.256968)
		(width 0.1016)
		(layer "F.Cu")
		(net "LAN2_P2_R")
	)
	(segment
		(start 187.36945 -164.040566)
		(end 186.23534 -164.040566)
		(width 0.1016)
		(layer "F.Cu")
		(net "LAN2_P2_R")
	)
	(segment
		(start 174.850044 -167.256968)
		(end 174.850044 -167.992044)
		(width 0.1016)
		(layer "F.Cu")
		(net "LAN2_P2_R")
	)
	(segment
		(start 181.335934 -165.485572)
		(end 176.62144 -165.485572)
		(width 0.1016)
		(layer "F.Cu")
		(net "LAN2_P2_R")
	)
	(via
		(at 186.23534 -164.040566)
		(size 0.508)
		(drill 0.254)
		(layers "F.Cu" "B.Cu")
		(net "LAN2_P2_R")
	)
	(segment
		(start 156.83484 -175.683672)
		(end 157.383226 -176.232058)
		(width 0.1016)
		(layer "F.Cu")
		(net "N54365556")
	)
	(segment
		(start 159.375602 -175.502316)
		(end 158.517336 -175.502316)
		(width 0.1016)
		(layer "F.Cu")
		(net "N54365556")
	)
	(segment
		(start 157.383226 -176.232058)
		(end 157.60192 -176.232058)
		(width 0.1016)
		(layer "F.Cu")
		(net "N54365556")
	)
	(segment
		(start 157.787594 -176.232058)
		(end 157.60192 -176.232058)
		(width 0.1016)
		(layer "F.Cu")
		(net "N54365556")
	)
	(segment
		(start 158.517336 -175.502316)
		(end 157.787594 -176.232058)
		(width 0.1016)
		(layer "F.Cu")
		(net "N54365556")
	)
	(segment
		(start 155.926028 -175.683672)
		(end 156.83484 -175.683672)
		(width 0.1016)
		(layer "F.Cu")
		(net "N54365556")
	)
	(via
		(at 157.60192 -176.232058)
		(size 0.508)
		(drill 0.254)
		(layers "F.Cu" "B.Cu")
		(net "N54365556")
	)
	(segment
		(start 181.200044 -167.992044)
		(end 181.200044 -166.890446)
		(width 0.1016)
		(layer "F.Cu")
		(net "LAN2_P3_R")
	)
	(segment
		(start 185.08726 -165.056566)
		(end 187.36945 -165.056566)
		(width 0.1016)
		(layer "F.Cu")
		(net "LAN2_P3_R")
	)
	(segment
		(start 181.200044 -166.890446)
		(end 183.033924 -165.056566)
		(width 0.1016)
		(layer "F.Cu")
		(net "LAN2_P3_R")
	)
	(segment
		(start 183.033924 -165.056566)
		(end 185.08726 -165.056566)
		(width 0.1016)
		(layer "F.Cu")
		(net "LAN2_P3_R")
	)
	(via
		(at 185.08726 -165.056566)
		(size 0.508)
		(drill 0.254)
		(layers "F.Cu" "B.Cu")
		(net "LAN2_P3_R")
	)
	(segment
		(start 157.89148 -170.701716)
		(end 157.52064 -170.330876)
		(width 0.1016)
		(layer "F.Cu")
		(net "N54365623")
	)
	(segment
		(start 159.375602 -172.252386)
		(end 158.42234 -172.252386)
		(width 0.1016)
		(layer "F.Cu")
		(net "N54365623")
	)
	(segment
		(start 158.42234 -172.252386)
		(end 157.89148 -171.721526)
		(width 0.1016)
		(layer "F.Cu")
		(net "N54365623")
	)
	(segment
		(start 156.986986 -170.512486)
		(end 157.168342 -170.330876)
		(width 0.1016)
		(layer "F.Cu")
		(net "N54365623")
	)
	(segment
		(start 157.89148 -171.721526)
		(end 157.89148 -170.701716)
		(width 0.1016)
		(layer "F.Cu")
		(net "N54365623")
	)
	(segment
		(start 156.986986 -171.496482)
		(end 156.986986 -170.512486)
		(width 0.1016)
		(layer "F.Cu")
		(net "N54365623")
	)
	(segment
		(start 157.168342 -170.330876)
		(end 157.52064 -170.330876)
		(width 0.1016)
		(layer "F.Cu")
		(net "N54365623")
	)
	(via
		(at 157.52064 -170.330876)
		(size 0.508)
		(drill 0.254)
		(layers "F.Cu" "B.Cu")
		(net "N54365623")
	)
	(segment
		(start 72.568816 -81.786476)
		(end 72.568816 -81.739486)
		(width 0.1016)
		(layer "F.Cu")
		(net "N32265582")
	)
	(segment
		(start 72.205088 -82.150204)
		(end 72.568816 -81.786476)
		(width 0.1016)
		(layer "F.Cu")
		(net "N32265582")
	)
	(segment
		(start 72.205088 -82.29727)
		(end 72.205088 -82.150204)
		(width 0.1016)
		(layer "F.Cu")
		(net "N32265582")
	)
	(via
		(at 74.130662 -83.066382)
		(size 0.6604)
		(drill 0.3302)
		(layers "F.Cu" "B.Cu")
		(net "N32265582")
	)
	(via
		(at 72.568816 -81.739486)
		(size 0.508)
		(drill 0.254)
		(layers "F.Cu" "B.Cu")
		(net "N32265582")
	)
	(segment
		(start 76.66736 -84.565998)
		(end 77.033882 -84.93252)
		(width 0.1016)
		(layer "B.Cu")
		(net "N32265582")
	)
	(segment
		(start 74.130662 -83.066382)
		(end 74.443844 -82.7532)
		(width 0.1016)
		(layer "B.Cu")
		(net "N32265582")
	)
	(segment
		(start 72.724264 -82.863436)
		(end 72.724264 -81.894934)
		(width 0.1016)
		(layer "B.Cu")
		(net "N32265582")
	)
	(segment
		(start 74.443844 -82.7532)
		(end 75.98029 -82.7532)
		(width 0.1016)
		(layer "B.Cu")
		(net "N32265582")
	)
	(segment
		(start 72.724264 -81.894934)
		(end 72.568816 -81.739486)
		(width 0.1016)
		(layer "B.Cu")
		(net "N32265582")
	)
	(segment
		(start 77.033882 -84.93252)
		(end 77.46238 -84.93252)
		(width 0.1016)
		(layer "B.Cu")
		(net "N32265582")
	)
	(segment
		(start 74.013822 -83.183222)
		(end 73.04405 -83.183222)
		(width 0.1016)
		(layer "B.Cu")
		(net "N32265582")
	)
	(segment
		(start 75.98029 -82.7532)
		(end 76.66736 -83.44027)
		(width 0.1016)
		(layer "B.Cu")
		(net "N32265582")
	)
	(segment
		(start 76.66736 -83.44027)
		(end 76.66736 -84.565998)
		(width 0.1016)
		(layer "B.Cu")
		(net "N32265582")
	)
	(segment
		(start 73.04405 -83.183222)
		(end 72.724264 -82.863436)
		(width 0.1016)
		(layer "B.Cu")
		(net "N32265582")
	)
	(segment
		(start 74.130662 -83.066382)
		(end 74.013822 -83.183222)
		(width 0.1016)
		(layer "B.Cu")
		(net "N32265582")
	)
	(segment
		(start 155.929838 -174.583344)
		(end 155.653994 -174.859188)
		(width 0.1016)
		(layer "F.Cu")
		(net "N54365554")
	)
	(segment
		(start 157.93212 -174.85233)
		(end 157.663134 -174.583344)
		(width 0.1016)
		(layer "F.Cu")
		(net "N54365554")
	)
	(segment
		(start 157.663134 -174.583344)
		(end 155.929838 -174.583344)
		(width 0.1016)
		(layer "F.Cu")
		(net "N54365554")
	)
	(segment
		(start 154.170888 -174.957232)
		(end 154.18308 -174.969424)
		(width 0.1016)
		(layer "F.Cu")
		(net "N54365554")
	)
	(segment
		(start 154.18308 -174.969424)
		(end 155.543758 -174.969424)
		(width 0.1016)
		(layer "F.Cu")
		(net "N54365554")
	)
	(segment
		(start 159.375602 -174.85233)
		(end 157.93212 -174.85233)
		(width 0.1016)
		(layer "F.Cu")
		(net "N54365554")
	)
	(segment
		(start 155.543758 -174.969424)
		(end 155.653994 -174.859188)
		(width 0.1016)
		(layer "F.Cu")
		(net "N54365554")
	)
	(segment
		(start 154.170888 -174.956216)
		(end 154.170888 -174.957232)
		(width 0.1016)
		(layer "F.Cu")
		(net "N54365554")
	)
	(via
		(at 155.653994 -174.859188)
		(size 0.508)
		(drill 0.254)
		(layers "F.Cu" "B.Cu")
		(net "N54365554")
	)
	(segment
		(start 188.209428 -162.984688)
		(end 189.849506 -162.984688)
		(width 0.1016)
		(layer "F.Cu")
		(net "N54134271")
	)
	(segment
		(start 188.16955 -165.056566)
		(end 188.49086 -165.056566)
		(width 0.1016)
		(layer "F.Cu")
		(net "N54134271")
	)
	(segment
		(start 188.16955 -166.072566)
		(end 188.16955 -165.056566)
		(width 0.1016)
		(layer "F.Cu")
		(net "N54134271")
	)
	(segment
		(start 188.976 -164.571426)
		(end 188.44514 -164.040566)
		(width 0.1016)
		(layer "F.Cu")
		(net "N54134271")
	)
	(segment
		(start 188.16955 -164.040566)
		(end 188.16955 -163.024566)
		(width 0.1016)
		(layer "F.Cu")
		(net "N54134271")
	)
	(segment
		(start 188.16955 -163.024566)
		(end 188.209428 -162.984688)
		(width 0.1016)
		(layer "F.Cu")
		(net "N54134271")
	)
	(segment
		(start 188.49086 -165.056566)
		(end 188.976 -164.571426)
		(width 0.1016)
		(layer "F.Cu")
		(net "N54134271")
	)
	(segment
		(start 188.44514 -164.040566)
		(end 188.16955 -164.040566)
		(width 0.1016)
		(layer "F.Cu")
		(net "N54134271")
	)
	(via
		(at 188.976 -164.571426)
		(size 0.508)
		(drill 0.254)
		(layers "F.Cu" "B.Cu")
		(net "N54134271")
	)
	(segment
		(start 165.217602 -172.902372)
		(end 166.47795 -172.902372)
		(width 0.1016)
		(layer "F.Cu")
		(net "N54365625")
	)
	(segment
		(start 168.227502 -171.15282)
		(end 167.225726 -172.154596)
		(width 0.1016)
		(layer "F.Cu")
		(net "N54365625")
	)
	(segment
		(start 166.47795 -172.902372)
		(end 167.225726 -172.154596)
		(width 0.1016)
		(layer "F.Cu")
		(net "N54365625")
	)
	(segment
		(start 168.87698 -171.15282)
		(end 168.227502 -171.15282)
		(width 0.1016)
		(layer "F.Cu")
		(net "N54365625")
	)
	(via
		(at 167.225726 -172.154596)
		(size 0.762)
		(drill 0.381)
		(layers "F.Cu" "B.Cu")
		(net "N54365625")
	)
	(via
		(at 163.56838 -183.552846)
		(size 0.6604)
		(drill 0.3302)
		(layers "F.Cu" "B.Cu")
		(net "N54365776")
	)
	(segment
		(start 163.31438 -183.298846)
		(end 163.56838 -183.552846)
		(width 0.1016)
		(layer "B.Cu")
		(net "N54365776")
	)
	(segment
		(start 164.611558 -184.067196)
		(end 164.08273 -184.067196)
		(width 0.1016)
		(layer "B.Cu")
		(net "N54365776")
	)
	(segment
		(start 164.08273 -184.067196)
		(end 163.56838 -183.552846)
		(width 0.1016)
		(layer "B.Cu")
		(net "N54365776")
	)
	(segment
		(start 163.00196 -182.075582)
		(end 163.31438 -182.388002)
		(width 0.1016)
		(layer "B.Cu")
		(net "N54365776")
	)
	(segment
		(start 165.217602 -175.502316)
		(end 164.116512 -175.502316)
		(width 0.1016)
		(layer "B.Cu")
		(net "N54365776")
	)
	(segment
		(start 164.116512 -175.502316)
		(end 163.00196 -176.616868)
		(width 0.1016)
		(layer "B.Cu")
		(net "N54365776")
	)
	(segment
		(start 163.31438 -182.388002)
		(end 163.31438 -183.298846)
		(width 0.1016)
		(layer "B.Cu")
		(net "N54365776")
	)
	(segment
		(start 163.00196 -176.616868)
		(end 163.00196 -182.075582)
		(width 0.1016)
		(layer "B.Cu")
		(net "N54365776")
	)
	(via
		(at 167.18788 -170.636438)
		(size 0.6604)
		(drill 0.3302)
		(layers "F.Cu" "B.Cu")
		(net "N54365835")
	)
	(segment
		(start 166.29126 -172.252386)
		(end 165.217602 -172.252386)
		(width 0.1016)
		(layer "B.Cu")
		(net "N54365835")
	)
	(segment
		(start 167.865806 -171.85513)
		(end 167.865806 -170.880532)
		(width 0.1016)
		(layer "B.Cu")
		(net "N54365835")
	)
	(segment
		(start 167.18788 -171.355766)
		(end 166.29126 -172.252386)
		(width 0.1016)
		(layer "B.Cu")
		(net "N54365835")
	)
	(segment
		(start 167.621712 -170.636438)
		(end 167.18788 -170.636438)
		(width 0.1016)
		(layer "B.Cu")
		(net "N54365835")
	)
	(segment
		(start 167.18788 -170.636438)
		(end 167.18788 -171.355766)
		(width 0.1016)
		(layer "B.Cu")
		(net "N54365835")
	)
	(segment
		(start 167.865806 -170.880532)
		(end 167.621712 -170.636438)
		(width 0.1016)
		(layer "B.Cu")
		(net "N54365835")
	)
	(via
		(at 165.14064 -186.28233)
		(size 0.6604)
		(drill 0.3302)
		(layers "F.Cu" "B.Cu")
		(net "N54365772")
	)
	(segment
		(start 165.07714 -186.28233)
		(end 165.14064 -186.28233)
		(width 0.1016)
		(layer "B.Cu")
		(net "N54365772")
	)
	(segment
		(start 165.245796 -186.28233)
		(end 165.14064 -186.28233)
		(width 0.1016)
		(layer "B.Cu")
		(net "N54365772")
	)
	(segment
		(start 165.346126 -186.182)
		(end 165.245796 -186.28233)
		(width 0.1016)
		(layer "B.Cu")
		(net "N54365772")
	)
	(segment
		(start 163.06038 -183.777636)
		(end 163.893754 -184.61101)
		(width 0.1016)
		(layer "B.Cu")
		(net "N54365772")
	)
	(segment
		(start 164.26561 -174.85233)
		(end 162.74796 -176.36998)
		(width 0.1016)
		(layer "B.Cu")
		(net "N54365772")
	)
	(segment
		(start 164.852858 -185.172096)
		(end 165.346126 -185.665364)
		(width 0.1016)
		(layer "B.Cu")
		(net "N54365772")
	)
	(segment
		(start 165.217602 -174.85233)
		(end 164.26561 -174.85233)
		(width 0.1016)
		(layer "B.Cu")
		(net "N54365772")
	)
	(segment
		(start 165.346126 -185.665364)
		(end 165.346126 -186.182)
		(width 0.1016)
		(layer "B.Cu")
		(net "N54365772")
	)
	(segment
		(start 162.74796 -176.36998)
		(end 162.74796 -182.180992)
		(width 0.1016)
		(layer "B.Cu")
		(net "N54365772")
	)
	(segment
		(start 162.74796 -182.180992)
		(end 163.06038 -182.493412)
		(width 0.1016)
		(layer "B.Cu")
		(net "N54365772")
	)
	(segment
		(start 163.06038 -182.493412)
		(end 163.06038 -183.777636)
		(width 0.1016)
		(layer "B.Cu")
		(net "N54365772")
	)
	(segment
		(start 163.893754 -184.61101)
		(end 163.893754 -185.098944)
		(width 0.1016)
		(layer "B.Cu")
		(net "N54365772")
	)
	(segment
		(start 164.852858 -185.083196)
		(end 164.852858 -185.172096)
		(width 0.1016)
		(layer "B.Cu")
		(net "N54365772")
	)
	(segment
		(start 163.893754 -185.098944)
		(end 165.07714 -186.28233)
		(width 0.1016)
		(layer "B.Cu")
		(net "N54365772")
	)
	(segment
		(start 124.1679 -44.556426)
		(end 124.1679 -44.405042)
		(width 0.1016)
		(layer "F.Cu")
		(net "LPC_CPU_NODE1_LAD0_SIO")
	)
	(segment
		(start 124.1679 -44.405042)
		(end 123.652534 -43.889676)
		(width 0.1016)
		(layer "F.Cu")
		(net "LPC_CPU_NODE1_LAD0_SIO")
	)
	(segment
		(start 123.652534 -43.889676)
		(end 122.451622 -43.889676)
		(width 0.1016)
		(layer "F.Cu")
		(net "LPC_CPU_NODE1_LAD0_SIO")
	)
	(via
		(at 124.1679 -44.556426)
		(size 0.508)
		(drill 0.254)
		(layers "F.Cu" "B.Cu")
		(net "LPC_CPU_NODE1_LAD0_SIO")
	)
	(segment
		(start 122.49785 -44.732702)
		(end 123.991624 -44.732702)
		(width 0.1016)
		(layer "B.Cu")
		(net "LPC_CPU_NODE1_LAD0_SIO")
	)
	(segment
		(start 123.991624 -44.732702)
		(end 124.1679 -44.556426)
		(width 0.1016)
		(layer "B.Cu")
		(net "LPC_CPU_NODE1_LAD0_SIO")
	)
	(segment
		(start 167.1447 -171.297092)
		(end 167.1447 -170.717718)
		(width 0.1016)
		(layer "F.Cu")
		(net "N54365613")
	)
	(segment
		(start 167.449754 -170.033696)
		(end 167.1447 -170.33875)
		(width 0.1016)
		(layer "F.Cu")
		(net "N54365613")
	)
	(segment
		(start 166.189406 -172.252386)
		(end 167.1447 -171.297092)
		(width 0.1016)
		(layer "F.Cu")
		(net "N54365613")
	)
	(segment
		(start 168.87698 -170.033696)
		(end 167.449754 -170.033696)
		(width 0.1016)
		(layer "F.Cu")
		(net "N54365613")
	)
	(segment
		(start 167.1447 -170.33875)
		(end 167.1447 -170.717718)
		(width 0.1016)
		(layer "F.Cu")
		(net "N54365613")
	)
	(segment
		(start 165.217602 -172.252386)
		(end 166.189406 -172.252386)
		(width 0.1016)
		(layer "F.Cu")
		(net "N54365613")
	)
	(via
		(at 167.1447 -170.717718)
		(size 0.762)
		(drill 0.381)
		(layers "F.Cu" "B.Cu")
		(net "N54365613")
	)
	(segment
		(start 119.690134 -48.514)
		(end 120.84558 -47.358554)
		(width 0.1016)
		(layer "F.Cu")
		(net "LPC_CPU_NODE1_FRAME_SIO_L")
	)
	(segment
		(start 119.690134 -49.475136)
		(end 119.690134 -48.514)
		(width 0.1016)
		(layer "F.Cu")
		(net "LPC_CPU_NODE1_FRAME_SIO_L")
	)
	(segment
		(start 120.84558 -47.358554)
		(end 120.9167 -47.287434)
		(width 0.1016)
		(layer "F.Cu")
		(net "LPC_CPU_NODE1_FRAME_SIO_L")
	)
	(segment
		(start 120.9167 -44.90212)
		(end 121.429018 -44.389802)
		(width 0.1016)
		(layer "F.Cu")
		(net "LPC_CPU_NODE1_FRAME_SIO_L")
	)
	(segment
		(start 121.429018 -44.389802)
		(end 122.451622 -44.389802)
		(width 0.1016)
		(layer "F.Cu")
		(net "LPC_CPU_NODE1_FRAME_SIO_L")
	)
	(segment
		(start 120.9167 -47.287434)
		(end 120.9167 -44.90212)
		(width 0.1016)
		(layer "F.Cu")
		(net "LPC_CPU_NODE1_FRAME_SIO_L")
	)
	(via
		(at 120.84558 -47.358554)
		(size 0.508)
		(drill 0.254)
		(layers "F.Cu" "B.Cu")
		(net "LPC_CPU_NODE1_FRAME_SIO_L")
	)
	(via
		(at 166.08298 -169.920666)
		(size 0.6604)
		(drill 0.3302)
		(layers "F.Cu" "B.Cu")
		(net "N54365821")
	)
	(segment
		(start 166.313104 -171.408852)
		(end 166.313104 -171.077636)
		(width 0.1016)
		(layer "B.Cu")
		(net "N54365821")
	)
	(segment
		(start 168.783762 -169.920666)
		(end 166.08298 -169.920666)
		(width 0.1016)
		(layer "B.Cu")
		(net "N54365821")
	)
	(segment
		(start 165.217602 -171.6024)
		(end 166.119556 -171.6024)
		(width 0.1016)
		(layer "B.Cu")
		(net "N54365821")
	)
	(segment
		(start 165.96106 -170.725592)
		(end 165.96106 -170.042586)
		(width 0.1016)
		(layer "B.Cu")
		(net "N54365821")
	)
	(segment
		(start 166.313104 -171.077636)
		(end 165.96106 -170.725592)
		(width 0.1016)
		(layer "B.Cu")
		(net "N54365821")
	)
	(segment
		(start 165.96106 -170.042586)
		(end 166.08298 -169.920666)
		(width 0.1016)
		(layer "B.Cu")
		(net "N54365821")
	)
	(segment
		(start 166.119556 -171.6024)
		(end 166.313104 -171.408852)
		(width 0.1016)
		(layer "B.Cu")
		(net "N54365821")
	)
	(segment
		(start 122.67692 -45.992034)
		(end 122.451622 -45.766736)
		(width 0.1016)
		(layer "F.Cu")
		(net "IRQ_CPU_NODE1_SERIAL_SIO")
	)
	(segment
		(start 122.451622 -45.766736)
		(end 122.451622 -44.889674)
		(width 0.1016)
		(layer "F.Cu")
		(net "IRQ_CPU_NODE1_SERIAL_SIO")
	)
	(via
		(at 122.67692 -45.992034)
		(size 0.508)
		(drill 0.254)
		(layers "F.Cu" "B.Cu")
		(net "IRQ_CPU_NODE1_SERIAL_SIO")
	)
	(segment
		(start 122.502168 -45.817282)
		(end 121.54789 -45.817282)
		(width 0.1016)
		(layer "B.Cu")
		(net "IRQ_CPU_NODE1_SERIAL_SIO")
	)
	(segment
		(start 122.67692 -45.992034)
		(end 122.502168 -45.817282)
		(width 0.1016)
		(layer "B.Cu")
		(net "IRQ_CPU_NODE1_SERIAL_SIO")
	)
	(via
		(at 157.52572 -172.293534)
		(size 0.6604)
		(drill 0.3302)
		(layers "F.Cu" "B.Cu")
		(net "N54365837")
	)
	(segment
		(start 158.1404 -172.902372)
		(end 157.531562 -172.293534)
		(width 0.1016)
		(layer "B.Cu")
		(net "N54365837")
	)
	(segment
		(start 157.531562 -172.293534)
		(end 157.52572 -172.293534)
		(width 0.1016)
		(layer "B.Cu")
		(net "N54365837")
	)
	(segment
		(start 156.77769 -172.496988)
		(end 156.981144 -172.293534)
		(width 0.1016)
		(layer "B.Cu")
		(net "N54365837")
	)
	(segment
		(start 156.77769 -173.409864)
		(end 156.77769 -172.496988)
		(width 0.1016)
		(layer "B.Cu")
		(net "N54365837")
	)
	(segment
		(start 159.375602 -172.902372)
		(end 158.1404 -172.902372)
		(width 0.1016)
		(layer "B.Cu")
		(net "N54365837")
	)
	(segment
		(start 156.981144 -172.293534)
		(end 157.52572 -172.293534)
		(width 0.1016)
		(layer "B.Cu")
		(net "N54365837")
	)
	(via
		(at 156.33954 -175.966374)
		(size 0.6604)
		(drill 0.3302)
		(layers "F.Cu" "B.Cu")
		(net "N54365764")
	)
	(segment
		(start 159.375602 -174.85233)
		(end 158.421324 -174.85233)
		(width 0.1016)
		(layer "B.Cu")
		(net "N54365764")
	)
	(segment
		(start 158.29788 -175.378364)
		(end 158.29788 -175.155606)
		(width 0.1016)
		(layer "B.Cu")
		(net "N54365764")
	)
	(segment
		(start 156.33954 -175.966374)
		(end 156.675836 -175.966374)
		(width 0.1016)
		(layer "B.Cu")
		(net "N54365764")
	)
	(segment
		(start 160.45688 -175.928782)
		(end 160.45688 -175.675036)
		(width 0.1016)
		(layer "B.Cu")
		(net "N54365764")
	)
	(segment
		(start 159.375602 -175.502316)
		(end 158.421832 -175.502316)
		(width 0.1016)
		(layer "B.Cu")
		(net "N54365764")
	)
	(segment
		(start 160.45688 -175.675036)
		(end 160.28416 -175.502316)
		(width 0.1016)
		(layer "B.Cu")
		(net "N54365764")
	)
	(segment
		(start 158.421324 -174.85233)
		(end 158.29788 -174.975774)
		(width 0.1016)
		(layer "B.Cu")
		(net "N54365764")
	)
	(segment
		(start 158.421832 -175.502316)
		(end 158.29788 -175.378364)
		(width 0.1016)
		(layer "B.Cu")
		(net "N54365764")
	)
	(segment
		(start 155.723844 -176.23663)
		(end 155.9941 -175.966374)
		(width 0.1016)
		(layer "B.Cu")
		(net "N54365764")
	)
	(segment
		(start 158.29788 -174.975774)
		(end 158.29788 -175.155606)
		(width 0.1016)
		(layer "B.Cu")
		(net "N54365764")
	)
	(segment
		(start 160.233106 -176.152556)
		(end 160.45688 -175.928782)
		(width 0.1016)
		(layer "B.Cu")
		(net "N54365764")
	)
	(segment
		(start 156.675836 -175.966374)
		(end 157.486604 -175.155606)
		(width 0.1016)
		(layer "B.Cu")
		(net "N54365764")
	)
	(segment
		(start 155.723844 -177.13833)
		(end 155.723844 -176.23663)
		(width 0.1016)
		(layer "B.Cu")
		(net "N54365764")
	)
	(segment
		(start 157.486604 -175.155606)
		(end 158.29788 -175.155606)
		(width 0.1016)
		(layer "B.Cu")
		(net "N54365764")
	)
	(segment
		(start 155.9941 -175.966374)
		(end 156.33954 -175.966374)
		(width 0.1016)
		(layer "B.Cu")
		(net "N54365764")
	)
	(segment
		(start 160.28416 -175.502316)
		(end 159.375602 -175.502316)
		(width 0.1016)
		(layer "B.Cu")
		(net "N54365764")
	)
	(segment
		(start 159.375602 -176.152556)
		(end 160.233106 -176.152556)
		(width 0.1016)
		(layer "B.Cu")
		(net "N54365764")
	)
	(via
		(at 169.977562 -170.95216)
		(size 0.6604)
		(drill 0.3302)
		(layers "F.Cu" "B.Cu")
		(net "N54365823")
	)
	(segment
		(start 165.217602 -174.202344)
		(end 168.323514 -174.202344)
		(width 0.1016)
		(layer "B.Cu")
		(net "N54365823")
	)
	(segment
		(start 168.323514 -174.202344)
		(end 170.1292 -172.396658)
		(width 0.1016)
		(layer "B.Cu")
		(net "N54365823")
	)
	(segment
		(start 170.1292 -171.103798)
		(end 169.977562 -170.95216)
		(width 0.1016)
		(layer "B.Cu")
		(net "N54365823")
	)
	(segment
		(start 170.1292 -172.396658)
		(end 170.1292 -171.103798)
		(width 0.1016)
		(layer "B.Cu")
		(net "N54365823")
	)
	(segment
		(start 168.783762 -170.720766)
		(end 169.746168 -170.720766)
		(width 0.1016)
		(layer "B.Cu")
		(net "N54365823")
	)
	(segment
		(start 169.746168 -170.720766)
		(end 169.977562 -170.95216)
		(width 0.1016)
		(layer "B.Cu")
		(net "N54365823")
	)
	(segment
		(start 154.252168 -173.074838)
		(end 155.312364 -173.074838)
		(width 0.1016)
		(layer "F.Cu")
		(net "N54365603")
	)
	(segment
		(start 155.335224 -173.051978)
		(end 155.584906 -173.051978)
		(width 0.1016)
		(layer "F.Cu")
		(net "N54365603")
	)
	(segment
		(start 155.312364 -173.074838)
		(end 155.335224 -173.051978)
		(width 0.1016)
		(layer "F.Cu")
		(net "N54365603")
	)
	(segment
		(start 156.37637 -174.202344)
		(end 155.902914 -173.728888)
		(width 0.1016)
		(layer "F.Cu")
		(net "N54365603")
	)
	(segment
		(start 155.902914 -173.369986)
		(end 155.61818 -173.085252)
		(width 0.1016)
		(layer "F.Cu")
		(net "N54365603")
	)
	(segment
		(start 155.902914 -173.728888)
		(end 155.902914 -173.369986)
		(width 0.1016)
		(layer "F.Cu")
		(net "N54365603")
	)
	(segment
		(start 154.252168 -173.0756)
		(end 154.252168 -173.074838)
		(width 0.1016)
		(layer "F.Cu")
		(net "N54365603")
	)
	(segment
		(start 155.584906 -173.051978)
		(end 155.61818 -173.085252)
		(width 0.1016)
		(layer "F.Cu")
		(net "N54365603")
	)
	(segment
		(start 159.375602 -174.202344)
		(end 156.37637 -174.202344)
		(width 0.1016)
		(layer "F.Cu")
		(net "N54365603")
	)
	(via
		(at 155.61818 -173.085252)
		(size 0.508)
		(drill 0.254)
		(layers "F.Cu" "B.Cu")
		(net "N54365603")
	)
	(segment
		(start 164.140388 -176.152556)
		(end 164.05098 -176.063148)
		(width 0.1016)
		(layer "F.Cu")
		(net "N54365542")
	)
	(segment
		(start 165.217602 -174.85233)
		(end 166.484046 -174.85233)
		(width 0.1016)
		(layer "F.Cu")
		(net "N54365542")
	)
	(segment
		(start 165.217602 -176.152556)
		(end 164.140388 -176.152556)
		(width 0.1016)
		(layer "F.Cu")
		(net "N54365542")
	)
	(segment
		(start 164.05098 -175.59401)
		(end 164.142674 -175.502316)
		(width 0.1016)
		(layer "F.Cu")
		(net "N54365542")
	)
	(segment
		(start 166.484046 -174.85233)
		(end 166.96436 -175.332644)
		(width 0.1016)
		(layer "F.Cu")
		(net "N54365542")
	)
	(segment
		(start 166.98214 -174.16145)
		(end 166.98214 -175.314864)
		(width 0.1016)
		(layer "F.Cu")
		(net "N54365542")
	)
	(segment
		(start 166.794688 -175.502316)
		(end 166.96436 -175.332644)
		(width 0.1016)
		(layer "F.Cu")
		(net "N54365542")
	)
	(segment
		(start 166.98214 -175.314864)
		(end 166.96436 -175.332644)
		(width 0.1016)
		(layer "F.Cu")
		(net "N54365542")
	)
	(segment
		(start 167.177212 -173.966378)
		(end 166.98214 -174.16145)
		(width 0.1016)
		(layer "F.Cu")
		(net "N54365542")
	)
	(segment
		(start 167.558212 -173.966378)
		(end 167.177212 -173.966378)
		(width 0.1016)
		(layer "F.Cu")
		(net "N54365542")
	)
	(segment
		(start 164.142674 -175.502316)
		(end 165.217602 -175.502316)
		(width 0.1016)
		(layer "F.Cu")
		(net "N54365542")
	)
	(segment
		(start 165.217602 -175.502316)
		(end 166.794688 -175.502316)
		(width 0.1016)
		(layer "F.Cu")
		(net "N54365542")
	)
	(segment
		(start 164.05098 -176.063148)
		(end 164.05098 -175.59401)
		(width 0.1016)
		(layer "F.Cu")
		(net "N54365542")
	)
	(via
		(at 166.96436 -175.332644)
		(size 0.508)
		(drill 0.254)
		(layers "F.Cu" "B.Cu")
		(net "N54365542")
	)
	(segment
		(start 8.327136 -160.493456)
		(end 13.832078 -160.493456)
		(width 0.1016)
		(layer "F.Cu")
		(net "UART_RTS_P5_L_N")
	)
	(segment
		(start 43.0149 -205.199488)
		(end 43.0149 -199.50938)
		(width 0.1016)
		(layer "F.Cu")
		(net "UART_RTS_P5_L_N")
	)
	(segment
		(start 5.858764 -162.961828)
		(end 8.327136 -160.493456)
		(width 0.1016)
		(layer "F.Cu")
		(net "UART_RTS_P5_L_N")
	)
	(segment
		(start 13.832078 -160.493456)
		(end 14.28496 -160.040574)
		(width 0.1016)
		(layer "F.Cu")
		(net "UART_RTS_P5_L_N")
	)
	(segment
		(start 5.858764 -164.062156)
		(end 5.858764 -162.961828)
		(width 0.1016)
		(layer "F.Cu")
		(net "UART_RTS_P5_L_N")
	)
	(via
		(at 43.0149 -199.50938)
		(size 0.508)
		(drill 0.254)
		(layers "F.Cu" "B.Cu")
		(net "UART_RTS_P5_L_N")
	)
	(via
		(at 14.28496 -160.040574)
		(size 0.508)
		(drill 0.254)
		(layers "F.Cu" "B.Cu")
		(net "UART_RTS_P5_L_N")
	)
	(segment
		(start 42.971212 -199.465692)
		(end 43.0149 -199.50938)
		(width 0.1143)
		(layer "In2.Cu")
		(net "UART_RTS_P5_L_N")
	)
	(segment
		(start 39.87292 -197.65645)
		(end 39.87292 -198.496428)
		(width 0.1143)
		(layer "In2.Cu")
		(net "UART_RTS_P5_L_N")
	)
	(segment
		(start 16.350742 -161.083752)
		(end 30.704536 -175.437546)
		(width 0.1143)
		(layer "In2.Cu")
		(net "UART_RTS_P5_L_N")
	)
	(segment
		(start 30.704536 -175.437546)
		(end 30.704536 -182.147464)
		(width 0.1143)
		(layer "In2.Cu")
		(net "UART_RTS_P5_L_N")
	)
	(segment
		(start 30.704536 -182.147464)
		(end 30.56636 -182.28564)
		(width 0.1143)
		(layer "In2.Cu")
		(net "UART_RTS_P5_L_N")
	)
	(segment
		(start 29.755338 -188.849762)
		(end 30.227524 -189.321948)
		(width 0.1143)
		(layer "In2.Cu")
		(net "UART_RTS_P5_L_N")
	)
	(segment
		(start 14.28496 -160.236916)
		(end 15.131796 -161.083752)
		(width 0.1143)
		(layer "In2.Cu")
		(net "UART_RTS_P5_L_N")
	)
	(segment
		(start 29.755338 -186.87796)
		(end 29.755338 -188.849762)
		(width 0.1143)
		(layer "In2.Cu")
		(net "UART_RTS_P5_L_N")
	)
	(segment
		(start 30.56636 -186.066938)
		(end 29.755338 -186.87796)
		(width 0.1143)
		(layer "In2.Cu")
		(net "UART_RTS_P5_L_N")
	)
	(segment
		(start 30.56636 -182.28564)
		(end 30.56636 -186.066938)
		(width 0.1143)
		(layer "In2.Cu")
		(net "UART_RTS_P5_L_N")
	)
	(segment
		(start 39.87292 -198.496428)
		(end 40.289988 -198.913496)
		(width 0.1143)
		(layer "In2.Cu")
		(net "UART_RTS_P5_L_N")
	)
	(segment
		(start 40.289988 -198.913496)
		(end 41.129966 -198.913496)
		(width 0.1143)
		(layer "In2.Cu")
		(net "UART_RTS_P5_L_N")
	)
	(segment
		(start 31.538418 -189.321948)
		(end 39.87292 -197.65645)
		(width 0.1143)
		(layer "In2.Cu")
		(net "UART_RTS_P5_L_N")
	)
	(segment
		(start 15.131796 -161.083752)
		(end 16.350742 -161.083752)
		(width 0.1143)
		(layer "In2.Cu")
		(net "UART_RTS_P5_L_N")
	)
	(segment
		(start 41.682162 -199.465692)
		(end 42.971212 -199.465692)
		(width 0.1143)
		(layer "In2.Cu")
		(net "UART_RTS_P5_L_N")
	)
	(segment
		(start 14.28496 -160.040574)
		(end 14.28496 -160.236916)
		(width 0.1143)
		(layer "In2.Cu")
		(net "UART_RTS_P5_L_N")
	)
	(segment
		(start 41.129966 -198.913496)
		(end 41.682162 -199.465692)
		(width 0.1143)
		(layer "In2.Cu")
		(net "UART_RTS_P5_L_N")
	)
	(segment
		(start 30.227524 -189.321948)
		(end 31.538418 -189.321948)
		(width 0.1143)
		(layer "In2.Cu")
		(net "UART_RTS_P5_L_N")
	)
	(segment
		(start 162.9918 -188.1378)
		(end 162.9918 -187.3504)
		(width 0.1016)
		(layer "F.Cu")
		(net "UART_RX_RP5_L")
	)
	(segment
		(start 162.9918 -187.3504)
		(end 162.7378 -187.0964)
		(width 0.1016)
		(layer "F.Cu")
		(net "UART_RX_RP5_L")
	)
	(segment
		(start 161.15538 -185.07202)
		(end 161.46018 -184.76722)
		(width 0.1016)
		(layer "F.Cu")
		(net "UART_RX_RP5_L")
	)
	(segment
		(start 162.7378 -186.508136)
		(end 161.912554 -185.68289)
		(width 0.1016)
		(layer "F.Cu")
		(net "UART_RX_RP5_L")
	)
	(segment
		(start 164.6047 -173.552358)
		(end 165.217602 -173.552358)
		(width 0.1016)
		(layer "F.Cu")
		(net "UART_RX_RP5_L")
	)
	(segment
		(start 161.46018 -184.76722)
		(end 161.46018 -176.696878)
		(width 0.1016)
		(layer "F.Cu")
		(net "UART_RX_RP5_L")
	)
	(segment
		(start 162.7378 -187.0964)
		(end 162.7378 -186.508136)
		(width 0.1016)
		(layer "F.Cu")
		(net "UART_RX_RP5_L")
	)
	(segment
		(start 162.53968 -191.395604)
		(end 162.53968 -188.58992)
		(width 0.1016)
		(layer "F.Cu")
		(net "UART_RX_RP5_L")
	)
	(segment
		(start 165.015672 -200.591674)
		(end 163.99764 -199.573642)
		(width 0.1016)
		(layer "F.Cu")
		(net "UART_RX_RP5_L")
	)
	(segment
		(start 161.40811 -185.68289)
		(end 161.15538 -185.43016)
		(width 0.1016)
		(layer "F.Cu")
		(net "UART_RX_RP5_L")
	)
	(segment
		(start 161.15538 -185.43016)
		(end 161.15538 -185.07202)
		(width 0.1016)
		(layer "F.Cu")
		(net "UART_RX_RP5_L")
	)
	(segment
		(start 161.46018 -176.696878)
		(end 164.6047 -173.552358)
		(width 0.1016)
		(layer "F.Cu")
		(net "UART_RX_RP5_L")
	)
	(segment
		(start 161.912554 -185.68289)
		(end 161.40811 -185.68289)
		(width 0.1016)
		(layer "F.Cu")
		(net "UART_RX_RP5_L")
	)
	(segment
		(start 163.99764 -199.10171)
		(end 162.56254 -197.66661)
		(width 0.1016)
		(layer "F.Cu")
		(net "UART_RX_RP5_L")
	)
	(segment
		(start 165.015672 -205.199488)
		(end 165.015672 -200.591674)
		(width 0.1016)
		(layer "F.Cu")
		(net "UART_RX_RP5_L")
	)
	(segment
		(start 163.99764 -199.573642)
		(end 163.99764 -199.10171)
		(width 0.1016)
		(layer "F.Cu")
		(net "UART_RX_RP5_L")
	)
	(segment
		(start 162.53968 -188.58992)
		(end 162.9918 -188.1378)
		(width 0.1016)
		(layer "F.Cu")
		(net "UART_RX_RP5_L")
	)
	(via
		(at 162.56254 -197.66661)
		(size 0.508)
		(drill 0.254)
		(layers "F.Cu" "B.Cu")
		(net "UART_RX_RP5_L")
	)
	(via
		(at 162.53968 -191.395604)
		(size 0.508)
		(drill 0.254)
		(layers "F.Cu" "B.Cu")
		(net "UART_RX_RP5_L")
	)
	(segment
		(start 162.56254 -197.66661)
		(end 162.67938 -197.54977)
		(width 0.1016)
		(layer "B.Cu")
		(net "UART_RX_RP5_L")
	)
	(segment
		(start 162.67938 -197.54977)
		(end 162.67938 -191.535304)
		(width 0.1016)
		(layer "B.Cu")
		(net "UART_RX_RP5_L")
	)
	(segment
		(start 162.67938 -191.535304)
		(end 162.53968 -191.395604)
		(width 0.1016)
		(layer "B.Cu")
		(net "UART_RX_RP5_L")
	)
	(segment
		(start 12.963652 -163.557712)
		(end 13.652754 -163.557712)
		(width 0.508)
		(layer "F.Cu")
		(net "N54065132")
	)
	(segment
		(start 13.652754 -165.615366)
		(end 13.652754 -164.700712)
		(width 0.508)
		(layer "F.Cu")
		(net "N54065132")
	)
	(segment
		(start 12.490196 -158.075122)
		(end 12.20724 -157.792166)
		(width 0.508)
		(layer "F.Cu")
		(net "N54065132")
	)
	(segment
		(start 13.959332 -157.329378)
		(end 12.966954 -157.329378)
		(width 0.508)
		(layer "F.Cu")
		(net "N54065132")
	)
	(segment
		(start 13.652754 -163.557712)
		(end 13.652754 -164.700712)
		(width 0.508)
		(layer "F.Cu")
		(net "N54065132")
	)
	(segment
		(start 13.397484 -158.075122)
		(end 12.490196 -158.075122)
		(width 0.508)
		(layer "F.Cu")
		(net "N54065132")
	)
	(segment
		(start 14.035024 -158.935928)
		(end 14.035024 -158.712662)
		(width 0.508)
		(layer "F.Cu")
		(net "N54065132")
	)
	(segment
		(start 14.035024 -158.712662)
		(end 13.397484 -158.075122)
		(width 0.508)
		(layer "F.Cu")
		(net "N54065132")
	)
	(segment
		(start 13.959332 -156.186378)
		(end 13.26642 -156.186378)
		(width 0.508)
		(layer "F.Cu")
		(net "N54065132")
	)
	(via
		(at 13.26642 -156.186378)
		(size 0.508)
		(drill 0.254)
		(layers "F.Cu" "B.Cu")
		(net "N54065132")
	)
	(via
		(at 13.652754 -165.615366)
		(size 0.508)
		(drill 0.254)
		(layers "F.Cu" "B.Cu")
		(net "N54065132")
	)
	(via
		(at 12.963652 -163.557712)
		(size 0.508)
		(drill 0.254)
		(layers "F.Cu" "B.Cu")
		(net "N54065132")
	)
	(via
		(at 12.20724 -157.792166)
		(size 0.508)
		(drill 0.254)
		(layers "F.Cu" "B.Cu")
		(net "N54065132")
	)
	(via
		(at 12.966954 -157.329378)
		(size 0.508)
		(drill 0.254)
		(layers "F.Cu" "B.Cu")
		(net "N54065132")
	)
	(segment
		(start 14.452854 -164.823648)
		(end 15.6464 -166.017194)
		(width 0.1016)
		(layer "F.Cu")
		(net "LAN1_P4_R")
	)
	(segment
		(start 16.839438 -164.824156)
		(end 17.396206 -164.824156)
		(width 0.1016)
		(layer "F.Cu")
		(net "LAN1_P4_R")
	)
	(segment
		(start 14.452854 -164.700712)
		(end 14.452854 -164.823648)
		(width 0.1016)
		(layer "F.Cu")
		(net "LAN1_P4_R")
	)
	(segment
		(start 15.6464 -166.017194)
		(end 16.839438 -164.824156)
		(width 0.1016)
		(layer "F.Cu")
		(net "LAN1_P4_R")
	)
	(via
		(at 15.6464 -166.017194)
		(size 0.508)
		(drill 0.254)
		(layers "F.Cu" "B.Cu")
		(net "LAN1_P4_R")
	)
	(segment
		(start 17.396206 -163.554156)
		(end 16.675354 -163.554156)
		(width 0.1016)
		(layer "F.Cu")
		(net "LAN1_P3_R")
	)
	(segment
		(start 15.409672 -164.327078)
		(end 14.640306 -163.557712)
		(width 0.1016)
		(layer "F.Cu")
		(net "LAN1_P3_R")
	)
	(segment
		(start 14.640306 -163.557712)
		(end 14.452854 -163.557712)
		(width 0.1016)
		(layer "F.Cu")
		(net "LAN1_P3_R")
	)
	(segment
		(start 16.675354 -163.554156)
		(end 16.1671 -164.06241)
		(width 0.1016)
		(layer "F.Cu")
		(net "LAN1_P3_R")
	)
	(segment
		(start 16.1671 -164.06241)
		(end 16.1671 -164.327078)
		(width 0.1016)
		(layer "F.Cu")
		(net "LAN1_P3_R")
	)
	(segment
		(start 16.1671 -164.327078)
		(end 15.409672 -164.327078)
		(width 0.1016)
		(layer "F.Cu")
		(net "LAN1_P3_R")
	)
	(via
		(at 16.1671 -164.327078)
		(size 0.508)
		(drill 0.254)
		(layers "F.Cu" "B.Cu")
		(net "LAN1_P3_R")
	)
	(segment
		(start 16.15694 -157.204156)
		(end 16.15694 -157.204918)
		(width 0.1016)
		(layer "F.Cu")
		(net "LAN1_P2_R")
	)
	(segment
		(start 17.396206 -157.204156)
		(end 16.15694 -157.204156)
		(width 0.1016)
		(layer "F.Cu")
		(net "LAN1_P2_R")
	)
	(segment
		(start 14.759432 -157.329378)
		(end 16.03248 -157.329378)
		(width 0.1016)
		(layer "F.Cu")
		(net "LAN1_P2_R")
	)
	(segment
		(start 16.03248 -157.329378)
		(end 16.15694 -157.204918)
		(width 0.1016)
		(layer "F.Cu")
		(net "LAN1_P2_R")
	)
	(via
		(at 16.15694 -157.204918)
		(size 0.508)
		(drill 0.254)
		(layers "F.Cu" "B.Cu")
		(net "LAN1_P2_R")
	)
	(segment
		(start 14.759432 -156.186378)
		(end 15.894558 -156.186378)
		(width 0.1016)
		(layer "F.Cu")
		(net "LAN1_P1_R")
	)
	(segment
		(start 15.894558 -156.186378)
		(end 16.14678 -155.934156)
		(width 0.1016)
		(layer "F.Cu")
		(net "LAN1_P1_R")
	)
	(segment
		(start 17.396206 -155.934156)
		(end 16.14678 -155.934156)
		(width 0.1016)
		(layer "F.Cu")
		(net "LAN1_P1_R")
	)
	(via
		(at 16.14678 -155.934156)
		(size 0.508)
		(drill 0.254)
		(layers "F.Cu" "B.Cu")
		(net "LAN1_P1_R")
	)
	(segment
		(start 31.522162 -169.408602)
		(end 31.522162 -169.072052)
		(width 0.1016)
		(layer "F.Cu")
		(net "CM_PWR_CTL_IN_R")
	)
	(segment
		(start 32.091122 -169.79646)
		(end 31.91002 -169.79646)
		(width 0.1016)
		(layer "F.Cu")
		(net "CM_PWR_CTL_IN_R")
	)
	(segment
		(start 33.895538 -171.567856)
		(end 33.895538 -170.996356)
		(width 0.1016)
		(layer "F.Cu")
		(net "CM_PWR_CTL_IN_R")
	)
	(segment
		(start 33.302448 -170.403266)
		(end 33.5407 -170.641518)
		(width 0.1016)
		(layer "F.Cu")
		(net "CM_PWR_CTL_IN_R")
	)
	(segment
		(start 33.79216 -171.671234)
		(end 33.895538 -171.567856)
		(width 0.1016)
		(layer "F.Cu")
		(net "CM_PWR_CTL_IN_R")
	)
	(segment
		(start 33.895538 -170.996356)
		(end 33.5407 -170.641518)
		(width 0.1016)
		(layer "F.Cu")
		(net "CM_PWR_CTL_IN_R")
	)
	(segment
		(start 32.414718 -170.120056)
		(end 32.091122 -169.79646)
		(width 0.1016)
		(layer "F.Cu")
		(net "CM_PWR_CTL_IN_R")
	)
	(segment
		(start 32.414718 -171.671234)
		(end 33.79216 -171.671234)
		(width 0.1016)
		(layer "F.Cu")
		(net "CM_PWR_CTL_IN_R")
	)
	(segment
		(start 31.91002 -169.79646)
		(end 31.522162 -169.408602)
		(width 0.1016)
		(layer "F.Cu")
		(net "CM_PWR_CTL_IN_R")
	)
	(segment
		(start 32.414718 -170.403266)
		(end 33.302448 -170.403266)
		(width 0.1016)
		(layer "F.Cu")
		(net "CM_PWR_CTL_IN_R")
	)
	(segment
		(start 32.414718 -170.403266)
		(end 32.414718 -170.120056)
		(width 0.1016)
		(layer "F.Cu")
		(net "CM_PWR_CTL_IN_R")
	)
	(via
		(at 33.5407 -170.641518)
		(size 0.508)
		(drill 0.254)
		(layers "F.Cu" "B.Cu")
		(net "CM_PWR_CTL_IN_R")
	)
	(segment
		(start 6.50875 -166.190422)
		(end 6.138672 -166.5605)
		(width 0.1016)
		(layer "F.Cu")
		(net "N54258454")
	)
	(segment
		(start 6.50875 -164.062156)
		(end 6.50875 -166.190422)
		(width 0.1016)
		(layer "F.Cu")
		(net "N54258454")
	)
	(segment
		(start 5.88518 -167.373554)
		(end 5.88518 -166.813992)
		(width 0.1016)
		(layer "F.Cu")
		(net "N54258454")
	)
	(segment
		(start 5.88518 -166.813992)
		(end 6.138672 -166.5605)
		(width 0.1016)
		(layer "F.Cu")
		(net "N54258454")
	)
	(via
		(at 6.138672 -166.5605)
		(size 0.508)
		(drill 0.254)
		(layers "F.Cu" "B.Cu")
		(net "N54258454")
	)
	(segment
		(start 83.816444 -124.504196)
		(end 83.84921 -124.536962)
		(width 0.1016)
		(layer "F.Cu")
		(net "N53313325")
	)
	(segment
		(start 83.816444 -123.641612)
		(end 83.816444 -124.504196)
		(width 0.1016)
		(layer "F.Cu")
		(net "N53313325")
	)
	(segment
		(start 125.991112 -42.389806)
		(end 126.07544 -42.474134)
		(width 0.1016)
		(layer "F.Cu")
		(net "LPC_CPU_NODE1_LAD3_SIO")
	)
	(segment
		(start 122.451622 -42.389806)
		(end 125.991112 -42.389806)
		(width 0.1016)
		(layer "F.Cu")
		(net "LPC_CPU_NODE1_LAD3_SIO")
	)
	(via
		(at 126.07544 -42.474134)
		(size 0.508)
		(drill 0.254)
		(layers "F.Cu" "B.Cu")
		(net "LPC_CPU_NODE1_LAD3_SIO")
	)
	(segment
		(start 123.595892 -41.684702)
		(end 124.194316 -42.283126)
		(width 0.1016)
		(layer "B.Cu")
		(net "LPC_CPU_NODE1_LAD3_SIO")
	)
	(segment
		(start 124.194316 -42.283126)
		(end 125.88494 -42.283126)
		(width 0.1016)
		(layer "B.Cu")
		(net "LPC_CPU_NODE1_LAD3_SIO")
	)
	(segment
		(start 125.88494 -42.283126)
		(end 126.07544 -42.473626)
		(width 0.1016)
		(layer "B.Cu")
		(net "LPC_CPU_NODE1_LAD3_SIO")
	)
	(segment
		(start 126.07544 -42.473626)
		(end 126.07544 -42.474134)
		(width 0.1016)
		(layer "B.Cu")
		(net "LPC_CPU_NODE1_LAD3_SIO")
	)
	(segment
		(start 122.49785 -41.684702)
		(end 123.595892 -41.684702)
		(width 0.1016)
		(layer "B.Cu")
		(net "LPC_CPU_NODE1_LAD3_SIO")
	)
	(segment
		(start 85.141816 -131.354068)
		(end 85.30844 -131.187444)
		(width 0.1016)
		(layer "F.Cu")
		(net "N53313479")
	)
	(segment
		(start 85.30844 -131.187444)
		(end 85.601048 -130.894836)
		(width 0.1016)
		(layer "F.Cu")
		(net "N53313479")
	)
	(segment
		(start 83.866228 -132.463032)
		(end 83.866228 -132.23367)
		(width 0.1016)
		(layer "F.Cu")
		(net "N53313479")
	)
	(segment
		(start 83.866228 -132.23367)
		(end 84.74583 -131.354068)
		(width 0.1016)
		(layer "F.Cu")
		(net "N53313479")
	)
	(segment
		(start 84.74583 -131.354068)
		(end 85.141816 -131.354068)
		(width 0.1016)
		(layer "F.Cu")
		(net "N53313479")
	)
	(segment
		(start 85.601048 -130.894836)
		(end 85.601048 -129.398776)
		(width 0.1016)
		(layer "F.Cu")
		(net "N53313479")
	)
	(via
		(at 85.30844 -131.187444)
		(size 0.508)
		(drill 0.254)
		(layers "F.Cu" "B.Cu")
		(net "N53313479")
	)
	(via
		(at 166.87038 -196.281294)
		(size 0.6604)
		(drill 0.3302)
		(layers "F.Cu" "B.Cu")
		(net "UART_RTS_RP6_L_N")
	)
	(segment
		(start 167.579548 -196.990462)
		(end 167.579548 -201.209656)
		(width 0.1016)
		(layer "B.Cu")
		(net "UART_RTS_RP6_L_N")
	)
	(segment
		(start 165.159436 -196.281294)
		(end 166.87038 -196.281294)
		(width 0.1016)
		(layer "B.Cu")
		(net "UART_RTS_RP6_L_N")
	)
	(segment
		(start 162.09518 -184.17794)
		(end 162.814 -184.89676)
		(width 0.1016)
		(layer "B.Cu")
		(net "UART_RTS_RP6_L_N")
	)
	(segment
		(start 168.015666 -201.645774)
		(end 168.015666 -205.199488)
		(width 0.1016)
		(layer "B.Cu")
		(net "UART_RTS_RP6_L_N")
	)
	(segment
		(start 162.814 -185.674)
		(end 163.322 -186.182)
		(width 0.1016)
		(layer "B.Cu")
		(net "UART_RTS_RP6_L_N")
	)
	(segment
		(start 161.78276 -177.761646)
		(end 161.78276 -182.581296)
		(width 0.1016)
		(layer "B.Cu")
		(net "UART_RTS_RP6_L_N")
	)
	(segment
		(start 162.09518 -182.893716)
		(end 162.09518 -184.17794)
		(width 0.1016)
		(layer "B.Cu")
		(net "UART_RTS_RP6_L_N")
	)
	(segment
		(start 161.78276 -182.581296)
		(end 162.09518 -182.893716)
		(width 0.1016)
		(layer "B.Cu")
		(net "UART_RTS_RP6_L_N")
	)
	(segment
		(start 162.814 -184.89676)
		(end 162.814 -185.674)
		(width 0.1016)
		(layer "B.Cu")
		(net "UART_RTS_RP6_L_N")
	)
	(segment
		(start 163.63442 -194.756278)
		(end 165.159436 -196.281294)
		(width 0.1016)
		(layer "B.Cu")
		(net "UART_RTS_RP6_L_N")
	)
	(segment
		(start 167.579548 -201.209656)
		(end 168.015666 -201.645774)
		(width 0.1016)
		(layer "B.Cu")
		(net "UART_RTS_RP6_L_N")
	)
	(segment
		(start 166.87038 -196.281294)
		(end 167.579548 -196.990462)
		(width 0.1016)
		(layer "B.Cu")
		(net "UART_RTS_RP6_L_N")
	)
	(segment
		(start 159.375602 -176.802542)
		(end 160.823656 -176.802542)
		(width 0.1016)
		(layer "B.Cu")
		(net "UART_RTS_RP6_L_N")
	)
	(segment
		(start 163.63442 -187.1726)
		(end 163.63442 -194.756278)
		(width 0.1016)
		(layer "B.Cu")
		(net "UART_RTS_RP6_L_N")
	)
	(segment
		(start 163.322 -186.182)
		(end 163.322 -186.86018)
		(width 0.1016)
		(layer "B.Cu")
		(net "UART_RTS_RP6_L_N")
	)
	(segment
		(start 163.322 -186.86018)
		(end 163.63442 -187.1726)
		(width 0.1016)
		(layer "B.Cu")
		(net "UART_RTS_RP6_L_N")
	)
	(segment
		(start 160.823656 -176.802542)
		(end 161.78276 -177.761646)
		(width 0.1016)
		(layer "B.Cu")
		(net "UART_RTS_RP6_L_N")
	)
	(segment
		(start 122.451622 -42.889678)
		(end 124.057156 -42.889678)
		(width 0.1016)
		(layer "F.Cu")
		(net "LPC_CPU_NODE1_LAD2_SIO")
	)
	(segment
		(start 124.057156 -42.889678)
		(end 124.21616 -43.048682)
		(width 0.1016)
		(layer "F.Cu")
		(net "LPC_CPU_NODE1_LAD2_SIO")
	)
	(via
		(at 124.21616 -43.048682)
		(size 0.508)
		(drill 0.254)
		(layers "F.Cu" "B.Cu")
		(net "LPC_CPU_NODE1_LAD2_SIO")
	)
	(segment
		(start 123.86818 -42.700702)
		(end 124.21616 -43.048682)
		(width 0.1016)
		(layer "B.Cu")
		(net "LPC_CPU_NODE1_LAD2_SIO")
	)
	(segment
		(start 122.49785 -42.700702)
		(end 123.86818 -42.700702)
		(width 0.1016)
		(layer "B.Cu")
		(net "LPC_CPU_NODE1_LAD2_SIO")
	)
	(segment
		(start 86.914228 -132.463032)
		(end 86.914228 -132.449316)
		(width 0.1016)
		(layer "F.Cu")
		(net "N53313513")
	)
	(segment
		(start 87.887048 -131.304792)
		(end 87.9729 -131.390644)
		(width 0.1016)
		(layer "F.Cu")
		(net "N53313513")
	)
	(segment
		(start 87.887048 -129.398776)
		(end 87.887048 -131.304792)
		(width 0.1016)
		(layer "F.Cu")
		(net "N53313513")
	)
	(segment
		(start 86.914228 -132.449316)
		(end 87.9729 -131.390644)
		(width 0.1016)
		(layer "F.Cu")
		(net "N53313513")
	)
	(via
		(at 87.9729 -131.390644)
		(size 0.508)
		(drill 0.254)
		(layers "F.Cu" "B.Cu")
		(net "N53313513")
	)
	(segment
		(start 40.72128 -199.794876)
		(end 41.014904 -200.088246)
		(width 0.1016)
		(layer "F.Cu")
		(net "UART_RX_P5_L")
	)
	(segment
		(start 9.459214 -162.949636)
		(end 9.108948 -163.299902)
		(width 0.1016)
		(layer "F.Cu")
		(net "UART_RX_P5_L")
	)
	(segment
		(start 41.014904 -200.088246)
		(end 41.014904 -205.199488)
		(width 0.1016)
		(layer "F.Cu")
		(net "UART_RX_P5_L")
	)
	(segment
		(start 9.108948 -163.299902)
		(end 9.108948 -164.062156)
		(width 0.1016)
		(layer "F.Cu")
		(net "UART_RX_P5_L")
	)
	(segment
		(start 40.72128 -199.731884)
		(end 40.72128 -199.794876)
		(width 0.1016)
		(layer "F.Cu")
		(net "UART_RX_P5_L")
	)
	(segment
		(start 14.736572 -162.949636)
		(end 9.459214 -162.949636)
		(width 0.1016)
		(layer "F.Cu")
		(net "UART_RX_P5_L")
	)
	(segment
		(start 15.08506 -163.298124)
		(end 14.736572 -162.949636)
		(width 0.1016)
		(layer "F.Cu")
		(net "UART_RX_P5_L")
	)
	(via
		(at 15.08506 -163.298124)
		(size 0.508)
		(drill 0.254)
		(layers "F.Cu" "B.Cu")
		(net "UART_RX_P5_L")
	)
	(via
		(at 40.72128 -199.731884)
		(size 0.508)
		(drill 0.254)
		(layers "F.Cu" "B.Cu")
		(net "UART_RX_P5_L")
	)
	(segment
		(start 19.8501 -168.629838)
		(end 19.8501 -182.15991)
		(width 0.1143)
		(layer "In2.Cu")
		(net "UART_RX_P5_L")
	)
	(segment
		(start 15.08506 -163.298124)
		(end 15.08506 -163.864798)
		(width 0.1143)
		(layer "In2.Cu")
		(net "UART_RX_P5_L")
	)
	(segment
		(start 15.08506 -163.864798)
		(end 19.8501 -168.629838)
		(width 0.1143)
		(layer "In2.Cu")
		(net "UART_RX_P5_L")
	)
	(segment
		(start 36.950142 -199.538082)
		(end 40.527478 -199.538082)
		(width 0.1143)
		(layer "In2.Cu")
		(net "UART_RX_P5_L")
	)
	(segment
		(start 32.90824 -194.101974)
		(end 36.304982 -197.498716)
		(width 0.1143)
		(layer "In2.Cu")
		(net "UART_RX_P5_L")
	)
	(segment
		(start 36.304982 -198.892922)
		(end 36.950142 -199.538082)
		(width 0.1143)
		(layer "In2.Cu")
		(net "UART_RX_P5_L")
	)
	(segment
		(start 36.304982 -197.498716)
		(end 36.304982 -198.892922)
		(width 0.1143)
		(layer "In2.Cu")
		(net "UART_RX_P5_L")
	)
	(segment
		(start 40.527478 -199.538082)
		(end 40.72128 -199.731884)
		(width 0.1143)
		(layer "In2.Cu")
		(net "UART_RX_P5_L")
	)
	(segment
		(start 19.8501 -182.15991)
		(end 31.792164 -194.101974)
		(width 0.1143)
		(layer "In2.Cu")
		(net "UART_RX_P5_L")
	)
	(segment
		(start 31.792164 -194.101974)
		(end 32.90824 -194.101974)
		(width 0.1143)
		(layer "In2.Cu")
		(net "UART_RX_P5_L")
	)
	(segment
		(start 89.1286 -130.18008)
		(end 89.129108 -130.18008)
		(width 0.1016)
		(layer "F.Cu")
		(net "N53313596")
	)
	(segment
		(start 89.02954 -130.08102)
		(end 89.1286 -130.18008)
		(width 0.1016)
		(layer "F.Cu")
		(net "N53313596")
	)
	(segment
		(start 89.129108 -130.180588)
		(end 89.416128 -130.467608)
		(width 0.1016)
		(layer "F.Cu")
		(net "N53313596")
	)
	(segment
		(start 89.02954 -129.398776)
		(end 89.02954 -130.08102)
		(width 0.1016)
		(layer "F.Cu")
		(net "N53313596")
	)
	(segment
		(start 91.486228 -131.91363)
		(end 91.486228 -132.463032)
		(width 0.1016)
		(layer "F.Cu")
		(net "N53313596")
	)
	(segment
		(start 89.129108 -130.18008)
		(end 89.129108 -130.180588)
		(width 0.1016)
		(layer "F.Cu")
		(net "N53313596")
	)
	(segment
		(start 89.030048 -129.398776)
		(end 89.02954 -129.398776)
		(width 0.1016)
		(layer "F.Cu")
		(net "N53313596")
	)
	(segment
		(start 90.040206 -130.467608)
		(end 91.486228 -131.91363)
		(width 0.1016)
		(layer "F.Cu")
		(net "N53313596")
	)
	(segment
		(start 89.416128 -130.467608)
		(end 90.040206 -130.467608)
		(width 0.1016)
		(layer "F.Cu")
		(net "N53313596")
	)
	(via
		(at 89.129108 -130.18008)
		(size 0.508)
		(drill 0.254)
		(layers "F.Cu" "B.Cu")
		(net "N53313596")
	)
	(segment
		(start 93.668596 -118.141496)
		(end 93.854778 -117.955314)
		(width 0.1016)
		(layer "F.Cu")
		(net "N53313289")
	)
	(segment
		(start 92.416376 -118.141496)
		(end 93.668596 -118.141496)
		(width 0.1016)
		(layer "F.Cu")
		(net "N53313289")
	)
	(segment
		(start 84.458048 -129.64414)
		(end 84.458048 -129.398776)
		(width 0.1016)
		(layer "F.Cu")
		(net "N53313464")
	)
	(segment
		(start 82.84718 -131.670044)
		(end 82.84718 -131.255008)
		(width 0.1016)
		(layer "F.Cu")
		(net "N53313464")
	)
	(segment
		(start 82.342228 -132.174996)
		(end 82.84718 -131.670044)
		(width 0.1016)
		(layer "F.Cu")
		(net "N53313464")
	)
	(segment
		(start 82.84718 -131.255008)
		(end 84.458048 -129.64414)
		(width 0.1016)
		(layer "F.Cu")
		(net "N53313464")
	)
	(segment
		(start 82.342228 -132.463032)
		(end 82.342228 -132.174996)
		(width 0.1016)
		(layer "F.Cu")
		(net "N53313464")
	)
	(via
		(at 82.84718 -131.670044)
		(size 0.508)
		(drill 0.254)
		(layers "F.Cu" "B.Cu")
		(net "N53313464")
	)
	(segment
		(start 84.458048 -128.598676)
		(end 83.736688 -127.877316)
		(width 0.1016)
		(layer "F.Cu")
		(net "PORT80_LOUT1")
	)
	(segment
		(start 83.736688 -127.877316)
		(end 83.736688 -127.522478)
		(width 0.1016)
		(layer "F.Cu")
		(net "PORT80_LOUT1")
	)
	(segment
		(start 85.366352 -125.19152)
		(end 85.366352 -125.849888)
		(width 0.1016)
		(layer "F.Cu")
		(net "PORT80_LOUT1")
	)
	(segment
		(start 85.366352 -125.849888)
		(end 83.736688 -127.479552)
		(width 0.1016)
		(layer "F.Cu")
		(net "PORT80_LOUT1")
	)
	(segment
		(start 83.736688 -127.479552)
		(end 83.736688 -127.522478)
		(width 0.1016)
		(layer "F.Cu")
		(net "PORT80_LOUT1")
	)
	(via
		(at 83.736688 -127.522478)
		(size 0.508)
		(drill 0.254)
		(layers "F.Cu" "B.Cu")
		(net "PORT80_LOUT1")
	)
	(segment
		(start 93.43644 -123.141486)
		(end 92.416376 -123.141486)
		(width 0.1016)
		(layer "F.Cu")
		(net "N53313389")
	)
	(segment
		(start 94.25432 -122.323606)
		(end 93.43644 -123.141486)
		(width 0.1016)
		(layer "F.Cu")
		(net "N53313389")
	)
	(segment
		(start 86.74354 -130.156966)
		(end 86.744048 -130.156966)
		(width 0.1016)
		(layer "F.Cu")
		(net "N53313501")
	)
	(segment
		(start 86.74354 -130.739896)
		(end 86.74354 -130.156966)
		(width 0.1016)
		(layer "F.Cu")
		(net "N53313501")
	)
	(segment
		(start 85.390228 -132.093208)
		(end 86.74354 -130.739896)
		(width 0.1016)
		(layer "F.Cu")
		(net "N53313501")
	)
	(segment
		(start 86.744048 -130.156966)
		(end 86.744048 -129.398776)
		(width 0.1016)
		(layer "F.Cu")
		(net "N53313501")
	)
	(segment
		(start 85.390228 -132.463032)
		(end 85.390228 -132.093208)
		(width 0.1016)
		(layer "F.Cu")
		(net "N53313501")
	)
	(via
		(at 86.744048 -130.156966)
		(size 0.508)
		(drill 0.254)
		(layers "F.Cu" "B.Cu")
		(net "N53313501")
	)
	(segment
		(start 80.845152 -130.690112)
		(end 80.845152 -132.461)
		(width 0.1016)
		(layer "F.Cu")
		(net "N53313646")
	)
	(segment
		(start 81.30032 -130.234944)
		(end 80.845152 -130.690112)
		(width 0.1016)
		(layer "F.Cu")
		(net "N53313646")
	)
	(segment
		(start 82.08264 -129.452624)
		(end 81.30032 -130.234944)
		(width 0.1016)
		(layer "F.Cu")
		(net "N53313646")
	)
	(segment
		(start 83.245706 -129.452624)
		(end 82.08264 -129.452624)
		(width 0.1016)
		(layer "F.Cu")
		(net "N53313646")
	)
	(via
		(at 81.30032 -130.234944)
		(size 0.508)
		(drill 0.254)
		(layers "F.Cu" "B.Cu")
		(net "N53313646")
	)
	(segment
		(start 89.962228 -131.893818)
		(end 89.962228 -132.463032)
		(width 0.1016)
		(layer "F.Cu")
		(net "N53313577")
	)
	(segment
		(start 90.365326 -113.371376)
		(end 90.98534 -113.371376)
		(width 0.1016)
		(layer "F.Cu")
		(net "N53313577")
	)
	(segment
		(start 90.1065 -113.11255)
		(end 90.365326 -113.371376)
		(width 0.1016)
		(layer "F.Cu")
		(net "N53313577")
	)
	(segment
		(start 89.64676 -131.57835)
		(end 89.962228 -131.893818)
		(width 0.1016)
		(layer "F.Cu")
		(net "N53313577")
	)
	(via
		(at 89.64676 -131.57835)
		(size 0.508)
		(drill 0.254)
		(layers "F.Cu" "B.Cu")
		(net "N53313577")
	)
	(via
		(at 90.1065 -113.11255)
		(size 0.508)
		(drill 0.254)
		(layers "F.Cu" "B.Cu")
		(net "N53313577")
	)
	(segment
		(start 86.741 -123.561348)
		(end 86.741 -120.567704)
		(width 0.1143)
		(layer "In7.Cu")
		(net "N53313577")
	)
	(segment
		(start 85.66912 -124.633228)
		(end 86.741 -123.561348)
		(width 0.1143)
		(layer "In7.Cu")
		(net "N53313577")
	)
	(segment
		(start 87.948516 -130.69824)
		(end 85.66912 -128.418844)
		(width 0.1143)
		(layer "In7.Cu")
		(net "N53313577")
	)
	(segment
		(start 87.964518 -130.69824)
		(end 87.948516 -130.69824)
		(width 0.1143)
		(layer "In7.Cu")
		(net "N53313577")
	)
	(segment
		(start 89.64676 -131.57835)
		(end 89.64676 -131.579874)
		(width 0.1143)
		(layer "In7.Cu")
		(net "N53313577")
	)
	(segment
		(start 89.64676 -131.579874)
		(end 89.587324 -131.63931)
		(width 0.1143)
		(layer "In7.Cu")
		(net "N53313577")
	)
	(segment
		(start 89.623138 -113.11255)
		(end 90.1065 -113.11255)
		(width 0.1143)
		(layer "In7.Cu")
		(net "N53313577")
	)
	(segment
		(start 89.587324 -131.63931)
		(end 88.905588 -131.63931)
		(width 0.1143)
		(layer "In7.Cu")
		(net "N53313577")
	)
	(segment
		(start 86.741 -120.567704)
		(end 88.94572 -118.362984)
		(width 0.1143)
		(layer "In7.Cu")
		(net "N53313577")
	)
	(segment
		(start 88.94572 -118.362984)
		(end 88.94572 -113.789968)
		(width 0.1143)
		(layer "In7.Cu")
		(net "N53313577")
	)
	(segment
		(start 88.905588 -131.63931)
		(end 87.964518 -130.69824)
		(width 0.1143)
		(layer "In7.Cu")
		(net "N53313577")
	)
	(segment
		(start 88.94572 -113.789968)
		(end 89.623138 -113.11255)
		(width 0.1143)
		(layer "In7.Cu")
		(net "N53313577")
	)
	(segment
		(start 85.66912 -128.418844)
		(end 85.66912 -124.633228)
		(width 0.1143)
		(layer "In7.Cu")
		(net "N53313577")
	)
	(segment
		(start 87.887048 -128.598676)
		(end 87.887048 -127.141732)
		(width 0.1016)
		(layer "F.Cu")
		(net "PORT80_LOUT4")
	)
	(segment
		(start 86.866476 -125.19152)
		(end 86.866476 -126.12116)
		(width 0.1016)
		(layer "F.Cu")
		(net "PORT80_LOUT4")
	)
	(segment
		(start 86.866476 -126.12116)
		(end 87.22868 -126.483364)
		(width 0.1016)
		(layer "F.Cu")
		(net "PORT80_LOUT4")
	)
	(segment
		(start 87.887048 -127.141732)
		(end 87.22868 -126.483364)
		(width 0.1016)
		(layer "F.Cu")
		(net "PORT80_LOUT4")
	)
	(via
		(at 87.22868 -126.483364)
		(size 0.508)
		(drill 0.254)
		(layers "F.Cu" "B.Cu")
		(net "PORT80_LOUT4")
	)
	(segment
		(start 82.930746 -125.985016)
		(end 82.930746 -128.337564)
		(width 0.1016)
		(layer "F.Cu")
		(net "PORT80_LOUT0")
	)
	(segment
		(start 83.816444 -123.141486)
		(end 82.84718 -123.141486)
		(width 0.1016)
		(layer "F.Cu")
		(net "PORT80_LOUT0")
	)
	(segment
		(start 82.63128 -123.357386)
		(end 82.63128 -125.563122)
		(width 0.1016)
		(layer "F.Cu")
		(net "PORT80_LOUT0")
	)
	(segment
		(start 82.930746 -128.337564)
		(end 83.245706 -128.652524)
		(width 0.1016)
		(layer "F.Cu")
		(net "PORT80_LOUT0")
	)
	(segment
		(start 82.99196 -125.923802)
		(end 82.930746 -125.985016)
		(width 0.1016)
		(layer "F.Cu")
		(net "PORT80_LOUT0")
	)
	(segment
		(start 82.84718 -123.141486)
		(end 82.63128 -123.357386)
		(width 0.1016)
		(layer "F.Cu")
		(net "PORT80_LOUT0")
	)
	(segment
		(start 82.63128 -125.563122)
		(end 82.99196 -125.923802)
		(width 0.1016)
		(layer "F.Cu")
		(net "PORT80_LOUT0")
	)
	(via
		(at 82.99196 -125.923802)
		(size 0.508)
		(drill 0.254)
		(layers "F.Cu" "B.Cu")
		(net "PORT80_LOUT0")
	)
	(segment
		(start 86.36635 -126.276354)
		(end 86.589108 -126.499112)
		(width 0.1016)
		(layer "F.Cu")
		(net "PORT80_LOUT3")
	)
	(segment
		(start 86.744048 -128.105408)
		(end 86.589108 -127.950468)
		(width 0.1016)
		(layer "F.Cu")
		(net "PORT80_LOUT3")
	)
	(segment
		(start 86.589108 -126.499112)
		(end 86.589108 -127.950468)
		(width 0.1016)
		(layer "F.Cu")
		(net "PORT80_LOUT3")
	)
	(segment
		(start 86.744048 -128.598676)
		(end 86.744048 -128.105408)
		(width 0.1016)
		(layer "F.Cu")
		(net "PORT80_LOUT3")
	)
	(segment
		(start 86.36635 -125.19152)
		(end 86.36635 -126.276354)
		(width 0.1016)
		(layer "F.Cu")
		(net "PORT80_LOUT3")
	)
	(via
		(at 86.589108 -127.950468)
		(size 0.508)
		(drill 0.254)
		(layers "F.Cu" "B.Cu")
		(net "PORT80_LOUT3")
	)
	(segment
		(start 90.584782 -114.171476)
		(end 90.05951 -114.696748)
		(width 0.1016)
		(layer "F.Cu")
		(net "PORT80_LOUT6")
	)
	(segment
		(start 90.98534 -114.171476)
		(end 90.584782 -114.171476)
		(width 0.1016)
		(layer "F.Cu")
		(net "PORT80_LOUT6")
	)
	(segment
		(start 89.86647 -114.889788)
		(end 90.05951 -114.696748)
		(width 0.1016)
		(layer "F.Cu")
		(net "PORT80_LOUT6")
	)
	(segment
		(start 89.86647 -116.591588)
		(end 89.86647 -114.889788)
		(width 0.1016)
		(layer "F.Cu")
		(net "PORT80_LOUT6")
	)
	(via
		(at 90.05951 -114.696748)
		(size 0.508)
		(drill 0.254)
		(layers "F.Cu" "B.Cu")
		(net "PORT80_LOUT6")
	)
	(segment
		(start 88.61298 -127.399034)
		(end 88.28786 -127.073914)
		(width 0.1016)
		(layer "F.Cu")
		(net "PORT80_LOUT7")
	)
	(segment
		(start 89.030048 -128.598676)
		(end 89.030048 -127.816102)
		(width 0.1016)
		(layer "F.Cu")
		(net "PORT80_LOUT7")
	)
	(segment
		(start 89.030048 -127.816102)
		(end 88.61298 -127.399034)
		(width 0.1016)
		(layer "F.Cu")
		(net "PORT80_LOUT7")
	)
	(segment
		(start 87.366348 -125.846332)
		(end 87.366348 -125.19152)
		(width 0.1016)
		(layer "F.Cu")
		(net "PORT80_LOUT7")
	)
	(segment
		(start 88.28786 -126.949454)
		(end 87.69604 -126.357634)
		(width 0.1016)
		(layer "F.Cu")
		(net "PORT80_LOUT7")
	)
	(segment
		(start 87.69604 -126.357634)
		(end 87.69604 -126.176024)
		(width 0.1016)
		(layer "F.Cu")
		(net "PORT80_LOUT7")
	)
	(segment
		(start 88.28786 -127.073914)
		(end 88.28786 -126.949454)
		(width 0.1016)
		(layer "F.Cu")
		(net "PORT80_LOUT7")
	)
	(segment
		(start 87.69604 -126.176024)
		(end 87.366348 -125.846332)
		(width 0.1016)
		(layer "F.Cu")
		(net "PORT80_LOUT7")
	)
	(via
		(at 88.61298 -127.399034)
		(size 0.508)
		(drill 0.254)
		(layers "F.Cu" "B.Cu")
		(net "PORT80_LOUT7")
	)
	(segment
		(start 39.014908 -199.080374)
		(end 38.94328 -199.008746)
		(width 0.1016)
		(layer "F.Cu")
		(net "UART_DTR_P5_L_N")
	)
	(segment
		(start 7.5311 -159.29991)
		(end 11.767312 -159.29991)
		(width 0.1016)
		(layer "F.Cu")
		(net "UART_DTR_P5_L_N")
	)
	(segment
		(start 39.014908 -205.199488)
		(end 39.014908 -199.080374)
		(width 0.1016)
		(layer "F.Cu")
		(net "UART_DTR_P5_L_N")
	)
	(segment
		(start 4.558792 -162.272218)
		(end 7.5311 -159.29991)
		(width 0.1016)
		(layer "F.Cu")
		(net "UART_DTR_P5_L_N")
	)
	(segment
		(start 4.558792 -164.062156)
		(end 4.558792 -162.272218)
		(width 0.1016)
		(layer "F.Cu")
		(net "UART_DTR_P5_L_N")
	)
	(segment
		(start 11.767312 -159.29991)
		(end 12.32916 -158.738062)
		(width 0.1016)
		(layer "F.Cu")
		(net "UART_DTR_P5_L_N")
	)
	(via
		(at 38.94328 -199.008746)
		(size 0.508)
		(drill 0.254)
		(layers "F.Cu" "B.Cu")
		(net "UART_DTR_P5_L_N")
	)
	(via
		(at 12.32916 -158.738062)
		(size 0.508)
		(drill 0.254)
		(layers "F.Cu" "B.Cu")
		(net "UART_DTR_P5_L_N")
	)
	(segment
		(start 30.069536 -181.1655)
		(end 29.93136 -181.303676)
		(width 0.1143)
		(layer "In2.Cu")
		(net "UART_DTR_P5_L_N")
	)
	(segment
		(start 29.93136 -181.303676)
		(end 29.93136 -185.80227)
		(width 0.1143)
		(layer "In2.Cu")
		(net "UART_DTR_P5_L_N")
	)
	(segment
		(start 29.93136 -185.80227)
		(end 29.120338 -186.613292)
		(width 0.1143)
		(layer "In2.Cu")
		(net "UART_DTR_P5_L_N")
	)
	(segment
		(start 12.32916 -158.738062)
		(end 12.32916 -159.639762)
		(width 0.1143)
		(layer "In2.Cu")
		(net "UART_DTR_P5_L_N")
	)
	(segment
		(start 31.76143 -190.443104)
		(end 38.81628 -197.497954)
		(width 0.1143)
		(layer "In2.Cu")
		(net "UART_DTR_P5_L_N")
	)
	(segment
		(start 16.087598 -161.718752)
		(end 30.069536 -175.70069)
		(width 0.1143)
		(layer "In2.Cu")
		(net "UART_DTR_P5_L_N")
	)
	(segment
		(start 13.15466 -160.042352)
		(end 14.83106 -161.718752)
		(width 0.1143)
		(layer "In2.Cu")
		(net "UART_DTR_P5_L_N")
	)
	(segment
		(start 30.450536 -190.443104)
		(end 31.76143 -190.443104)
		(width 0.1143)
		(layer "In2.Cu")
		(net "UART_DTR_P5_L_N")
	)
	(segment
		(start 14.83106 -161.718752)
		(end 16.087598 -161.718752)
		(width 0.1143)
		(layer "In2.Cu")
		(net "UART_DTR_P5_L_N")
	)
	(segment
		(start 38.81628 -198.881746)
		(end 38.94328 -199.008746)
		(width 0.1143)
		(layer "In2.Cu")
		(net "UART_DTR_P5_L_N")
	)
	(segment
		(start 38.81628 -197.497954)
		(end 38.81628 -198.881746)
		(width 0.1143)
		(layer "In2.Cu")
		(net "UART_DTR_P5_L_N")
	)
	(segment
		(start 30.069536 -175.70069)
		(end 30.069536 -181.1655)
		(width 0.1143)
		(layer "In2.Cu")
		(net "UART_DTR_P5_L_N")
	)
	(segment
		(start 12.73175 -160.042352)
		(end 13.15466 -160.042352)
		(width 0.1143)
		(layer "In2.Cu")
		(net "UART_DTR_P5_L_N")
	)
	(segment
		(start 12.32916 -159.639762)
		(end 12.73175 -160.042352)
		(width 0.1143)
		(layer "In2.Cu")
		(net "UART_DTR_P5_L_N")
	)
	(segment
		(start 29.120338 -186.613292)
		(end 29.120338 -189.112906)
		(width 0.1143)
		(layer "In2.Cu")
		(net "UART_DTR_P5_L_N")
	)
	(segment
		(start 29.120338 -189.112906)
		(end 30.450536 -190.443104)
		(width 0.1143)
		(layer "In2.Cu")
		(net "UART_DTR_P5_L_N")
	)
	(segment
		(start 96.027494 -118.63705)
		(end 96.810322 -118.63705)
		(width 0.1016)
		(layer "F.Cu")
		(net "N53313558")
	)
	(segment
		(start 88.438228 -132.463032)
		(end 88.438228 -131.796536)
		(width 0.1016)
		(layer "F.Cu")
		(net "N53313558")
	)
	(segment
		(start 88.438228 -131.796536)
		(end 89.07526 -131.159504)
		(width 0.1016)
		(layer "F.Cu")
		(net "N53313558")
	)
	(segment
		(start 96.810322 -118.63705)
		(end 96.834706 -118.661434)
		(width 0.1016)
		(layer "F.Cu")
		(net "N53313558")
	)
	(via
		(at 89.07526 -131.159504)
		(size 0.508)
		(drill 0.254)
		(layers "F.Cu" "B.Cu")
		(net "N53313558")
	)
	(via
		(at 96.834706 -118.661434)
		(size 0.508)
		(drill 0.254)
		(layers "F.Cu" "B.Cu")
		(net "N53313558")
	)
	(segment
		(start 87.17534 -121.0564)
		(end 89.570306 -118.661434)
		(width 0.1143)
		(layer "In7.Cu")
		(net "N53313558")
	)
	(segment
		(start 89.07526 -131.159504)
		(end 88.331548 -130.415792)
		(width 0.1143)
		(layer "In7.Cu")
		(net "N53313558")
	)
	(segment
		(start 87.17534 -123.795028)
		(end 87.17534 -121.0564)
		(width 0.1143)
		(layer "In7.Cu")
		(net "N53313558")
	)
	(segment
		(start 89.570306 -118.661434)
		(end 96.834706 -118.661434)
		(width 0.1143)
		(layer "In7.Cu")
		(net "N53313558")
	)
	(segment
		(start 88.133936 -130.415792)
		(end 86.06536 -128.347216)
		(width 0.1143)
		(layer "In7.Cu")
		(net "N53313558")
	)
	(segment
		(start 86.06536 -128.347216)
		(end 86.06536 -124.905008)
		(width 0.1143)
		(layer "In7.Cu")
		(net "N53313558")
	)
	(segment
		(start 86.06536 -124.905008)
		(end 87.17534 -123.795028)
		(width 0.1143)
		(layer "In7.Cu")
		(net "N53313558")
	)
	(segment
		(start 88.331548 -130.415792)
		(end 88.133936 -130.415792)
		(width 0.1143)
		(layer "In7.Cu")
		(net "N53313558")
	)
	(segment
		(start 15.564866 -188.721746)
		(end 15.313152 -188.569092)
		(width 0.10414)
		(layer "F.Cu")
		(net "LAN1_P4_P")
	)
	(segment
		(start 16.056356 -191.58966)
		(end 15.887954 -190.904876)
		(width 0.10414)
		(layer "F.Cu")
		(net "LAN1_P4_P")
	)
	(segment
		(start 19.355054 -167.676068)
		(end 18.993104 -169.878502)
		(width 0.10414)
		(layer "F.Cu")
		(net "LAN1_P4_P")
	)
	(segment
		(start 18.13179 -191.293242)
		(end 16.30807 -191.742314)
		(width 0.10414)
		(layer "F.Cu")
		(net "LAN1_P4_P")
	)
	(segment
		(start 17.396206 -166.094156)
		(end 18.1102 -166.094156)
		(width 0.10414)
		(layer "F.Cu")
		(net "LAN1_P4_P")
	)
	(segment
		(start 20.014946 -202.942698)
		(end 19.73199 -202.659742)
		(width 0.10414)
		(layer "F.Cu")
		(net "LAN1_P4_P")
	)
	(segment
		(start 15.887954 -190.904876)
		(end 16.0401 -190.653416)
		(width 0.10414)
		(layer "F.Cu")
		(net "LAN1_P4_P")
	)
	(segment
		(start 16.0401 -190.653416)
		(end 17.86382 -190.204598)
		(width 0.10414)
		(layer "F.Cu")
		(net "LAN1_P4_P")
	)
	(segment
		(start 19.73199 -202.659742)
		(end 19.73199 -195.862702)
		(width 0.10414)
		(layer "F.Cu")
		(net "LAN1_P4_P")
	)
	(segment
		(start 18.52803 -166.511986)
		(end 18.876264 -166.511986)
		(width 0.10414)
		(layer "F.Cu")
		(net "LAN1_P4_P")
	)
	(segment
		(start 17.1323 -185.269632)
		(end 17.1323 -184.681876)
		(width 0.10414)
		(layer "F.Cu")
		(net "LAN1_P4_P")
	)
	(segment
		(start 18.1102 -166.094156)
		(end 18.52803 -166.511986)
		(width 0.10414)
		(layer "F.Cu")
		(net "LAN1_P4_P")
	)
	(segment
		(start 17.120362 -187.18403)
		(end 17.459706 -186.624468)
		(width 0.10414)
		(layer "F.Cu")
		(net "LAN1_P4_P")
	)
	(segment
		(start 17.1323 -175.612806)
		(end 17.1323 -184.681876)
		(width 0.10414)
		(layer "F.Cu")
		(net "LAN1_P4_P")
	)
	(segment
		(start 17.13865 -185.321194)
		(end 17.1323 -185.269632)
		(width 0.10414)
		(layer "F.Cu")
		(net "LAN1_P4_P")
	)
	(segment
		(start 16.30807 -191.742314)
		(end 16.056356 -191.58966)
		(width 0.10414)
		(layer "F.Cu")
		(net "LAN1_P4_P")
	)
	(segment
		(start 19.73199 -195.862702)
		(end 18.691352 -191.632586)
		(width 0.10414)
		(layer "F.Cu")
		(net "LAN1_P4_P")
	)
	(segment
		(start 15.296896 -187.632848)
		(end 17.120362 -187.18403)
		(width 0.10414)
		(layer "F.Cu")
		(net "LAN1_P4_P")
	)
	(segment
		(start 20.014946 -205.199488)
		(end 20.014946 -202.942698)
		(width 0.10414)
		(layer "F.Cu")
		(net "LAN1_P4_P")
	)
	(segment
		(start 17.388586 -188.272674)
		(end 15.564866 -188.721746)
		(width 0.10414)
		(layer "F.Cu")
		(net "LAN1_P4_P")
	)
	(segment
		(start 17.459706 -186.624468)
		(end 17.13865 -185.321194)
		(width 0.10414)
		(layer "F.Cu")
		(net "LAN1_P4_P")
	)
	(segment
		(start 15.14475 -187.884308)
		(end 15.296896 -187.632848)
		(width 0.10414)
		(layer "F.Cu")
		(net "LAN1_P4_P")
	)
	(segment
		(start 15.313152 -188.569092)
		(end 15.14475 -187.884308)
		(width 0.10414)
		(layer "F.Cu")
		(net "LAN1_P4_P")
	)
	(segment
		(start 18.202656 -189.644782)
		(end 17.948148 -188.612018)
		(width 0.10414)
		(layer "F.Cu")
		(net "LAN1_P4_P")
	)
	(segment
		(start 17.948148 -188.612018)
		(end 17.388586 -188.272674)
		(width 0.10414)
		(layer "F.Cu")
		(net "LAN1_P4_P")
	)
	(segment
		(start 18.993104 -169.878502)
		(end 17.1323 -175.612806)
		(width 0.10414)
		(layer "F.Cu")
		(net "LAN1_P4_P")
	)
	(segment
		(start 19.354292 -166.990014)
		(end 19.355054 -167.676068)
		(width 0.10414)
		(layer "F.Cu")
		(net "LAN1_P4_P")
	)
	(segment
		(start 18.876264 -166.511986)
		(end 19.354292 -166.990014)
		(width 0.10414)
		(layer "F.Cu")
		(net "LAN1_P4_P")
	)
	(segment
		(start 17.86382 -190.204598)
		(end 18.202656 -189.644782)
		(width 0.10414)
		(layer "F.Cu")
		(net "LAN1_P4_P")
	)
	(segment
		(start 18.691352 -191.632586)
		(end 18.13179 -191.293242)
		(width 0.10414)
		(layer "F.Cu")
		(net "LAN1_P4_P")
	)
	(via
		(at 17.1323 -184.681876)
		(size 0.4064)
		(drill 0.2032)
		(layers "F.Cu" "B.Cu")
		(net "LAN1_P4_P")
	)
	(segment
		(start 94.953836 -117.854984)
		(end 95.29826 -117.854984)
		(width 0.1016)
		(layer "F.Cu")
		(net "PORT80_LOUT5")
	)
	(segment
		(start 95.22968 -118.63705)
		(end 95.227394 -118.63705)
		(width 0.1016)
		(layer "F.Cu")
		(net "PORT80_LOUT5")
	)
	(segment
		(start 95.29826 -117.854984)
		(end 95.29826 -118.56847)
		(width 0.1016)
		(layer "F.Cu")
		(net "PORT80_LOUT5")
	)
	(segment
		(start 94.167198 -118.641622)
		(end 94.953836 -117.854984)
		(width 0.1016)
		(layer "F.Cu")
		(net "PORT80_LOUT5")
	)
	(segment
		(start 92.416376 -118.641622)
		(end 94.167198 -118.641622)
		(width 0.1016)
		(layer "F.Cu")
		(net "PORT80_LOUT5")
	)
	(segment
		(start 95.29826 -118.56847)
		(end 95.22968 -118.63705)
		(width 0.1016)
		(layer "F.Cu")
		(net "PORT80_LOUT5")
	)
	(via
		(at 95.29826 -117.854984)
		(size 0.508)
		(drill 0.254)
		(layers "F.Cu" "B.Cu")
		(net "PORT80_LOUT5")
	)
	(segment
		(start 26.014934 -205.199488)
		(end 26.014934 -199.628252)
		(width 0.1016)
		(layer "F.Cu")
		(net "GND62")
	)
	(via
		(at 26.014934 -199.628252)
		(size 0.508)
		(drill 0.254)
		(layers "F.Cu" "B.Cu")
		(net "GND62")
	)
	(segment
		(start 82.038444 -118.645686)
		(end 82.042508 -118.641622)
		(width 0.1016)
		(layer "F.Cu")
		(net "N53313175")
	)
	(segment
		(start 82.042508 -118.641622)
		(end 83.816444 -118.641622)
		(width 0.1016)
		(layer "F.Cu")
		(net "N53313175")
	)
	(segment
		(start 85.866478 -126.831598)
		(end 85.131148 -127.566928)
		(width 0.1016)
		(layer "F.Cu")
		(net "PORT80_LOUT2")
	)
	(segment
		(start 85.601048 -128.598676)
		(end 85.13064 -128.128268)
		(width 0.1016)
		(layer "F.Cu")
		(net "PORT80_LOUT2")
	)
	(segment
		(start 85.13064 -127.566928)
		(end 85.13064 -127.708914)
		(width 0.1016)
		(layer "F.Cu")
		(net "PORT80_LOUT2")
	)
	(segment
		(start 85.131148 -127.708914)
		(end 85.13064 -127.708914)
		(width 0.1016)
		(layer "F.Cu")
		(net "PORT80_LOUT2")
	)
	(segment
		(start 85.131148 -127.566928)
		(end 85.13064 -127.566928)
		(width 0.1016)
		(layer "F.Cu")
		(net "PORT80_LOUT2")
	)
	(segment
		(start 85.13064 -128.128268)
		(end 85.13064 -127.708914)
		(width 0.1016)
		(layer "F.Cu")
		(net "PORT80_LOUT2")
	)
	(segment
		(start 85.866478 -125.19152)
		(end 85.866478 -126.831598)
		(width 0.1016)
		(layer "F.Cu")
		(net "PORT80_LOUT2")
	)
	(via
		(at 85.131148 -127.708914)
		(size 0.508)
		(drill 0.254)
		(layers "F.Cu" "B.Cu")
		(net "PORT80_LOUT2")
	)
	(segment
		(start 27.0891 -198.013574)
		(end 27.0891 -198.639176)
		(width 0.1016)
		(layer "F.Cu")
		(net "GND61")
	)
	(segment
		(start 27.0891 -198.639176)
		(end 26.5049 -199.223376)
		(width 0.1016)
		(layer "F.Cu")
		(net "GND61")
	)
	(segment
		(start 26.5049 -200.139808)
		(end 27.014932 -200.64984)
		(width 0.1016)
		(layer "F.Cu")
		(net "GND61")
	)
	(segment
		(start 26.5049 -199.223376)
		(end 26.5049 -200.139808)
		(width 0.1016)
		(layer "F.Cu")
		(net "GND61")
	)
	(segment
		(start 27.014932 -200.64984)
		(end 27.014932 -205.199488)
		(width 0.1016)
		(layer "F.Cu")
		(net "GND61")
	)
	(via
		(at 27.0891 -198.013574)
		(size 0.508)
		(drill 0.254)
		(layers "F.Cu" "B.Cu")
		(net "GND61")
	)
	(segment
		(start 16.69796 -182.158386)
		(end 16.69796 -175.543972)
		(width 0.10414)
		(layer "F.Cu")
		(net "LAN1_P4_N")
	)
	(segment
		(start 18.696178 -166.946326)
		(end 18.52803 -166.946326)
		(width 0.10414)
		(layer "F.Cu")
		(net "LAN1_P4_N")
	)
	(segment
		(start 16.994632 -186.553348)
		(end 16.71066 -185.399934)
		(width 0.10414)
		(layer "F.Cu")
		(net "LAN1_P4_N")
	)
	(segment
		(start 18.569686 -169.775632)
		(end 18.61693 -169.486072)
		(width 0.10414)
		(layer "F.Cu")
		(net "LAN1_P4_N")
	)
	(segment
		(start 18.563082 -169.03192)
		(end 18.70837 -168.928034)
		(width 0.10414)
		(layer "F.Cu")
		(net "LAN1_P4_N")
	)
	(segment
		(start 18.92046 -167.640762)
		(end 18.919952 -167.1701)
		(width 0.10414)
		(layer "F.Cu")
		(net "LAN1_P4_N")
	)
	(segment
		(start 18.233136 -170.812714)
		(end 18.12036 -170.592242)
		(width 0.10414)
		(layer "F.Cu")
		(net "LAN1_P4_N")
	)
	(segment
		(start 16.23695 -192.207134)
		(end 15.677388 -191.868298)
		(width 0.10414)
		(layer "F.Cu")
		(net "LAN1_P4_N")
	)
	(segment
		(start 18.512028 -169.340784)
		(end 18.563082 -169.03192)
		(width 0.10414)
		(layer "F.Cu")
		(net "LAN1_P4_N")
	)
	(segment
		(start 17.819116 -171.520358)
		(end 17.91589 -171.22267)
		(width 0.10414)
		(layer "F.Cu")
		(net "LAN1_P4_N")
	)
	(segment
		(start 16.69796 -175.543972)
		(end 17.630648 -172.668946)
		(width 0.10414)
		(layer "F.Cu")
		(net "LAN1_P4_N")
	)
	(segment
		(start 19.29765 -195.915534)
		(end 18.312384 -191.91097)
		(width 0.10414)
		(layer "F.Cu")
		(net "LAN1_P4_N")
	)
	(segment
		(start 18.437606 -170.182286)
		(end 18.569686 -169.775632)
		(width 0.10414)
		(layer "F.Cu")
		(net "LAN1_P4_N")
	)
	(segment
		(start 17.56918 -188.890402)
		(end 17.317466 -188.737748)
		(width 0.10414)
		(layer "F.Cu")
		(net "LAN1_P4_N")
	)
	(segment
		(start 17.835118 -172.038518)
		(end 17.931892 -171.74083)
		(width 0.10414)
		(layer "F.Cu")
		(net "LAN1_P4_N")
	)
	(segment
		(start 15.493746 -189.186566)
		(end 14.934184 -188.84773)
		(width 0.10414)
		(layer "F.Cu")
		(net "LAN1_P4_N")
	)
	(segment
		(start 18.12036 -170.592242)
		(end 18.217134 -170.294554)
		(width 0.10414)
		(layer "F.Cu")
		(net "LAN1_P4_N")
	)
	(segment
		(start 15.42288 -190.833756)
		(end 15.761462 -190.274448)
		(width 0.10414)
		(layer "F.Cu")
		(net "LAN1_P4_N")
	)
	(segment
		(start 18.61693 -169.486072)
		(end 18.512028 -169.340784)
		(width 0.10414)
		(layer "F.Cu")
		(net "LAN1_P4_N")
	)
	(segment
		(start 14.934184 -188.84773)
		(end 14.679676 -187.813188)
		(width 0.10414)
		(layer "F.Cu")
		(net "LAN1_P4_N")
	)
	(segment
		(start 17.585182 -189.82563)
		(end 17.737582 -189.573916)
		(width 0.10414)
		(layer "F.Cu")
		(net "LAN1_P4_N")
	)
	(segment
		(start 18.1102 -167.364156)
		(end 17.396206 -167.364156)
		(width 0.10414)
		(layer "F.Cu")
		(net "LAN1_P4_N")
	)
	(segment
		(start 17.614646 -172.150786)
		(end 17.835118 -172.038518)
		(width 0.10414)
		(layer "F.Cu")
		(net "LAN1_P4_N")
	)
	(segment
		(start 17.737582 -189.573916)
		(end 17.56918 -188.890402)
		(width 0.10414)
		(layer "F.Cu")
		(net "LAN1_P4_N")
	)
	(segment
		(start 18.312384 -191.91097)
		(end 18.06067 -191.758316)
		(width 0.10414)
		(layer "F.Cu")
		(net "LAN1_P4_N")
	)
	(segment
		(start 18.217134 -170.294554)
		(end 18.437606 -170.182286)
		(width 0.10414)
		(layer "F.Cu")
		(net "LAN1_P4_N")
	)
	(segment
		(start 15.761462 -190.274448)
		(end 17.585182 -189.82563)
		(width 0.10414)
		(layer "F.Cu")
		(net "LAN1_P4_N")
	)
	(segment
		(start 19.29765 -202.659742)
		(end 19.29765 -195.915534)
		(width 0.10414)
		(layer "F.Cu")
		(net "LAN1_P4_N")
	)
	(segment
		(start 17.630648 -172.668946)
		(end 17.517872 -172.448474)
		(width 0.10414)
		(layer "F.Cu")
		(net "LAN1_P4_N")
	)
	(segment
		(start 19.014948 -205.199488)
		(end 19.014948 -202.942444)
		(width 0.10414)
		(layer "F.Cu")
		(net "LAN1_P4_N")
	)
	(segment
		(start 18.06067 -191.758316)
		(end 16.23695 -192.207134)
		(width 0.10414)
		(layer "F.Cu")
		(net "LAN1_P4_N")
	)
	(segment
		(start 17.91589 -171.22267)
		(end 18.136362 -171.110402)
		(width 0.10414)
		(layer "F.Cu")
		(net "LAN1_P4_N")
	)
	(segment
		(start 18.759424 -168.61917)
		(end 18.654776 -168.474136)
		(width 0.10414)
		(layer "F.Cu")
		(net "LAN1_P4_N")
	)
	(segment
		(start 17.931892 -171.74083)
		(end 17.819116 -171.520358)
		(width 0.10414)
		(layer "F.Cu")
		(net "LAN1_P4_N")
	)
	(segment
		(start 19.014948 -202.942444)
		(end 19.29765 -202.659742)
		(width 0.10414)
		(layer "F.Cu")
		(net "LAN1_P4_N")
	)
	(segment
		(start 18.654776 -168.474136)
		(end 18.70583 -168.165272)
		(width 0.10414)
		(layer "F.Cu")
		(net "LAN1_P4_N")
	)
	(segment
		(start 17.317466 -188.737748)
		(end 15.493746 -189.186566)
		(width 0.10414)
		(layer "F.Cu")
		(net "LAN1_P4_N")
	)
	(segment
		(start 18.851118 -168.061386)
		(end 18.92046 -167.640762)
		(width 0.10414)
		(layer "F.Cu")
		(net "LAN1_P4_N")
	)
	(segment
		(start 15.018258 -187.25388)
		(end 16.841978 -186.805062)
		(width 0.10414)
		(layer "F.Cu")
		(net "LAN1_P4_N")
	)
	(segment
		(start 18.52803 -166.946326)
		(end 18.1102 -167.364156)
		(width 0.10414)
		(layer "F.Cu")
		(net "LAN1_P4_N")
	)
	(segment
		(start 15.677388 -191.868298)
		(end 15.42288 -190.833756)
		(width 0.10414)
		(layer "F.Cu")
		(net "LAN1_P4_N")
	)
	(segment
		(start 17.517872 -172.448474)
		(end 17.614646 -172.150786)
		(width 0.10414)
		(layer "F.Cu")
		(net "LAN1_P4_N")
	)
	(segment
		(start 16.71066 -185.399934)
		(end 16.69796 -185.296302)
		(width 0.10414)
		(layer "F.Cu")
		(net "LAN1_P4_N")
	)
	(segment
		(start 16.69796 -185.296302)
		(end 16.69796 -182.158386)
		(width 0.10414)
		(layer "F.Cu")
		(net "LAN1_P4_N")
	)
	(segment
		(start 14.679676 -187.813188)
		(end 15.018258 -187.25388)
		(width 0.10414)
		(layer "F.Cu")
		(net "LAN1_P4_N")
	)
	(segment
		(start 18.70583 -168.165272)
		(end 18.851118 -168.061386)
		(width 0.10414)
		(layer "F.Cu")
		(net "LAN1_P4_N")
	)
	(segment
		(start 18.919952 -167.1701)
		(end 18.696178 -166.946326)
		(width 0.10414)
		(layer "F.Cu")
		(net "LAN1_P4_N")
	)
	(segment
		(start 18.70837 -168.928034)
		(end 18.759424 -168.61917)
		(width 0.10414)
		(layer "F.Cu")
		(net "LAN1_P4_N")
	)
	(segment
		(start 16.841978 -186.805062)
		(end 16.994632 -186.553348)
		(width 0.10414)
		(layer "F.Cu")
		(net "LAN1_P4_N")
	)
	(segment
		(start 18.136362 -171.110402)
		(end 18.233136 -170.812714)
		(width 0.10414)
		(layer "F.Cu")
		(net "LAN1_P4_N")
	)
	(via
		(at 16.69796 -182.158386)
		(size 0.4064)
		(drill 0.2032)
		(layers "F.Cu" "B.Cu")
		(net "LAN1_P4_N")
	)
	(via
		(at 24.68372 -199.763888)
		(size 0.508)
		(drill 0.254)
		(layers "F.Cu" "B.Cu")
		(net "GND27")
	)
	(segment
		(start 24.684736 -199.763888)
		(end 25.014936 -200.094088)
		(width 0.1016)
		(layer "B.Cu")
		(net "GND27")
	)
	(segment
		(start 25.014936 -200.094088)
		(end 25.014936 -205.199488)
		(width 0.1016)
		(layer "B.Cu")
		(net "GND27")
	)
	(segment
		(start 24.68372 -199.763888)
		(end 24.684736 -199.763888)
		(width 0.1016)
		(layer "B.Cu")
		(net "GND27")
	)
	(segment
		(start 179.512214 -169.704766)
		(end 179.512214 -169.123614)
		(width 0.10414)
		(layer "F.Cu")
		(net "LAN2_P3_N")
	)
	(segment
		(start 179.930044 -168.705784)
		(end 179.930044 -167.992044)
		(width 0.10414)
		(layer "F.Cu")
		(net "LAN2_P3_N")
	)
	(segment
		(start 179.512214 -169.123614)
		(end 179.930044 -168.705784)
		(width 0.10414)
		(layer "F.Cu")
		(net "LAN2_P3_N")
	)
	(segment
		(start 179.930044 -170.122596)
		(end 179.512214 -169.704766)
		(width 0.10414)
		(layer "F.Cu")
		(net "LAN2_P3_N")
	)
	(via
		(at 179.930044 -170.122596)
		(size 0.508)
		(drill 0.254)
		(layers "F.Cu" "B.Cu")
		(net "LAN2_P3_N")
	)
	(segment
		(start 180.316632 -169.318686)
		(end 179.687982 -169.318686)
		(width 0.10414)
		(layer "B.Cu")
		(net "LAN2_P3_N")
	)
	(segment
		(start 183.7309 -195.154042)
		(end 183.7309 -180.19522)
		(width 0.10414)
		(layer "B.Cu")
		(net "LAN2_P3_N")
	)
	(segment
		(start 183.7309 -179.13858)
		(end 183.515 -178.92268)
		(width 0.10414)
		(layer "B.Cu")
		(net "LAN2_P3_N")
	)
	(segment
		(start 183.515 -176.49698)
		(end 183.7309 -176.28108)
		(width 0.10414)
		(layer "B.Cu")
		(net "LAN2_P3_N")
	)
	(segment
		(start 181.111652 -169.789094)
		(end 181.036214 -169.610532)
		(width 0.10414)
		(layer "B.Cu")
		(net "LAN2_P3_N")
	)
	(segment
		(start 183.515 -179.6669)
		(end 183.7309 -179.451)
		(width 0.10414)
		(layer "B.Cu")
		(net "LAN2_P3_N")
	)
	(segment
		(start 183.7309 -178.39436)
		(end 183.7309 -178.08194)
		(width 0.10414)
		(layer "B.Cu")
		(net "LAN2_P3_N")
	)
	(segment
		(start 183.7309 -175.22444)
		(end 183.7309 -174.91202)
		(width 0.10414)
		(layer "B.Cu")
		(net "LAN2_P3_N")
	)
	(segment
		(start 183.7309 -177.33772)
		(end 183.7309 -177.0253)
		(width 0.10414)
		(layer "B.Cu")
		(net "LAN2_P3_N")
	)
	(segment
		(start 184.015634 -202.942444)
		(end 184.298336 -202.659742)
		(width 0.10414)
		(layer "B.Cu")
		(net "LAN2_P3_N")
	)
	(segment
		(start 183.515 -174.69612)
		(end 183.515 -174.3837)
		(width 0.10414)
		(layer "B.Cu")
		(net "LAN2_P3_N")
	)
	(segment
		(start 183.631332 -173.240954)
		(end 183.43499 -173.142402)
		(width 0.10414)
		(layer "B.Cu")
		(net "LAN2_P3_N")
	)
	(segment
		(start 179.512214 -169.704766)
		(end 179.930044 -170.122596)
		(width 0.10414)
		(layer "B.Cu")
		(net "LAN2_P3_N")
	)
	(segment
		(start 183.7309 -177.0253)
		(end 183.515 -176.8094)
		(width 0.10414)
		(layer "B.Cu")
		(net "LAN2_P3_N")
	)
	(segment
		(start 183.7309 -173.540928)
		(end 183.631332 -173.240954)
		(width 0.10414)
		(layer "B.Cu")
		(net "LAN2_P3_N")
	)
	(segment
		(start 183.57342 -196.68617)
		(end 183.7309 -195.154042)
		(width 0.10414)
		(layer "B.Cu")
		(net "LAN2_P3_N")
	)
	(segment
		(start 183.515 -175.75276)
		(end 183.515 -175.44034)
		(width 0.10414)
		(layer "B.Cu")
		(net "LAN2_P3_N")
	)
	(segment
		(start 179.512214 -169.494454)
		(end 179.512214 -169.704766)
		(width 0.10414)
		(layer "B.Cu")
		(net "LAN2_P3_N")
	)
	(segment
		(start 183.43499 -173.142402)
		(end 183.336438 -172.845476)
		(width 0.10414)
		(layer "B.Cu")
		(net "LAN2_P3_N")
	)
	(segment
		(start 183.7309 -174.91202)
		(end 183.515 -174.69612)
		(width 0.10414)
		(layer "B.Cu")
		(net "LAN2_P3_N")
	)
	(segment
		(start 183.7309 -180.19522)
		(end 183.515 -179.97932)
		(width 0.10414)
		(layer "B.Cu")
		(net "LAN2_P3_N")
	)
	(segment
		(start 183.7309 -175.96866)
		(end 183.515 -175.75276)
		(width 0.10414)
		(layer "B.Cu")
		(net "LAN2_P3_N")
	)
	(segment
		(start 183.435244 -172.649388)
		(end 182.874412 -170.95597)
		(width 0.10414)
		(layer "B.Cu")
		(net "LAN2_P3_N")
	)
	(segment
		(start 184.298336 -202.659742)
		(end 184.298336 -200.415398)
		(width 0.10414)
		(layer "B.Cu")
		(net "LAN2_P3_N")
	)
	(segment
		(start 184.298336 -200.415398)
		(end 183.57342 -197.809612)
		(width 0.10414)
		(layer "B.Cu")
		(net "LAN2_P3_N")
	)
	(segment
		(start 183.57342 -197.809612)
		(end 183.57342 -196.68617)
		(width 0.10414)
		(layer "B.Cu")
		(net "LAN2_P3_N")
	)
	(segment
		(start 183.7309 -178.08194)
		(end 183.515 -177.86604)
		(width 0.10414)
		(layer "B.Cu")
		(net "LAN2_P3_N")
	)
	(segment
		(start 183.515 -174.3837)
		(end 183.7309 -174.1678)
		(width 0.10414)
		(layer "B.Cu")
		(net "LAN2_P3_N")
	)
	(segment
		(start 183.7309 -176.28108)
		(end 183.7309 -175.96866)
		(width 0.10414)
		(layer "B.Cu")
		(net "LAN2_P3_N")
	)
	(segment
		(start 181.401466 -169.90695)
		(end 181.111652 -169.789094)
		(width 0.10414)
		(layer "B.Cu")
		(net "LAN2_P3_N")
	)
	(segment
		(start 179.687982 -169.318686)
		(end 179.512214 -169.494454)
		(width 0.10414)
		(layer "B.Cu")
		(net "LAN2_P3_N")
	)
	(segment
		(start 182.874412 -170.95597)
		(end 181.86527 -169.946828)
		(width 0.10414)
		(layer "B.Cu")
		(net "LAN2_P3_N")
	)
	(segment
		(start 184.015634 -205.199488)
		(end 184.015634 -202.942444)
		(width 0.10414)
		(layer "B.Cu")
		(net "LAN2_P3_N")
	)
	(segment
		(start 183.515 -177.55362)
		(end 183.7309 -177.33772)
		(width 0.10414)
		(layer "B.Cu")
		(net "LAN2_P3_N")
	)
	(segment
		(start 183.336438 -172.845476)
		(end 183.435244 -172.649388)
		(width 0.10414)
		(layer "B.Cu")
		(net "LAN2_P3_N")
	)
	(segment
		(start 183.7309 -179.451)
		(end 183.7309 -179.13858)
		(width 0.10414)
		(layer "B.Cu")
		(net "LAN2_P3_N")
	)
	(segment
		(start 181.036214 -169.610532)
		(end 180.316632 -169.318686)
		(width 0.10414)
		(layer "B.Cu")
		(net "LAN2_P3_N")
	)
	(segment
		(start 183.515 -176.8094)
		(end 183.515 -176.49698)
		(width 0.10414)
		(layer "B.Cu")
		(net "LAN2_P3_N")
	)
	(segment
		(start 183.7309 -174.1678)
		(end 183.7309 -173.540928)
		(width 0.10414)
		(layer "B.Cu")
		(net "LAN2_P3_N")
	)
	(segment
		(start 183.515 -178.92268)
		(end 183.515 -178.61026)
		(width 0.10414)
		(layer "B.Cu")
		(net "LAN2_P3_N")
	)
	(segment
		(start 183.515 -177.86604)
		(end 183.515 -177.55362)
		(width 0.10414)
		(layer "B.Cu")
		(net "LAN2_P3_N")
	)
	(segment
		(start 181.580028 -169.831004)
		(end 181.401466 -169.90695)
		(width 0.10414)
		(layer "B.Cu")
		(net "LAN2_P3_N")
	)
	(segment
		(start 183.515 -179.97932)
		(end 183.515 -179.6669)
		(width 0.10414)
		(layer "B.Cu")
		(net "LAN2_P3_N")
	)
	(segment
		(start 183.515 -175.44034)
		(end 183.7309 -175.22444)
		(width 0.10414)
		(layer "B.Cu")
		(net "LAN2_P3_N")
	)
	(segment
		(start 181.86527 -169.946828)
		(end 181.580028 -169.831004)
		(width 0.10414)
		(layer "B.Cu")
		(net "LAN2_P3_N")
	)
	(segment
		(start 183.515 -178.61026)
		(end 183.7309 -178.39436)
		(width 0.10414)
		(layer "B.Cu")
		(net "LAN2_P3_N")
	)
	(segment
		(start 18.288 -199.027796)
		(end 17.014952 -200.300844)
		(width 0.1016)
		(layer "F.Cu")
		(net "CM_PWR_CTL_IN")
	)
	(segment
		(start 17.014952 -200.300844)
		(end 17.014952 -205.199488)
		(width 0.1016)
		(layer "F.Cu")
		(net "CM_PWR_CTL_IN")
	)
	(segment
		(start 18.288 -196.134228)
		(end 18.288 -199.027796)
		(width 0.1016)
		(layer "F.Cu")
		(net "CM_PWR_CTL_IN")
	)
	(segment
		(start 16.98752 -193.45275)
		(end 16.98752 -194.833748)
		(width 0.1016)
		(layer "F.Cu")
		(net "CM_PWR_CTL_IN")
	)
	(segment
		(start 31.614618 -170.403266)
		(end 30.84576 -170.403266)
		(width 0.1016)
		(layer "F.Cu")
		(net "CM_PWR_CTL_IN")
	)
	(segment
		(start 16.98752 -194.833748)
		(end 18.288 -196.134228)
		(width 0.1016)
		(layer "F.Cu")
		(net "CM_PWR_CTL_IN")
	)
	(segment
		(start 30.84576 -170.403266)
		(end 30.75178 -170.309286)
		(width 0.1016)
		(layer "F.Cu")
		(net "CM_PWR_CTL_IN")
	)
	(via
		(at 16.98752 -193.45275)
		(size 0.508)
		(drill 0.254)
		(layers "F.Cu" "B.Cu")
		(net "CM_PWR_CTL_IN")
	)
	(via
		(at 22.81174 -194.53987)
		(size 0.508)
		(drill 0.254)
		(layers "F.Cu" "B.Cu")
		(net "CM_PWR_CTL_IN")
	)
	(via
		(at 30.75178 -170.309286)
		(size 0.508)
		(drill 0.254)
		(layers "F.Cu" "B.Cu")
		(net "CM_PWR_CTL_IN")
	)
	(segment
		(start 31.46298 -185.293254)
		(end 31.46298 -170.914568)
		(width 0.1016)
		(layer "B.Cu")
		(net "CM_PWR_CTL_IN")
	)
	(segment
		(start 22.81174 -194.53987)
		(end 22.8092 -194.53987)
		(width 0.1016)
		(layer "B.Cu")
		(net "CM_PWR_CTL_IN")
	)
	(segment
		(start 22.8092 -193.947034)
		(end 31.46298 -185.293254)
		(width 0.1016)
		(layer "B.Cu")
		(net "CM_PWR_CTL_IN")
	)
	(segment
		(start 30.857698 -170.309286)
		(end 30.75178 -170.309286)
		(width 0.1016)
		(layer "B.Cu")
		(net "CM_PWR_CTL_IN")
	)
	(segment
		(start 22.8092 -194.53987)
		(end 22.8092 -193.947034)
		(width 0.1016)
		(layer "B.Cu")
		(net "CM_PWR_CTL_IN")
	)
	(segment
		(start 31.46298 -170.914568)
		(end 30.857698 -170.309286)
		(width 0.1016)
		(layer "B.Cu")
		(net "CM_PWR_CTL_IN")
	)
	(segment
		(start 18.07464 -194.53987)
		(end 16.98752 -193.45275)
		(width 0.1143)
		(layer "In2.Cu")
		(net "CM_PWR_CTL_IN")
	)
	(segment
		(start 22.81174 -194.53987)
		(end 18.07464 -194.53987)
		(width 0.1143)
		(layer "In2.Cu")
		(net "CM_PWR_CTL_IN")
	)
	(via
		(at 163.9316 -186.5884)
		(size 0.6604)
		(drill 0.3302)
		(layers "F.Cu" "B.Cu")
		(net "UART_RI_RP6_L_N")
	)
	(segment
		(start 162.08756 -182.454804)
		(end 162.08756 -175.70069)
		(width 0.1016)
		(layer "B.Cu")
		(net "UART_RI_RP6_L_N")
	)
	(segment
		(start 164.592 -187.68695)
		(end 164.592 -187.2488)
		(width 0.1016)
		(layer "B.Cu")
		(net "UART_RI_RP6_L_N")
	)
	(segment
		(start 163.1188 -185.337958)
		(end 163.1188 -184.770268)
		(width 0.1016)
		(layer "B.Cu")
		(net "UART_RI_RP6_L_N")
	)
	(segment
		(start 163.9316 -186.5884)
		(end 163.718494 -186.375294)
		(width 0.1016)
		(layer "B.Cu")
		(net "UART_RI_RP6_L_N")
	)
	(segment
		(start 163.718494 -185.937652)
		(end 163.1188 -185.337958)
		(width 0.1016)
		(layer "B.Cu")
		(net "UART_RI_RP6_L_N")
	)
	(segment
		(start 163.718494 -186.375294)
		(end 163.718494 -185.937652)
		(width 0.1016)
		(layer "B.Cu")
		(net "UART_RI_RP6_L_N")
	)
	(segment
		(start 162.39998 -182.767224)
		(end 162.08756 -182.454804)
		(width 0.1016)
		(layer "B.Cu")
		(net "UART_RI_RP6_L_N")
	)
	(segment
		(start 164.592 -187.2488)
		(end 163.9316 -186.5884)
		(width 0.1016)
		(layer "B.Cu")
		(net "UART_RI_RP6_L_N")
	)
	(segment
		(start 162.08756 -175.70069)
		(end 160.589214 -174.202344)
		(width 0.1016)
		(layer "B.Cu")
		(net "UART_RI_RP6_L_N")
	)
	(segment
		(start 160.589214 -174.202344)
		(end 159.375602 -174.202344)
		(width 0.1016)
		(layer "B.Cu")
		(net "UART_RI_RP6_L_N")
	)
	(segment
		(start 163.1188 -184.770268)
		(end 162.39998 -184.051448)
		(width 0.1016)
		(layer "B.Cu")
		(net "UART_RI_RP6_L_N")
	)
	(segment
		(start 162.39998 -184.051448)
		(end 162.39998 -182.767224)
		(width 0.1016)
		(layer "B.Cu")
		(net "UART_RI_RP6_L_N")
	)
	(segment
		(start 16.682466 -158.474156)
		(end 16.264636 -158.891986)
		(width 0.10414)
		(layer "F.Cu")
		(net "LAN1_P2_P")
	)
	(segment
		(start 17.396206 -158.474156)
		(end 16.682466 -158.474156)
		(width 0.10414)
		(layer "F.Cu")
		(net "LAN1_P2_P")
	)
	(segment
		(start 16.264636 -158.891986)
		(end 15.975076 -158.891986)
		(width 0.10414)
		(layer "F.Cu")
		(net "LAN1_P2_P")
	)
	(segment
		(start 15.975076 -158.891986)
		(end 15.54607 -158.46298)
		(width 0.10414)
		(layer "F.Cu")
		(net "LAN1_P2_P")
	)
	(via
		(at 15.54607 -158.46298)
		(size 0.508)
		(drill 0.254)
		(layers "F.Cu" "B.Cu")
		(net "LAN1_P2_P")
	)
	(segment
		(start 16.822166 -177.132234)
		(end 17.500854 -161.075624)
		(width 0.10414)
		(layer "B.Cu")
		(net "LAN1_P2_P")
	)
	(segment
		(start 16.36522 -158.88081)
		(end 15.9639 -158.88081)
		(width 0.10414)
		(layer "B.Cu")
		(net "LAN1_P2_P")
	)
	(segment
		(start 18.982944 -192.183766)
		(end 16.82242 -183.186324)
		(width 0.10414)
		(layer "B.Cu")
		(net "LAN1_P2_P")
	)
	(segment
		(start 19.73199 -199.80275)
		(end 19.719798 -197.739254)
		(width 0.10414)
		(layer "B.Cu")
		(net "LAN1_P2_P")
	)
	(segment
		(start 17.493488 -160.976564)
		(end 17.268444 -159.784034)
		(width 0.10414)
		(layer "B.Cu")
		(net "LAN1_P2_P")
	)
	(segment
		(start 16.82242 -183.186324)
		(end 16.82242 -177.285396)
		(width 0.10414)
		(layer "B.Cu")
		(net "LAN1_P2_P")
	)
	(segment
		(start 19.73199 -202.659742)
		(end 19.73199 -199.80275)
		(width 0.10414)
		(layer "B.Cu")
		(net "LAN1_P2_P")
	)
	(segment
		(start 19.386296 -194.47256)
		(end 18.982944 -192.183766)
		(width 0.10414)
		(layer "B.Cu")
		(net "LAN1_P2_P")
	)
	(segment
		(start 19.719798 -197.739254)
		(end 19.386296 -194.47256)
		(width 0.10414)
		(layer "B.Cu")
		(net "LAN1_P2_P")
	)
	(segment
		(start 17.268444 -159.784034)
		(end 16.36522 -158.88081)
		(width 0.10414)
		(layer "B.Cu")
		(net "LAN1_P2_P")
	)
	(segment
		(start 15.9639 -158.88081)
		(end 15.54607 -158.46298)
		(width 0.10414)
		(layer "B.Cu")
		(net "LAN1_P2_P")
	)
	(segment
		(start 16.82242 -177.285396)
		(end 16.822166 -177.132234)
		(width 0.10414)
		(layer "B.Cu")
		(net "LAN1_P2_P")
	)
	(segment
		(start 20.014946 -202.942698)
		(end 19.73199 -202.659742)
		(width 0.10414)
		(layer "B.Cu")
		(net "LAN1_P2_P")
	)
	(segment
		(start 17.500854 -161.075624)
		(end 17.493488 -160.976564)
		(width 0.10414)
		(layer "B.Cu")
		(net "LAN1_P2_P")
	)
	(segment
		(start 20.014946 -205.199488)
		(end 20.014946 -202.942698)
		(width 0.10414)
		(layer "B.Cu")
		(net "LAN1_P2_P")
	)
	(segment
		(start 10.390632 -150.196296)
		(end 10.390632 -149.781514)
		(width 0.1016)
		(layer "F.Cu")
		(net "N54310606")
	)
	(segment
		(start 10.390632 -149.781514)
		(end 10.390632 -148.392642)
		(width 0.1016)
		(layer "F.Cu")
		(net "N54310606")
	)
	(segment
		(start 10.248138 -151.71039)
		(end 10.248138 -150.33879)
		(width 0.1016)
		(layer "F.Cu")
		(net "N54310606")
	)
	(segment
		(start 10.248138 -150.33879)
		(end 10.390632 -150.196296)
		(width 0.1016)
		(layer "F.Cu")
		(net "N54310606")
	)
	(via
		(at 10.390632 -149.781514)
		(size 0.508)
		(drill 0.254)
		(layers "F.Cu" "B.Cu")
		(net "N54310606")
	)
	(segment
		(start 11.304778 -150.896828)
		(end 11.304778 -151.71039)
		(width 0.1016)
		(layer "F.Cu")
		(net "N54310598")
	)
	(segment
		(start 11.040618 -149.866604)
		(end 11.304778 -150.130764)
		(width 0.1016)
		(layer "F.Cu")
		(net "N54310598")
	)
	(segment
		(start 11.040618 -148.392642)
		(end 11.040618 -149.866604)
		(width 0.1016)
		(layer "F.Cu")
		(net "N54310598")
	)
	(segment
		(start 11.304778 -150.130764)
		(end 11.304778 -150.896828)
		(width 0.1016)
		(layer "F.Cu")
		(net "N54310598")
	)
	(via
		(at 11.304778 -150.896828)
		(size 0.508)
		(drill 0.254)
		(layers "F.Cu" "B.Cu")
		(net "N54310598")
	)
	(segment
		(start 7.65556 -139.020296)
		(end 7.65556 -139.881102)
		(width 0.1016)
		(layer "F.Cu")
		(net "N54310545")
	)
	(segment
		(start 7.790688 -142.550642)
		(end 7.790688 -140.01623)
		(width 0.1016)
		(layer "F.Cu")
		(net "N54310545")
	)
	(segment
		(start 7.65556 -139.881102)
		(end 7.790688 -140.01623)
		(width 0.1016)
		(layer "F.Cu")
		(net "N54310545")
	)
	(via
		(at 7.790688 -140.01623)
		(size 0.508)
		(drill 0.254)
		(layers "F.Cu" "B.Cu")
		(net "N54310545")
	)
	(segment
		(start 176.120044 -168.705784)
		(end 176.120044 -167.992044)
		(width 0.10414)
		(layer "F.Cu")
		(net "LAN2_P2_P")
	)
	(segment
		(start 182.73268 -199.727058)
		(end 182.73268 -202.659742)
		(width 0.10414)
		(layer "F.Cu")
		(net "LAN2_P2_P")
	)
	(segment
		(start 176.120044 -169.479214)
		(end 176.323752 -169.479214)
		(width 0.10414)
		(layer "F.Cu")
		(net "LAN2_P2_P")
	)
	(segment
		(start 176.537874 -169.123614)
		(end 176.120044 -168.705784)
		(width 0.10414)
		(layer "F.Cu")
		(net "LAN2_P2_P")
	)
	(segment
		(start 182.73268 -202.659742)
		(end 183.015636 -202.942698)
		(width 0.10414)
		(layer "F.Cu")
		(net "LAN2_P2_P")
	)
	(segment
		(start 176.323752 -169.479214)
		(end 176.537874 -169.265092)
		(width 0.10414)
		(layer "F.Cu")
		(net "LAN2_P2_P")
	)
	(segment
		(start 182.7784 -194.874134)
		(end 182.7784 -199.681338)
		(width 0.10414)
		(layer "F.Cu")
		(net "LAN2_P2_P")
	)
	(segment
		(start 183.015636 -202.942698)
		(end 183.015636 -205.199488)
		(width 0.10414)
		(layer "F.Cu")
		(net "LAN2_P2_P")
	)
	(segment
		(start 176.537874 -169.265092)
		(end 176.537874 -169.123614)
		(width 0.10414)
		(layer "F.Cu")
		(net "LAN2_P2_P")
	)
	(segment
		(start 182.7784 -199.681338)
		(end 182.73268 -199.727058)
		(width 0.10414)
		(layer "F.Cu")
		(net "LAN2_P2_P")
	)
	(segment
		(start 183.19623 -194.456304)
		(end 182.7784 -194.874134)
		(width 0.10414)
		(layer "F.Cu")
		(net "LAN2_P2_P")
	)
	(via
		(at 183.19623 -194.456304)
		(size 0.508)
		(drill 0.254)
		(layers "F.Cu" "B.Cu")
		(net "LAN2_P2_P")
	)
	(via
		(at 176.120044 -169.479214)
		(size 0.508)
		(drill 0.254)
		(layers "F.Cu" "B.Cu")
		(net "LAN2_P2_P")
	)
	(segment
		(start 183.632602 -189.910974)
		(end 183.434228 -189.75324)
		(width 0.10414)
		(layer "In7.Cu")
		(net "LAN2_P2_P")
	)
	(segment
		(start 183.434228 -189.75324)
		(end 183.399176 -189.442344)
		(width 0.10414)
		(layer "In7.Cu")
		(net "LAN2_P2_P")
	)
	(segment
		(start 182.995316 -185.843672)
		(end 182.960264 -185.532776)
		(width 0.10414)
		(layer "In7.Cu")
		(net "LAN2_P2_P")
	)
	(segment
		(start 183.777382 -191.199262)
		(end 183.74233 -190.888366)
		(width 0.10414)
		(layer "In7.Cu")
		(net "LAN2_P2_P")
	)
	(segment
		(start 183.543956 -190.730632)
		(end 183.508904 -190.419736)
		(width 0.10414)
		(layer "In7.Cu")
		(net "LAN2_P2_P")
	)
	(segment
		(start 183.19623 -194.456304)
		(end 182.7403 -194.912234)
		(width 0.10414)
		(layer "In7.Cu")
		(net "LAN2_P2_P")
	)
	(segment
		(start 183.19369 -186.001406)
		(end 182.995316 -185.843672)
		(width 0.10414)
		(layer "In7.Cu")
		(net "LAN2_P2_P")
	)
	(segment
		(start 183.289448 -188.464952)
		(end 183.448198 -188.267086)
		(width 0.10414)
		(layer "In7.Cu")
		(net "LAN2_P2_P")
	)
	(segment
		(start 182.922164 -195.320666)
		(end 183.469534 -195.320666)
		(width 0.10414)
		(layer "In7.Cu")
		(net "LAN2_P2_P")
	)
	(segment
		(start 183.119014 -185.33491)
		(end 183.083962 -185.024014)
		(width 0.10414)
		(layer "In7.Cu")
		(net "LAN2_P2_P")
	)
	(segment
		(start 183.399176 -189.442344)
		(end 183.557926 -189.244478)
		(width 0.10414)
		(layer "In7.Cu")
		(net "LAN2_P2_P")
	)
	(segment
		(start 176.575974 -169.935144)
		(end 176.120044 -169.479214)
		(width 0.10414)
		(layer "In7.Cu")
		(net "LAN2_P2_P")
	)
	(segment
		(start 182.960264 -185.532776)
		(end 183.119014 -185.33491)
		(width 0.10414)
		(layer "In7.Cu")
		(net "LAN2_P2_P")
	)
	(segment
		(start 183.105044 -186.821064)
		(end 183.069992 -186.510168)
		(width 0.10414)
		(layer "In7.Cu")
		(net "LAN2_P2_P")
	)
	(segment
		(start 183.667654 -190.22187)
		(end 183.632602 -189.910974)
		(width 0.10414)
		(layer "In7.Cu")
		(net "LAN2_P2_P")
	)
	(segment
		(start 184.00522 -193.228976)
		(end 183.961786 -192.84315)
		(width 0.10414)
		(layer "In7.Cu")
		(net "LAN2_P2_P")
	)
	(segment
		(start 183.33847 -187.289694)
		(end 183.303418 -186.978798)
		(width 0.10414)
		(layer "In7.Cu")
		(net "LAN2_P2_P")
	)
	(segment
		(start 183.303418 -186.978798)
		(end 183.105044 -186.821064)
		(width 0.10414)
		(layer "In7.Cu")
		(net "LAN2_P2_P")
	)
	(segment
		(start 183.069992 -186.510168)
		(end 183.228742 -186.312302)
		(width 0.10414)
		(layer "In7.Cu")
		(net "LAN2_P2_P")
	)
	(segment
		(start 183.009286 -184.357264)
		(end 182.09387 -176.169828)
		(width 0.10414)
		(layer "In7.Cu")
		(net "LAN2_P2_P")
	)
	(segment
		(start 182.09387 -176.169828)
		(end 176.575974 -170.651932)
		(width 0.10414)
		(layer "In7.Cu")
		(net "LAN2_P2_P")
	)
	(segment
		(start 184.00522 -194.78498)
		(end 184.00522 -193.228976)
		(width 0.10414)
		(layer "In7.Cu")
		(net "LAN2_P2_P")
	)
	(segment
		(start 183.469534 -195.320666)
		(end 184.00522 -194.78498)
		(width 0.10414)
		(layer "In7.Cu")
		(net "LAN2_P2_P")
	)
	(segment
		(start 183.508904 -190.419736)
		(end 183.667654 -190.22187)
		(width 0.10414)
		(layer "In7.Cu")
		(net "LAN2_P2_P")
	)
	(segment
		(start 183.961786 -192.84315)
		(end 183.763412 -192.685416)
		(width 0.10414)
		(layer "In7.Cu")
		(net "LAN2_P2_P")
	)
	(segment
		(start 183.228742 -186.312302)
		(end 183.19369 -186.001406)
		(width 0.10414)
		(layer "In7.Cu")
		(net "LAN2_P2_P")
	)
	(segment
		(start 183.413146 -187.95619)
		(end 183.214772 -187.798456)
		(width 0.10414)
		(layer "In7.Cu")
		(net "LAN2_P2_P")
	)
	(segment
		(start 183.653684 -191.708024)
		(end 183.618632 -191.397128)
		(width 0.10414)
		(layer "In7.Cu")
		(net "LAN2_P2_P")
	)
	(segment
		(start 183.522874 -188.933582)
		(end 183.3245 -188.775848)
		(width 0.10414)
		(layer "In7.Cu")
		(net "LAN2_P2_P")
	)
	(segment
		(start 183.557926 -189.244478)
		(end 183.522874 -188.933582)
		(width 0.10414)
		(layer "In7.Cu")
		(net "LAN2_P2_P")
	)
	(segment
		(start 183.72836 -192.37452)
		(end 183.88711 -192.176654)
		(width 0.10414)
		(layer "In7.Cu")
		(net "LAN2_P2_P")
	)
	(segment
		(start 183.852058 -191.865758)
		(end 183.653684 -191.708024)
		(width 0.10414)
		(layer "In7.Cu")
		(net "LAN2_P2_P")
	)
	(segment
		(start 183.3245 -188.775848)
		(end 183.289448 -188.464952)
		(width 0.10414)
		(layer "In7.Cu")
		(net "LAN2_P2_P")
	)
	(segment
		(start 183.448198 -188.267086)
		(end 183.413146 -187.95619)
		(width 0.10414)
		(layer "In7.Cu")
		(net "LAN2_P2_P")
	)
	(segment
		(start 183.88711 -192.176654)
		(end 183.852058 -191.865758)
		(width 0.10414)
		(layer "In7.Cu")
		(net "LAN2_P2_P")
	)
	(segment
		(start 183.74233 -190.888366)
		(end 183.543956 -190.730632)
		(width 0.10414)
		(layer "In7.Cu")
		(net "LAN2_P2_P")
	)
	(segment
		(start 182.7403 -195.138802)
		(end 182.922164 -195.320666)
		(width 0.10414)
		(layer "In7.Cu")
		(net "LAN2_P2_P")
	)
	(segment
		(start 176.575974 -170.651932)
		(end 176.575974 -169.935144)
		(width 0.10414)
		(layer "In7.Cu")
		(net "LAN2_P2_P")
	)
	(segment
		(start 182.7403 -194.912234)
		(end 182.7403 -195.138802)
		(width 0.10414)
		(layer "In7.Cu")
		(net "LAN2_P2_P")
	)
	(segment
		(start 183.17972 -187.48756)
		(end 183.33847 -187.289694)
		(width 0.10414)
		(layer "In7.Cu")
		(net "LAN2_P2_P")
	)
	(segment
		(start 183.618632 -191.397128)
		(end 183.777382 -191.199262)
		(width 0.10414)
		(layer "In7.Cu")
		(net "LAN2_P2_P")
	)
	(segment
		(start 183.763412 -192.685416)
		(end 183.72836 -192.37452)
		(width 0.10414)
		(layer "In7.Cu")
		(net "LAN2_P2_P")
	)
	(segment
		(start 183.214772 -187.798456)
		(end 183.17972 -187.48756)
		(width 0.10414)
		(layer "In7.Cu")
		(net "LAN2_P2_P")
	)
	(segment
		(start 183.083962 -185.024014)
		(end 183.009286 -184.357264)
		(width 0.10414)
		(layer "In7.Cu")
		(net "LAN2_P2_P")
	)
	(segment
		(start 165.52926 -197.637146)
		(end 165.52926 -197.298056)
		(width 0.1016)
		(layer "F.Cu")
		(net "UART_RX_RP6_L")
	)
	(segment
		(start 165.2016 -196.970396)
		(end 165.2016 -195.712588)
		(width 0.1016)
		(layer "F.Cu")
		(net "UART_RX_RP6_L")
	)
	(segment
		(start 165.52926 -197.298056)
		(end 165.2016 -196.970396)
		(width 0.1016)
		(layer "F.Cu")
		(net "UART_RX_RP6_L")
	)
	(via
		(at 165.2016 -195.712588)
		(size 0.508)
		(drill 0.254)
		(layers "F.Cu" "B.Cu")
		(net "UART_RX_RP6_L")
	)
	(via
		(at 165.52926 -197.637146)
		(size 0.508)
		(drill 0.254)
		(layers "F.Cu" "B.Cu")
		(net "UART_RX_RP6_L")
	)
	(segment
		(start 164.861748 -198.304658)
		(end 164.861748 -200.732644)
		(width 0.1016)
		(layer "B.Cu")
		(net "UART_RX_RP6_L")
	)
	(segment
		(start 165.227 -191.332358)
		(end 165.74516 -191.850518)
		(width 0.1016)
		(layer "B.Cu")
		(net "UART_RX_RP6_L")
	)
	(segment
		(start 165.74516 -195.169028)
		(end 165.2016 -195.712588)
		(width 0.1016)
		(layer "B.Cu")
		(net "UART_RX_RP6_L")
	)
	(segment
		(start 160.420558 -173.552358)
		(end 162.39236 -175.52416)
		(width 0.1016)
		(layer "B.Cu")
		(net "UART_RX_RP6_L")
	)
	(segment
		(start 166.01567 -201.886566)
		(end 166.01567 -205.199488)
		(width 0.1016)
		(layer "B.Cu")
		(net "UART_RX_RP6_L")
	)
	(segment
		(start 162.39236 -175.52416)
		(end 162.39236 -182.328312)
		(width 0.1016)
		(layer "B.Cu")
		(net "UART_RX_RP6_L")
	)
	(segment
		(start 162.70478 -182.640732)
		(end 162.70478 -183.924956)
		(width 0.1016)
		(layer "B.Cu")
		(net "UART_RX_RP6_L")
	)
	(segment
		(start 164.5666 -186.354466)
		(end 164.5666 -186.4614)
		(width 0.1016)
		(layer "B.Cu")
		(net "UART_RX_RP6_L")
	)
	(segment
		(start 163.4236 -184.643776)
		(end 163.4236 -185.211466)
		(width 0.1016)
		(layer "B.Cu")
		(net "UART_RX_RP6_L")
	)
	(segment
		(start 164.5666 -186.4614)
		(end 165.227 -187.1218)
		(width 0.1016)
		(layer "B.Cu")
		(net "UART_RX_RP6_L")
	)
	(segment
		(start 159.375602 -173.552358)
		(end 160.420558 -173.552358)
		(width 0.1016)
		(layer "B.Cu")
		(net "UART_RX_RP6_L")
	)
	(segment
		(start 164.861748 -200.732644)
		(end 166.01567 -201.886566)
		(width 0.1016)
		(layer "B.Cu")
		(net "UART_RX_RP6_L")
	)
	(segment
		(start 163.4236 -185.211466)
		(end 164.5666 -186.354466)
		(width 0.1016)
		(layer "B.Cu")
		(net "UART_RX_RP6_L")
	)
	(segment
		(start 162.39236 -182.328312)
		(end 162.70478 -182.640732)
		(width 0.1016)
		(layer "B.Cu")
		(net "UART_RX_RP6_L")
	)
	(segment
		(start 162.70478 -183.924956)
		(end 163.4236 -184.643776)
		(width 0.1016)
		(layer "B.Cu")
		(net "UART_RX_RP6_L")
	)
	(segment
		(start 165.74516 -191.850518)
		(end 165.74516 -195.169028)
		(width 0.1016)
		(layer "B.Cu")
		(net "UART_RX_RP6_L")
	)
	(segment
		(start 165.52926 -197.637146)
		(end 164.861748 -198.304658)
		(width 0.1016)
		(layer "B.Cu")
		(net "UART_RX_RP6_L")
	)
	(segment
		(start 165.227 -187.1218)
		(end 165.227 -191.332358)
		(width 0.1016)
		(layer "B.Cu")
		(net "UART_RX_RP6_L")
	)
	(segment
		(start 12.104878 -151.71039)
		(end 12.079478 -151.68499)
		(width 0.1016)
		(layer "F.Cu")
		(net "N54310596")
	)
	(segment
		(start 12.079478 -151.68499)
		(end 12.079478 -149.598634)
		(width 0.1016)
		(layer "F.Cu")
		(net "N54310596")
	)
	(segment
		(start 11.690604 -149.20976)
		(end 12.079478 -149.598634)
		(width 0.1016)
		(layer "F.Cu")
		(net "N54310596")
	)
	(segment
		(start 11.690604 -148.392642)
		(end 11.690604 -149.20976)
		(width 0.1016)
		(layer "F.Cu")
		(net "N54310596")
	)
	(via
		(at 12.079478 -149.598634)
		(size 0.508)
		(drill 0.254)
		(layers "F.Cu" "B.Cu")
		(net "N54310596")
	)
	(segment
		(start 8.440674 -141.311884)
		(end 8.440674 -142.550642)
		(width 0.1016)
		(layer "F.Cu")
		(net "N54310543")
	)
	(segment
		(start 8.67156 -139.020296)
		(end 8.67156 -139.942824)
		(width 0.1016)
		(layer "F.Cu")
		(net "N54310543")
	)
	(segment
		(start 8.67156 -139.942824)
		(end 8.440674 -140.17371)
		(width 0.1016)
		(layer "F.Cu")
		(net "N54310543")
	)
	(segment
		(start 8.440674 -140.17371)
		(end 8.440674 -141.311884)
		(width 0.1016)
		(layer "F.Cu")
		(net "N54310543")
	)
	(via
		(at 8.440674 -141.311884)
		(size 0.508)
		(drill 0.254)
		(layers "F.Cu" "B.Cu")
		(net "N54310543")
	)
	(segment
		(start 21.7551 -193.973196)
		(end 21.625814 -194.23761)
		(width 0.10414)
		(layer "F.Cu")
		(net "LAN1_P3_P")
	)
	(segment
		(start 21.625814 -194.23761)
		(end 21.8313 -194.835018)
		(width 0.10414)
		(layer "F.Cu")
		(net "LAN1_P3_P")
	)
	(segment
		(start 17.396206 -161.014156)
		(end 18.1102 -161.014156)
		(width 0.10414)
		(layer "F.Cu")
		(net "LAN1_P3_P")
	)
	(segment
		(start 20.5867 -165.419024)
		(end 20.5867 -168.300908)
		(width 0.10414)
		(layer "F.Cu")
		(net "LAN1_P3_P")
	)
	(segment
		(start 21.8313 -194.835018)
		(end 21.8313 -194.988942)
		(width 0.10414)
		(layer "F.Cu")
		(net "LAN1_P3_P")
	)
	(segment
		(start 18.33118 -176.334674)
		(end 18.33118 -176.859946)
		(width 0.10414)
		(layer "F.Cu")
		(net "LAN1_P3_P")
	)
	(segment
		(start 19.298158 -161.713164)
		(end 19.879818 -162.57524)
		(width 0.10414)
		(layer "F.Cu")
		(net "LAN1_P3_P")
	)
	(segment
		(start 23.01494 -202.942698)
		(end 23.01494 -205.199488)
		(width 0.10414)
		(layer "F.Cu")
		(net "LAN1_P3_P")
	)
	(segment
		(start 18.33118 -184.648856)
		(end 20.843748 -191.96177)
		(width 0.10414)
		(layer "F.Cu")
		(net "LAN1_P3_P")
	)
	(segment
		(start 18.34261 -176.26584)
		(end 18.33118 -176.334674)
		(width 0.10414)
		(layer "F.Cu")
		(net "LAN1_P3_P")
	)
	(segment
		(start 21.8313 -194.988942)
		(end 22.72665 -199.280272)
		(width 0.10414)
		(layer "F.Cu")
		(net "LAN1_P3_P")
	)
	(segment
		(start 22.631908 -192.056512)
		(end 22.978364 -193.063876)
		(width 0.10414)
		(layer "F.Cu")
		(net "LAN1_P3_P")
	)
	(segment
		(start 22.731984 -199.546464)
		(end 22.731984 -202.659742)
		(width 0.10414)
		(layer "F.Cu")
		(net "LAN1_P3_P")
	)
	(segment
		(start 19.108166 -161.431986)
		(end 19.298158 -161.713164)
		(width 0.10414)
		(layer "F.Cu")
		(net "LAN1_P3_P")
	)
	(segment
		(start 20.843748 -191.96177)
		(end 21.108162 -192.091056)
		(width 0.10414)
		(layer "F.Cu")
		(net "LAN1_P3_P")
	)
	(segment
		(start 19.879818 -162.57524)
		(end 20.5867 -165.419024)
		(width 0.10414)
		(layer "F.Cu")
		(net "LAN1_P3_P")
	)
	(segment
		(start 22.72665 -199.280272)
		(end 22.731984 -199.546464)
		(width 0.10414)
		(layer "F.Cu")
		(net "LAN1_P3_P")
	)
	(segment
		(start 18.33118 -176.859946)
		(end 18.33118 -184.648856)
		(width 0.10414)
		(layer "F.Cu")
		(net "LAN1_P3_P")
	)
	(segment
		(start 22.69109 -193.651378)
		(end 21.7551 -193.973196)
		(width 0.10414)
		(layer "F.Cu")
		(net "LAN1_P3_P")
	)
	(segment
		(start 18.52803 -161.431986)
		(end 19.108166 -161.431986)
		(width 0.10414)
		(layer "F.Cu")
		(net "LAN1_P3_P")
	)
	(segment
		(start 22.731984 -202.659742)
		(end 23.01494 -202.942698)
		(width 0.10414)
		(layer "F.Cu")
		(net "LAN1_P3_P")
	)
	(segment
		(start 18.1102 -161.014156)
		(end 18.52803 -161.431986)
		(width 0.10414)
		(layer "F.Cu")
		(net "LAN1_P3_P")
	)
	(segment
		(start 20.5867 -168.300908)
		(end 20.176998 -170.830494)
		(width 0.10414)
		(layer "F.Cu")
		(net "LAN1_P3_P")
	)
	(segment
		(start 21.108162 -192.091056)
		(end 22.044152 -191.769238)
		(width 0.10414)
		(layer "F.Cu")
		(net "LAN1_P3_P")
	)
	(segment
		(start 22.978364 -193.063876)
		(end 22.69109 -193.651378)
		(width 0.10414)
		(layer "F.Cu")
		(net "LAN1_P3_P")
	)
	(segment
		(start 20.176998 -170.830494)
		(end 18.34261 -176.26584)
		(width 0.10414)
		(layer "F.Cu")
		(net "LAN1_P3_P")
	)
	(segment
		(start 22.044152 -191.769238)
		(end 22.631908 -192.056512)
		(width 0.10414)
		(layer "F.Cu")
		(net "LAN1_P3_P")
	)
	(via
		(at 18.33118 -176.859946)
		(size 0.4064)
		(drill 0.2032)
		(layers "F.Cu" "B.Cu")
		(net "LAN1_P3_P")
	)
	(segment
		(start 9.3218 -137.254996)
		(end 9.80694 -136.769856)
		(width 0.1016)
		(layer "F.Cu")
		(net "N54310592")
	)
	(segment
		(start 9.80694 -136.769856)
		(end 10.04316 -136.769856)
		(width 0.1016)
		(layer "F.Cu")
		(net "N54310592")
	)
	(segment
		(start 11.711178 -136.769856)
		(end 10.04316 -136.769856)
		(width 0.1016)
		(layer "F.Cu")
		(net "N54310592")
	)
	(segment
		(start 12.73556 -138.220196)
		(end 12.73556 -137.794238)
		(width 0.1016)
		(layer "F.Cu")
		(net "N54310592")
	)
	(segment
		(start 9.09066 -142.550642)
		(end 9.09066 -140.4874)
		(width 0.1016)
		(layer "F.Cu")
		(net "N54310592")
	)
	(segment
		(start 9.09066 -140.4874)
		(end 9.3218 -140.25626)
		(width 0.1016)
		(layer "F.Cu")
		(net "N54310592")
	)
	(segment
		(start 9.3218 -140.25626)
		(end 9.3218 -137.254996)
		(width 0.1016)
		(layer "F.Cu")
		(net "N54310592")
	)
	(segment
		(start 12.73556 -137.794238)
		(end 11.711178 -136.769856)
		(width 0.1016)
		(layer "F.Cu")
		(net "N54310592")
	)
	(via
		(at 10.04316 -136.769856)
		(size 0.508)
		(drill 0.254)
		(layers "F.Cu" "B.Cu")
		(net "N54310592")
	)
	(segment
		(start 7.140448 -150.296372)
		(end 7.140448 -148.392642)
		(width 0.1016)
		(layer "F.Cu")
		(net "N54310531")
	)
	(segment
		(start 7.13867 -151.331168)
		(end 7.140448 -151.32939)
		(width 0.1016)
		(layer "F.Cu")
		(net "N54310531")
	)
	(segment
		(start 7.140448 -151.32939)
		(end 7.140448 -150.296372)
		(width 0.1016)
		(layer "F.Cu")
		(net "N54310531")
	)
	(via
		(at 7.140448 -150.296372)
		(size 0.508)
		(drill 0.254)
		(layers "F.Cu" "B.Cu")
		(net "N54310531")
	)
	(segment
		(start 12.73556 -139.845288)
		(end 12.73556 -139.020296)
		(width 0.1016)
		(layer "F.Cu")
		(net "N54310590")
	)
	(segment
		(start 12.73556 -139.979908)
		(end 12.73556 -139.845288)
		(width 0.1016)
		(layer "F.Cu")
		(net "N54310590")
	)
	(segment
		(start 11.690604 -141.024864)
		(end 12.73556 -139.979908)
		(width 0.1016)
		(layer "F.Cu")
		(net "N54310590")
	)
	(segment
		(start 11.690604 -142.550642)
		(end 11.690604 -141.024864)
		(width 0.1016)
		(layer "F.Cu")
		(net "N54310590")
	)
	(via
		(at 12.73556 -139.845288)
		(size 0.508)
		(drill 0.254)
		(layers "F.Cu" "B.Cu")
		(net "N54310590")
	)
	(via
		(at 162.802824 -190.663322)
		(size 0.6604)
		(drill 0.3302)
		(layers "F.Cu" "B.Cu")
		(net "UART_DTR_RP6_L_N")
	)
	(segment
		(start 162.98418 -197.369684)
		(end 162.98418 -190.844678)
		(width 0.1016)
		(layer "B.Cu")
		(net "UART_DTR_RP6_L_N")
	)
	(segment
		(start 162.98418 -190.844678)
		(end 162.802824 -190.663322)
		(width 0.1016)
		(layer "B.Cu")
		(net "UART_DTR_RP6_L_N")
	)
	(segment
		(start 161.17062 -178.511454)
		(end 161.17062 -182.789322)
		(width 0.1016)
		(layer "B.Cu")
		(net "UART_DTR_RP6_L_N")
	)
	(segment
		(start 162.973512 -190.256668)
		(end 162.802824 -190.427356)
		(width 0.1016)
		(layer "B.Cu")
		(net "UART_DTR_RP6_L_N")
	)
	(segment
		(start 160.52038 -183.860948)
		(end 160.817814 -184.158382)
		(width 0.1016)
		(layer "B.Cu")
		(net "UART_DTR_RP6_L_N")
	)
	(segment
		(start 162.09518 -185.865262)
		(end 162.7124 -186.482482)
		(width 0.1016)
		(layer "B.Cu")
		(net "UART_DTR_RP6_L_N")
	)
	(segment
		(start 163.29914 -197.684644)
		(end 162.98418 -197.369684)
		(width 0.1016)
		(layer "B.Cu")
		(net "UART_DTR_RP6_L_N")
	)
	(segment
		(start 161.213038 -184.158382)
		(end 162.09518 -185.040524)
		(width 0.1016)
		(layer "B.Cu")
		(net "UART_DTR_RP6_L_N")
	)
	(segment
		(start 162.7124 -186.482482)
		(end 162.7124 -187.140088)
		(width 0.1016)
		(layer "B.Cu")
		(net "UART_DTR_RP6_L_N")
	)
	(segment
		(start 162.7124 -187.140088)
		(end 162.973512 -187.4012)
		(width 0.1016)
		(layer "B.Cu")
		(net "UART_DTR_RP6_L_N")
	)
	(segment
		(start 162.09518 -185.040524)
		(end 162.09518 -185.865262)
		(width 0.1016)
		(layer "B.Cu")
		(net "UART_DTR_RP6_L_N")
	)
	(segment
		(start 164.015674 -205.199488)
		(end 164.015674 -201.886566)
		(width 0.1016)
		(layer "B.Cu")
		(net "UART_DTR_RP6_L_N")
	)
	(segment
		(start 160.52038 -183.439562)
		(end 160.52038 -183.860948)
		(width 0.1016)
		(layer "B.Cu")
		(net "UART_DTR_RP6_L_N")
	)
	(segment
		(start 163.29914 -201.170032)
		(end 163.29914 -197.684644)
		(width 0.1016)
		(layer "B.Cu")
		(net "UART_DTR_RP6_L_N")
	)
	(segment
		(start 161.17062 -182.789322)
		(end 160.52038 -183.439562)
		(width 0.1016)
		(layer "B.Cu")
		(net "UART_DTR_RP6_L_N")
	)
	(segment
		(start 162.802824 -190.427356)
		(end 162.802824 -190.663322)
		(width 0.1016)
		(layer "B.Cu")
		(net "UART_DTR_RP6_L_N")
	)
	(segment
		(start 160.817814 -184.158382)
		(end 161.213038 -184.158382)
		(width 0.1016)
		(layer "B.Cu")
		(net "UART_DTR_RP6_L_N")
	)
	(segment
		(start 164.015674 -201.886566)
		(end 163.29914 -201.170032)
		(width 0.1016)
		(layer "B.Cu")
		(net "UART_DTR_RP6_L_N")
	)
	(segment
		(start 159.375602 -178.102514)
		(end 160.76168 -178.102514)
		(width 0.1016)
		(layer "B.Cu")
		(net "UART_DTR_RP6_L_N")
	)
	(segment
		(start 160.76168 -178.102514)
		(end 161.17062 -178.511454)
		(width 0.1016)
		(layer "B.Cu")
		(net "UART_DTR_RP6_L_N")
	)
	(segment
		(start 162.973512 -187.4012)
		(end 162.973512 -190.256668)
		(width 0.1016)
		(layer "B.Cu")
		(net "UART_DTR_RP6_L_N")
	)
	(segment
		(start 11.71956 -139.915392)
		(end 11.040618 -140.594334)
		(width 0.1016)
		(layer "F.Cu")
		(net "N54310604")
	)
	(segment
		(start 11.71956 -139.020296)
		(end 11.71956 -139.915392)
		(width 0.1016)
		(layer "F.Cu")
		(net "N54310604")
	)
	(segment
		(start 11.040618 -142.550642)
		(end 11.040618 -141.208252)
		(width 0.1016)
		(layer "F.Cu")
		(net "N54310604")
	)
	(segment
		(start 11.040618 -140.594334)
		(end 11.040618 -141.208252)
		(width 0.1016)
		(layer "F.Cu")
		(net "N54310604")
	)
	(via
		(at 11.040618 -141.208252)
		(size 0.508)
		(drill 0.254)
		(layers "F.Cu" "B.Cu")
		(net "N54310604")
	)
	(segment
		(start 43.337226 -170.641264)
		(end 43.337226 -170.41876)
		(width 0.1016)
		(layer "F.Cu")
		(net "N53103066")
	)
	(segment
		(start 43.337226 -170.41876)
		(end 42.62374 -169.705274)
		(width 0.1016)
		(layer "F.Cu")
		(net "N53103066")
	)
	(segment
		(start 42.269918 -170.059096)
		(end 42.62374 -169.705274)
		(width 0.1016)
		(layer "F.Cu")
		(net "N53103066")
	)
	(segment
		(start 41.862248 -170.059096)
		(end 42.269918 -170.059096)
		(width 0.1016)
		(layer "F.Cu")
		(net "N53103066")
	)
	(via
		(at 42.62374 -169.705274)
		(size 0.508)
		(drill 0.254)
		(layers "F.Cu" "B.Cu")
		(net "N53103066")
	)
	(segment
		(start 17.89684 -179.82565)
		(end 17.89684 -176.29886)
		(width 0.10414)
		(layer "F.Cu")
		(net "LAN1_P3_N")
	)
	(segment
		(start 21.85035 -197.209918)
		(end 21.74875 -197.364096)
		(width 0.10414)
		(layer "F.Cu")
		(net "LAN1_P3_N")
	)
	(segment
		(start 19.753834 -170.725592)
		(end 20.15236 -168.265856)
		(width 0.10414)
		(layer "F.Cu")
		(net "LAN1_P3_N")
	)
	(segment
		(start 17.89684 -179.82565)
		(end 17.89684 -184.7215)
		(width 0.10414)
		(layer "F.Cu")
		(net "LAN1_P3_N")
	)
	(segment
		(start 21.443696 -193.620644)
		(end 21.156422 -194.208654)
		(width 0.10414)
		(layer "F.Cu")
		(net "LAN1_P3_N")
	)
	(segment
		(start 19.826732 -164.786818)
		(end 19.936714 -164.605208)
		(width 0.10414)
		(layer "F.Cu")
		(net "LAN1_P3_N")
	)
	(segment
		(start 21.813012 -197.67042)
		(end 21.967444 -197.771258)
		(width 0.10414)
		(layer "F.Cu")
		(net "LAN1_P3_N")
	)
	(segment
		(start 20.15236 -166.014654)
		(end 20.15236 -165.472364)
		(width 0.10414)
		(layer "F.Cu")
		(net "LAN1_P3_N")
	)
	(segment
		(start 21.631656 -196.802756)
		(end 21.786088 -196.903594)
		(width 0.10414)
		(layer "F.Cu")
		(net "LAN1_P3_N")
	)
	(segment
		(start 20.15236 -165.472364)
		(end 20.084542 -165.20033)
		(width 0.10414)
		(layer "F.Cu")
		(net "LAN1_P3_N")
	)
	(segment
		(start 22.279356 -192.367916)
		(end 22.508972 -193.03492)
		(width 0.10414)
		(layer "F.Cu")
		(net "LAN1_P3_N")
	)
	(segment
		(start 22.508972 -193.03492)
		(end 22.379686 -193.298826)
		(width 0.10414)
		(layer "F.Cu")
		(net "LAN1_P3_N")
	)
	(segment
		(start 19.47672 -162.754564)
		(end 18.937986 -161.956242)
		(width 0.10414)
		(layer "F.Cu")
		(net "LAN1_P3_N")
	)
	(segment
		(start 18.87728 -161.866326)
		(end 18.52803 -161.866326)
		(width 0.10414)
		(layer "F.Cu")
		(net "LAN1_P3_N")
	)
	(segment
		(start 21.74875 -197.364096)
		(end 21.813012 -197.67042)
		(width 0.10414)
		(layer "F.Cu")
		(net "LAN1_P3_N")
	)
	(segment
		(start 18.52803 -161.866326)
		(end 18.1102 -162.284156)
		(width 0.10414)
		(layer "F.Cu")
		(net "LAN1_P3_N")
	)
	(segment
		(start 19.936714 -164.605208)
		(end 19.861022 -164.301678)
		(width 0.10414)
		(layer "F.Cu")
		(net "LAN1_P3_N")
	)
	(segment
		(start 21.156422 -194.208654)
		(end 21.39696 -194.907662)
		(width 0.10414)
		(layer "F.Cu")
		(net "LAN1_P3_N")
	)
	(segment
		(start 21.930106 -198.23176)
		(end 21.994368 -198.538084)
		(width 0.10414)
		(layer "F.Cu")
		(net "LAN1_P3_N")
	)
	(segment
		(start 18.937986 -161.956242)
		(end 18.87728 -161.866326)
		(width 0.10414)
		(layer "F.Cu")
		(net "LAN1_P3_N")
	)
	(segment
		(start 21.39696 -195.0339)
		(end 21.668994 -196.342254)
		(width 0.10414)
		(layer "F.Cu")
		(net "LAN1_P3_N")
	)
	(segment
		(start 22.293072 -199.329548)
		(end 22.297644 -199.551036)
		(width 0.10414)
		(layer "F.Cu")
		(net "LAN1_P3_N")
	)
	(segment
		(start 22.014942 -202.942444)
		(end 22.014942 -205.199488)
		(width 0.10414)
		(layer "F.Cu")
		(net "LAN1_P3_N")
	)
	(segment
		(start 21.39696 -194.907662)
		(end 21.39696 -195.0339)
		(width 0.10414)
		(layer "F.Cu")
		(net "LAN1_P3_N")
	)
	(segment
		(start 19.678904 -164.19195)
		(end 19.603212 -163.888166)
		(width 0.10414)
		(layer "F.Cu")
		(net "LAN1_P3_N")
	)
	(segment
		(start 21.967444 -197.771258)
		(end 22.031706 -198.077582)
		(width 0.10414)
		(layer "F.Cu")
		(net "LAN1_P3_N")
	)
	(segment
		(start 19.98218 -166.497254)
		(end 19.98218 -166.184834)
		(width 0.10414)
		(layer "F.Cu")
		(net "LAN1_P3_N")
	)
	(segment
		(start 22.1488 -198.638922)
		(end 22.293072 -199.329548)
		(width 0.10414)
		(layer "F.Cu")
		(net "LAN1_P3_N")
	)
	(segment
		(start 21.567394 -196.496432)
		(end 21.631656 -196.802756)
		(width 0.10414)
		(layer "F.Cu")
		(net "LAN1_P3_N")
	)
	(segment
		(start 19.861022 -164.301678)
		(end 19.678904 -164.19195)
		(width 0.10414)
		(layer "F.Cu")
		(net "LAN1_P3_N")
	)
	(segment
		(start 17.89684 -184.7215)
		(end 20.491196 -192.273174)
		(width 0.10414)
		(layer "F.Cu")
		(net "LAN1_P3_N")
	)
	(segment
		(start 19.713194 -163.706556)
		(end 19.47672 -162.754564)
		(width 0.10414)
		(layer "F.Cu")
		(net "LAN1_P3_N")
	)
	(segment
		(start 20.15236 -166.667434)
		(end 19.98218 -166.497254)
		(width 0.10414)
		(layer "F.Cu")
		(net "LAN1_P3_N")
	)
	(segment
		(start 22.379686 -193.298826)
		(end 21.443696 -193.620644)
		(width 0.10414)
		(layer "F.Cu")
		(net "LAN1_P3_N")
	)
	(segment
		(start 21.786088 -196.903594)
		(end 21.85035 -197.209918)
		(width 0.10414)
		(layer "F.Cu")
		(net "LAN1_P3_N")
	)
	(segment
		(start 22.031706 -198.077582)
		(end 21.930106 -198.23176)
		(width 0.10414)
		(layer "F.Cu")
		(net "LAN1_P3_N")
	)
	(segment
		(start 20.491196 -192.273174)
		(end 21.079206 -192.560448)
		(width 0.10414)
		(layer "F.Cu")
		(net "LAN1_P3_N")
	)
	(segment
		(start 22.297644 -202.659742)
		(end 22.014942 -202.942444)
		(width 0.10414)
		(layer "F.Cu")
		(net "LAN1_P3_N")
	)
	(segment
		(start 17.89684 -176.29886)
		(end 17.9197 -176.16043)
		(width 0.10414)
		(layer "F.Cu")
		(net "LAN1_P3_N")
	)
	(segment
		(start 19.603212 -163.888166)
		(end 19.713194 -163.706556)
		(width 0.10414)
		(layer "F.Cu")
		(net "LAN1_P3_N")
	)
	(segment
		(start 20.084542 -165.20033)
		(end 19.902424 -165.090602)
		(width 0.10414)
		(layer "F.Cu")
		(net "LAN1_P3_N")
	)
	(segment
		(start 22.297644 -199.551036)
		(end 22.297644 -202.659742)
		(width 0.10414)
		(layer "F.Cu")
		(net "LAN1_P3_N")
	)
	(segment
		(start 17.9197 -176.16043)
		(end 19.753834 -170.725592)
		(width 0.10414)
		(layer "F.Cu")
		(net "LAN1_P3_N")
	)
	(segment
		(start 21.668994 -196.342254)
		(end 21.567394 -196.496432)
		(width 0.10414)
		(layer "F.Cu")
		(net "LAN1_P3_N")
	)
	(segment
		(start 19.902424 -165.090602)
		(end 19.826732 -164.786818)
		(width 0.10414)
		(layer "F.Cu")
		(net "LAN1_P3_N")
	)
	(segment
		(start 20.15236 -168.265856)
		(end 20.15236 -166.667434)
		(width 0.10414)
		(layer "F.Cu")
		(net "LAN1_P3_N")
	)
	(segment
		(start 22.015196 -192.23863)
		(end 22.279356 -192.367916)
		(width 0.10414)
		(layer "F.Cu")
		(net "LAN1_P3_N")
	)
	(segment
		(start 21.079206 -192.560448)
		(end 22.015196 -192.23863)
		(width 0.10414)
		(layer "F.Cu")
		(net "LAN1_P3_N")
	)
	(segment
		(start 19.98218 -166.184834)
		(end 20.15236 -166.014654)
		(width 0.10414)
		(layer "F.Cu")
		(net "LAN1_P3_N")
	)
	(segment
		(start 21.994368 -198.538084)
		(end 22.1488 -198.638922)
		(width 0.10414)
		(layer "F.Cu")
		(net "LAN1_P3_N")
	)
	(segment
		(start 18.1102 -162.284156)
		(end 17.396206 -162.284156)
		(width 0.10414)
		(layer "F.Cu")
		(net "LAN1_P3_N")
	)
	(via
		(at 17.89684 -179.82565)
		(size 0.4064)
		(drill 0.2032)
		(layers "F.Cu" "B.Cu")
		(net "LAN1_P3_N")
	)
	(segment
		(start 177.390044 -168.705784)
		(end 177.390044 -167.992044)
		(width 0.10414)
		(layer "F.Cu")
		(net "LAN2_P2_N")
	)
	(segment
		(start 182.29834 -199.546972)
		(end 182.29834 -202.659742)
		(width 0.10414)
		(layer "F.Cu")
		(net "LAN2_P2_N")
	)
	(segment
		(start 182.29834 -202.659742)
		(end 182.015638 -202.942444)
		(width 0.10414)
		(layer "F.Cu")
		(net "LAN2_P2_N")
	)
	(segment
		(start 177.13706 -169.479214)
		(end 176.972214 -169.314368)
		(width 0.10414)
		(layer "F.Cu")
		(net "LAN2_P2_N")
	)
	(segment
		(start 182.34406 -199.501252)
		(end 182.29834 -199.546972)
		(width 0.10414)
		(layer "F.Cu")
		(net "LAN2_P2_N")
	)
	(segment
		(start 176.972214 -169.123614)
		(end 177.390044 -168.705784)
		(width 0.10414)
		(layer "F.Cu")
		(net "LAN2_P2_N")
	)
	(segment
		(start 177.390044 -169.479214)
		(end 177.13706 -169.479214)
		(width 0.10414)
		(layer "F.Cu")
		(net "LAN2_P2_N")
	)
	(segment
		(start 181.92623 -194.456304)
		(end 182.34406 -194.874134)
		(width 0.10414)
		(layer "F.Cu")
		(net "LAN2_P2_N")
	)
	(segment
		(start 176.972214 -169.314368)
		(end 176.972214 -169.123614)
		(width 0.10414)
		(layer "F.Cu")
		(net "LAN2_P2_N")
	)
	(segment
		(start 182.015638 -202.942444)
		(end 182.015638 -205.199488)
		(width 0.10414)
		(layer "F.Cu")
		(net "LAN2_P2_N")
	)
	(segment
		(start 182.34406 -194.874134)
		(end 182.34406 -199.501252)
		(width 0.10414)
		(layer "F.Cu")
		(net "LAN2_P2_N")
	)
	(via
		(at 181.92623 -194.456304)
		(size 0.508)
		(drill 0.254)
		(layers "F.Cu" "B.Cu")
		(net "LAN2_P2_N")
	)
	(via
		(at 177.390044 -169.479214)
		(size 0.508)
		(drill 0.254)
		(layers "F.Cu" "B.Cu")
		(net "LAN2_P2_N")
	)
	(segment
		(start 182.436008 -176.005236)
		(end 176.934114 -170.503342)
		(width 0.10414)
		(layer "In7.Cu")
		(net "LAN2_P2_N")
	)
	(segment
		(start 176.934114 -170.503342)
		(end 176.934114 -169.935144)
		(width 0.10414)
		(layer "In7.Cu")
		(net "LAN2_P2_N")
	)
	(segment
		(start 176.934114 -169.935144)
		(end 177.390044 -169.479214)
		(width 0.10414)
		(layer "In7.Cu")
		(net "LAN2_P2_N")
	)
	(segment
		(start 183.618124 -195.678806)
		(end 184.36336 -194.93357)
		(width 0.10414)
		(layer "In7.Cu")
		(net "LAN2_P2_N")
	)
	(segment
		(start 184.36336 -193.20891)
		(end 182.436008 -176.005236)
		(width 0.10414)
		(layer "In7.Cu")
		(net "LAN2_P2_N")
	)
	(segment
		(start 182.773574 -195.678806)
		(end 183.618124 -195.678806)
		(width 0.10414)
		(layer "In7.Cu")
		(net "LAN2_P2_N")
	)
	(segment
		(start 182.38216 -194.912234)
		(end 182.38216 -195.287392)
		(width 0.10414)
		(layer "In7.Cu")
		(net "LAN2_P2_N")
	)
	(segment
		(start 182.38216 -195.287392)
		(end 182.773574 -195.678806)
		(width 0.10414)
		(layer "In7.Cu")
		(net "LAN2_P2_N")
	)
	(segment
		(start 184.36336 -194.93357)
		(end 184.36336 -193.20891)
		(width 0.10414)
		(layer "In7.Cu")
		(net "LAN2_P2_N")
	)
	(segment
		(start 181.92623 -194.456304)
		(end 182.38216 -194.912234)
		(width 0.10414)
		(layer "In7.Cu")
		(net "LAN2_P2_N")
	)
	(segment
		(start 18.72869 -153.811986)
		(end 18.52803 -153.811986)
		(width 0.10414)
		(layer "F.Cu")
		(net "LAN1_P1_P")
	)
	(segment
		(start 18.1102 -153.394156)
		(end 17.396206 -153.394156)
		(width 0.10414)
		(layer "F.Cu")
		(net "LAN1_P1_P")
	)
	(segment
		(start 19.14652 -153.394156)
		(end 18.72869 -153.811986)
		(width 0.10414)
		(layer "F.Cu")
		(net "LAN1_P1_P")
	)
	(segment
		(start 18.52803 -153.811986)
		(end 18.1102 -153.394156)
		(width 0.10414)
		(layer "F.Cu")
		(net "LAN1_P1_P")
	)
	(via
		(at 19.14652 -153.394156)
		(size 0.508)
		(drill 0.254)
		(layers "F.Cu" "B.Cu")
		(net "LAN1_P1_P")
	)
	(segment
		(start 18.752566 -174.473108)
		(end 18.12798 -177.693066)
		(width 0.10414)
		(layer "B.Cu")
		(net "LAN1_P1_P")
	)
	(segment
		(start 19.14652 -153.394156)
		(end 19.56435 -153.811986)
		(width 0.10414)
		(layer "B.Cu")
		(net "LAN1_P1_P")
	)
	(segment
		(start 20.10283 -153.811986)
		(end 20.354798 -154.25293)
		(width 0.10414)
		(layer "B.Cu")
		(net "LAN1_P1_P")
	)
	(segment
		(start 18.12798 -177.693066)
		(end 18.12798 -183.337454)
		(width 0.10414)
		(layer "B.Cu")
		(net "LAN1_P1_P")
	)
	(segment
		(start 22.731984 -202.659742)
		(end 23.01494 -202.942698)
		(width 0.10414)
		(layer "B.Cu")
		(net "LAN1_P1_P")
	)
	(segment
		(start 23.01494 -202.942698)
		(end 23.01494 -205.199488)
		(width 0.10414)
		(layer "B.Cu")
		(net "LAN1_P1_P")
	)
	(segment
		(start 20.553426 -155.271724)
		(end 18.752566 -174.473108)
		(width 0.10414)
		(layer "B.Cu")
		(net "LAN1_P1_P")
	)
	(segment
		(start 20.354798 -154.25293)
		(end 20.553426 -155.271724)
		(width 0.10414)
		(layer "B.Cu")
		(net "LAN1_P1_P")
	)
	(segment
		(start 18.12798 -183.337454)
		(end 22.731984 -199.593962)
		(width 0.10414)
		(layer "B.Cu")
		(net "LAN1_P1_P")
	)
	(segment
		(start 22.731984 -199.593962)
		(end 22.731984 -202.659742)
		(width 0.10414)
		(layer "B.Cu")
		(net "LAN1_P1_P")
	)
	(segment
		(start 19.56435 -153.811986)
		(end 20.10283 -153.811986)
		(width 0.10414)
		(layer "B.Cu")
		(net "LAN1_P1_P")
	)
	(segment
		(start 9.740646 -148.392642)
		(end 9.740646 -147.668996)
		(width 0.1016)
		(layer "F.Cu")
		(net "UART_RX_P6_L")
	)
	(segment
		(start 9.740646 -147.668996)
		(end 10.07491 -147.334732)
		(width 0.1016)
		(layer "F.Cu")
		(net "UART_RX_P6_L")
	)
	(segment
		(start 11.92149 -147.334732)
		(end 12.823952 -148.237194)
		(width 0.1016)
		(layer "F.Cu")
		(net "UART_RX_P6_L")
	)
	(segment
		(start 14.082776 -148.237194)
		(end 14.58976 -148.744178)
		(width 0.1016)
		(layer "F.Cu")
		(net "UART_RX_P6_L")
	)
	(segment
		(start 10.07491 -147.334732)
		(end 11.92149 -147.334732)
		(width 0.1016)
		(layer "F.Cu")
		(net "UART_RX_P6_L")
	)
	(segment
		(start 12.823952 -148.237194)
		(end 14.082776 -148.237194)
		(width 0.1016)
		(layer "F.Cu")
		(net "UART_RX_P6_L")
	)
	(via
		(at 41.81602 -198.430388)
		(size 0.508)
		(drill 0.254)
		(layers "F.Cu" "B.Cu")
		(net "UART_RX_P6_L")
	)
	(via
		(at 14.58976 -148.744178)
		(size 0.508)
		(drill 0.254)
		(layers "F.Cu" "B.Cu")
		(net "UART_RX_P6_L")
	)
	(segment
		(start 41.81602 -199.388222)
		(end 41.014904 -200.189338)
		(width 0.1016)
		(layer "B.Cu")
		(net "UART_RX_P6_L")
	)
	(segment
		(start 41.81602 -198.430388)
		(end 41.81602 -199.388222)
		(width 0.1016)
		(layer "B.Cu")
		(net "UART_RX_P6_L")
	)
	(segment
		(start 41.014904 -200.189338)
		(end 41.014904 -205.199488)
		(width 0.1016)
		(layer "B.Cu")
		(net "UART_RX_P6_L")
	)
	(segment
		(start 32.33547 -187.709048)
		(end 33.6296 -189.003178)
		(width 0.1143)
		(layer "In2.Cu")
		(net "UART_RX_P6_L")
	)
	(segment
		(start 32.44342 -182.883556)
		(end 32.49803 -182.938166)
		(width 0.1143)
		(layer "In2.Cu")
		(net "UART_RX_P6_L")
	)
	(segment
		(start 32.49803 -182.938166)
		(end 32.49803 -183.303926)
		(width 0.1143)
		(layer "In2.Cu")
		(net "UART_RX_P6_L")
	)
	(segment
		(start 22.18436 -164.836094)
		(end 32.44342 -175.095154)
		(width 0.1143)
		(layer "In2.Cu")
		(net "UART_RX_P6_L")
	)
	(segment
		(start 15.581884 -148.744178)
		(end 22.18436 -155.346654)
		(width 0.1143)
		(layer "In2.Cu")
		(net "UART_RX_P6_L")
	)
	(segment
		(start 34.638234 -189.003178)
		(end 35.30854 -189.673484)
		(width 0.1143)
		(layer "In2.Cu")
		(net "UART_RX_P6_L")
	)
	(segment
		(start 32.33547 -183.466486)
		(end 32.33547 -187.709048)
		(width 0.1143)
		(layer "In2.Cu")
		(net "UART_RX_P6_L")
	)
	(segment
		(start 41.946322 -197.941438)
		(end 41.81602 -198.07174)
		(width 0.1143)
		(layer "In2.Cu")
		(net "UART_RX_P6_L")
	)
	(segment
		(start 35.30854 -190.777368)
		(end 41.946322 -197.41515)
		(width 0.1143)
		(layer "In2.Cu")
		(net "UART_RX_P6_L")
	)
	(segment
		(start 35.30854 -189.673484)
		(end 35.30854 -190.777368)
		(width 0.1143)
		(layer "In2.Cu")
		(net "UART_RX_P6_L")
	)
	(segment
		(start 14.58976 -148.744178)
		(end 15.581884 -148.744178)
		(width 0.1143)
		(layer "In2.Cu")
		(net "UART_RX_P6_L")
	)
	(segment
		(start 32.44342 -175.095154)
		(end 32.44342 -182.883556)
		(width 0.1143)
		(layer "In2.Cu")
		(net "UART_RX_P6_L")
	)
	(segment
		(start 22.18436 -155.346654)
		(end 22.18436 -164.836094)
		(width 0.1143)
		(layer "In2.Cu")
		(net "UART_RX_P6_L")
	)
	(segment
		(start 33.6296 -189.003178)
		(end 34.638234 -189.003178)
		(width 0.1143)
		(layer "In2.Cu")
		(net "UART_RX_P6_L")
	)
	(segment
		(start 41.81602 -198.07174)
		(end 41.81602 -198.430388)
		(width 0.1143)
		(layer "In2.Cu")
		(net "UART_RX_P6_L")
	)
	(segment
		(start 41.946322 -197.41515)
		(end 41.946322 -197.941438)
		(width 0.1143)
		(layer "In2.Cu")
		(net "UART_RX_P6_L")
	)
	(segment
		(start 32.49803 -183.303926)
		(end 32.33547 -183.466486)
		(width 0.1143)
		(layer "In2.Cu")
		(net "UART_RX_P6_L")
	)
	(via
		(at 170.815 -198.013066)
		(size 0.508)
		(drill 0.254)
		(layers "F.Cu" "B.Cu")
		(net "GND3")
	)
	(segment
		(start 171.01566 -199.629268)
		(end 170.5737 -199.187308)
		(width 0.1016)
		(layer "B.Cu")
		(net "GND3")
	)
	(segment
		(start 171.01566 -205.199488)
		(end 171.01566 -199.629268)
		(width 0.1016)
		(layer "B.Cu")
		(net "GND3")
	)
	(segment
		(start 170.5737 -199.187308)
		(end 170.5737 -198.254366)
		(width 0.1016)
		(layer "B.Cu")
		(net "GND3")
	)
	(segment
		(start 170.5737 -198.254366)
		(end 170.815 -198.013066)
		(width 0.1016)
		(layer "B.Cu")
		(net "GND3")
	)
	(segment
		(start 170.129962 -199.827134)
		(end 170.13174 -199.827134)
		(width 0.1016)
		(layer "F.Cu")
		(net "GND37")
	)
	(segment
		(start 170.015662 -205.199488)
		(end 170.0149 -205.199488)
		(width 0.1016)
		(layer "F.Cu")
		(net "GND37")
	)
	(segment
		(start 170.0149 -205.199488)
		(end 170.0149 -199.942196)
		(width 0.1016)
		(layer "F.Cu")
		(net "GND37")
	)
	(segment
		(start 170.0149 -199.942196)
		(end 170.129962 -199.827134)
		(width 0.1016)
		(layer "F.Cu")
		(net "GND37")
	)
	(via
		(at 170.13174 -199.827134)
		(size 0.508)
		(drill 0.254)
		(layers "F.Cu" "B.Cu")
		(net "GND37")
	)
	(segment
		(start 173.015656 -198.999094)
		(end 172.55998 -199.45477)
		(width 0.1016)
		(layer "F.Cu")
		(net "GND36")
	)
	(segment
		(start 172.55998 -199.45477)
		(end 172.55998 -202.762612)
		(width 0.1016)
		(layer "F.Cu")
		(net "GND36")
	)
	(segment
		(start 172.55998 -202.762612)
		(end 173.015656 -203.218288)
		(width 0.1016)
		(layer "F.Cu")
		(net "GND36")
	)
	(segment
		(start 173.015656 -203.218288)
		(end 173.015656 -205.199488)
		(width 0.1016)
		(layer "F.Cu")
		(net "GND36")
	)
	(via
		(at 173.015656 -198.999094)
		(size 0.508)
		(drill 0.254)
		(layers "F.Cu" "B.Cu")
		(net "GND36")
	)
	(segment
		(start 18.11782 -154.656536)
		(end 18.11782 -154.664156)
		(width 0.10414)
		(layer "F.Cu")
		(net "LAN1_P1_N")
	)
	(segment
		(start 18.72869 -154.246326)
		(end 18.52803 -154.246326)
		(width 0.10414)
		(layer "F.Cu")
		(net "LAN1_P1_N")
	)
	(segment
		(start 18.11782 -154.664156)
		(end 17.396206 -154.664156)
		(width 0.10414)
		(layer "F.Cu")
		(net "LAN1_P1_N")
	)
	(segment
		(start 19.14652 -154.664156)
		(end 18.72869 -154.246326)
		(width 0.10414)
		(layer "F.Cu")
		(net "LAN1_P1_N")
	)
	(segment
		(start 18.52803 -154.246326)
		(end 18.11782 -154.656536)
		(width 0.10414)
		(layer "F.Cu")
		(net "LAN1_P1_N")
	)
	(via
		(at 19.14652 -154.664156)
		(size 0.508)
		(drill 0.254)
		(layers "F.Cu" "B.Cu")
		(net "LAN1_P1_N")
	)
	(segment
		(start 18.870676 -166.525702)
		(end 18.90014 -166.214298)
		(width 0.10414)
		(layer "B.Cu")
		(net "LAN1_P1_N")
	)
	(segment
		(start 19.058636 -164.528246)
		(end 19.0881 -164.216842)
		(width 0.10414)
		(layer "B.Cu")
		(net "LAN1_P1_N")
	)
	(segment
		(start 19.29384 -164.046408)
		(end 20.115022 -155.293568)
		(width 0.10414)
		(layer "B.Cu")
		(net "LAN1_P1_N")
	)
	(segment
		(start 20.115022 -155.293568)
		(end 19.942048 -154.406346)
		(width 0.10414)
		(layer "B.Cu")
		(net "LAN1_P1_N")
	)
	(segment
		(start 22.014942 -202.942444)
		(end 22.297644 -202.659742)
		(width 0.10414)
		(layer "B.Cu")
		(net "LAN1_P1_N")
	)
	(segment
		(start 19.850608 -154.246326)
		(end 19.56435 -154.246326)
		(width 0.10414)
		(layer "B.Cu")
		(net "LAN1_P1_N")
	)
	(segment
		(start 18.80616 -167.213026)
		(end 19.012154 -167.042592)
		(width 0.10414)
		(layer "B.Cu")
		(net "LAN1_P1_N")
	)
	(segment
		(start 19.041618 -166.731188)
		(end 18.870676 -166.525702)
		(width 0.10414)
		(layer "B.Cu")
		(net "LAN1_P1_N")
	)
	(segment
		(start 19.135598 -165.73246)
		(end 18.964656 -165.526974)
		(width 0.10414)
		(layer "B.Cu")
		(net "LAN1_P1_N")
	)
	(segment
		(start 18.947638 -167.729916)
		(end 18.776696 -167.52443)
		(width 0.10414)
		(layer "B.Cu")
		(net "LAN1_P1_N")
	)
	(segment
		(start 18.99412 -165.21557)
		(end 19.200114 -165.045136)
		(width 0.10414)
		(layer "B.Cu")
		(net "LAN1_P1_N")
	)
	(segment
		(start 18.90014 -166.214298)
		(end 19.106134 -166.043864)
		(width 0.10414)
		(layer "B.Cu")
		(net "LAN1_P1_N")
	)
	(segment
		(start 19.012154 -167.042592)
		(end 19.041618 -166.731188)
		(width 0.10414)
		(layer "B.Cu")
		(net "LAN1_P1_N")
	)
	(segment
		(start 18.853658 -168.728644)
		(end 18.682716 -168.523158)
		(width 0.10414)
		(layer "B.Cu")
		(net "LAN1_P1_N")
	)
	(segment
		(start 19.106134 -166.043864)
		(end 19.135598 -165.73246)
		(width 0.10414)
		(layer "B.Cu")
		(net "LAN1_P1_N")
	)
	(segment
		(start 18.776696 -167.52443)
		(end 18.80616 -167.213026)
		(width 0.10414)
		(layer "B.Cu")
		(net "LAN1_P1_N")
	)
	(segment
		(start 18.322036 -174.411386)
		(end 18.759678 -169.727372)
		(width 0.10414)
		(layer "B.Cu")
		(net "LAN1_P1_N")
	)
	(segment
		(start 18.918174 -168.04132)
		(end 18.947638 -167.729916)
		(width 0.10414)
		(layer "B.Cu")
		(net "LAN1_P1_N")
	)
	(segment
		(start 18.71218 -168.211754)
		(end 18.918174 -168.04132)
		(width 0.10414)
		(layer "B.Cu")
		(net "LAN1_P1_N")
	)
	(segment
		(start 18.824194 -169.040048)
		(end 18.853658 -168.728644)
		(width 0.10414)
		(layer "B.Cu")
		(net "LAN1_P1_N")
	)
	(segment
		(start 22.297644 -202.659742)
		(end 22.297644 -199.654414)
		(width 0.10414)
		(layer "B.Cu")
		(net "LAN1_P1_N")
	)
	(segment
		(start 19.0881 -164.216842)
		(end 19.29384 -164.046408)
		(width 0.10414)
		(layer "B.Cu")
		(net "LAN1_P1_N")
	)
	(segment
		(start 22.014942 -205.199488)
		(end 22.014942 -202.942444)
		(width 0.10414)
		(layer "B.Cu")
		(net "LAN1_P1_N")
	)
	(segment
		(start 19.200114 -165.045136)
		(end 19.229578 -164.733732)
		(width 0.10414)
		(layer "B.Cu")
		(net "LAN1_P1_N")
	)
	(segment
		(start 18.964656 -165.526974)
		(end 18.99412 -165.21557)
		(width 0.10414)
		(layer "B.Cu")
		(net "LAN1_P1_N")
	)
	(segment
		(start 18.759678 -169.727372)
		(end 18.824194 -169.040048)
		(width 0.10414)
		(layer "B.Cu")
		(net "LAN1_P1_N")
	)
	(segment
		(start 19.942048 -154.406346)
		(end 19.850608 -154.246326)
		(width 0.10414)
		(layer "B.Cu")
		(net "LAN1_P1_N")
	)
	(segment
		(start 19.229578 -164.733732)
		(end 19.058636 -164.528246)
		(width 0.10414)
		(layer "B.Cu")
		(net "LAN1_P1_N")
	)
	(segment
		(start 17.69364 -183.397906)
		(end 17.69364 -177.651156)
		(width 0.10414)
		(layer "B.Cu")
		(net "LAN1_P1_N")
	)
	(segment
		(start 19.56435 -154.246326)
		(end 19.14652 -154.664156)
		(width 0.10414)
		(layer "B.Cu")
		(net "LAN1_P1_N")
	)
	(segment
		(start 17.69364 -177.651156)
		(end 18.322036 -174.411386)
		(width 0.10414)
		(layer "B.Cu")
		(net "LAN1_P1_N")
	)
	(segment
		(start 18.682716 -168.523158)
		(end 18.71218 -168.211754)
		(width 0.10414)
		(layer "B.Cu")
		(net "LAN1_P1_N")
	)
	(segment
		(start 22.297644 -199.654414)
		(end 17.69364 -183.397906)
		(width 0.10414)
		(layer "B.Cu")
		(net "LAN1_P1_N")
	)
	(via
		(at 173.09592 -197.456552)
		(size 0.508)
		(drill 0.254)
		(layers "F.Cu" "B.Cu")
		(net "GND2")
	)
	(segment
		(start 174.015654 -202.96378)
		(end 174.015654 -205.199488)
		(width 0.1016)
		(layer "B.Cu")
		(net "GND2")
	)
	(segment
		(start 173.56582 -199.454262)
		(end 173.09338 -199.926702)
		(width 0.1016)
		(layer "B.Cu")
		(net "GND2")
	)
	(segment
		(start 173.09592 -197.456552)
		(end 173.09592 -197.813422)
		(width 0.1016)
		(layer "B.Cu")
		(net "GND2")
	)
	(segment
		(start 173.09338 -199.926702)
		(end 173.09338 -202.041506)
		(width 0.1016)
		(layer "B.Cu")
		(net "GND2")
	)
	(segment
		(start 173.09338 -202.041506)
		(end 174.015654 -202.96378)
		(width 0.1016)
		(layer "B.Cu")
		(net "GND2")
	)
	(segment
		(start 173.56582 -198.283322)
		(end 173.56582 -199.454262)
		(width 0.1016)
		(layer "B.Cu")
		(net "GND2")
	)
	(segment
		(start 173.09592 -197.813422)
		(end 173.56582 -198.283322)
		(width 0.1016)
		(layer "B.Cu")
		(net "GND2")
	)
	(segment
		(start 185.55081 -118.711472)
		(end 184.89676 -119.365522)
		(width 0.1016)
		(layer "F.Cu")
		(net "PWRGD_NODE1_P3V3_STB_PG_CPLD")
	)
	(segment
		(start 185.84418 -118.711472)
		(end 185.55081 -118.711472)
		(width 0.1016)
		(layer "F.Cu")
		(net "PWRGD_NODE1_P3V3_STB_PG_CPLD")
	)
	(segment
		(start 181.01056 -119.365522)
		(end 184.89676 -119.365522)
		(width 0.1016)
		(layer "F.Cu")
		(net "PWRGD_NODE1_P3V3_STB_PG_CPLD")
	)
	(via
		(at 184.89676 -119.365522)
		(size 0.508)
		(drill 0.254)
		(layers "F.Cu" "B.Cu")
		(net "PWRGD_NODE1_P3V3_STB_PG_CPLD")
	)
	(segment
		(start 7.80034 -159.949896)
		(end 12.27836 -159.949896)
		(width 0.1016)
		(layer "F.Cu")
		(net "UART_TX_P5_L")
	)
	(segment
		(start 40.014906 -200.040494)
		(end 40.014906 -205.199488)
		(width 0.1016)
		(layer "F.Cu")
		(net "UART_TX_P5_L")
	)
	(segment
		(start 39.41318 -198.286624)
		(end 39.41318 -199.438768)
		(width 0.1016)
		(layer "F.Cu")
		(net "UART_TX_P5_L")
	)
	(segment
		(start 5.208778 -164.062156)
		(end 5.208778 -162.541458)
		(width 0.1016)
		(layer "F.Cu")
		(net "UART_TX_P5_L")
	)
	(segment
		(start 12.76858 -159.459676)
		(end 12.76858 -159.459422)
		(width 0.1016)
		(layer "F.Cu")
		(net "UART_TX_P5_L")
	)
	(segment
		(start 12.27836 -159.949896)
		(end 12.76858 -159.459676)
		(width 0.1016)
		(layer "F.Cu")
		(net "UART_TX_P5_L")
	)
	(segment
		(start 39.41318 -199.438768)
		(end 40.014906 -200.040494)
		(width 0.1016)
		(layer "F.Cu")
		(net "UART_TX_P5_L")
	)
	(segment
		(start 5.208778 -162.541458)
		(end 7.80034 -159.949896)
		(width 0.1016)
		(layer "F.Cu")
		(net "UART_TX_P5_L")
	)
	(via
		(at 39.41318 -198.286624)
		(size 0.508)
		(drill 0.254)
		(layers "F.Cu" "B.Cu")
		(net "UART_TX_P5_L")
	)
	(via
		(at 12.76858 -159.459422)
		(size 0.508)
		(drill 0.254)
		(layers "F.Cu" "B.Cu")
		(net "UART_TX_P5_L")
	)
	(segment
		(start 29.437838 -188.981334)
		(end 29.437838 -186.745626)
		(width 0.1143)
		(layer "In2.Cu")
		(net "UART_TX_P5_L")
	)
	(segment
		(start 30.387036 -182.01513)
		(end 30.387036 -175.569118)
		(width 0.1143)
		(layer "In2.Cu")
		(net "UART_TX_P5_L")
	)
	(segment
		(start 30.24886 -185.934604)
		(end 30.24886 -182.153306)
		(width 0.1143)
		(layer "In2.Cu")
		(net "UART_TX_P5_L")
	)
	(segment
		(start 30.433264 -189.97676)
		(end 29.437838 -188.981334)
		(width 0.1143)
		(layer "In2.Cu")
		(net "UART_TX_P5_L")
	)
	(segment
		(start 13.074142 -159.511492)
		(end 12.82065 -159.511492)
		(width 0.1143)
		(layer "In2.Cu")
		(net "UART_TX_P5_L")
	)
	(segment
		(start 31.744158 -189.97676)
		(end 30.433264 -189.97676)
		(width 0.1143)
		(layer "In2.Cu")
		(net "UART_TX_P5_L")
	)
	(segment
		(start 30.24886 -182.153306)
		(end 30.387036 -182.01513)
		(width 0.1143)
		(layer "In2.Cu")
		(net "UART_TX_P5_L")
	)
	(segment
		(start 29.437838 -186.745626)
		(end 30.24886 -185.934604)
		(width 0.1143)
		(layer "In2.Cu")
		(net "UART_TX_P5_L")
	)
	(segment
		(start 39.41318 -197.645782)
		(end 31.744158 -189.97676)
		(width 0.1143)
		(layer "In2.Cu")
		(net "UART_TX_P5_L")
	)
	(segment
		(start 30.387036 -175.569118)
		(end 16.21917 -161.401252)
		(width 0.1143)
		(layer "In2.Cu")
		(net "UART_TX_P5_L")
	)
	(segment
		(start 39.41318 -198.286624)
		(end 39.41318 -197.645782)
		(width 0.1143)
		(layer "In2.Cu")
		(net "UART_TX_P5_L")
	)
	(segment
		(start 14.963902 -161.401252)
		(end 13.074142 -159.511492)
		(width 0.1143)
		(layer "In2.Cu")
		(net "UART_TX_P5_L")
	)
	(segment
		(start 16.21917 -161.401252)
		(end 14.963902 -161.401252)
		(width 0.1143)
		(layer "In2.Cu")
		(net "UART_TX_P5_L")
	)
	(segment
		(start 12.82065 -159.511492)
		(end 12.76858 -159.459422)
		(width 0.1143)
		(layer "In2.Cu")
		(net "UART_TX_P5_L")
	)
	(segment
		(start 7.150862 -144.688306)
		(end 11.490706 -144.688306)
		(width 0.1016)
		(layer "F.Cu")
		(net "UART_DTR_P6_L_N")
	)
	(segment
		(start 11.490706 -144.688306)
		(end 12.92098 -143.258032)
		(width 0.1016)
		(layer "F.Cu")
		(net "UART_DTR_P6_L_N")
	)
	(segment
		(start 5.19049 -146.648678)
		(end 7.150862 -144.688306)
		(width 0.1016)
		(layer "F.Cu")
		(net "UART_DTR_P6_L_N")
	)
	(segment
		(start 5.19049 -148.392642)
		(end 5.19049 -146.648678)
		(width 0.1016)
		(layer "F.Cu")
		(net "UART_DTR_P6_L_N")
	)
	(via
		(at 40.76192 -197.506082)
		(size 0.508)
		(drill 0.254)
		(layers "F.Cu" "B.Cu")
		(net "UART_DTR_P6_L_N")
	)
	(via
		(at 12.92098 -143.258032)
		(size 0.508)
		(drill 0.254)
		(layers "F.Cu" "B.Cu")
		(net "UART_DTR_P6_L_N")
	)
	(segment
		(start 40.76192 -198.167244)
		(end 39.014908 -199.914256)
		(width 0.1016)
		(layer "B.Cu")
		(net "UART_DTR_P6_L_N")
	)
	(segment
		(start 39.014908 -199.914256)
		(end 39.014908 -205.199488)
		(width 0.1016)
		(layer "B.Cu")
		(net "UART_DTR_P6_L_N")
	)
	(segment
		(start 40.76192 -197.506082)
		(end 40.76192 -198.167244)
		(width 0.1016)
		(layer "B.Cu")
		(net "UART_DTR_P6_L_N")
	)
	(segment
		(start 31.30423 -187.737242)
		(end 31.30423 -182.805832)
		(width 0.1143)
		(layer "In2.Cu")
		(net "UART_DTR_P6_L_N")
	)
	(segment
		(start 40.76192 -197.29958)
		(end 32.007302 -188.544962)
		(width 0.1143)
		(layer "In2.Cu")
		(net "UART_DTR_P6_L_N")
	)
	(segment
		(start 32.007302 -188.544962)
		(end 32.007302 -188.440314)
		(width 0.1143)
		(layer "In2.Cu")
		(net "UART_DTR_P6_L_N")
	)
	(segment
		(start 31.30423 -182.805832)
		(end 31.441136 -182.668926)
		(width 0.1143)
		(layer "In2.Cu")
		(net "UART_DTR_P6_L_N")
	)
	(segment
		(start 16.654018 -160.203896)
		(end 16.654018 -151.877268)
		(width 0.1143)
		(layer "In2.Cu")
		(net "UART_DTR_P6_L_N")
	)
	(segment
		(start 31.441136 -174.991014)
		(end 16.654018 -160.203896)
		(width 0.1143)
		(layer "In2.Cu")
		(net "UART_DTR_P6_L_N")
	)
	(segment
		(start 13.55598 -145.923508)
		(end 12.92098 -145.288508)
		(width 0.1143)
		(layer "In2.Cu")
		(net "UART_DTR_P6_L_N")
	)
	(segment
		(start 32.007302 -188.440314)
		(end 31.30423 -187.737242)
		(width 0.1143)
		(layer "In2.Cu")
		(net "UART_DTR_P6_L_N")
	)
	(segment
		(start 13.55598 -148.77923)
		(end 13.55598 -145.923508)
		(width 0.1143)
		(layer "In2.Cu")
		(net "UART_DTR_P6_L_N")
	)
	(segment
		(start 31.441136 -182.668926)
		(end 31.441136 -174.991014)
		(width 0.1143)
		(layer "In2.Cu")
		(net "UART_DTR_P6_L_N")
	)
	(segment
		(start 40.76192 -197.506082)
		(end 40.76192 -197.29958)
		(width 0.1143)
		(layer "In2.Cu")
		(net "UART_DTR_P6_L_N")
	)
	(segment
		(start 12.92098 -145.288508)
		(end 12.92098 -143.258032)
		(width 0.1143)
		(layer "In2.Cu")
		(net "UART_DTR_P6_L_N")
	)
	(segment
		(start 16.654018 -151.877268)
		(end 13.55598 -148.77923)
		(width 0.1143)
		(layer "In2.Cu")
		(net "UART_DTR_P6_L_N")
	)
	(segment
		(start 180.511958 -117.864128)
		(end 183.79948 -117.864128)
		(width 0.1016)
		(layer "F.Cu")
		(net "PWRGD_NODE1_P5V_STB_PG_CPLD")
	)
	(segment
		(start 180.010562 -118.365524)
		(end 180.511958 -117.864128)
		(width 0.1016)
		(layer "F.Cu")
		(net "PWRGD_NODE1_P5V_STB_PG_CPLD")
	)
	(segment
		(start 184.61482 -117.048788)
		(end 184.61482 -117.04701)
		(width 0.1016)
		(layer "F.Cu")
		(net "PWRGD_NODE1_P5V_STB_PG_CPLD")
	)
	(segment
		(start 184.700164 -116.961666)
		(end 184.61482 -117.04701)
		(width 0.1016)
		(layer "F.Cu")
		(net "PWRGD_NODE1_P5V_STB_PG_CPLD")
	)
	(segment
		(start 183.79948 -117.864128)
		(end 184.61482 -117.048788)
		(width 0.1016)
		(layer "F.Cu")
		(net "PWRGD_NODE1_P5V_STB_PG_CPLD")
	)
	(segment
		(start 185.802778 -116.961666)
		(end 184.700164 -116.961666)
		(width 0.1016)
		(layer "F.Cu")
		(net "PWRGD_NODE1_P5V_STB_PG_CPLD")
	)
	(via
		(at 184.61482 -117.04701)
		(size 0.508)
		(drill 0.254)
		(layers "F.Cu" "B.Cu")
		(net "PWRGD_NODE1_P5V_STB_PG_CPLD")
	)
	(segment
		(start 185.49112 -198.15429)
		(end 185.49112 -198.928736)
		(width 0.10414)
		(layer "F.Cu")
		(net "LAN2_P1_P")
	)
	(segment
		(start 171.040044 -169.77868)
		(end 171.457874 -169.36085)
		(width 0.10414)
		(layer "F.Cu")
		(net "LAN2_P1_P")
	)
	(segment
		(start 171.040044 -168.705784)
		(end 171.040044 -167.992044)
		(width 0.10414)
		(layer "F.Cu")
		(net "LAN2_P1_P")
	)
	(segment
		(start 171.457874 -169.123614)
		(end 171.040044 -168.705784)
		(width 0.10414)
		(layer "F.Cu")
		(net "LAN2_P1_P")
	)
	(segment
		(start 185.49112 -198.928736)
		(end 185.732674 -199.17029)
		(width 0.10414)
		(layer "F.Cu")
		(net "LAN2_P1_P")
	)
	(segment
		(start 185.90895 -197.73646)
		(end 185.49112 -198.15429)
		(width 0.10414)
		(layer "F.Cu")
		(net "LAN2_P1_P")
	)
	(segment
		(start 185.732674 -202.659742)
		(end 186.01563 -202.942698)
		(width 0.10414)
		(layer "F.Cu")
		(net "LAN2_P1_P")
	)
	(segment
		(start 171.457874 -169.36085)
		(end 171.457874 -169.123614)
		(width 0.10414)
		(layer "F.Cu")
		(net "LAN2_P1_P")
	)
	(segment
		(start 186.01563 -202.942698)
		(end 186.01563 -205.199488)
		(width 0.10414)
		(layer "F.Cu")
		(net "LAN2_P1_P")
	)
	(segment
		(start 185.732674 -199.17029)
		(end 185.732674 -202.659742)
		(width 0.10414)
		(layer "F.Cu")
		(net "LAN2_P1_P")
	)
	(via
		(at 171.040044 -169.77868)
		(size 0.508)
		(drill 0.254)
		(layers "F.Cu" "B.Cu")
		(net "LAN2_P1_P")
	)
	(via
		(at 185.90895 -197.73646)
		(size 0.508)
		(drill 0.254)
		(layers "F.Cu" "B.Cu")
		(net "LAN2_P1_P")
	)
	(segment
		(start 171.040044 -169.77868)
		(end 171.495974 -170.23461)
		(width 0.10414)
		(layer "In7.Cu")
		(net "LAN2_P1_P")
	)
	(segment
		(start 171.495974 -170.61942)
		(end 172.148754 -171.272454)
		(width 0.10414)
		(layer "In7.Cu")
		(net "LAN2_P1_P")
	)
	(segment
		(start 185.45302 -198.19239)
		(end 185.90895 -197.73646)
		(width 0.10414)
		(layer "In7.Cu")
		(net "LAN2_P1_P")
	)
	(segment
		(start 177.836322 -173.607476)
		(end 178.275234 -174.02302)
		(width 0.10414)
		(layer "In7.Cu")
		(net "LAN2_P1_P")
	)
	(segment
		(start 182.379874 -197.92188)
		(end 182.48249 -197.993508)
		(width 0.10414)
		(layer "In7.Cu")
		(net "LAN2_P1_P")
	)
	(segment
		(start 174.84979 -172.096176)
		(end 177.836322 -173.607476)
		(width 0.10414)
		(layer "In7.Cu")
		(net "LAN2_P1_P")
	)
	(segment
		(start 182.48249 -197.993508)
		(end 182.48249 -197.997318)
		(width 0.10414)
		(layer "In7.Cu")
		(net "LAN2_P1_P")
	)
	(segment
		(start 181.314852 -196.856858)
		(end 182.379874 -197.92188)
		(width 0.10414)
		(layer "In7.Cu")
		(net "LAN2_P1_P")
	)
	(segment
		(start 180.69814 -195.10756)
		(end 181.314852 -196.856858)
		(width 0.10414)
		(layer "In7.Cu")
		(net "LAN2_P1_P")
	)
	(segment
		(start 185.45302 -198.592694)
		(end 185.45302 -198.19239)
		(width 0.10414)
		(layer "In7.Cu")
		(net "LAN2_P1_P")
	)
	(segment
		(start 178.275234 -174.02302)
		(end 180.69814 -176.445926)
		(width 0.10414)
		(layer "In7.Cu")
		(net "LAN2_P1_P")
	)
	(segment
		(start 172.148754 -171.272454)
		(end 174.47895 -172.096176)
		(width 0.10414)
		(layer "In7.Cu")
		(net "LAN2_P1_P")
	)
	(segment
		(start 174.47895 -172.096176)
		(end 174.84979 -172.096176)
		(width 0.10414)
		(layer "In7.Cu")
		(net "LAN2_P1_P")
	)
	(segment
		(start 184.395364 -198.88327)
		(end 184.52338 -198.916544)
		(width 0.10414)
		(layer "In7.Cu")
		(net "LAN2_P1_P")
	)
	(segment
		(start 171.495974 -170.23461)
		(end 171.495974 -170.61942)
		(width 0.10414)
		(layer "In7.Cu")
		(net "LAN2_P1_P")
	)
	(segment
		(start 185.12917 -198.916544)
		(end 185.45302 -198.592694)
		(width 0.10414)
		(layer "In7.Cu")
		(net "LAN2_P1_P")
	)
	(segment
		(start 182.48249 -197.997318)
		(end 184.386728 -198.88327)
		(width 0.10414)
		(layer "In7.Cu")
		(net "LAN2_P1_P")
	)
	(segment
		(start 184.52338 -198.916544)
		(end 185.12917 -198.916544)
		(width 0.10414)
		(layer "In7.Cu")
		(net "LAN2_P1_P")
	)
	(segment
		(start 180.69814 -176.445926)
		(end 180.69814 -195.10756)
		(width 0.10414)
		(layer "In7.Cu")
		(net "LAN2_P1_P")
	)
	(segment
		(start 184.386728 -198.88327)
		(end 184.395364 -198.88327)
		(width 0.10414)
		(layer "In7.Cu")
		(net "LAN2_P1_P")
	)
	(segment
		(start 181.21503 -172.120814)
		(end 181.63286 -171.702984)
		(width 0.10414)
		(layer "F.Cu")
		(net "LAN2_P4_P")
	)
	(segment
		(start 181.63286 -171.702984)
		(end 181.63286 -171.422822)
		(width 0.10414)
		(layer "F.Cu")
		(net "LAN2_P4_P")
	)
	(segment
		(start 181.8513 -171.066714)
		(end 184.157874 -169.343324)
		(width 0.10414)
		(layer "F.Cu")
		(net "LAN2_P4_P")
	)
	(segment
		(start 184.157874 -169.123614)
		(end 183.740044 -168.705784)
		(width 0.10414)
		(layer "F.Cu")
		(net "LAN2_P4_P")
	)
	(segment
		(start 181.63286 -171.422822)
		(end 181.8513 -171.066714)
		(width 0.10414)
		(layer "F.Cu")
		(net "LAN2_P4_P")
	)
	(segment
		(start 184.157874 -169.343324)
		(end 184.157874 -169.123614)
		(width 0.10414)
		(layer "F.Cu")
		(net "LAN2_P4_P")
	)
	(segment
		(start 183.740044 -168.705784)
		(end 183.740044 -167.992044)
		(width 0.10414)
		(layer "F.Cu")
		(net "LAN2_P4_P")
	)
	(via
		(at 181.21503 -172.120814)
		(size 0.508)
		(drill 0.254)
		(layers "F.Cu" "B.Cu")
		(net "LAN2_P4_P")
	)
	(segment
		(start 181.373272 -197.490588)
		(end 181.510686 -197.583806)
		(width 0.10414)
		(layer "B.Cu")
		(net "LAN2_P4_P")
	)
	(segment
		(start 181.269386 -195.856606)
		(end 181.394354 -195.970906)
		(width 0.10414)
		(layer "B.Cu")
		(net "LAN2_P4_P")
	)
	(segment
		(start 181.5338 -198.335392)
		(end 181.671214 -198.42861)
		(width 0.10414)
		(layer "B.Cu")
		(net "LAN2_P4_P")
	)
	(segment
		(start 181.47538 -198.028306)
		(end 181.5338 -198.335392)
		(width 0.10414)
		(layer "B.Cu")
		(net "LAN2_P4_P")
	)
	(segment
		(start 181.32933 -197.259956)
		(end 181.373272 -197.490588)
		(width 0.10414)
		(layer "B.Cu")
		(net "LAN2_P4_P")
	)
	(segment
		(start 181.98211 -175.899318)
		(end 181.893718 -176.096422)
		(width 0.10414)
		(layer "B.Cu")
		(net "LAN2_P4_P")
	)
	(segment
		(start 182.17388 -178.864768)
		(end 182.17388 -179.177188)
		(width 0.10414)
		(layer "B.Cu")
		(net "LAN2_P4_P")
	)
	(segment
		(start 181.99862 -180.640228)
		(end 182.17388 -180.815488)
		(width 0.10414)
		(layer "B.Cu")
		(net "LAN2_P4_P")
	)
	(segment
		(start 181.893718 -176.096422)
		(end 181.99862 -176.36998)
		(width 0.10414)
		(layer "B.Cu")
		(net "LAN2_P4_P")
	)
	(segment
		(start 181.99862 -176.738788)
		(end 182.17388 -176.914048)
		(width 0.10414)
		(layer "B.Cu")
		(net "LAN2_P4_P")
	)
	(segment
		(start 181.569106 -197.8914)
		(end 181.47538 -198.028306)
		(width 0.10414)
		(layer "B.Cu")
		(net "LAN2_P4_P")
	)
	(segment
		(start 182.17388 -177.889408)
		(end 182.17388 -178.201828)
		(width 0.10414)
		(layer "B.Cu")
		(net "LAN2_P4_P")
	)
	(segment
		(start 180.853588 -171.380404)
		(end 180.560472 -171.67352)
		(width 0.10414)
		(layer "B.Cu")
		(net "LAN2_P4_P")
	)
	(segment
		(start 181.648862 -175.03013)
		(end 181.56047 -175.22698)
		(width 0.10414)
		(layer "B.Cu")
		(net "LAN2_P4_P")
	)
	(segment
		(start 181.407816 -196.28358)
		(end 181.293008 -196.408294)
		(width 0.10414)
		(layer "B.Cu")
		(net "LAN2_P4_P")
	)
	(segment
		(start 181.394354 -195.970906)
		(end 181.407816 -196.28358)
		(width 0.10414)
		(layer "B.Cu")
		(net "LAN2_P4_P")
	)
	(segment
		(start 181.672738 -175.519334)
		(end 181.869842 -175.607218)
		(width 0.10414)
		(layer "B.Cu")
		(net "LAN2_P4_P")
	)
	(segment
		(start 181.006242 -173.780958)
		(end 181.203346 -173.868842)
		(width 0.10414)
		(layer "B.Cu")
		(net "LAN2_P4_P")
	)
	(segment
		(start 180.52796 -172.533056)
		(end 181.006242 -173.780958)
		(width 0.10414)
		(layer "B.Cu")
		(net "LAN2_P4_P")
	)
	(segment
		(start 181.99862 -176.36998)
		(end 181.99862 -176.738788)
		(width 0.10414)
		(layer "B.Cu")
		(net "LAN2_P4_P")
	)
	(segment
		(start 181.249066 -195.388484)
		(end 181.269386 -195.856606)
		(width 0.10414)
		(layer "B.Cu")
		(net "LAN2_P4_P")
	)
	(segment
		(start 181.99862 -189.727586)
		(end 181.296564 -194.877182)
		(width 0.10414)
		(layer "B.Cu")
		(net "LAN2_P4_P")
	)
	(segment
		(start 181.99862 -179.664868)
		(end 182.17388 -179.840128)
		(width 0.10414)
		(layer "B.Cu")
		(net "LAN2_P4_P")
	)
	(segment
		(start 181.732682 -199.385682)
		(end 181.732682 -202.659742)
		(width 0.10414)
		(layer "B.Cu")
		(net "LAN2_P4_P")
	)
	(segment
		(start 181.315614 -174.160942)
		(end 181.227222 -174.357792)
		(width 0.10414)
		(layer "B.Cu")
		(net "LAN2_P4_P")
	)
	(segment
		(start 182.17388 -178.201828)
		(end 181.99862 -178.377088)
		(width 0.10414)
		(layer "B.Cu")
		(net "LAN2_P4_P")
	)
	(segment
		(start 181.510686 -197.583806)
		(end 181.569106 -197.8914)
		(width 0.10414)
		(layer "B.Cu")
		(net "LAN2_P4_P")
	)
	(segment
		(start 182.17388 -177.226468)
		(end 181.99862 -177.401728)
		(width 0.10414)
		(layer "B.Cu")
		(net "LAN2_P4_P")
	)
	(segment
		(start 181.671214 -198.42861)
		(end 181.729634 -198.736204)
		(width 0.10414)
		(layer "B.Cu")
		(net "LAN2_P4_P")
	)
	(segment
		(start 181.729634 -198.736204)
		(end 181.635654 -198.87311)
		(width 0.10414)
		(layer "B.Cu")
		(net "LAN2_P4_P")
	)
	(segment
		(start 181.99862 -177.401728)
		(end 181.99862 -177.714148)
		(width 0.10414)
		(layer "B.Cu")
		(net "LAN2_P4_P")
	)
	(segment
		(start 181.33949 -174.650146)
		(end 181.536594 -174.73803)
		(width 0.10414)
		(layer "B.Cu")
		(net "LAN2_P4_P")
	)
	(segment
		(start 181.56047 -175.22698)
		(end 181.672738 -175.519334)
		(width 0.10414)
		(layer "B.Cu")
		(net "LAN2_P4_P")
	)
	(segment
		(start 181.21503 -172.120814)
		(end 181.62016 -171.715684)
		(width 0.10414)
		(layer "B.Cu")
		(net "LAN2_P4_P")
	)
	(segment
		(start 181.99862 -178.689508)
		(end 182.17388 -178.864768)
		(width 0.10414)
		(layer "B.Cu")
		(net "LAN2_P4_P")
	)
	(segment
		(start 181.99862 -181.303168)
		(end 181.99862 -189.727586)
		(width 0.10414)
		(layer "B.Cu")
		(net "LAN2_P4_P")
	)
	(segment
		(start 180.560472 -171.67352)
		(end 180.52796 -172.533056)
		(width 0.10414)
		(layer "B.Cu")
		(net "LAN2_P4_P")
	)
	(segment
		(start 181.536594 -174.73803)
		(end 181.648862 -175.03013)
		(width 0.10414)
		(layer "B.Cu")
		(net "LAN2_P4_P")
	)
	(segment
		(start 181.99862 -179.352448)
		(end 181.99862 -179.664868)
		(width 0.10414)
		(layer "B.Cu")
		(net "LAN2_P4_P")
	)
	(segment
		(start 181.293008 -196.408294)
		(end 181.32933 -197.259956)
		(width 0.10414)
		(layer "B.Cu")
		(net "LAN2_P4_P")
	)
	(segment
		(start 182.17388 -179.177188)
		(end 181.99862 -179.352448)
		(width 0.10414)
		(layer "B.Cu")
		(net "LAN2_P4_P")
	)
	(segment
		(start 181.447694 -171.380404)
		(end 180.853588 -171.380404)
		(width 0.10414)
		(layer "B.Cu")
		(net "LAN2_P4_P")
	)
	(segment
		(start 182.17388 -180.152548)
		(end 181.99862 -180.327808)
		(width 0.10414)
		(layer "B.Cu")
		(net "LAN2_P4_P")
	)
	(segment
		(start 182.17388 -180.815488)
		(end 182.17388 -181.127908)
		(width 0.10414)
		(layer "B.Cu")
		(net "LAN2_P4_P")
	)
	(segment
		(start 181.227222 -174.357792)
		(end 181.33949 -174.650146)
		(width 0.10414)
		(layer "B.Cu")
		(net "LAN2_P4_P")
	)
	(segment
		(start 181.635654 -198.87311)
		(end 181.732682 -199.385682)
		(width 0.10414)
		(layer "B.Cu")
		(net "LAN2_P4_P")
	)
	(segment
		(start 181.869842 -175.607218)
		(end 181.98211 -175.899318)
		(width 0.10414)
		(layer "B.Cu")
		(net "LAN2_P4_P")
	)
	(segment
		(start 181.99862 -178.377088)
		(end 181.99862 -178.689508)
		(width 0.10414)
		(layer "B.Cu")
		(net "LAN2_P4_P")
	)
	(segment
		(start 182.17388 -179.840128)
		(end 182.17388 -180.152548)
		(width 0.10414)
		(layer "B.Cu")
		(net "LAN2_P4_P")
	)
	(segment
		(start 182.015638 -202.942698)
		(end 182.015638 -205.199488)
		(width 0.10414)
		(layer "B.Cu")
		(net "LAN2_P4_P")
	)
	(segment
		(start 182.17388 -176.914048)
		(end 182.17388 -177.226468)
		(width 0.10414)
		(layer "B.Cu")
		(net "LAN2_P4_P")
	)
	(segment
		(start 181.99862 -180.327808)
		(end 181.99862 -180.640228)
		(width 0.10414)
		(layer "B.Cu")
		(net "LAN2_P4_P")
	)
	(segment
		(start 181.62016 -171.715684)
		(end 181.62016 -171.55287)
		(width 0.10414)
		(layer "B.Cu")
		(net "LAN2_P4_P")
	)
	(segment
		(start 182.17388 -181.127908)
		(end 181.99862 -181.303168)
		(width 0.10414)
		(layer "B.Cu")
		(net "LAN2_P4_P")
	)
	(segment
		(start 181.732682 -202.659742)
		(end 182.015638 -202.942698)
		(width 0.10414)
		(layer "B.Cu")
		(net "LAN2_P4_P")
	)
	(segment
		(start 181.62016 -171.55287)
		(end 181.447694 -171.380404)
		(width 0.10414)
		(layer "B.Cu")
		(net "LAN2_P4_P")
	)
	(segment
		(start 181.296564 -194.877182)
		(end 181.249066 -195.388484)
		(width 0.10414)
		(layer "B.Cu")
		(net "LAN2_P4_P")
	)
	(segment
		(start 181.99862 -177.714148)
		(end 182.17388 -177.889408)
		(width 0.10414)
		(layer "B.Cu")
		(net "LAN2_P4_P")
	)
	(segment
		(start 181.203346 -173.868842)
		(end 181.315614 -174.160942)
		(width 0.10414)
		(layer "B.Cu")
		(net "LAN2_P4_P")
	)
	(segment
		(start 183.388 -185.7756)
		(end 182.9562 -185.3438)
		(width 0.381)
		(layer "F.Cu")
		(net "POWER_SW3_PWR_CTR_12V_R")
	)
	(segment
		(start 182.9562 -185.3438)
		(end 182.9562 -182.5498)
		(width 0.381)
		(layer "F.Cu")
		(net "POWER_SW3_PWR_CTR_12V_R")
	)
	(segment
		(start 185.8518 -185.7756)
		(end 183.388 -185.7756)
		(width 0.381)
		(layer "F.Cu")
		(net "POWER_SW3_PWR_CTR_12V_R")
	)
	(segment
		(start 186.2582 -190.6778)
		(end 186.2582 -186.182)
		(width 0.381)
		(layer "F.Cu")
		(net "POWER_SW3_PWR_CTR_12V_R")
	)
	(segment
		(start 186.2582 -186.182)
		(end 185.8518 -185.7756)
		(width 0.381)
		(layer "F.Cu")
		(net "POWER_SW3_PWR_CTR_12V_R")
	)
	(segment
		(start 184.912 -192.024)
		(end 186.2582 -190.6778)
		(width 0.381)
		(layer "F.Cu")
		(net "POWER_SW3_PWR_CTR_12V_R")
	)
	(segment
		(start 178.816 -194.0052)
		(end 180.7972 -192.024)
		(width 0.381)
		(layer "F.Cu")
		(net "POWER_SW3_PWR_CTR_12V_R")
	)
	(segment
		(start 178.816 -195.7832)
		(end 178.816 -194.0052)
		(width 0.381)
		(layer "F.Cu")
		(net "POWER_SW3_PWR_CTR_12V_R")
	)
	(segment
		(start 180.7972 -192.024)
		(end 184.912 -192.024)
		(width 0.381)
		(layer "F.Cu")
		(net "POWER_SW3_PWR_CTR_12V_R")
	)
	(via
		(at 178.816 -195.7832)
		(size 0.508)
		(drill 0.254)
		(layers "F.Cu" "B.Cu")
		(net "POWER_SW3_PWR_CTR_12V_R")
	)
	(via
		(at 185.293 -189.5602)
		(size 0.508)
		(drill 0.254)
		(layers "F.Cu" "B.Cu")
		(net "POWER_SW3_PWR_CTR_12V_R")
	)
	(segment
		(start 178.435 -201.96048)
		(end 179.015644 -202.541124)
		(width 0.381)
		(layer "B.Cu")
		(net "POWER_SW3_PWR_CTR_12V_R")
	)
	(segment
		(start 185.293 -188.86805)
		(end 185.293 -189.5602)
		(width 0.381)
		(layer "B.Cu")
		(net "POWER_SW3_PWR_CTR_12V_R")
	)
	(segment
		(start 178.816 -195.7832)
		(end 178.435 -196.1642)
		(width 0.381)
		(layer "B.Cu")
		(net "POWER_SW3_PWR_CTR_12V_R")
	)
	(segment
		(start 179.015644 -202.541124)
		(end 179.015644 -205.199488)
		(width 0.381)
		(layer "B.Cu")
		(net "POWER_SW3_PWR_CTR_12V_R")
	)
	(segment
		(start 178.435 -196.1642)
		(end 178.435 -201.96048)
		(width 0.381)
		(layer "B.Cu")
		(net "POWER_SW3_PWR_CTR_12V_R")
	)
	(segment
		(start 178.816 -195.7832)
		(end 185.039 -189.5602)
		(width 0.381)
		(layer "In2.Cu")
		(net "POWER_SW3_PWR_CTR_12V_R")
	)
	(segment
		(start 185.039 -189.5602)
		(end 185.293 -189.5602)
		(width 0.381)
		(layer "In2.Cu")
		(net "POWER_SW3_PWR_CTR_12V_R")
	)
	(segment
		(start 184.63895 -197.73646)
		(end 185.05678 -198.15429)
		(width 0.10414)
		(layer "F.Cu")
		(net "LAN2_P1_N")
	)
	(segment
		(start 185.298334 -199.350376)
		(end 185.298334 -202.659742)
		(width 0.10414)
		(layer "F.Cu")
		(net "LAN2_P1_N")
	)
	(segment
		(start 172.310044 -169.77868)
		(end 171.892214 -169.36085)
		(width 0.10414)
		(layer "F.Cu")
		(net "LAN2_P1_N")
	)
	(segment
		(start 171.892214 -169.123614)
		(end 172.310044 -168.705784)
		(width 0.10414)
		(layer "F.Cu")
		(net "LAN2_P1_N")
	)
	(segment
		(start 185.015632 -202.942444)
		(end 185.015632 -205.199488)
		(width 0.10414)
		(layer "F.Cu")
		(net "LAN2_P1_N")
	)
	(segment
		(start 171.892214 -169.36085)
		(end 171.892214 -169.123614)
		(width 0.10414)
		(layer "F.Cu")
		(net "LAN2_P1_N")
	)
	(segment
		(start 185.298334 -202.659742)
		(end 185.015632 -202.942444)
		(width 0.10414)
		(layer "F.Cu")
		(net "LAN2_P1_N")
	)
	(segment
		(start 185.05678 -199.108822)
		(end 185.298334 -199.350376)
		(width 0.10414)
		(layer "F.Cu")
		(net "LAN2_P1_N")
	)
	(segment
		(start 172.310044 -168.705784)
		(end 172.310044 -167.992044)
		(width 0.10414)
		(layer "F.Cu")
		(net "LAN2_P1_N")
	)
	(segment
		(start 185.05678 -198.15429)
		(end 185.05678 -199.108822)
		(width 0.10414)
		(layer "F.Cu")
		(net "LAN2_P1_N")
	)
	(via
		(at 184.63895 -197.73646)
		(size 0.508)
		(drill 0.254)
		(layers "F.Cu" "B.Cu")
		(net "LAN2_P1_N")
	)
	(via
		(at 172.310044 -169.77868)
		(size 0.508)
		(drill 0.254)
		(layers "F.Cu" "B.Cu")
		(net "LAN2_P1_N")
	)
	(segment
		(start 176.155858 -172.355256)
		(end 176.435004 -172.49648)
		(width 0.10414)
		(layer "In7.Cu")
		(net "LAN2_P1_N")
	)
	(segment
		(start 181.577488 -196.524118)
		(end 181.625748 -196.661024)
		(width 0.10414)
		(layer "In7.Cu")
		(net "LAN2_P1_N")
	)
	(segment
		(start 172.642022 -171.066714)
		(end 172.780452 -171.000166)
		(width 0.10414)
		(layer "In7.Cu")
		(net "LAN2_P1_N")
	)
	(segment
		(start 176.893982 -172.578268)
		(end 176.95291 -172.758608)
		(width 0.10414)
		(layer "In7.Cu")
		(net "LAN2_P1_N")
	)
	(segment
		(start 175.637952 -172.093128)
		(end 175.817784 -172.033692)
		(width 0.10414)
		(layer "In7.Cu")
		(net "LAN2_P1_N")
	)
	(segment
		(start 171.854114 -170.47083)
		(end 172.344842 -170.961558)
		(width 0.10414)
		(layer "In7.Cu")
		(net "LAN2_P1_N")
	)
	(segment
		(start 173.141386 -171.243244)
		(end 173.436534 -171.347638)
		(width 0.10414)
		(layer "In7.Cu")
		(net "LAN2_P1_N")
	)
	(segment
		(start 176.614836 -172.437044)
		(end 176.893982 -172.578268)
		(width 0.10414)
		(layer "In7.Cu")
		(net "LAN2_P1_N")
	)
	(segment
		(start 178.044856 -173.311312)
		(end 178.52517 -173.766226)
		(width 0.10414)
		(layer "In7.Cu")
		(net "LAN2_P1_N")
	)
	(segment
		(start 181.05628 -176.297336)
		(end 181.05628 -192.44945)
		(width 0.10414)
		(layer "In7.Cu")
		(net "LAN2_P1_N")
	)
	(segment
		(start 176.435004 -172.49648)
		(end 176.614836 -172.437044)
		(width 0.10414)
		(layer "In7.Cu")
		(net "LAN2_P1_N")
	)
	(segment
		(start 184.085738 -198.197724)
		(end 184.151524 -198.378572)
		(width 0.10414)
		(layer "In7.Cu")
		(net "LAN2_P1_N")
	)
	(segment
		(start 175.817784 -172.033692)
		(end 176.09693 -172.174916)
		(width 0.10414)
		(layer "In7.Cu")
		(net "LAN2_P1_N")
	)
	(segment
		(start 182.807864 -197.753732)
		(end 182.988458 -197.687438)
		(width 0.10414)
		(layer "In7.Cu")
		(net "LAN2_P1_N")
	)
	(segment
		(start 181.17058 -192.87617)
		(end 181.05628 -192.99047)
		(width 0.10414)
		(layer "In7.Cu")
		(net "LAN2_P1_N")
	)
	(segment
		(start 181.05628 -192.99047)
		(end 181.05628 -193.30289)
		(width 0.10414)
		(layer "In7.Cu")
		(net "LAN2_P1_N")
	)
	(segment
		(start 171.854114 -170.23461)
		(end 171.854114 -170.47083)
		(width 0.10414)
		(layer "In7.Cu")
		(net "LAN2_P1_N")
	)
	(segment
		(start 174.540418 -171.738036)
		(end 174.935388 -171.738036)
		(width 0.10414)
		(layer "In7.Cu")
		(net "LAN2_P1_N")
	)
	(segment
		(start 181.363874 -195.588128)
		(end 181.296564 -195.727574)
		(width 0.10414)
		(layer "In7.Cu")
		(net "LAN2_P1_N")
	)
	(segment
		(start 172.344842 -170.961558)
		(end 172.642022 -171.066714)
		(width 0.10414)
		(layer "In7.Cu")
		(net "LAN2_P1_N")
	)
	(segment
		(start 181.625748 -196.661024)
		(end 181.827932 -196.863208)
		(width 0.10414)
		(layer "In7.Cu")
		(net "LAN2_P1_N")
	)
	(segment
		(start 172.310044 -169.77868)
		(end 171.854114 -170.23461)
		(width 0.10414)
		(layer "In7.Cu")
		(net "LAN2_P1_N")
	)
	(segment
		(start 176.09693 -172.174916)
		(end 176.155858 -172.355256)
		(width 0.10414)
		(layer "In7.Cu")
		(net "LAN2_P1_N")
	)
	(segment
		(start 181.827932 -196.863208)
		(end 181.998112 -196.863208)
		(width 0.10414)
		(layer "In7.Cu")
		(net "LAN2_P1_N")
	)
	(segment
		(start 181.25948 -195.29298)
		(end 181.363874 -195.588128)
		(width 0.10414)
		(layer "In7.Cu")
		(net "LAN2_P1_N")
	)
	(segment
		(start 177.749962 -173.16196)
		(end 178.044856 -173.311312)
		(width 0.10414)
		(layer "In7.Cu")
		(net "LAN2_P1_N")
	)
	(segment
		(start 181.400958 -196.022722)
		(end 181.540404 -196.089524)
		(width 0.10414)
		(layer "In7.Cu")
		(net "LAN2_P1_N")
	)
	(segment
		(start 182.218838 -197.254114)
		(end 182.611014 -197.646036)
		(width 0.10414)
		(layer "In7.Cu")
		(net "LAN2_P1_N")
	)
	(segment
		(start 181.17058 -193.41719)
		(end 181.17058 -193.72961)
		(width 0.10414)
		(layer "In7.Cu")
		(net "LAN2_P1_N")
	)
	(segment
		(start 183.337708 -198.000112)
		(end 183.62168 -198.132192)
		(width 0.10414)
		(layer "In7.Cu")
		(net "LAN2_P1_N")
	)
	(segment
		(start 181.17058 -193.72961)
		(end 181.05628 -193.84391)
		(width 0.10414)
		(layer "In7.Cu")
		(net "LAN2_P1_N")
	)
	(segment
		(start 173.0756 -171.10456)
		(end 173.141386 -171.243244)
		(width 0.10414)
		(layer "In7.Cu")
		(net "LAN2_P1_N")
	)
	(segment
		(start 184.569354 -198.558404)
		(end 184.98058 -198.558404)
		(width 0.10414)
		(layer "In7.Cu")
		(net "LAN2_P1_N")
	)
	(segment
		(start 181.120034 -195.226178)
		(end 181.25948 -195.29298)
		(width 0.10414)
		(layer "In7.Cu")
		(net "LAN2_P1_N")
	)
	(segment
		(start 181.05628 -195.046092)
		(end 181.11978 -195.225416)
		(width 0.10414)
		(layer "In7.Cu")
		(net "LAN2_P1_N")
	)
	(segment
		(start 173.436534 -171.347638)
		(end 173.574964 -171.28109)
		(width 0.10414)
		(layer "In7.Cu")
		(net "LAN2_P1_N")
	)
	(segment
		(start 181.296564 -195.727574)
		(end 181.400958 -196.022722)
		(width 0.10414)
		(layer "In7.Cu")
		(net "LAN2_P1_N")
	)
	(segment
		(start 181.540404 -196.089524)
		(end 181.644798 -196.384672)
		(width 0.10414)
		(layer "In7.Cu")
		(net "LAN2_P1_N")
	)
	(segment
		(start 185.09488 -198.444104)
		(end 185.09488 -198.19239)
		(width 0.10414)
		(layer "In7.Cu")
		(net "LAN2_P1_N")
	)
	(segment
		(start 183.802274 -198.065898)
		(end 184.085738 -198.197724)
		(width 0.10414)
		(layer "In7.Cu")
		(net "LAN2_P1_N")
	)
	(segment
		(start 173.574964 -171.28109)
		(end 173.870112 -171.385484)
		(width 0.10414)
		(layer "In7.Cu")
		(net "LAN2_P1_N")
	)
	(segment
		(start 173.935898 -171.524168)
		(end 174.540418 -171.738036)
		(width 0.10414)
		(layer "In7.Cu")
		(net "LAN2_P1_N")
	)
	(segment
		(start 185.09488 -198.19239)
		(end 184.63895 -197.73646)
		(width 0.10414)
		(layer "In7.Cu")
		(net "LAN2_P1_N")
	)
	(segment
		(start 172.780452 -171.000166)
		(end 173.0756 -171.10456)
		(width 0.10414)
		(layer "In7.Cu")
		(net "LAN2_P1_N")
	)
	(segment
		(start 181.644798 -196.384672)
		(end 181.577488 -196.524118)
		(width 0.10414)
		(layer "In7.Cu")
		(net "LAN2_P1_N")
	)
	(segment
		(start 182.611014 -197.646036)
		(end 182.678324 -197.69328)
		(width 0.10414)
		(layer "In7.Cu")
		(net "LAN2_P1_N")
	)
	(segment
		(start 178.52517 -173.766226)
		(end 181.05628 -176.297336)
		(width 0.10414)
		(layer "In7.Cu")
		(net "LAN2_P1_N")
	)
	(segment
		(start 184.151524 -198.378572)
		(end 184.497472 -198.539608)
		(width 0.10414)
		(layer "In7.Cu")
		(net "LAN2_P1_N")
	)
	(segment
		(start 181.17058 -192.56375)
		(end 181.17058 -192.87617)
		(width 0.10414)
		(layer "In7.Cu")
		(net "LAN2_P1_N")
	)
	(segment
		(start 173.870112 -171.385484)
		(end 173.935898 -171.524168)
		(width 0.10414)
		(layer "In7.Cu")
		(net "LAN2_P1_N")
	)
	(segment
		(start 184.98058 -198.558404)
		(end 185.09488 -198.444104)
		(width 0.10414)
		(layer "In7.Cu")
		(net "LAN2_P1_N")
	)
	(segment
		(start 181.11978 -195.225416)
		(end 181.120034 -195.226178)
		(width 0.10414)
		(layer "In7.Cu")
		(net "LAN2_P1_N")
	)
	(segment
		(start 176.95291 -172.758608)
		(end 177.232056 -172.899832)
		(width 0.10414)
		(layer "In7.Cu")
		(net "LAN2_P1_N")
	)
	(segment
		(start 174.935388 -171.738036)
		(end 175.637952 -172.093128)
		(width 0.10414)
		(layer "In7.Cu")
		(net "LAN2_P1_N")
	)
	(segment
		(start 181.05628 -193.84391)
		(end 181.05628 -195.046092)
		(width 0.10414)
		(layer "In7.Cu")
		(net "LAN2_P1_N")
	)
	(segment
		(start 183.271922 -197.819264)
		(end 183.337708 -198.000112)
		(width 0.10414)
		(layer "In7.Cu")
		(net "LAN2_P1_N")
	)
	(segment
		(start 182.218838 -197.083934)
		(end 182.218838 -197.254114)
		(width 0.10414)
		(layer "In7.Cu")
		(net "LAN2_P1_N")
	)
	(segment
		(start 177.232056 -172.899832)
		(end 177.749962 -173.16196)
		(width 0.10414)
		(layer "In7.Cu")
		(net "LAN2_P1_N")
	)
	(segment
		(start 182.988458 -197.687438)
		(end 183.271922 -197.819264)
		(width 0.10414)
		(layer "In7.Cu")
		(net "LAN2_P1_N")
	)
	(segment
		(start 181.05628 -192.44945)
		(end 181.17058 -192.56375)
		(width 0.10414)
		(layer "In7.Cu")
		(net "LAN2_P1_N")
	)
	(segment
		(start 181.05628 -193.30289)
		(end 181.17058 -193.41719)
		(width 0.10414)
		(layer "In7.Cu")
		(net "LAN2_P1_N")
	)
	(segment
		(start 183.62168 -198.132192)
		(end 183.802274 -198.065898)
		(width 0.10414)
		(layer "In7.Cu")
		(net "LAN2_P1_N")
	)
	(segment
		(start 182.678324 -197.69328)
		(end 182.807864 -197.753732)
		(width 0.10414)
		(layer "In7.Cu")
		(net "LAN2_P1_N")
	)
	(segment
		(start 181.998112 -196.863208)
		(end 182.218838 -197.083934)
		(width 0.10414)
		(layer "In7.Cu")
		(net "LAN2_P1_N")
	)
	(segment
		(start 184.497472 -198.539608)
		(end 184.569354 -198.558404)
		(width 0.10414)
		(layer "In7.Cu")
		(net "LAN2_P1_N")
	)
	(segment
		(start 41.862248 -169.258996)
		(end 41.862248 -168.295066)
		(width 0.508)
		(layer "F.Cu")
		(net "P12V_DBG")
	)
	(via
		(at 6.06044 -93.03385)
		(size 0.508)
		(drill 0.254)
		(layers "F.Cu" "B.Cu")
		(net "P12V_DBG")
	)
	(via
		(at 9.0805 -92.606622)
		(size 0.508)
		(drill 0.254)
		(layers "F.Cu" "B.Cu")
		(net "P12V_DBG")
	)
	(via
		(at 3.33248 -95.471234)
		(size 0.508)
		(drill 0.254)
		(layers "F.Cu" "B.Cu")
		(net "P12V_DBG")
	)
	(via
		(at 9.72312 -91.994736)
		(size 0.508)
		(drill 0.254)
		(layers "F.Cu" "B.Cu")
		(net "P12V_DBG")
	)
	(via
		(at 5.46862 -93.723714)
		(size 0.508)
		(drill 0.254)
		(layers "F.Cu" "B.Cu")
		(net "P12V_DBG")
	)
	(via
		(at 4.65836 -93.078808)
		(size 0.508)
		(drill 0.254)
		(layers "F.Cu" "B.Cu")
		(net "P12V_DBG")
	)
	(via
		(at 10.33526 -91.32697)
		(size 0.508)
		(drill 0.254)
		(layers "F.Cu" "B.Cu")
		(net "P12V_DBG")
	)
	(via
		(at 41.862248 -168.295066)
		(size 0.508)
		(drill 0.254)
		(layers "F.Cu" "B.Cu")
		(net "P12V_DBG")
	)
	(via
		(at 4.06654 -93.768672)
		(size 0.508)
		(drill 0.254)
		(layers "F.Cu" "B.Cu")
		(net "P12V_DBG")
	)
	(via
		(at 3.34518 -94.658942)
		(size 0.508)
		(drill 0.254)
		(layers "F.Cu" "B.Cu")
		(net "P12V_DBG")
	)
	(via
		(at 8.48868 -93.296486)
		(size 0.508)
		(drill 0.254)
		(layers "F.Cu" "B.Cu")
		(net "P12V_DBG")
	)
	(segment
		(start 22.895814 -168.235884)
		(end 20.56892 -165.90899)
		(width 0.508)
		(layer "In6.Cu")
		(net "P12V_DBG")
	)
	(segment
		(start 10.563606 -144.33296)
		(end 7.0231 -140.792454)
		(width 0.508)
		(layer "In6.Cu")
		(net "P12V_DBG")
	)
	(segment
		(start 41.749726 -168.182544)
		(end 39.97452 -168.182544)
		(width 0.508)
		(layer "In6.Cu")
		(net "P12V_DBG")
	)
	(segment
		(start 20.56892 -152.493726)
		(end 12.408154 -144.33296)
		(width 0.508)
		(layer "In6.Cu")
		(net "P12V_DBG")
	)
	(segment
		(start 7.0231 -138.97737)
		(end 6.0198 -137.97407)
		(width 0.508)
		(layer "In6.Cu")
		(net "P12V_DBG")
	)
	(segment
		(start 20.56892 -165.90899)
		(end 20.56892 -152.493726)
		(width 0.508)
		(layer "In6.Cu")
		(net "P12V_DBG")
	)
	(segment
		(start 5.32765 -136.880854)
		(end 5.32765 -95.020384)
		(width 0.508)
		(layer "In6.Cu")
		(net "P12V_DBG")
	)
	(segment
		(start 38.800024 -167.008048)
		(end 33.139888 -167.008048)
		(width 0.508)
		(layer "In6.Cu")
		(net "P12V_DBG")
	)
	(segment
		(start 39.97452 -168.182544)
		(end 38.800024 -167.008048)
		(width 0.508)
		(layer "In6.Cu")
		(net "P12V_DBG")
	)
	(segment
		(start 6.0198 -137.573004)
		(end 5.32765 -136.880854)
		(width 0.508)
		(layer "In6.Cu")
		(net "P12V_DBG")
	)
	(segment
		(start 5.37464 -94.973394)
		(end 5.37464 -93.817694)
		(width 0.508)
		(layer "In6.Cu")
		(net "P12V_DBG")
	)
	(segment
		(start 7.0231 -140.792454)
		(end 7.0231 -138.97737)
		(width 0.508)
		(layer "In6.Cu")
		(net "P12V_DBG")
	)
	(segment
		(start 41.862248 -168.295066)
		(end 41.749726 -168.182544)
		(width 0.508)
		(layer "In6.Cu")
		(net "P12V_DBG")
	)
	(segment
		(start 31.912052 -168.235884)
		(end 22.895814 -168.235884)
		(width 0.508)
		(layer "In6.Cu")
		(net "P12V_DBG")
	)
	(segment
		(start 6.0198 -137.97407)
		(end 6.0198 -137.573004)
		(width 0.508)
		(layer "In6.Cu")
		(net "P12V_DBG")
	)
	(segment
		(start 5.32765 -95.020384)
		(end 5.37464 -94.973394)
		(width 0.508)
		(layer "In6.Cu")
		(net "P12V_DBG")
	)
	(segment
		(start 33.139888 -167.008048)
		(end 31.912052 -168.235884)
		(width 0.508)
		(layer "In6.Cu")
		(net "P12V_DBG")
	)
	(segment
		(start 12.408154 -144.33296)
		(end 10.563606 -144.33296)
		(width 0.508)
		(layer "In6.Cu")
		(net "P12V_DBG")
	)
	(segment
		(start 5.37464 -93.817694)
		(end 5.46862 -93.723714)
		(width 0.508)
		(layer "In6.Cu")
		(net "P12V_DBG")
	)
	(segment
		(start 5.840476 -146.917918)
		(end 5.840476 -148.392642)
		(width 0.1016)
		(layer "F.Cu")
		(net "UART_TX_P6_L")
	)
	(segment
		(start 13.712952 -144.461992)
		(end 13.712952 -144.462246)
		(width 0.1016)
		(layer "F.Cu")
		(net "UART_TX_P6_L")
	)
	(segment
		(start 13.712952 -144.462246)
		(end 13.182092 -144.993106)
		(width 0.1016)
		(layer "F.Cu")
		(net "UART_TX_P6_L")
	)
	(segment
		(start 13.182092 -144.993106)
		(end 7.765288 -144.993106)
		(width 0.1016)
		(layer "F.Cu")
		(net "UART_TX_P6_L")
	)
	(segment
		(start 7.765288 -144.993106)
		(end 5.840476 -146.917918)
		(width 0.1016)
		(layer "F.Cu")
		(net "UART_TX_P6_L")
	)
	(via
		(at 41.437052 -197.75551)
		(size 0.508)
		(drill 0.254)
		(layers "F.Cu" "B.Cu")
		(net "UART_TX_P6_L")
	)
	(via
		(at 13.712952 -144.461992)
		(size 0.508)
		(drill 0.254)
		(layers "F.Cu" "B.Cu")
		(net "UART_TX_P6_L")
	)
	(segment
		(start 41.437052 -197.972934)
		(end 40.014906 -199.39508)
		(width 0.1016)
		(layer "B.Cu")
		(net "UART_TX_P6_L")
	)
	(segment
		(start 41.437052 -197.75551)
		(end 41.437052 -197.972934)
		(width 0.1016)
		(layer "B.Cu")
		(net "UART_TX_P6_L")
	)
	(segment
		(start 40.014906 -199.39508)
		(end 40.014906 -205.199488)
		(width 0.1016)
		(layer "B.Cu")
		(net "UART_TX_P6_L")
	)
	(segment
		(start 31.62173 -182.938166)
		(end 31.62173 -187.557664)
		(width 0.1143)
		(layer "In2.Cu")
		(net "UART_TX_P6_L")
	)
	(segment
		(start 13.875004 -145.791428)
		(end 13.875004 -148.649182)
		(width 0.1143)
		(layer "In2.Cu")
		(net "UART_TX_P6_L")
	)
	(segment
		(start 31.758636 -174.859442)
		(end 31.758636 -182.80126)
		(width 0.1143)
		(layer "In2.Cu")
		(net "UART_TX_P6_L")
	)
	(segment
		(start 34.87166 -190.78956)
		(end 41.437052 -197.354952)
		(width 0.1143)
		(layer "In2.Cu")
		(net "UART_TX_P6_L")
	)
	(segment
		(start 13.712952 -145.629376)
		(end 13.875004 -145.791428)
		(width 0.1143)
		(layer "In2.Cu")
		(net "UART_TX_P6_L")
	)
	(segment
		(start 21.86686 -155.478226)
		(end 21.86686 -164.967666)
		(width 0.1143)
		(layer "In2.Cu")
		(net "UART_TX_P6_L")
	)
	(segment
		(start 15.77594 -149.387306)
		(end 21.86686 -155.478226)
		(width 0.1143)
		(layer "In2.Cu")
		(net "UART_TX_P6_L")
	)
	(segment
		(start 33.41624 -189.353698)
		(end 33.41624 -189.353952)
		(width 0.1143)
		(layer "In2.Cu")
		(net "UART_TX_P6_L")
	)
	(segment
		(start 13.875004 -148.649182)
		(end 14.613128 -149.387306)
		(width 0.1143)
		(layer "In2.Cu")
		(net "UART_TX_P6_L")
	)
	(segment
		(start 33.23082 -189.168278)
		(end 33.41624 -189.353698)
		(width 0.1143)
		(layer "In2.Cu")
		(net "UART_TX_P6_L")
	)
	(segment
		(start 14.613128 -149.387306)
		(end 15.77594 -149.387306)
		(width 0.1143)
		(layer "In2.Cu")
		(net "UART_TX_P6_L")
	)
	(segment
		(start 33.23082 -189.166754)
		(end 33.23082 -189.168278)
		(width 0.1143)
		(layer "In2.Cu")
		(net "UART_TX_P6_L")
	)
	(segment
		(start 21.86686 -164.967666)
		(end 31.758636 -174.859442)
		(width 0.1143)
		(layer "In2.Cu")
		(net "UART_TX_P6_L")
	)
	(segment
		(start 31.62173 -187.557664)
		(end 33.23082 -189.166754)
		(width 0.1143)
		(layer "In2.Cu")
		(net "UART_TX_P6_L")
	)
	(segment
		(start 34.87166 -189.685676)
		(end 34.87166 -190.78956)
		(width 0.1143)
		(layer "In2.Cu")
		(net "UART_TX_P6_L")
	)
	(segment
		(start 34.539936 -189.353952)
		(end 34.87166 -189.685676)
		(width 0.1143)
		(layer "In2.Cu")
		(net "UART_TX_P6_L")
	)
	(segment
		(start 33.41624 -189.353952)
		(end 34.539936 -189.353952)
		(width 0.1143)
		(layer "In2.Cu")
		(net "UART_TX_P6_L")
	)
	(segment
		(start 31.758636 -182.80126)
		(end 31.62173 -182.938166)
		(width 0.1143)
		(layer "In2.Cu")
		(net "UART_TX_P6_L")
	)
	(segment
		(start 13.712952 -144.461992)
		(end 13.712952 -145.629376)
		(width 0.1143)
		(layer "In2.Cu")
		(net "UART_TX_P6_L")
	)
	(segment
		(start 41.437052 -197.354952)
		(end 41.437052 -197.75551)
		(width 0.1143)
		(layer "In2.Cu")
		(net "UART_TX_P6_L")
	)
	(segment
		(start 184.592214 -169.561002)
		(end 184.592214 -169.123614)
		(width 0.10414)
		(layer "F.Cu")
		(net "LAN2_P4_N")
	)
	(segment
		(start 182.0672 -171.545504)
		(end 182.177944 -171.36491)
		(width 0.10414)
		(layer "F.Cu")
		(net "LAN2_P4_N")
	)
	(segment
		(start 182.0672 -171.702984)
		(end 182.0672 -171.545504)
		(width 0.10414)
		(layer "F.Cu")
		(net "LAN2_P4_N")
	)
	(segment
		(start 184.592214 -169.123614)
		(end 185.010044 -168.705784)
		(width 0.10414)
		(layer "F.Cu")
		(net "LAN2_P4_N")
	)
	(segment
		(start 182.48503 -172.120814)
		(end 182.0672 -171.702984)
		(width 0.10414)
		(layer "F.Cu")
		(net "LAN2_P4_N")
	)
	(segment
		(start 185.010044 -168.705784)
		(end 185.010044 -167.992044)
		(width 0.10414)
		(layer "F.Cu")
		(net "LAN2_P4_N")
	)
	(segment
		(start 182.177944 -171.36491)
		(end 184.592214 -169.561002)
		(width 0.10414)
		(layer "F.Cu")
		(net "LAN2_P4_N")
	)
	(via
		(at 182.48503 -172.120814)
		(size 0.508)
		(drill 0.254)
		(layers "F.Cu" "B.Cu")
		(net "LAN2_P4_N")
	)
	(segment
		(start 180.132736 -171.48683)
		(end 180.673502 -170.946064)
		(width 0.10414)
		(layer "B.Cu")
		(net "LAN2_P4_N")
	)
	(segment
		(start 180.81371 -195.377562)
		(end 180.864764 -194.827652)
		(width 0.10414)
		(layer "B.Cu")
		(net "LAN2_P4_N")
	)
	(segment
		(start 180.673502 -170.946064)
		(end 181.62778 -170.946064)
		(width 0.10414)
		(layer "B.Cu")
		(net "LAN2_P4_N")
	)
	(segment
		(start 181.56428 -189.697868)
		(end 181.56428 -176.450498)
		(width 0.10414)
		(layer "B.Cu")
		(net "LAN2_P4_N")
	)
	(segment
		(start 181.298342 -202.659742)
		(end 181.298342 -199.426576)
		(width 0.10414)
		(layer "B.Cu")
		(net "LAN2_P4_N")
	)
	(segment
		(start 180.864764 -194.827652)
		(end 181.56428 -189.697868)
		(width 0.10414)
		(layer "B.Cu")
		(net "LAN2_P4_N")
	)
	(segment
		(start 181.01564 -202.942444)
		(end 181.298342 -202.659742)
		(width 0.10414)
		(layer "B.Cu")
		(net "LAN2_P4_N")
	)
	(segment
		(start 181.298342 -199.426576)
		(end 180.896514 -197.309994)
		(width 0.10414)
		(layer "B.Cu")
		(net "LAN2_P4_N")
	)
	(segment
		(start 181.01564 -205.199488)
		(end 181.01564 -202.942444)
		(width 0.10414)
		(layer "B.Cu")
		(net "LAN2_P4_N")
	)
	(segment
		(start 180.896514 -197.309994)
		(end 180.81371 -195.377562)
		(width 0.10414)
		(layer "B.Cu")
		(net "LAN2_P4_N")
	)
	(segment
		(start 182.0545 -171.372784)
		(end 182.0545 -171.690284)
		(width 0.10414)
		(layer "B.Cu")
		(net "LAN2_P4_N")
	)
	(segment
		(start 181.56428 -176.450498)
		(end 180.090318 -172.605446)
		(width 0.10414)
		(layer "B.Cu")
		(net "LAN2_P4_N")
	)
	(segment
		(start 180.090318 -172.605446)
		(end 180.132736 -171.48683)
		(width 0.10414)
		(layer "B.Cu")
		(net "LAN2_P4_N")
	)
	(segment
		(start 182.0545 -171.690284)
		(end 182.48503 -172.120814)
		(width 0.10414)
		(layer "B.Cu")
		(net "LAN2_P4_N")
	)
	(segment
		(start 181.62778 -170.946064)
		(end 182.0545 -171.372784)
		(width 0.10414)
		(layer "B.Cu")
		(net "LAN2_P4_N")
	)
	(segment
		(start 121.360692 -147.675092)
		(end 122.4026 -148.717)
		(width 0.381)
		(layer "F.Cu")
		(net "POWER_SW3_PWR_CTR_12V")
	)
	(segment
		(start 124.1298 -151.2316)
		(end 124.1298 -151.52624)
		(width 0.381)
		(layer "F.Cu")
		(net "POWER_SW3_PWR_CTR_12V")
	)
	(segment
		(start 124.3838 -151.78024)
		(end 124.3838 -152.43556)
		(width 0.381)
		(layer "F.Cu")
		(net "POWER_SW3_PWR_CTR_12V")
	)
	(segment
		(start 120.61444 -147.675092)
		(end 121.360692 -147.675092)
		(width 0.381)
		(layer "F.Cu")
		(net "POWER_SW3_PWR_CTR_12V")
	)
	(segment
		(start 123.1646 -150.6474)
		(end 123.5456 -150.6474)
		(width 0.381)
		(layer "F.Cu")
		(net "POWER_SW3_PWR_CTR_12V")
	)
	(segment
		(start 124.3838 -152.43556)
		(end 124.39904 -152.4508)
		(width 0.381)
		(layer "F.Cu")
		(net "POWER_SW3_PWR_CTR_12V")
	)
	(segment
		(start 118.48973 -147.746466)
		(end 120.543066 -147.746466)
		(width 0.381)
		(layer "F.Cu")
		(net "POWER_SW3_PWR_CTR_12V")
	)
	(segment
		(start 124.39904 -152.4508)
		(end 124.4092 -152.4508)
		(width 0.381)
		(layer "F.Cu")
		(net "POWER_SW3_PWR_CTR_12V")
	)
	(segment
		(start 124.1298 -151.52624)
		(end 124.3838 -151.78024)
		(width 0.381)
		(layer "F.Cu")
		(net "POWER_SW3_PWR_CTR_12V")
	)
	(segment
		(start 122.4026 -148.717)
		(end 122.4026 -149.8854)
		(width 0.381)
		(layer "F.Cu")
		(net "POWER_SW3_PWR_CTR_12V")
	)
	(segment
		(start 123.5456 -150.6474)
		(end 124.1298 -151.2316)
		(width 0.381)
		(layer "F.Cu")
		(net "POWER_SW3_PWR_CTR_12V")
	)
	(segment
		(start 122.4026 -149.8854)
		(end 123.1646 -150.6474)
		(width 0.381)
		(layer "F.Cu")
		(net "POWER_SW3_PWR_CTR_12V")
	)
	(segment
		(start 120.543066 -147.746466)
		(end 120.61444 -147.675092)
		(width 0.381)
		(layer "F.Cu")
		(net "POWER_SW3_PWR_CTR_12V")
	)
	(via
		(at 185.7248 -181.9148)
		(size 0.508)
		(drill 0.254)
		(layers "F.Cu" "B.Cu")
		(net "POWER_SW3_PWR_CTR_12V")
	)
	(via
		(at 124.4092 -152.4508)
		(size 0.508)
		(drill 0.254)
		(layers "F.Cu" "B.Cu")
		(net "POWER_SW3_PWR_CTR_12V")
	)
	(segment
		(start 150.2791 -159.2707)
		(end 149.2377 -159.2707)
		(width 0.381)
		(layer "In7.Cu")
		(net "POWER_SW3_PWR_CTR_12V")
	)
	(segment
		(start 163.5252 -163.7284)
		(end 157.7594 -163.7284)
		(width 0.381)
		(layer "In7.Cu")
		(net "POWER_SW3_PWR_CTR_12V")
	)
	(segment
		(start 154.8892 -160.8582)
		(end 151.8666 -160.8582)
		(width 0.381)
		(layer "In7.Cu")
		(net "POWER_SW3_PWR_CTR_12V")
	)
	(segment
		(start 151.8666 -160.8582)
		(end 150.2791 -159.2707)
		(width 0.381)
		(layer "In7.Cu")
		(net "POWER_SW3_PWR_CTR_12V")
	)
	(segment
		(start 164.0586 -164.2618)
		(end 163.5252 -163.7284)
		(width 0.381)
		(layer "In7.Cu")
		(net "POWER_SW3_PWR_CTR_12V")
	)
	(segment
		(start 133.831584 -154.0256)
		(end 132.1308 -154.0256)
		(width 0.381)
		(layer "In7.Cu")
		(net "POWER_SW3_PWR_CTR_12V")
	)
	(segment
		(start 131.0132 -152.908)
		(end 130.302 -152.908)
		(width 0.381)
		(layer "In7.Cu")
		(net "POWER_SW3_PWR_CTR_12V")
	)
	(segment
		(start 130.302 -152.908)
		(end 129.9464 -153.2636)
		(width 0.381)
		(layer "In7.Cu")
		(net "POWER_SW3_PWR_CTR_12V")
	)
	(segment
		(start 144.945608 -154.978608)
		(end 134.784592 -154.978608)
		(width 0.381)
		(layer "In7.Cu")
		(net "POWER_SW3_PWR_CTR_12V")
	)
	(segment
		(start 129.9464 -153.2636)
		(end 125.222 -153.2636)
		(width 0.381)
		(layer "In7.Cu")
		(net "POWER_SW3_PWR_CTR_12V")
	)
	(segment
		(start 125.222 -153.2636)
		(end 124.4092 -152.4508)
		(width 0.381)
		(layer "In7.Cu")
		(net "POWER_SW3_PWR_CTR_12V")
	)
	(segment
		(start 185.7248 -181.9148)
		(end 186.7408 -180.8988)
		(width 0.381)
		(layer "In7.Cu")
		(net "POWER_SW3_PWR_CTR_12V")
	)
	(segment
		(start 157.7594 -163.7284)
		(end 154.8892 -160.8582)
		(width 0.381)
		(layer "In7.Cu")
		(net "POWER_SW3_PWR_CTR_12V")
	)
	(segment
		(start 186.7408 -171.1198)
		(end 179.8828 -164.2618)
		(width 0.381)
		(layer "In7.Cu")
		(net "POWER_SW3_PWR_CTR_12V")
	)
	(segment
		(start 134.784592 -154.978608)
		(end 133.831584 -154.0256)
		(width 0.381)
		(layer "In7.Cu")
		(net "POWER_SW3_PWR_CTR_12V")
	)
	(segment
		(start 186.7408 -180.8988)
		(end 186.7408 -171.1198)
		(width 0.381)
		(layer "In7.Cu")
		(net "POWER_SW3_PWR_CTR_12V")
	)
	(segment
		(start 179.8828 -164.2618)
		(end 164.0586 -164.2618)
		(width 0.381)
		(layer "In7.Cu")
		(net "POWER_SW3_PWR_CTR_12V")
	)
	(segment
		(start 132.1308 -154.0256)
		(end 131.0132 -152.908)
		(width 0.381)
		(layer "In7.Cu")
		(net "POWER_SW3_PWR_CTR_12V")
	)
	(segment
		(start 149.2377 -159.2707)
		(end 144.945608 -154.978608)
		(width 0.381)
		(layer "In7.Cu")
		(net "POWER_SW3_PWR_CTR_12V")
	)
	(segment
		(start 110.51032 -150.38197)
		(end 110.51032 -150.795482)
		(width 0.381)
		(layer "F.Cu")
		(net "POWER_SW2_PWR_CTR_12V")
	)
	(segment
		(start 123.7742 -153.133044)
		(end 124.6124 -153.971244)
		(width 0.381)
		(layer "F.Cu")
		(net "POWER_SW2_PWR_CTR_12V")
	)
	(segment
		(start 123.7742 -152.6286)
		(end 123.7742 -153.133044)
		(width 0.381)
		(layer "F.Cu")
		(net "POWER_SW2_PWR_CTR_12V")
	)
	(segment
		(start 111.13516 -151.420322)
		(end 116.673122 -151.420322)
		(width 0.381)
		(layer "F.Cu")
		(net "POWER_SW2_PWR_CTR_12V")
	)
	(segment
		(start 120.2182 -152.3492)
		(end 122.1486 -152.3492)
		(width 0.381)
		(layer "F.Cu")
		(net "POWER_SW2_PWR_CTR_12V")
	)
	(segment
		(start 109.579918 -149.245066)
		(end 109.579918 -149.451568)
		(width 0.381)
		(layer "F.Cu")
		(net "POWER_SW2_PWR_CTR_12V")
	)
	(segment
		(start 117.4242 -152.1714)
		(end 120.0404 -152.1714)
		(width 0.254)
		(layer "F.Cu")
		(net "POWER_SW2_PWR_CTR_12V")
	)
	(segment
		(start 109.579918 -149.451568)
		(end 110.51032 -150.38197)
		(width 0.381)
		(layer "F.Cu")
		(net "POWER_SW2_PWR_CTR_12V")
	)
	(segment
		(start 124.6124 -153.971244)
		(end 124.6124 -154.466544)
		(width 0.381)
		(layer "F.Cu")
		(net "POWER_SW2_PWR_CTR_12V")
	)
	(segment
		(start 122.1486 -152.3492)
		(end 122.301 -152.1968)
		(width 0.381)
		(layer "F.Cu")
		(net "POWER_SW2_PWR_CTR_12V")
	)
	(segment
		(start 116.673122 -151.420322)
		(end 117.4242 -152.1714)
		(width 0.381)
		(layer "F.Cu")
		(net "POWER_SW2_PWR_CTR_12V")
	)
	(segment
		(start 123.3424 -152.1968)
		(end 123.7742 -152.6286)
		(width 0.381)
		(layer "F.Cu")
		(net "POWER_SW2_PWR_CTR_12V")
	)
	(segment
		(start 122.301 -152.1968)
		(end 123.3424 -152.1968)
		(width 0.381)
		(layer "F.Cu")
		(net "POWER_SW2_PWR_CTR_12V")
	)
	(segment
		(start 120.0404 -152.1714)
		(end 120.2182 -152.3492)
		(width 0.381)
		(layer "F.Cu")
		(net "POWER_SW2_PWR_CTR_12V")
	)
	(segment
		(start 110.51032 -150.795482)
		(end 111.13516 -151.420322)
		(width 0.381)
		(layer "F.Cu")
		(net "POWER_SW2_PWR_CTR_12V")
	)
	(via
		(at 124.6124 -154.466544)
		(size 0.508)
		(drill 0.254)
		(layers "F.Cu" "B.Cu")
		(net "POWER_SW2_PWR_CTR_12V")
	)
	(via
		(at 183.1594 -175.1076)
		(size 0.508)
		(drill 0.254)
		(layers "F.Cu" "B.Cu")
		(net "POWER_SW2_PWR_CTR_12V")
	)
	(segment
		(start 131.953 -155.2194)
		(end 133.8199 -157.0863)
		(width 0.381)
		(layer "In7.Cu")
		(net "POWER_SW2_PWR_CTR_12V")
	)
	(segment
		(start 163.91128 -165.38448)
		(end 164.2364 -165.7096)
		(width 0.381)
		(layer "In7.Cu")
		(net "POWER_SW2_PWR_CTR_12V")
	)
	(segment
		(start 145.9484 -160.7312)
		(end 150.622 -160.7312)
		(width 0.381)
		(layer "In7.Cu")
		(net "POWER_SW2_PWR_CTR_12V")
	)
	(segment
		(start 154.9019 -161.7599)
		(end 158.52648 -165.38448)
		(width 0.381)
		(layer "In7.Cu")
		(net "POWER_SW2_PWR_CTR_12V")
	)
	(segment
		(start 131.1656 -155.2194)
		(end 131.953 -155.2194)
		(width 0.381)
		(layer "In7.Cu")
		(net "POWER_SW2_PWR_CTR_12V")
	)
	(segment
		(start 133.8199 -157.0863)
		(end 136.3853 -157.0863)
		(width 0.381)
		(layer "In7.Cu")
		(net "POWER_SW2_PWR_CTR_12V")
	)
	(segment
		(start 151.6507 -161.7599)
		(end 154.9019 -161.7599)
		(width 0.381)
		(layer "In7.Cu")
		(net "POWER_SW2_PWR_CTR_12V")
	)
	(segment
		(start 179.324 -165.2016)
		(end 183.1594 -169.037)
		(width 0.381)
		(layer "In7.Cu")
		(net "POWER_SW2_PWR_CTR_12V")
	)
	(segment
		(start 164.2364 -165.7096)
		(end 166.37 -165.7096)
		(width 0.381)
		(layer "In7.Cu")
		(net "POWER_SW2_PWR_CTR_12V")
	)
	(segment
		(start 136.7536 -156.718)
		(end 141.9352 -156.718)
		(width 0.381)
		(layer "In7.Cu")
		(net "POWER_SW2_PWR_CTR_12V")
	)
	(segment
		(start 183.1594 -169.037)
		(end 183.1594 -175.1076)
		(width 0.381)
		(layer "In7.Cu")
		(net "POWER_SW2_PWR_CTR_12V")
	)
	(segment
		(start 136.3853 -157.0863)
		(end 136.7536 -156.718)
		(width 0.381)
		(layer "In7.Cu")
		(net "POWER_SW2_PWR_CTR_12V")
	)
	(segment
		(start 124.6124 -154.466544)
		(end 125.129544 -153.9494)
		(width 0.381)
		(layer "In7.Cu")
		(net "POWER_SW2_PWR_CTR_12V")
	)
	(segment
		(start 158.52648 -165.38448)
		(end 163.91128 -165.38448)
		(width 0.381)
		(layer "In7.Cu")
		(net "POWER_SW2_PWR_CTR_12V")
	)
	(segment
		(start 150.622 -160.7312)
		(end 151.6507 -161.7599)
		(width 0.381)
		(layer "In7.Cu")
		(net "POWER_SW2_PWR_CTR_12V")
	)
	(segment
		(start 166.878 -165.2016)
		(end 179.324 -165.2016)
		(width 0.381)
		(layer "In7.Cu")
		(net "POWER_SW2_PWR_CTR_12V")
	)
	(segment
		(start 125.129544 -153.9494)
		(end 129.8956 -153.9494)
		(width 0.381)
		(layer "In7.Cu")
		(net "POWER_SW2_PWR_CTR_12V")
	)
	(segment
		(start 141.9352 -156.718)
		(end 145.9484 -160.7312)
		(width 0.381)
		(layer "In7.Cu")
		(net "POWER_SW2_PWR_CTR_12V")
	)
	(segment
		(start 129.8956 -153.9494)
		(end 131.1656 -155.2194)
		(width 0.381)
		(layer "In7.Cu")
		(net "POWER_SW2_PWR_CTR_12V")
	)
	(segment
		(start 166.37 -165.7096)
		(end 166.878 -165.2016)
		(width 0.381)
		(layer "In7.Cu")
		(net "POWER_SW2_PWR_CTR_12V")
	)
	(segment
		(start 186.9186 -176.6062)
		(end 186.9186 -178.308)
		(width 0.381)
		(layer "F.Cu")
		(net "POWER_SW2_PWR_CTR_12V_R")
	)
	(segment
		(start 186.182 -175.8696)
		(end 186.9186 -176.6062)
		(width 0.381)
		(layer "F.Cu")
		(net "POWER_SW2_PWR_CTR_12V_R")
	)
	(segment
		(start 179.9082 -196.2404)
		(end 179.9082 -194.7164)
		(width 0.381)
		(layer "F.Cu")
		(net "POWER_SW2_PWR_CTR_12V_R")
	)
	(segment
		(start 181.6862 -192.9384)
		(end 185.5724 -192.9384)
		(width 0.381)
		(layer "F.Cu")
		(net "POWER_SW2_PWR_CTR_12V_R")
	)
	(segment
		(start 186.9186 -191.5922)
		(end 186.9186 -178.308)
		(width 0.381)
		(layer "F.Cu")
		(net "POWER_SW2_PWR_CTR_12V_R")
	)
	(segment
		(start 179.0446 -197.104)
		(end 179.9082 -196.2404)
		(width 0.381)
		(layer "F.Cu")
		(net "POWER_SW2_PWR_CTR_12V_R")
	)
	(segment
		(start 179.9082 -194.7164)
		(end 181.6862 -192.9384)
		(width 0.381)
		(layer "F.Cu")
		(net "POWER_SW2_PWR_CTR_12V_R")
	)
	(segment
		(start 177.6984 -197.104)
		(end 179.0446 -197.104)
		(width 0.381)
		(layer "F.Cu")
		(net "POWER_SW2_PWR_CTR_12V_R")
	)
	(segment
		(start 185.5724 -192.9384)
		(end 186.9186 -191.5922)
		(width 0.381)
		(layer "F.Cu")
		(net "POWER_SW2_PWR_CTR_12V_R")
	)
	(via
		(at 185.6232 -185.0136)
		(size 0.508)
		(drill 0.254)
		(layers "F.Cu" "B.Cu")
		(net "POWER_SW2_PWR_CTR_12V_R")
	)
	(via
		(at 177.6984 -197.104)
		(size 0.508)
		(drill 0.254)
		(layers "F.Cu" "B.Cu")
		(net "POWER_SW2_PWR_CTR_12V_R")
	)
	(segment
		(start 185.293 -185.3438)
		(end 185.6232 -185.0136)
		(width 0.381)
		(layer "B.Cu")
		(net "POWER_SW2_PWR_CTR_12V_R")
	)
	(segment
		(start 185.293 -185.78195)
		(end 185.293 -185.3438)
		(width 0.381)
		(layer "B.Cu")
		(net "POWER_SW2_PWR_CTR_12V_R")
	)
	(segment
		(start 177.710846 -202.7174)
		(end 178.015646 -203.0222)
		(width 0.381)
		(layer "B.Cu")
		(net "POWER_SW2_PWR_CTR_12V_R")
	)
	(segment
		(start 178.015646 -203.0222)
		(end 178.015646 -205.199488)
		(width 0.381)
		(layer "B.Cu")
		(net "POWER_SW2_PWR_CTR_12V_R")
	)
	(segment
		(start 177.6984 -197.104)
		(end 177.6984 -202.7174)
		(width 0.381)
		(layer "B.Cu")
		(net "POWER_SW2_PWR_CTR_12V_R")
	)
	(segment
		(start 177.6984 -202.7174)
		(end 177.710846 -202.7174)
		(width 0.381)
		(layer "B.Cu")
		(net "POWER_SW2_PWR_CTR_12V_R")
	)
	(segment
		(start 185.6232 -185.2168)
		(end 185.6232 -185.0136)
		(width 0.381)
		(layer "In2.Cu")
		(net "POWER_SW2_PWR_CTR_12V_R")
	)
	(segment
		(start 177.6984 -197.104)
		(end 177.6984 -193.1416)
		(width 0.381)
		(layer "In2.Cu")
		(net "POWER_SW2_PWR_CTR_12V_R")
	)
	(segment
		(start 177.6984 -193.1416)
		(end 185.6232 -185.2168)
		(width 0.381)
		(layer "In2.Cu")
		(net "POWER_SW2_PWR_CTR_12V_R")
	)
	(segment
		(start 9.130284 -162.644836)
		(end 15.042642 -162.644836)
		(width 0.1016)
		(layer "F.Cu")
		(net "UART_RI_P5_L_N")
	)
	(segment
		(start 15.78864 -163.390834)
		(end 15.78864 -163.599114)
		(width 0.1016)
		(layer "F.Cu")
		(net "UART_RI_P5_L_N")
	)
	(segment
		(start 8.458962 -163.316158)
		(end 9.130284 -162.644836)
		(width 0.1016)
		(layer "F.Cu")
		(net "UART_RI_P5_L_N")
	)
	(segment
		(start 8.458962 -164.062156)
		(end 8.458962 -163.316158)
		(width 0.1016)
		(layer "F.Cu")
		(net "UART_RI_P5_L_N")
	)
	(segment
		(start 15.042642 -162.644836)
		(end 15.78864 -163.390834)
		(width 0.1016)
		(layer "F.Cu")
		(net "UART_RI_P5_L_N")
	)
	(via
		(at 31.9024 -192.786)
		(size 0.508)
		(drill 0.254)
		(layers "F.Cu" "B.Cu")
		(net "UART_RI_P5_L_N")
	)
	(via
		(at 15.78864 -163.599114)
		(size 0.508)
		(drill 0.254)
		(layers "F.Cu" "B.Cu")
		(net "UART_RI_P5_L_N")
	)
	(segment
		(start 32.2326 -192.4558)
		(end 32.2326 -191.9986)
		(width 0.1016)
		(layer "B.Cu")
		(net "UART_RI_P5_L_N")
	)
	(segment
		(start 32.23895 -191.99225)
		(end 32.23895 -188.7728)
		(width 0.1016)
		(layer "B.Cu")
		(net "UART_RI_P5_L_N")
	)
	(segment
		(start 31.9024 -192.786)
		(end 32.2326 -192.4558)
		(width 0.1016)
		(layer "B.Cu")
		(net "UART_RI_P5_L_N")
	)
	(segment
		(start 32.2326 -191.9986)
		(end 32.23895 -191.99225)
		(width 0.1016)
		(layer "B.Cu")
		(net "UART_RI_P5_L_N")
	)
	(segment
		(start 31.9024 -192.786)
		(end 30.925262 -192.786)
		(width 0.1143)
		(layer "In2.Cu")
		(net "UART_RI_P5_L_N")
	)
	(segment
		(start 20.91817 -175.772318)
		(end 20.91817 -168.458388)
		(width 0.1143)
		(layer "In2.Cu")
		(net "UART_RI_P5_L_N")
	)
	(segment
		(start 20.91817 -168.458388)
		(end 16.058896 -163.599114)
		(width 0.1143)
		(layer "In2.Cu")
		(net "UART_RI_P5_L_N")
	)
	(segment
		(start 20.604988 -176.0855)
		(end 20.91817 -175.772318)
		(width 0.1143)
		(layer "In2.Cu")
		(net "UART_RI_P5_L_N")
	)
	(segment
		(start 16.058896 -163.599114)
		(end 15.78864 -163.599114)
		(width 0.1143)
		(layer "In2.Cu")
		(net "UART_RI_P5_L_N")
	)
	(segment
		(start 20.604988 -182.465726)
		(end 20.604988 -176.0855)
		(width 0.1143)
		(layer "In2.Cu")
		(net "UART_RI_P5_L_N")
	)
	(segment
		(start 30.925262 -192.786)
		(end 20.604988 -182.465726)
		(width 0.1143)
		(layer "In2.Cu")
		(net "UART_RI_P5_L_N")
	)
	(segment
		(start 123.978924 -43.655234)
		(end 123.713494 -43.389804)
		(width 0.1016)
		(layer "F.Cu")
		(net "LPC_CPU_NODE1_LAD1_SIO")
	)
	(segment
		(start 123.713494 -43.389804)
		(end 122.451622 -43.389804)
		(width 0.1016)
		(layer "F.Cu")
		(net "LPC_CPU_NODE1_LAD1_SIO")
	)
	(segment
		(start 125.39218 -43.655234)
		(end 123.978924 -43.655234)
		(width 0.1016)
		(layer "F.Cu")
		(net "LPC_CPU_NODE1_LAD1_SIO")
	)
	(via
		(at 125.39218 -43.655234)
		(size 0.508)
		(drill 0.254)
		(layers "F.Cu" "B.Cu")
		(net "LPC_CPU_NODE1_LAD1_SIO")
	)
	(segment
		(start 122.49785 -43.716702)
		(end 125.330712 -43.716702)
		(width 0.1016)
		(layer "B.Cu")
		(net "LPC_CPU_NODE1_LAD1_SIO")
	)
	(segment
		(start 125.330712 -43.716702)
		(end 125.39218 -43.655234)
		(width 0.1016)
		(layer "B.Cu")
		(net "LPC_CPU_NODE1_LAD1_SIO")
	)
	(via
		(at 170.00728 -199.09663)
		(size 0.508)
		(drill 0.254)
		(layers "F.Cu" "B.Cu")
		(net "Net_221")
	)
	(segment
		(start 169.58564 -199.51827)
		(end 169.58564 -200.039478)
		(width 0.1016)
		(layer "B.Cu")
		(net "Net_221")
	)
	(segment
		(start 170.015662 -202.311508)
		(end 170.015662 -205.199488)
		(width 0.1016)
		(layer "B.Cu")
		(net "Net_221")
	)
	(segment
		(start 169.58564 -200.039478)
		(end 169.583862 -200.039478)
		(width 0.1016)
		(layer "B.Cu")
		(net "Net_221")
	)
	(segment
		(start 169.583862 -201.879708)
		(end 170.015662 -202.311508)
		(width 0.1016)
		(layer "B.Cu")
		(net "Net_221")
	)
	(segment
		(start 170.00728 -199.09663)
		(end 169.58564 -199.51827)
		(width 0.1016)
		(layer "B.Cu")
		(net "Net_221")
	)
	(segment
		(start 169.583862 -200.039478)
		(end 169.583862 -201.879708)
		(width 0.1016)
		(layer "B.Cu")
		(net "Net_221")
	)
	(segment
		(start 172.015658 -205.199488)
		(end 172.015658 -199.759316)
		(width 0.1016)
		(layer "F.Cu")
		(net "Net_222")
	)
	(via
		(at 172.015658 -199.759316)
		(size 0.508)
		(drill 0.254)
		(layers "F.Cu" "B.Cu")
		(net "Net_222")
	)
	(segment
		(start 171.01566 -205.199488)
		(end 171.01566 -198.84517)
		(width 0.1016)
		(layer "F.Cu")
		(net "Net_223")
	)
	(via
		(at 171.01566 -198.84517)
		(size 0.508)
		(drill 0.254)
		(layers "F.Cu" "B.Cu")
		(net "Net_223")
	)
	(segment
		(start 168.77284 -199.61606)
		(end 169.447464 -200.290684)
		(width 0.1016)
		(layer "F.Cu")
		(net "Net_224")
	)
	(segment
		(start 169.447464 -201.723498)
		(end 169.015664 -202.155298)
		(width 0.1016)
		(layer "F.Cu")
		(net "Net_224")
	)
	(segment
		(start 169.015664 -202.155298)
		(end 169.015664 -204.699616)
		(width 0.1016)
		(layer "F.Cu")
		(net "Net_224")
	)
	(segment
		(start 169.447464 -200.290684)
		(end 169.447464 -201.723498)
		(width 0.1016)
		(layer "F.Cu")
		(net "Net_224")
	)
	(via
		(at 168.77284 -199.61606)
		(size 0.508)
		(drill 0.254)
		(layers "F.Cu" "B.Cu")
		(net "Net_224")
	)
	(via
		(at 172.08246 -198.656956)
		(size 0.508)
		(drill 0.254)
		(layers "F.Cu" "B.Cu")
		(net "Net_225")
	)
	(segment
		(start 172.56506 -199.486012)
		(end 172.08246 -199.003412)
		(width 0.1016)
		(layer "B.Cu")
		(net "Net_225")
	)
	(segment
		(start 173.015656 -205.199488)
		(end 173.015656 -202.9841)
		(width 0.1016)
		(layer "B.Cu")
		(net "Net_225")
	)
	(segment
		(start 172.56506 -202.533504)
		(end 172.56506 -199.486012)
		(width 0.1016)
		(layer "B.Cu")
		(net "Net_225")
	)
	(segment
		(start 172.08246 -199.003412)
		(end 172.08246 -198.656956)
		(width 0.1016)
		(layer "B.Cu")
		(net "Net_225")
	)
	(segment
		(start 173.015656 -202.9841)
		(end 172.56506 -202.533504)
		(width 0.1016)
		(layer "B.Cu")
		(net "Net_225")
	)
	(via
		(at 171.80306 -197.723506)
		(size 0.508)
		(drill 0.254)
		(layers "F.Cu" "B.Cu")
		(net "Net_226")
	)
	(segment
		(start 172.015658 -202.69708)
		(end 171.53382 -202.215242)
		(width 0.1016)
		(layer "B.Cu")
		(net "Net_226")
	)
	(segment
		(start 171.53382 -197.992746)
		(end 171.80306 -197.723506)
		(width 0.1016)
		(layer "B.Cu")
		(net "Net_226")
	)
	(segment
		(start 171.53382 -202.215242)
		(end 171.53382 -197.992746)
		(width 0.1016)
		(layer "B.Cu")
		(net "Net_226")
	)
	(segment
		(start 172.015658 -205.199488)
		(end 172.015658 -202.69708)
		(width 0.1016)
		(layer "B.Cu")
		(net "Net_226")
	)
	(segment
		(start -9.336532 -33.836102)
		(end -8.886444 -33.836102)
		(width 0.1016)
		(layer "F.Cu")
		(net "THRU_85_OHM")
	)
	(segment
		(start -8.886444 -189.609222)
		(end -8.886444 -186.565794)
		(width 0.1016)
		(layer "F.Cu")
		(net "IN3_85OHM")
	)
	(segment
		(start -9.336532 -189.609222)
		(end -9.336532 -186.558682)
		(width 0.1016)
		(layer "F.Cu")
		(net "IN3_85OHM")
	)
	(segment
		(start -9.336532 -186.558682)
		(end -10.123932 -185.771282)
		(width 0.1016)
		(layer "F.Cu")
		(net "IN3_85OHM")
	)
	(segment
		(start -8.886444 -186.565794)
		(end -8.091932 -185.771282)
		(width 0.1016)
		(layer "F.Cu")
		(net "IN3_85OHM")
	)
	(via
		(at -8.091932 -185.771282)
		(size 0.508)
		(drill 0.254)
		(layers "F.Cu" "B.Cu")
		(net "IN3_85OHM")
	)
	(via
		(at -10.123932 -185.771282)
		(size 0.508)
		(drill 0.254)
		(layers "F.Cu" "B.Cu")
		(net "IN3_85OHM")
	)
	(segment
		(start -11.34364 -148.407374)
		(end -12.92352 -139.372848)
		(width 0.127)
		(layer "In7.Cu")
		(net "IN3_85OHM")
	)
	(segment
		(start -10.81278 -127.412242)
		(end -13.20673 -113.87074)
		(width 0.127)
		(layer "In7.Cu")
		(net "IN3_85OHM")
	)
	(segment
		(start -11.219688 -100.295202)
		(end -12.657582 -108.45292)
		(width 0.127)
		(layer "In7.Cu")
		(net "IN3_85OHM")
	)
	(segment
		(start -12.37234 -154.183334)
		(end -11.853672 -151.269954)
		(width 0.127)
		(layer "In7.Cu")
		(net "IN3_85OHM")
	)
	(segment
		(start -10.91438 -175.016922)
		(end -9.815576 -168.797986)
		(width 0.127)
		(layer "In7.Cu")
		(net "IN3_85OHM")
	)
	(segment
		(start -10.123932 -185.771282)
		(end -9.243568 -184.890918)
		(width 0.1143)
		(layer "In7.Cu")
		(net "IN3_85OHM")
	)
	(segment
		(start -9.243568 -184.890918)
		(end -9.243568 -184.498996)
		(width 0.127)
		(layer "In7.Cu")
		(net "IN3_85OHM")
	)
	(segment
		(start -13.261848 -111.880142)
		(end -12.910058 -113.87074)
		(width 0.127)
		(layer "In7.Cu")
		(net "IN3_85OHM")
	)
	(segment
		(start -12.41298 -84.759292)
		(end -12.41298 -84.336382)
		(width 0.127)
		(layer "In7.Cu")
		(net "IN3_85OHM")
	)
	(segment
		(start -11.046968 -148.407882)
		(end -12.075668 -154.183842)
		(width 0.127)
		(layer "In7.Cu")
		(net "IN3_85OHM")
	)
	(segment
		(start -11.51636 -100.295202)
		(end -13.335 -89.964768)
		(width 0.127)
		(layer "In7.Cu")
		(net "IN3_85OHM")
	)
	(segment
		(start -13.20673 -113.87074)
		(end -13.55852 -111.880142)
		(width 0.127)
		(layer "In7.Cu")
		(net "IN3_85OHM")
	)
	(segment
		(start -13.55852 -111.880142)
		(end -12.954254 -108.45292)
		(width 0.127)
		(layer "In7.Cu")
		(net "IN3_85OHM")
	)
	(segment
		(start -10.617708 -175.016922)
		(end -8.951468 -184.473342)
		(width 0.127)
		(layer "In7.Cu")
		(net "IN3_85OHM")
	)
	(segment
		(start -12.626848 -139.373102)
		(end -11.046968 -148.407882)
		(width 0.127)
		(layer "In7.Cu")
		(net "IN3_85OHM")
	)
	(segment
		(start -9.243568 -184.498996)
		(end -10.91438 -175.016922)
		(width 0.127)
		(layer "In7.Cu")
		(net "IN3_85OHM")
	)
	(segment
		(start -12.12088 -84.7852)
		(end -13.038328 -89.965022)
		(width 0.127)
		(layer "In7.Cu")
		(net "IN3_85OHM")
	)
	(segment
		(start -12.12088 -84.336382)
		(end -12.12088 -84.7852)
		(width 0.127)
		(layer "In7.Cu")
		(net "IN3_85OHM")
	)
	(segment
		(start -9.518904 -168.79824)
		(end -10.617708 -175.016922)
		(width 0.127)
		(layer "In7.Cu")
		(net "IN3_85OHM")
	)
	(segment
		(start -13.335 -89.964768)
		(end -12.41298 -84.759292)
		(width 0.127)
		(layer "In7.Cu")
		(net "IN3_85OHM")
	)
	(segment
		(start -13.038328 -89.965022)
		(end -11.219688 -100.295202)
		(width 0.127)
		(layer "In7.Cu")
		(net "IN3_85OHM")
	)
	(segment
		(start -12.41298 -84.336382)
		(end -12.12088 -84.336382)
		(width 0.1016)
		(layer "In7.Cu")
		(net "IN3_85OHM")
	)
	(segment
		(start -12.075668 -154.183842)
		(end -9.518904 -168.79824)
		(width 0.127)
		(layer "In7.Cu")
		(net "IN3_85OHM")
	)
	(segment
		(start -12.92352 -139.372848)
		(end -10.81278 -127.412242)
		(width 0.127)
		(layer "In7.Cu")
		(net "IN3_85OHM")
	)
	(segment
		(start -8.951468 -184.911746)
		(end -8.091932 -185.771282)
		(width 0.1143)
		(layer "In7.Cu")
		(net "IN3_85OHM")
	)
	(segment
		(start -11.853672 -151.269954)
		(end -11.34364 -148.407374)
		(width 0.127)
		(layer "In7.Cu")
		(net "IN3_85OHM")
	)
	(segment
		(start -12.657582 -108.45292)
		(end -13.261848 -111.880142)
		(width 0.127)
		(layer "In7.Cu")
		(net "IN3_85OHM")
	)
	(segment
		(start -9.815576 -168.797986)
		(end -12.37234 -154.183334)
		(width 0.127)
		(layer "In7.Cu")
		(net "IN3_85OHM")
	)
	(segment
		(start -10.516108 -127.412242)
		(end -12.626848 -139.373102)
		(width 0.127)
		(layer "In7.Cu")
		(net "IN3_85OHM")
	)
	(segment
		(start -8.951468 -184.473342)
		(end -8.951468 -184.911746)
		(width 0.127)
		(layer "In7.Cu")
		(net "IN3_85OHM")
	)
	(segment
		(start -12.954254 -108.45292)
		(end -11.51636 -100.295202)
		(width 0.127)
		(layer "In7.Cu")
		(net "IN3_85OHM")
	)
	(segment
		(start -12.910058 -113.87074)
		(end -10.516108 -127.412242)
		(width 0.127)
		(layer "In7.Cu")
		(net "IN3_85OHM")
	)
	(segment
		(start -12.451334 -113.87074)
		(end -11.032236 -121.942098)
		(width 0.127)
		(layer "B.Cu")
		(net "BOT_85OHM")
	)
	(segment
		(start -13.245084 -109.356906)
		(end -12.451334 -113.87074)
		(width 0.127)
		(layer "B.Cu")
		(net "BOT_85OHM")
	)
	(segment
		(start -8.886444 -61.337698)
		(end -8.956548 -61.407802)
		(width 0.127)
		(layer "B.Cu")
		(net "BOT_85OHM")
	)
	(segment
		(start -10.787888 -162.563048)
		(end -14.650974 -140.693902)
		(width 0.127)
		(layer "B.Cu")
		(net "BOT_85OHM")
	)
	(segment
		(start -8.956548 -63.907162)
		(end -7.099808 -74.468482)
		(width 0.127)
		(layer "B.Cu")
		(net "BOT_85OHM")
	)
	(segment
		(start -14.650974 -140.693902)
		(end -11.866372 -124.914406)
		(width 0.127)
		(layer "B.Cu")
		(net "BOT_85OHM")
	)
	(segment
		(start -8.956548 -61.407802)
		(end -8.956548 -63.907162)
		(width 0.127)
		(layer "B.Cu")
		(net "BOT_85OHM")
	)
	(segment
		(start -9.256776 -63.959994)
		(end -9.261348 -63.933832)
		(width 0.127)
		(layer "B.Cu")
		(net "BOT_85OHM")
	)
	(segment
		(start -9.336532 -61.337698)
		(end -9.336532 -61.095382)
		(width 0.127)
		(layer "B.Cu")
		(net "BOT_85OHM")
	)
	(segment
		(start -7.099808 -74.468482)
		(end -13.085826 -108.45292)
		(width 0.127)
		(layer "B.Cu")
		(net "BOT_85OHM")
	)
	(segment
		(start -12.761468 -113.87074)
		(end -13.554964 -109.358176)
		(width 0.127)
		(layer "B.Cu")
		(net "BOT_85OHM")
	)
	(segment
		(start -13.554964 -109.358176)
		(end -13.395452 -108.45292)
		(width 0.127)
		(layer "B.Cu")
		(net "BOT_85OHM")
	)
	(segment
		(start -10.48131 -163.048442)
		(end -10.787888 -163.048442)
		(width 0.1016)
		(layer "B.Cu")
		(net "BOT_85OHM")
	)
	(segment
		(start -10.48131 -162.545522)
		(end -10.48131 -163.048442)
		(width 0.127)
		(layer "B.Cu")
		(net "BOT_85OHM")
	)
	(segment
		(start -8.886444 -61.095382)
		(end -8.886444 -61.337698)
		(width 0.127)
		(layer "B.Cu")
		(net "BOT_85OHM")
	)
	(segment
		(start -13.395452 -108.45292)
		(end -7.409434 -74.468482)
		(width 0.127)
		(layer "B.Cu")
		(net "BOT_85OHM")
	)
	(segment
		(start -7.409434 -74.468482)
		(end -9.256776 -63.959994)
		(width 0.127)
		(layer "B.Cu")
		(net "BOT_85OHM")
	)
	(segment
		(start -10.787888 -163.048442)
		(end -10.787888 -162.563048)
		(width 0.127)
		(layer "B.Cu")
		(net "BOT_85OHM")
	)
	(segment
		(start -13.085826 -108.45292)
		(end -13.245084 -109.356906)
		(width 0.127)
		(layer "B.Cu")
		(net "BOT_85OHM")
	)
	(segment
		(start -14.341348 -140.693902)
		(end -10.48131 -162.545522)
		(width 0.127)
		(layer "B.Cu")
		(net "BOT_85OHM")
	)
	(segment
		(start -11.032236 -121.942098)
		(end -14.341348 -140.693902)
		(width 0.127)
		(layer "B.Cu")
		(net "BOT_85OHM")
	)
	(segment
		(start -11.866372 -124.914406)
		(end -11.342116 -121.943876)
		(width 0.127)
		(layer "B.Cu")
		(net "BOT_85OHM")
	)
	(segment
		(start -9.261348 -63.933832)
		(end -9.261348 -61.412882)
		(width 0.127)
		(layer "B.Cu")
		(net "BOT_85OHM")
	)
	(segment
		(start -11.342116 -121.943876)
		(end -12.761468 -113.87074)
		(width 0.127)
		(layer "B.Cu")
		(net "BOT_85OHM")
	)
	(segment
		(start -9.261348 -61.412882)
		(end -9.336532 -61.337698)
		(width 0.127)
		(layer "B.Cu")
		(net "BOT_85OHM")
	)
	(segment
		(start -8.956548 -61.407802)
		(end -8.956548 -63.907162)
		(width 0.127)
		(layer "F.Cu")
		(net "TOP_85OHM")
	)
	(segment
		(start -9.256776 -63.959994)
		(end -9.261348 -63.933832)
		(width 0.127)
		(layer "F.Cu")
		(net "TOP_85OHM")
	)
	(segment
		(start -8.956548 -63.907162)
		(end -7.099808 -74.468482)
		(width 0.127)
		(layer "F.Cu")
		(net "TOP_85OHM")
	)
	(segment
		(start -11.866372 -124.914406)
		(end -11.342116 -121.943876)
		(width 0.127)
		(layer "F.Cu")
		(net "TOP_85OHM")
	)
	(segment
		(start -10.48131 -162.545522)
		(end -10.48131 -163.048442)
		(width 0.127)
		(layer "F.Cu")
		(net "TOP_85OHM")
	)
	(segment
		(start -8.886444 -61.337698)
		(end -8.956548 -61.407802)
		(width 0.127)
		(layer "F.Cu")
		(net "TOP_85OHM")
	)
	(segment
		(start -13.245084 -109.356906)
		(end -11.032236 -121.942098)
		(width 0.127)
		(layer "F.Cu")
		(net "TOP_85OHM")
	)
	(segment
		(start -7.099808 -74.468482)
		(end -13.245084 -109.356906)
		(width 0.127)
		(layer "F.Cu")
		(net "TOP_85OHM")
	)
	(segment
		(start -8.886444 -61.095382)
		(end -8.886444 -61.337698)
		(width 0.127)
		(layer "F.Cu")
		(net "TOP_85OHM")
	)
	(segment
		(start -11.032236 -121.942098)
		(end -14.341348 -140.693902)
		(width 0.127)
		(layer "F.Cu")
		(net "TOP_85OHM")
	)
	(segment
		(start -14.650974 -140.693902)
		(end -11.866372 -124.914406)
		(width 0.127)
		(layer "F.Cu")
		(net "TOP_85OHM")
	)
	(segment
		(start -10.787888 -163.048442)
		(end -10.787888 -162.563048)
		(width 0.127)
		(layer "F.Cu")
		(net "TOP_85OHM")
	)
	(segment
		(start -14.341348 -140.693902)
		(end -10.48131 -162.545522)
		(width 0.127)
		(layer "F.Cu")
		(net "TOP_85OHM")
	)
	(segment
		(start -11.342116 -121.943876)
		(end -13.554964 -109.358176)
		(width 0.127)
		(layer "F.Cu")
		(net "TOP_85OHM")
	)
	(segment
		(start -10.787888 -162.563048)
		(end -14.650974 -140.693902)
		(width 0.127)
		(layer "F.Cu")
		(net "TOP_85OHM")
	)
	(segment
		(start -13.554964 -109.358176)
		(end -7.409434 -74.468482)
		(width 0.127)
		(layer "F.Cu")
		(net "TOP_85OHM")
	)
	(segment
		(start -10.48131 -163.048442)
		(end -10.787888 -163.048442)
		(width 0.1016)
		(layer "F.Cu")
		(net "TOP_85OHM")
	)
	(segment
		(start -9.336532 -61.337698)
		(end -9.336532 -61.095382)
		(width 0.127)
		(layer "F.Cu")
		(net "TOP_85OHM")
	)
	(segment
		(start -7.409434 -74.468482)
		(end -9.256776 -63.959994)
		(width 0.127)
		(layer "F.Cu")
		(net "TOP_85OHM")
	)
	(segment
		(start -9.261348 -61.412882)
		(end -9.336532 -61.337698)
		(width 0.127)
		(layer "F.Cu")
		(net "TOP_85OHM")
	)
	(segment
		(start -9.261348 -63.933832)
		(end -9.261348 -61.412882)
		(width 0.127)
		(layer "F.Cu")
		(net "TOP_85OHM")
	)
	(segment
		(start 126.781052 -138.84275)
		(end 127.390652 -138.84275)
		(width 0.127)
		(layer "F.Cu")
		(net "CLK_100M_PCIE_SW_NODE1_C_DN")
	)
	(segment
		(start 126.781052 -138.83767)
		(end 126.781052 -138.84275)
		(width 0.127)
		(layer "F.Cu")
		(net "CLK_100M_PCIE_SW_NODE1_C_DN")
	)
	(segment
		(start 126.518924 -138.575542)
		(end 126.781052 -138.83767)
		(width 0.127)
		(layer "F.Cu")
		(net "CLK_100M_PCIE_SW_NODE1_C_DN")
	)
	(segment
		(start 125.787912 -138.575542)
		(end 126.518924 -138.575542)
		(width 0.127)
		(layer "F.Cu")
		(net "CLK_100M_PCIE_SW_NODE1_C_DN")
	)
	(segment
		(start 127.390652 -138.84275)
		(end 127.847852 -138.38555)
		(width 0.127)
		(layer "F.Cu")
		(net "CLK_100M_PCIE_SW_NODE1_C_DN")
	)
	(via
		(at 127.847852 -138.38555)
		(size 0.508)
		(drill 0.254)
		(layers "F.Cu" "B.Cu")
		(net "CLK_100M_PCIE_SW_NODE1_C_DN")
	)
	(segment
		(start 128.477772 -139.10691)
		(end 128.127252 -139.10691)
		(width 0.127)
		(layer "B.Cu")
		(net "CLK_100M_PCIE_SW_NODE1_C_DN")
	)
	(segment
		(start 128.762252 -137.14476)
		(end 129.117852 -137.50036)
		(width 0.127)
		(layer "B.Cu")
		(net "CLK_100M_PCIE_SW_NODE1_C_DN")
	)
	(segment
		(start 129.117852 -137.50036)
		(end 129.117852 -138.46683)
		(width 0.127)
		(layer "B.Cu")
		(net "CLK_100M_PCIE_SW_NODE1_C_DN")
	)
	(segment
		(start 127.847852 -138.82751)
		(end 127.847852 -138.38555)
		(width 0.127)
		(layer "B.Cu")
		(net "CLK_100M_PCIE_SW_NODE1_C_DN")
	)
	(segment
		(start 128.127252 -139.10691)
		(end 127.847852 -138.82751)
		(width 0.127)
		(layer "B.Cu")
		(net "CLK_100M_PCIE_SW_NODE1_C_DN")
	)
	(segment
		(start 129.117852 -138.46683)
		(end 128.477772 -139.10691)
		(width 0.127)
		(layer "B.Cu")
		(net "CLK_100M_PCIE_SW_NODE1_C_DN")
	)
	(segment
		(start 127.339852 -139.14755)
		(end 127.847852 -139.65555)
		(width 0.127)
		(layer "F.Cu")
		(net "CLK_100M_PCIE_SW_NODE1_C_DP")
	)
	(segment
		(start 126.755652 -139.14755)
		(end 127.339852 -139.14755)
		(width 0.127)
		(layer "F.Cu")
		(net "CLK_100M_PCIE_SW_NODE1_C_DP")
	)
	(segment
		(start 126.52756 -139.375642)
		(end 126.755652 -139.14755)
		(width 0.127)
		(layer "F.Cu")
		(net "CLK_100M_PCIE_SW_NODE1_C_DP")
	)
	(segment
		(start 125.787912 -139.375642)
		(end 126.52756 -139.375642)
		(width 0.127)
		(layer "F.Cu")
		(net "CLK_100M_PCIE_SW_NODE1_C_DP")
	)
	(via
		(at 127.847852 -139.65555)
		(size 0.508)
		(drill 0.254)
		(layers "F.Cu" "B.Cu")
		(net "CLK_100M_PCIE_SW_NODE1_C_DP")
	)
	(segment
		(start 129.422652 -137.50036)
		(end 129.422652 -138.593322)
		(width 0.127)
		(layer "B.Cu")
		(net "CLK_100M_PCIE_SW_NODE1_C_DP")
	)
	(segment
		(start 128.091692 -139.41171)
		(end 127.847852 -139.65555)
		(width 0.127)
		(layer "B.Cu")
		(net "CLK_100M_PCIE_SW_NODE1_C_DP")
	)
	(segment
		(start 129.778252 -137.14476)
		(end 129.422652 -137.50036)
		(width 0.127)
		(layer "B.Cu")
		(net "CLK_100M_PCIE_SW_NODE1_C_DP")
	)
	(segment
		(start 129.422652 -138.593322)
		(end 128.604264 -139.41171)
		(width 0.127)
		(layer "B.Cu")
		(net "CLK_100M_PCIE_SW_NODE1_C_DP")
	)
	(segment
		(start 128.604264 -139.41171)
		(end 128.091692 -139.41171)
		(width 0.127)
		(layer "B.Cu")
		(net "CLK_100M_PCIE_SW_NODE1_C_DP")
	)
	(segment
		(start 74.141838 -140.85951)
		(end 74.941938 -140.85951)
		(width 0.1016)
		(layer "F.Cu")
		(net "N3975090766")
	)
	(via
		(at 74.941938 -140.85951)
		(size 0.508)
		(drill 0.254)
		(layers "F.Cu" "B.Cu")
		(net "N3975090766")
	)
	(segment
		(start 76.415392 -141.288262)
		(end 75.37069 -141.288262)
		(width 0.1016)
		(layer "B.Cu")
		(net "N3975090766")
	)
	(segment
		(start 75.37069 -141.288262)
		(end 74.941938 -140.85951)
		(width 0.1016)
		(layer "B.Cu")
		(net "N3975090766")
	)
	(segment
		(start 70.941692 -139.259818)
		(end 71.341488 -139.659614)
		(width 0.1016)
		(layer "F.Cu")
		(net "N3975090767")
	)
	(segment
		(start 70.941692 -139.259564)
		(end 70.941692 -139.259818)
		(width 0.1016)
		(layer "F.Cu")
		(net "N3975090767")
	)
	(via
		(at 71.341488 -139.659614)
		(size 0.49022)
		(drill 0.254)
		(layers "F.Cu" "B.Cu")
		(net "N3975090767")
	)
	(segment
		(start 72.178672 -139.190222)
		(end 71.70928 -139.659614)
		(width 0.1016)
		(layer "B.Cu")
		(net "N3975090767")
	)
	(segment
		(start 71.70928 -139.659614)
		(end 71.341488 -139.659614)
		(width 0.1016)
		(layer "B.Cu")
		(net "N3975090767")
	)
	(segment
		(start 73.341738 -140.05941)
		(end 73.341992 -140.05941)
		(width 0.1016)
		(layer "F.Cu")
		(net "N3975090765")
	)
	(segment
		(start 73.341992 -140.05941)
		(end 73.741788 -139.659614)
		(width 0.1016)
		(layer "F.Cu")
		(net "N3975090765")
	)
	(via
		(at 73.741788 -139.659614)
		(size 0.49022)
		(drill 0.254)
		(layers "F.Cu" "B.Cu")
		(net "N3975090765")
	)
	(segment
		(start 74.99604 -139.659614)
		(end 73.741788 -139.659614)
		(width 0.1016)
		(layer "B.Cu")
		(net "N3975090765")
	)
	(segment
		(start 75.269852 -139.385802)
		(end 74.99604 -139.659614)
		(width 0.1016)
		(layer "B.Cu")
		(net "N3975090765")
	)
	(segment
		(start 69.741288 -141.260068)
		(end 69.341746 -141.65961)
		(width 0.1016)
		(layer "F.Cu")
		(net "N3975090755")
	)
	(via
		(at 69.741288 -141.260068)
		(size 0.49022)
		(drill 0.254)
		(layers "F.Cu" "B.Cu")
		(net "N3975090755")
	)
	(segment
		(start 69.732652 -142.880842)
		(end 69.741288 -142.821406)
		(width 0.1016)
		(layer "B.Cu")
		(net "N3975090755")
	)
	(segment
		(start 69.741288 -142.821406)
		(end 69.741288 -141.260068)
		(width 0.1016)
		(layer "B.Cu")
		(net "N3975090755")
	)
	(segment
		(start 135.737854 -152.968452)
		(end 135.902192 -153.13279)
		(width 0.1016)
		(layer "F.Cu")
		(net "PCIE_SW_RST_N")
	)
	(segment
		(start 135.798052 -153.23693)
		(end 135.902192 -153.13279)
		(width 0.1016)
		(layer "F.Cu")
		(net "PCIE_SW_RST_N")
	)
	(segment
		(start 135.798052 -154.4193)
		(end 135.798052 -153.23693)
		(width 0.1016)
		(layer "F.Cu")
		(net "PCIE_SW_RST_N")
	)
	(segment
		(start 135.737854 -151.32558)
		(end 135.737854 -152.968452)
		(width 0.1016)
		(layer "F.Cu")
		(net "PCIE_SW_RST_N")
	)
	(via
		(at 135.902192 -153.13279)
		(size 0.508)
		(drill 0.254)
		(layers "F.Cu" "B.Cu")
		(net "PCIE_SW_RST_N")
	)
	(segment
		(start 135.627872 -155.941268)
		(end 135.798052 -155.771088)
		(width 0.1016)
		(layer "F.Cu")
		(net "FM_CPLD_PCIE_SW_PERST_L")
	)
	(segment
		(start 135.626348 -155.941268)
		(end 135.627872 -155.941268)
		(width 0.1016)
		(layer "F.Cu")
		(net "FM_CPLD_PCIE_SW_PERST_L")
	)
	(segment
		(start 135.798052 -155.771088)
		(end 135.798052 -155.2194)
		(width 0.1016)
		(layer "F.Cu")
		(net "FM_CPLD_PCIE_SW_PERST_L")
	)
	(segment
		(start 135.23468 -156.332936)
		(end 135.626348 -155.941268)
		(width 0.1016)
		(layer "F.Cu")
		(net "FM_CPLD_PCIE_SW_PERST_L")
	)
	(segment
		(start 184.35193 -118.365524)
		(end 184.51322 -118.204234)
		(width 0.1016)
		(layer "F.Cu")
		(net "FM_CPLD_PCIE_SW_PERST_L")
	)
	(segment
		(start 181.01056 -118.365524)
		(end 184.35193 -118.365524)
		(width 0.1016)
		(layer "F.Cu")
		(net "FM_CPLD_PCIE_SW_PERST_L")
	)
	(via
		(at 135.23468 -156.332936)
		(size 0.508)
		(drill 0.254)
		(layers "F.Cu" "B.Cu")
		(net "FM_CPLD_PCIE_SW_PERST_L")
	)
	(via
		(at 184.51322 -118.204234)
		(size 0.508)
		(drill 0.254)
		(layers "F.Cu" "B.Cu")
		(net "FM_CPLD_PCIE_SW_PERST_L")
	)
	(via
		(at 161.54654 -119.37873)
		(size 0.508)
		(drill 0.254)
		(layers "F.Cu" "B.Cu")
		(net "FM_CPLD_PCIE_SW_PERST_L")
	)
	(segment
		(start 141.101826 -156.401262)
		(end 135.303006 -156.401262)
		(width 0.1143)
		(layer "In2.Cu")
		(net "FM_CPLD_PCIE_SW_PERST_L")
	)
	(segment
		(start 149.031452 -138.04646)
		(end 149.031452 -140.452348)
		(width 0.1143)
		(layer "In2.Cu")
		(net "FM_CPLD_PCIE_SW_PERST_L")
	)
	(segment
		(start 148.78431 -140.69949)
		(end 148.78431 -142.775432)
		(width 0.1143)
		(layer "In2.Cu")
		(net "FM_CPLD_PCIE_SW_PERST_L")
	)
	(segment
		(start 151.34463 -135.733282)
		(end 149.031452 -138.04646)
		(width 0.1143)
		(layer "In2.Cu")
		(net "FM_CPLD_PCIE_SW_PERST_L")
	)
	(segment
		(start 161.07664 -126.796292)
		(end 152.13965 -135.733282)
		(width 0.1143)
		(layer "In2.Cu")
		(net "FM_CPLD_PCIE_SW_PERST_L")
	)
	(segment
		(start 161.07664 -119.84863)
		(end 161.07664 -126.796292)
		(width 0.1143)
		(layer "In2.Cu")
		(net "FM_CPLD_PCIE_SW_PERST_L")
	)
	(segment
		(start 148.879052 -145.047716)
		(end 148.07438 -145.852388)
		(width 0.1143)
		(layer "In2.Cu")
		(net "FM_CPLD_PCIE_SW_PERST_L")
	)
	(segment
		(start 149.031452 -140.452348)
		(end 148.78431 -140.69949)
		(width 0.1143)
		(layer "In2.Cu")
		(net "FM_CPLD_PCIE_SW_PERST_L")
	)
	(segment
		(start 148.07438 -149.428708)
		(end 141.101826 -156.401262)
		(width 0.1143)
		(layer "In2.Cu")
		(net "FM_CPLD_PCIE_SW_PERST_L")
	)
	(segment
		(start 148.78431 -142.775432)
		(end 148.879052 -142.870174)
		(width 0.1143)
		(layer "In2.Cu")
		(net "FM_CPLD_PCIE_SW_PERST_L")
	)
	(segment
		(start 152.13965 -135.733282)
		(end 151.34463 -135.733282)
		(width 0.1143)
		(layer "In2.Cu")
		(net "FM_CPLD_PCIE_SW_PERST_L")
	)
	(segment
		(start 148.07438 -145.852388)
		(end 148.07438 -149.428708)
		(width 0.1143)
		(layer "In2.Cu")
		(net "FM_CPLD_PCIE_SW_PERST_L")
	)
	(segment
		(start 148.879052 -142.870174)
		(end 148.879052 -145.047716)
		(width 0.1143)
		(layer "In2.Cu")
		(net "FM_CPLD_PCIE_SW_PERST_L")
	)
	(segment
		(start 161.54654 -119.37873)
		(end 161.07664 -119.84863)
		(width 0.1143)
		(layer "In2.Cu")
		(net "FM_CPLD_PCIE_SW_PERST_L")
	)
	(segment
		(start 135.303006 -156.401262)
		(end 135.23468 -156.332936)
		(width 0.1143)
		(layer "In2.Cu")
		(net "FM_CPLD_PCIE_SW_PERST_L")
	)
	(segment
		(start 162.940746 -117.984524)
		(end 162.940746 -117.444266)
		(width 0.1143)
		(layer "In7.Cu")
		(net "FM_CPLD_PCIE_SW_PERST_L")
	)
	(segment
		(start 183.417464 -117.108478)
		(end 184.51322 -118.204234)
		(width 0.1143)
		(layer "In7.Cu")
		(net "FM_CPLD_PCIE_SW_PERST_L")
	)
	(segment
		(start 181.13883 -117.108478)
		(end 183.417464 -117.108478)
		(width 0.1143)
		(layer "In7.Cu")
		(net "FM_CPLD_PCIE_SW_PERST_L")
	)
	(segment
		(start 162.940746 -117.444266)
		(end 165.452298 -114.932714)
		(width 0.1143)
		(layer "In7.Cu")
		(net "FM_CPLD_PCIE_SW_PERST_L")
	)
	(segment
		(start 172.59554 -115.101878)
		(end 179.13223 -115.101878)
		(width 0.1143)
		(layer "In7.Cu")
		(net "FM_CPLD_PCIE_SW_PERST_L")
	)
	(segment
		(start 172.426376 -114.932714)
		(end 172.59554 -115.101878)
		(width 0.1143)
		(layer "In7.Cu")
		(net "FM_CPLD_PCIE_SW_PERST_L")
	)
	(segment
		(start 165.452298 -114.932714)
		(end 172.426376 -114.932714)
		(width 0.1143)
		(layer "In7.Cu")
		(net "FM_CPLD_PCIE_SW_PERST_L")
	)
	(segment
		(start 179.13223 -115.101878)
		(end 181.13883 -117.108478)
		(width 0.1143)
		(layer "In7.Cu")
		(net "FM_CPLD_PCIE_SW_PERST_L")
	)
	(segment
		(start 161.54654 -119.37873)
		(end 162.940746 -117.984524)
		(width 0.1143)
		(layer "In7.Cu")
		(net "FM_CPLD_PCIE_SW_PERST_L")
	)
	(segment
		(start 157.658562 -105.78973)
		(end 161.412936 -105.78973)
		(width 0.1016)
		(layer "F.Cu")
		(net "N34379705")
	)
	(segment
		(start 156.041852 -106.753914)
		(end 156.529532 -107.241594)
		(width 0.1016)
		(layer "F.Cu")
		(net "N34379705")
	)
	(segment
		(start 162.783774 -103.735886)
		(end 163.340034 -103.735886)
		(width 0.1016)
		(layer "F.Cu")
		(net "N34379705")
	)
	(segment
		(start 162.464242 -104.055418)
		(end 162.783774 -103.735886)
		(width 0.1016)
		(layer "F.Cu")
		(net "N34379705")
	)
	(segment
		(start 157.065472 -106.38282)
		(end 157.658562 -105.78973)
		(width 0.1016)
		(layer "F.Cu")
		(net "N34379705")
	)
	(segment
		(start 157.065472 -106.94543)
		(end 157.065472 -106.38282)
		(width 0.1016)
		(layer "F.Cu")
		(net "N34379705")
	)
	(segment
		(start 156.769308 -107.241594)
		(end 157.065472 -106.94543)
		(width 0.1016)
		(layer "F.Cu")
		(net "N34379705")
	)
	(segment
		(start 162.464242 -104.738424)
		(end 162.464242 -104.055418)
		(width 0.1016)
		(layer "F.Cu")
		(net "N34379705")
	)
	(segment
		(start 156.041852 -106.38028)
		(end 156.041852 -106.753914)
		(width 0.1016)
		(layer "F.Cu")
		(net "N34379705")
	)
	(segment
		(start 156.529532 -107.241594)
		(end 156.769308 -107.241594)
		(width 0.1016)
		(layer "F.Cu")
		(net "N34379705")
	)
	(segment
		(start 161.412936 -105.78973)
		(end 162.464242 -104.738424)
		(width 0.1016)
		(layer "F.Cu")
		(net "N34379705")
	)
	(via
		(at 156.529532 -107.241594)
		(size 0.508)
		(drill 0.254)
		(layers "F.Cu" "B.Cu")
		(net "N34379705")
	)
	(segment
		(start 126.453392 -134.40537)
		(end 127.338074 -135.290052)
		(width 0.1016)
		(layer "F.Cu")
		(net "PE_SW_USB_PERST_L")
	)
	(segment
		(start 155.551378 -105.58018)
		(end 155.22702 -105.904538)
		(width 0.1016)
		(layer "F.Cu")
		(net "PE_SW_USB_PERST_L")
	)
	(segment
		(start 156.041852 -105.58018)
		(end 155.551378 -105.58018)
		(width 0.1016)
		(layer "F.Cu")
		(net "PE_SW_USB_PERST_L")
	)
	(segment
		(start 127.517652 -134.16915)
		(end 127.517652 -133.5786)
		(width 0.1016)
		(layer "F.Cu")
		(net "PE_SW_USB_PERST_L")
	)
	(segment
		(start 127.517652 -133.5786)
		(end 126.955042 -133.5786)
		(width 0.1016)
		(layer "F.Cu")
		(net "PE_SW_USB_PERST_L")
	)
	(segment
		(start 127.338074 -134.348728)
		(end 127.517652 -134.16915)
		(width 0.1016)
		(layer "F.Cu")
		(net "PE_SW_USB_PERST_L")
	)
	(segment
		(start 155.22702 -105.904538)
		(end 155.22702 -106.153712)
		(width 0.1016)
		(layer "F.Cu")
		(net "PE_SW_USB_PERST_L")
	)
	(segment
		(start 127.338074 -135.290052)
		(end 127.338074 -135.825484)
		(width 0.1016)
		(layer "F.Cu")
		(net "PE_SW_USB_PERST_L")
	)
	(segment
		(start 126.955042 -133.5786)
		(end 126.453392 -134.08025)
		(width 0.1016)
		(layer "F.Cu")
		(net "PE_SW_USB_PERST_L")
	)
	(segment
		(start 126.453392 -134.08025)
		(end 126.453392 -134.40537)
		(width 0.1016)
		(layer "F.Cu")
		(net "PE_SW_USB_PERST_L")
	)
	(via
		(at 127.338074 -134.348728)
		(size 0.508)
		(drill 0.254)
		(layers "F.Cu" "B.Cu")
		(net "PE_SW_USB_PERST_L")
	)
	(via
		(at 155.22702 -106.153712)
		(size 0.508)
		(drill 0.254)
		(layers "F.Cu" "B.Cu")
		(net "PE_SW_USB_PERST_L")
	)
	(via
		(at 164.20084 -130.293618)
		(size 0.508)
		(drill 0.254)
		(layers "F.Cu" "B.Cu")
		(net "PE_SW_USB_PERST_L")
	)
	(segment
		(start 164.67455 -117.928644)
		(end 164.396674 -118.20652)
		(width 0.1143)
		(layer "In2.Cu")
		(net "PE_SW_USB_PERST_L")
	)
	(segment
		(start 164.618924 -121.420382)
		(end 164.618924 -125.082046)
		(width 0.1143)
		(layer "In2.Cu")
		(net "PE_SW_USB_PERST_L")
	)
	(segment
		(start 164.396674 -120.052592)
		(end 165.010084 -120.666002)
		(width 0.1143)
		(layer "In2.Cu")
		(net "PE_SW_USB_PERST_L")
	)
	(segment
		(start 164.67455 -117.565424)
		(end 164.67455 -117.928644)
		(width 0.1143)
		(layer "In2.Cu")
		(net "PE_SW_USB_PERST_L")
	)
	(segment
		(start 164.752274 -128.50495)
		(end 164.20084 -129.056384)
		(width 0.1143)
		(layer "In2.Cu")
		(net "PE_SW_USB_PERST_L")
	)
	(segment
		(start 165.010084 -121.029222)
		(end 164.618924 -121.420382)
		(width 0.1143)
		(layer "In2.Cu")
		(net "PE_SW_USB_PERST_L")
	)
	(segment
		(start 164.396674 -118.20652)
		(end 164.396674 -120.052592)
		(width 0.1143)
		(layer "In2.Cu")
		(net "PE_SW_USB_PERST_L")
	)
	(segment
		(start 154.76855 -107.645708)
		(end 156.840428 -109.717586)
		(width 0.1143)
		(layer "In2.Cu")
		(net "PE_SW_USB_PERST_L")
	)
	(segment
		(start 159.365696 -109.717586)
		(end 164.0332 -114.38509)
		(width 0.1143)
		(layer "In2.Cu")
		(net "PE_SW_USB_PERST_L")
	)
	(segment
		(start 164.20084 -129.056384)
		(end 164.20084 -130.293618)
		(width 0.1143)
		(layer "In2.Cu")
		(net "PE_SW_USB_PERST_L")
	)
	(segment
		(start 155.22702 -106.153712)
		(end 154.76855 -106.612182)
		(width 0.1143)
		(layer "In2.Cu")
		(net "PE_SW_USB_PERST_L")
	)
	(segment
		(start 165.010084 -120.666002)
		(end 165.010084 -121.029222)
		(width 0.1143)
		(layer "In2.Cu")
		(net "PE_SW_USB_PERST_L")
	)
	(segment
		(start 164.618924 -125.082046)
		(end 164.43325 -125.26772)
		(width 0.1143)
		(layer "In2.Cu")
		(net "PE_SW_USB_PERST_L")
	)
	(segment
		(start 154.76855 -106.612182)
		(end 154.76855 -107.645708)
		(width 0.1143)
		(layer "In2.Cu")
		(net "PE_SW_USB_PERST_L")
	)
	(segment
		(start 164.752274 -128.14173)
		(end 164.752274 -128.50495)
		(width 0.1143)
		(layer "In2.Cu")
		(net "PE_SW_USB_PERST_L")
	)
	(segment
		(start 164.0332 -114.38509)
		(end 164.0332 -116.924074)
		(width 0.1143)
		(layer "In2.Cu")
		(net "PE_SW_USB_PERST_L")
	)
	(segment
		(start 156.840428 -109.717586)
		(end 159.365696 -109.717586)
		(width 0.1143)
		(layer "In2.Cu")
		(net "PE_SW_USB_PERST_L")
	)
	(segment
		(start 164.43325 -127.822706)
		(end 164.752274 -128.14173)
		(width 0.1143)
		(layer "In2.Cu")
		(net "PE_SW_USB_PERST_L")
	)
	(segment
		(start 164.43325 -125.26772)
		(end 164.43325 -127.822706)
		(width 0.1143)
		(layer "In2.Cu")
		(net "PE_SW_USB_PERST_L")
	)
	(segment
		(start 164.0332 -116.924074)
		(end 164.67455 -117.565424)
		(width 0.1143)
		(layer "In2.Cu")
		(net "PE_SW_USB_PERST_L")
	)
	(segment
		(start 160.98901 -132.03936)
		(end 161.615628 -132.03936)
		(width 0.1143)
		(layer "In6.Cu")
		(net "PE_SW_USB_PERST_L")
	)
	(segment
		(start 127.338074 -134.348728)
		(end 127.656082 -134.03072)
		(width 0.1143)
		(layer "In6.Cu")
		(net "PE_SW_USB_PERST_L")
	)
	(segment
		(start 148.96084 -132.613654)
		(end 149.242272 -132.332222)
		(width 0.1143)
		(layer "In6.Cu")
		(net "PE_SW_USB_PERST_L")
	)
	(segment
		(start 130.02133 -134.03072)
		(end 131.438396 -132.613654)
		(width 0.1143)
		(layer "In6.Cu")
		(net "PE_SW_USB_PERST_L")
	)
	(segment
		(start 127.656082 -134.03072)
		(end 130.02133 -134.03072)
		(width 0.1143)
		(layer "In6.Cu")
		(net "PE_SW_USB_PERST_L")
	)
	(segment
		(start 163.683188 -130.81127)
		(end 164.20084 -130.293618)
		(width 0.1143)
		(layer "In6.Cu")
		(net "PE_SW_USB_PERST_L")
	)
	(segment
		(start 149.242272 -132.332222)
		(end 160.696148 -132.332222)
		(width 0.1143)
		(layer "In6.Cu")
		(net "PE_SW_USB_PERST_L")
	)
	(segment
		(start 160.696148 -132.332222)
		(end 160.98901 -132.03936)
		(width 0.1143)
		(layer "In6.Cu")
		(net "PE_SW_USB_PERST_L")
	)
	(segment
		(start 161.615628 -132.03936)
		(end 162.843972 -130.81127)
		(width 0.1143)
		(layer "In6.Cu")
		(net "PE_SW_USB_PERST_L")
	)
	(segment
		(start 131.438396 -132.613654)
		(end 148.96084 -132.613654)
		(width 0.1143)
		(layer "In6.Cu")
		(net "PE_SW_USB_PERST_L")
	)
	(segment
		(start 162.843972 -130.81127)
		(end 163.683188 -130.81127)
		(width 0.1143)
		(layer "In6.Cu")
		(net "PE_SW_USB_PERST_L")
	)
	(segment
		(start 124.037598 -137.375646)
		(end 124.450348 -137.375646)
		(width 0.1016)
		(layer "F.Cu")
		(net "PE_SW_BMC_PERST_L")
	)
	(segment
		(start 123.701302 -137.03935)
		(end 124.037598 -137.375646)
		(width 0.1016)
		(layer "F.Cu")
		(net "PE_SW_BMC_PERST_L")
	)
	(segment
		(start 125.787912 -137.375646)
		(end 124.450348 -137.375646)
		(width 0.1016)
		(layer "F.Cu")
		(net "PE_SW_BMC_PERST_L")
	)
	(via
		(at 70.86346 -118.057422)
		(size 0.508)
		(drill 0.254)
		(layers "F.Cu" "B.Cu")
		(net "PE_SW_BMC_PERST_L")
	)
	(via
		(at 124.450348 -137.375646)
		(size 0.508)
		(drill 0.254)
		(layers "F.Cu" "B.Cu")
		(net "PE_SW_BMC_PERST_L")
	)
	(segment
		(start 71.396352 -118.057422)
		(end 70.86346 -118.057422)
		(width 0.1016)
		(layer "B.Cu")
		(net "PE_SW_BMC_PERST_L")
	)
	(segment
		(start 71.721472 -120.659652)
		(end 71.72198 -120.659652)
		(width 0.1016)
		(layer "B.Cu")
		(net "PE_SW_BMC_PERST_L")
	)
	(segment
		(start 71.72198 -120.659652)
		(end 71.72198 -118.38305)
		(width 0.1016)
		(layer "B.Cu")
		(net "PE_SW_BMC_PERST_L")
	)
	(segment
		(start 71.72198 -118.38305)
		(end 71.396352 -118.057422)
		(width 0.1016)
		(layer "B.Cu")
		(net "PE_SW_BMC_PERST_L")
	)
	(segment
		(start 87.76208 -121.890282)
		(end 87.76208 -130.076702)
		(width 0.1143)
		(layer "In6.Cu")
		(net "PE_SW_BMC_PERST_L")
	)
	(segment
		(start 88.5317 -130.846322)
		(end 88.5317 -132.219446)
		(width 0.1143)
		(layer "In6.Cu")
		(net "PE_SW_BMC_PERST_L")
	)
	(segment
		(start 70.72122 -118.199662)
		(end 70.72122 -118.895368)
		(width 0.1143)
		(layer "In6.Cu")
		(net "PE_SW_BMC_PERST_L")
	)
	(segment
		(start 116.296948 -143.274542)
		(end 117.58168 -141.98981)
		(width 0.1143)
		(layer "In6.Cu")
		(net "PE_SW_BMC_PERST_L")
	)
	(segment
		(start 75.229212 -118.207536)
		(end 82.338926 -118.207536)
		(width 0.1143)
		(layer "In6.Cu")
		(net "PE_SW_BMC_PERST_L")
	)
	(segment
		(start 90.14206 -137.908792)
		(end 94.50324 -142.269972)
		(width 0.1143)
		(layer "In6.Cu")
		(net "PE_SW_BMC_PERST_L")
	)
	(segment
		(start 71.759826 -119.185436)
		(end 72.813418 -118.131844)
		(width 0.1143)
		(layer "In6.Cu")
		(net "PE_SW_BMC_PERST_L")
	)
	(segment
		(start 97.666302 -145.121376)
		(end 113.75263 -145.121376)
		(width 0.1143)
		(layer "In6.Cu")
		(net "PE_SW_BMC_PERST_L")
	)
	(segment
		(start 88.5317 -132.219446)
		(end 90.14206 -133.829806)
		(width 0.1143)
		(layer "In6.Cu")
		(net "PE_SW_BMC_PERST_L")
	)
	(segment
		(start 70.86346 -118.057422)
		(end 70.72122 -118.199662)
		(width 0.1143)
		(layer "In6.Cu")
		(net "PE_SW_BMC_PERST_L")
	)
	(segment
		(start 115.599464 -143.274542)
		(end 116.296948 -143.274542)
		(width 0.1143)
		(layer "In6.Cu")
		(net "PE_SW_BMC_PERST_L")
	)
	(segment
		(start 117.58168 -141.292326)
		(end 121.49836 -137.375646)
		(width 0.1143)
		(layer "In6.Cu")
		(net "PE_SW_BMC_PERST_L")
	)
	(segment
		(start 113.75263 -145.121376)
		(end 115.599464 -143.274542)
		(width 0.1143)
		(layer "In6.Cu")
		(net "PE_SW_BMC_PERST_L")
	)
	(segment
		(start 75.15352 -118.131844)
		(end 75.229212 -118.207536)
		(width 0.1143)
		(layer "In6.Cu")
		(net "PE_SW_BMC_PERST_L")
	)
	(segment
		(start 121.49836 -137.375646)
		(end 124.450348 -137.375646)
		(width 0.1143)
		(layer "In6.Cu")
		(net "PE_SW_BMC_PERST_L")
	)
	(segment
		(start 84.967572 -120.836182)
		(end 86.70798 -120.836182)
		(width 0.1143)
		(layer "In6.Cu")
		(net "PE_SW_BMC_PERST_L")
	)
	(segment
		(start 72.813418 -118.131844)
		(end 75.15352 -118.131844)
		(width 0.1143)
		(layer "In6.Cu")
		(net "PE_SW_BMC_PERST_L")
	)
	(segment
		(start 90.14206 -133.829806)
		(end 90.14206 -137.908792)
		(width 0.1143)
		(layer "In6.Cu")
		(net "PE_SW_BMC_PERST_L")
	)
	(segment
		(start 117.58168 -141.98981)
		(end 117.58168 -141.292326)
		(width 0.1143)
		(layer "In6.Cu")
		(net "PE_SW_BMC_PERST_L")
	)
	(segment
		(start 70.72122 -118.895368)
		(end 71.011288 -119.185436)
		(width 0.1143)
		(layer "In6.Cu")
		(net "PE_SW_BMC_PERST_L")
	)
	(segment
		(start 94.814898 -142.269972)
		(end 97.666302 -145.121376)
		(width 0.1143)
		(layer "In6.Cu")
		(net "PE_SW_BMC_PERST_L")
	)
	(segment
		(start 87.76208 -130.076702)
		(end 88.5317 -130.846322)
		(width 0.1143)
		(layer "In6.Cu")
		(net "PE_SW_BMC_PERST_L")
	)
	(segment
		(start 71.011288 -119.185436)
		(end 71.759826 -119.185436)
		(width 0.1143)
		(layer "In6.Cu")
		(net "PE_SW_BMC_PERST_L")
	)
	(segment
		(start 86.70798 -120.836182)
		(end 87.76208 -121.890282)
		(width 0.1143)
		(layer "In6.Cu")
		(net "PE_SW_BMC_PERST_L")
	)
	(segment
		(start 94.50324 -142.269972)
		(end 94.814898 -142.269972)
		(width 0.1143)
		(layer "In6.Cu")
		(net "PE_SW_BMC_PERST_L")
	)
	(segment
		(start 82.338926 -118.207536)
		(end 84.967572 -120.836182)
		(width 0.1143)
		(layer "In6.Cu")
		(net "PE_SW_BMC_PERST_L")
	)
	(segment
		(start 133.737858 -136.731756)
		(end 134.147052 -137.14095)
		(width 0.1778)
		(layer "F.Cu")
		(net "P1V0_PCI_SW_A")
	)
	(segment
		(start 125.787912 -144.17548)
		(end 126.782322 -144.17548)
		(width 0.1778)
		(layer "F.Cu")
		(net "P1V0_PCI_SW_A")
	)
	(segment
		(start 126.989332 -143.77543)
		(end 127.085852 -143.87195)
		(width 0.1778)
		(layer "F.Cu")
		(net "P1V0_PCI_SW_A")
	)
	(segment
		(start 133.338062 -135.825484)
		(end 133.338062 -137.09396)
		(width 0.1778)
		(layer "F.Cu")
		(net "P1V0_PCI_SW_A")
	)
	(segment
		(start 133.737858 -135.825484)
		(end 133.737858 -136.731756)
		(width 0.1778)
		(layer "F.Cu")
		(net "P1V0_PCI_SW_A")
	)
	(segment
		(start 125.787912 -138.975592)
		(end 124.627894 -138.975592)
		(width 0.1778)
		(layer "F.Cu")
		(net "P1V0_PCI_SW_A")
	)
	(segment
		(start 133.338062 -137.09396)
		(end 133.435852 -137.19175)
		(width 0.1778)
		(layer "F.Cu")
		(net "P1V0_PCI_SW_A")
	)
	(segment
		(start 125.787912 -143.77543)
		(end 126.989332 -143.77543)
		(width 0.1778)
		(layer "F.Cu")
		(net "P1V0_PCI_SW_A")
	)
	(segment
		(start 125.787912 -144.57553)
		(end 127.027432 -144.57553)
		(width 0.1778)
		(layer "F.Cu")
		(net "P1V0_PCI_SW_A")
	)
	(segment
		(start 126.782322 -144.17548)
		(end 127.085852 -143.87195)
		(width 0.1778)
		(layer "F.Cu")
		(net "P1V0_PCI_SW_A")
	)
	(segment
		(start 127.027432 -144.57553)
		(end 127.085852 -144.63395)
		(width 0.1778)
		(layer "F.Cu")
		(net "P1V0_PCI_SW_A")
	)
	(via
		(at 134.147052 -137.14095)
		(size 0.508)
		(drill 0.254)
		(layers "F.Cu" "B.Cu")
		(net "P1V0_PCI_SW_A")
	)
	(via
		(at 130.555492 -144.44345)
		(size 0.6604)
		(drill 0.3302)
		(layers "F.Cu" "B.Cu")
		(net "P1V0_PCI_SW_A")
	)
	(via
		(at 127.085852 -144.63395)
		(size 0.508)
		(drill 0.254)
		(layers "F.Cu" "B.Cu")
		(net "P1V0_PCI_SW_A")
	)
	(via
		(at 133.311392 -139.38377)
		(size 0.6604)
		(drill 0.3302)
		(layers "F.Cu" "B.Cu")
		(net "P1V0_PCI_SW_A")
	)
	(via
		(at 124.627894 -138.975592)
		(size 0.508)
		(drill 0.254)
		(layers "F.Cu" "B.Cu")
		(net "P1V0_PCI_SW_A")
	)
	(via
		(at 133.435852 -137.19175)
		(size 0.508)
		(drill 0.254)
		(layers "F.Cu" "B.Cu")
		(net "P1V0_PCI_SW_A")
	)
	(via
		(at 127.085852 -143.87195)
		(size 0.508)
		(drill 0.254)
		(layers "F.Cu" "B.Cu")
		(net "P1V0_PCI_SW_A")
	)
	(segment
		(start 126.647702 -143.87195)
		(end 127.085852 -143.87195)
		(width 0.4572)
		(layer "B.Cu")
		(net "P1V0_PCI_SW_A")
	)
	(segment
		(start 126.292102 -144.22755)
		(end 126.647702 -143.87195)
		(width 0.4572)
		(layer "B.Cu")
		(net "P1V0_PCI_SW_A")
	)
	(segment
		(start 126.292102 -144.22755)
		(end 126.698502 -144.63395)
		(width 0.4572)
		(layer "B.Cu")
		(net "P1V0_PCI_SW_A")
	)
	(segment
		(start 126.698502 -144.63395)
		(end 127.085852 -144.63395)
		(width 0.4572)
		(layer "B.Cu")
		(net "P1V0_PCI_SW_A")
	)
	(segment
		(start 126.919736 -141.775434)
		(end 125.787912 -141.775434)
		(width 0.1778)
		(layer "F.Cu")
		(net "P1V0_NODE1")
	)
	(segment
		(start 132.572252 -137.24255)
		(end 132.572252 -137.06475)
		(width 0.1778)
		(layer "F.Cu")
		(net "P1V0_NODE1")
	)
	(segment
		(start 140.382244 -138.575542)
		(end 140.039852 -138.23315)
		(width 0.1778)
		(layer "F.Cu")
		(net "P1V0_NODE1")
	)
	(segment
		(start 130.938016 -136.674606)
		(end 131.16052 -136.89711)
		(width 0.1778)
		(layer "F.Cu")
		(net "P1V0_NODE1")
	)
	(segment
		(start 128.940052 -133.4008)
		(end 128.940052 -135.823452)
		(width 0.1778)
		(layer "F.Cu")
		(net "P1V0_NODE1")
	)
	(segment
		(start 141.288008 -138.575542)
		(end 140.382244 -138.575542)
		(width 0.1778)
		(layer "F.Cu")
		(net "P1V0_NODE1")
	)
	(segment
		(start 157.572964 -75.540108)
		(end 157.572964 -75.12685)
		(width 0.254)
		(layer "F.Cu")
		(net "P1V0_NODE1")
	)
	(segment
		(start 133.258052 -149.91715)
		(end 133.338062 -149.99716)
		(width 0.1778)
		(layer "F.Cu")
		(net "P1V0_NODE1")
	)
	(segment
		(start 132.537962 -137.03046)
		(end 132.537962 -135.825484)
		(width 0.1778)
		(layer "F.Cu")
		(net "P1V0_NODE1")
	)
	(segment
		(start 128.171702 -133.4008)
		(end 128.940052 -133.4008)
		(width 0.4572)
		(layer "F.Cu")
		(net "P1V0_NODE1")
	)
	(segment
		(start 136.137904 -150.034498)
		(end 136.137904 -151.32558)
		(width 0.1778)
		(layer "F.Cu")
		(net "P1V0_NODE1")
	)
	(segment
		(start 137.73785 -134.711948)
		(end 137.550652 -134.52475)
		(width 0.1778)
		(layer "F.Cu")
		(net "P1V0_NODE1")
	)
	(segment
		(start 127.055372 -145.37563)
		(end 127.136652 -145.29435)
		(width 0.1778)
		(layer "F.Cu")
		(net "P1V0_NODE1")
	)
	(segment
		(start 132.572252 -137.06475)
		(end 132.537962 -137.03046)
		(width 0.1778)
		(layer "F.Cu")
		(net "P1V0_NODE1")
	)
	(segment
		(start 141.288008 -142.975584)
		(end 140.301218 -142.975584)
		(width 0.1778)
		(layer "F.Cu")
		(net "P1V0_NODE1")
	)
	(segment
		(start 140.247624 -148.575522)
		(end 141.288008 -148.575522)
		(width 0.1778)
		(layer "F.Cu")
		(net "P1V0_NODE1")
	)
	(segment
		(start 134.537958 -150.110444)
		(end 134.537958 -151.32558)
		(width 0.1778)
		(layer "F.Cu")
		(net "P1V0_NODE1")
	)
	(segment
		(start 128.940052 -135.823452)
		(end 128.93802 -135.825484)
		(width 0.1778)
		(layer "F.Cu")
		(net "P1V0_NODE1")
	)
	(segment
		(start 136.087104 -149.983698)
		(end 136.137904 -150.034498)
		(width 0.1778)
		(layer "F.Cu")
		(net "P1V0_NODE1")
	)
	(segment
		(start 140.223748 -137.375646)
		(end 141.288008 -137.375646)
		(width 0.1778)
		(layer "F.Cu")
		(net "P1V0_NODE1")
	)
	(segment
		(start 127.035052 -141.89075)
		(end 126.919736 -141.775434)
		(width 0.1778)
		(layer "F.Cu")
		(net "P1V0_NODE1")
	)
	(segment
		(start 125.787912 -145.37563)
		(end 127.055372 -145.37563)
		(width 0.1778)
		(layer "F.Cu")
		(net "P1V0_NODE1")
	)
	(segment
		(start 135.737854 -135.825484)
		(end 135.737854 -134.508748)
		(width 0.1778)
		(layer "F.Cu")
		(net "P1V0_NODE1")
	)
	(segment
		(start 159.351726 -77.14107)
		(end 159.173926 -77.14107)
		(width 0.254)
		(layer "F.Cu")
		(net "P1V0_NODE1")
	)
	(segment
		(start 140.014452 -148.34235)
		(end 140.247624 -148.575522)
		(width 0.1778)
		(layer "F.Cu")
		(net "P1V0_NODE1")
	)
	(segment
		(start 140.090652 -137.24255)
		(end 140.223748 -137.375646)
		(width 0.1778)
		(layer "F.Cu")
		(net "P1V0_NODE1")
	)
	(segment
		(start 137.73785 -135.825484)
		(end 137.73785 -134.711948)
		(width 0.1778)
		(layer "F.Cu")
		(net "P1V0_NODE1")
	)
	(segment
		(start 130.938016 -135.825484)
		(end 130.938016 -136.674606)
		(width 0.1778)
		(layer "F.Cu")
		(net "P1V0_NODE1")
	)
	(segment
		(start 132.137912 -151.32558)
		(end 132.137912 -149.94509)
		(width 0.1778)
		(layer "F.Cu")
		(net "P1V0_NODE1")
	)
	(segment
		(start 128.53797 -151.32558)
		(end 128.53797 -150.073868)
		(width 0.2032)
		(layer "F.Cu")
		(net "P1V0_NODE1")
	)
	(segment
		(start 140.301218 -142.975584)
		(end 140.065252 -143.21155)
		(width 0.1778)
		(layer "F.Cu")
		(net "P1V0_NODE1")
	)
	(segment
		(start 133.338062 -149.99716)
		(end 133.338062 -151.32558)
		(width 0.1778)
		(layer "F.Cu")
		(net "P1V0_NODE1")
	)
	(segment
		(start 128.53797 -150.073868)
		(end 128.457452 -149.99335)
		(width 0.2032)
		(layer "F.Cu")
		(net "P1V0_NODE1")
	)
	(segment
		(start 159.173926 -77.14107)
		(end 157.572964 -75.540108)
		(width 0.254)
		(layer "F.Cu")
		(net "P1V0_NODE1")
	)
	(segment
		(start 131.16052 -136.89711)
		(end 131.16052 -137.252456)
		(width 0.1778)
		(layer "F.Cu")
		(net "P1V0_NODE1")
	)
	(segment
		(start 134.705852 -149.94255)
		(end 134.537958 -150.110444)
		(width 0.1778)
		(layer "F.Cu")
		(net "P1V0_NODE1")
	)
	(segment
		(start 138.1379 -151.32558)
		(end 138.1379 -149.939502)
		(width 0.1778)
		(layer "F.Cu")
		(net "P1V0_NODE1")
	)
	(segment
		(start 125.787912 -146.975576)
		(end 127.106426 -146.975576)
		(width 0.1778)
		(layer "F.Cu")
		(net "P1V0_NODE1")
	)
	(via
		(at 160.623504 -77.535278)
		(size 0.508)
		(drill 0.254)
		(layers "F.Cu" "B.Cu")
		(net "P1V0_NODE1")
	)
	(via
		(at 140.2207 -58.197496)
		(size 0.508)
		(drill 0.254)
		(layers "F.Cu" "B.Cu")
		(net "P1V0_NODE1")
	)
	(via
		(at 139.569952 -59.182762)
		(size 0.508)
		(drill 0.254)
		(layers "F.Cu" "B.Cu")
		(net "P1V0_NODE1")
	)
	(via
		(at 136.087104 -149.983698)
		(size 0.508)
		(drill 0.254)
		(layers "F.Cu" "B.Cu")
		(net "P1V0_NODE1")
	)
	(via
		(at 137.51052 -86.450932)
		(size 0.508)
		(drill 0.254)
		(layers "F.Cu" "B.Cu")
		(net "P1V0_NODE1")
	)
	(via
		(at 134.011162 -85.650832)
		(size 0.508)
		(drill 0.254)
		(layers "F.Cu" "B.Cu")
		(net "P1V0_NODE1")
	)
	(via
		(at 132.20954 -85.673946)
		(size 0.508)
		(drill 0.254)
		(layers "F.Cu" "B.Cu")
		(net "P1V0_NODE1")
	)
	(via
		(at 160.978342 -78.851506)
		(size 0.508)
		(drill 0.254)
		(layers "F.Cu" "B.Cu")
		(net "P1V0_NODE1")
	)
	(via
		(at 160.452308 -78.20152)
		(size 0.508)
		(drill 0.254)
		(layers "F.Cu" "B.Cu")
		(net "P1V0_NODE1")
	)
	(via
		(at 132.572252 -137.24255)
		(size 0.508)
		(drill 0.254)
		(layers "F.Cu" "B.Cu")
		(net "P1V0_NODE1")
	)
	(via
		(at 158.45028 -81.549748)
		(size 0.508)
		(drill 0.254)
		(layers "F.Cu" "B.Cu")
		(net "P1V0_NODE1")
	)
	(via
		(at 154.7241 -83.442556)
		(size 0.508)
		(drill 0.254)
		(layers "F.Cu" "B.Cu")
		(net "P1V0_NODE1")
	)
	(via
		(at 138.85926 -59.198764)
		(size 0.508)
		(drill 0.254)
		(layers "F.Cu" "B.Cu")
		(net "P1V0_NODE1")
	)
	(via
		(at 127.035052 -141.89075)
		(size 0.508)
		(drill 0.254)
		(layers "F.Cu" "B.Cu")
		(net "P1V0_NODE1")
	)
	(via
		(at 159.258 -83.293204)
		(size 0.508)
		(drill 0.254)
		(layers "F.Cu" "B.Cu")
		(net "P1V0_NODE1")
	)
	(via
		(at 139.02436 -86.132162)
		(size 0.508)
		(drill 0.254)
		(layers "F.Cu" "B.Cu")
		(net "P1V0_NODE1")
	)
	(via
		(at 135.07593 -86.463886)
		(size 0.508)
		(drill 0.254)
		(layers "F.Cu" "B.Cu")
		(net "P1V0_NODE1")
	)
	(via
		(at 139.536932 -58.458862)
		(size 0.508)
		(drill 0.254)
		(layers "F.Cu" "B.Cu")
		(net "P1V0_NODE1")
	)
	(via
		(at 136.18972 -86.723728)
		(size 0.508)
		(drill 0.254)
		(layers "F.Cu" "B.Cu")
		(net "P1V0_NODE1")
	)
	(via
		(at 160.49244 -81.64957)
		(size 0.508)
		(drill 0.254)
		(layers "F.Cu" "B.Cu")
		(net "P1V0_NODE1")
	)
	(via
		(at 166.80942 -86.012782)
		(size 0.508)
		(drill 0.254)
		(layers "F.Cu" "B.Cu")
		(net "P1V0_NODE1")
	)
	(via
		(at 136.18718 -85.497162)
		(size 0.508)
		(drill 0.254)
		(layers "F.Cu" "B.Cu")
		(net "P1V0_NODE1")
	)
	(via
		(at 128.171702 -133.4008)
		(size 0.508)
		(drill 0.254)
		(layers "F.Cu" "B.Cu")
		(net "P1V0_NODE1")
	)
	(via
		(at 161.788348 -78.975712)
		(size 0.508)
		(drill 0.254)
		(layers "F.Cu" "B.Cu")
		(net "P1V0_NODE1")
	)
	(via
		(at 131.16052 -137.252456)
		(size 0.508)
		(drill 0.254)
		(layers "F.Cu" "B.Cu")
		(net "P1V0_NODE1")
	)
	(via
		(at 160.558988 -79.476092)
		(size 0.508)
		(drill 0.254)
		(layers "F.Cu" "B.Cu")
		(net "P1V0_NODE1")
	)
	(via
		(at 130.6576 -86.570566)
		(size 0.508)
		(drill 0.254)
		(layers "F.Cu" "B.Cu")
		(net "P1V0_NODE1")
	)
	(via
		(at 137.550652 -134.52475)
		(size 0.508)
		(drill 0.254)
		(layers "F.Cu" "B.Cu")
		(net "P1V0_NODE1")
	)
	(via
		(at 140.039852 -138.23315)
		(size 0.508)
		(drill 0.254)
		(layers "F.Cu" "B.Cu")
		(net "P1V0_NODE1")
	)
	(via
		(at 160.06826 -85.594444)
		(size 0.508)
		(drill 0.254)
		(layers "F.Cu" "B.Cu")
		(net "P1V0_NODE1")
	)
	(via
		(at 137.94994 -84.797392)
		(size 0.508)
		(drill 0.254)
		(layers "F.Cu" "B.Cu")
		(net "P1V0_NODE1")
	)
	(via
		(at 138.42746 -58.695844)
		(size 0.508)
		(drill 0.254)
		(layers "F.Cu" "B.Cu")
		(net "P1V0_NODE1")
	)
	(via
		(at 158.21406 -82.607658)
		(size 0.508)
		(drill 0.254)
		(layers "F.Cu" "B.Cu")
		(net "P1V0_NODE1")
	)
	(via
		(at 158.79826 -85.594444)
		(size 0.508)
		(drill 0.254)
		(layers "F.Cu" "B.Cu")
		(net "P1V0_NODE1")
	)
	(via
		(at 140.63726 -86.570566)
		(size 0.508)
		(drill 0.254)
		(layers "F.Cu" "B.Cu")
		(net "P1V0_NODE1")
	)
	(via
		(at 131.251452 -142.85595)
		(size 0.508)
		(drill 0.254)
		(layers "F.Cu" "B.Cu")
		(net "P1V0_NODE1")
	)
	(via
		(at 134.705852 -149.94255)
		(size 0.508)
		(drill 0.254)
		(layers "F.Cu" "B.Cu")
		(net "P1V0_NODE1")
	)
	(via
		(at 140.23848 -59.026552)
		(size 0.508)
		(drill 0.254)
		(layers "F.Cu" "B.Cu")
		(net "P1V0_NODE1")
	)
	(via
		(at 129.32156 -85.85327)
		(size 0.508)
		(drill 0.254)
		(layers "F.Cu" "B.Cu")
		(net "P1V0_NODE1")
	)
	(via
		(at 156.58846 -83.193636)
		(size 0.508)
		(drill 0.254)
		(layers "F.Cu" "B.Cu")
		(net "P1V0_NODE1")
	)
	(via
		(at 133.969252 -86.449662)
		(size 0.508)
		(drill 0.254)
		(layers "F.Cu" "B.Cu")
		(net "P1V0_NODE1")
	)
	(via
		(at 160.947608 -80.060292)
		(size 0.508)
		(drill 0.254)
		(layers "F.Cu" "B.Cu")
		(net "P1V0_NODE1")
	)
	(via
		(at 140.014452 -148.34235)
		(size 0.508)
		(drill 0.254)
		(layers "F.Cu" "B.Cu")
		(net "P1V0_NODE1")
	)
	(via
		(at 128.457452 -149.99335)
		(size 0.508)
		(drill 0.254)
		(layers "F.Cu" "B.Cu")
		(net "P1V0_NODE1")
	)
	(via
		(at 133.555232 -147.99691)
		(size 0.6604)
		(drill 0.3302)
		(layers "F.Cu" "B.Cu")
		(net "P1V0_NODE1")
	)
	(via
		(at 134.98322 -85.616796)
		(size 0.508)
		(drill 0.254)
		(layers "F.Cu" "B.Cu")
		(net "P1V0_NODE1")
	)
	(via
		(at 138.1379 -149.939502)
		(size 0.508)
		(drill 0.254)
		(layers "F.Cu" "B.Cu")
		(net "P1V0_NODE1")
	)
	(via
		(at 161.455608 -79.531972)
		(size 0.508)
		(drill 0.254)
		(layers "F.Cu" "B.Cu")
		(net "P1V0_NODE1")
	)
	(via
		(at 127.136652 -145.29435)
		(size 0.508)
		(drill 0.254)
		(layers "F.Cu" "B.Cu")
		(net "P1V0_NODE1")
	)
	(via
		(at 132.137912 -149.94509)
		(size 0.508)
		(drill 0.254)
		(layers "F.Cu" "B.Cu")
		(net "P1V0_NODE1")
	)
	(via
		(at 140.065252 -143.21155)
		(size 0.508)
		(drill 0.254)
		(layers "F.Cu" "B.Cu")
		(net "P1V0_NODE1")
	)
	(via
		(at 164.7063 -86.032594)
		(size 0.508)
		(drill 0.254)
		(layers "F.Cu" "B.Cu")
		(net "P1V0_NODE1")
	)
	(via
		(at 140.090652 -137.24255)
		(size 0.508)
		(drill 0.254)
		(layers "F.Cu" "B.Cu")
		(net "P1V0_NODE1")
	)
	(via
		(at 133.258052 -149.91715)
		(size 0.508)
		(drill 0.254)
		(layers "F.Cu" "B.Cu")
		(net "P1V0_NODE1")
	)
	(via
		(at 157.27426 -85.594444)
		(size 0.508)
		(drill 0.254)
		(layers "F.Cu" "B.Cu")
		(net "P1V0_NODE1")
	)
	(via
		(at 130.489452 -142.85595)
		(size 0.508)
		(drill 0.254)
		(layers "F.Cu" "B.Cu")
		(net "P1V0_NODE1")
	)
	(via
		(at 160.90138 -82.98434)
		(size 0.508)
		(drill 0.254)
		(layers "F.Cu" "B.Cu")
		(net "P1V0_NODE1")
	)
	(via
		(at 135.737854 -134.508748)
		(size 0.508)
		(drill 0.254)
		(layers "F.Cu" "B.Cu")
		(net "P1V0_NODE1")
	)
	(via
		(at 159.54756 -80.67294)
		(size 0.508)
		(drill 0.254)
		(layers "F.Cu" "B.Cu")
		(net "P1V0_NODE1")
	)
	(via
		(at 127.106426 -146.975576)
		(size 0.508)
		(drill 0.254)
		(layers "F.Cu" "B.Cu")
		(net "P1V0_NODE1")
	)
	(via
		(at 136.494012 -143.47825)
		(size 0.6604)
		(drill 0.3302)
		(layers "F.Cu" "B.Cu")
		(net "P1V0_NODE1")
	)
	(segment
		(start 127.720852 -141.89075)
		(end 127.035052 -141.89075)
		(width 0.4572)
		(layer "B.Cu")
		(net "P1V0_NODE1")
	)
	(segment
		(start 140.090652 -137.24255)
		(end 140.833602 -137.24255)
		(width 0.4572)
		(layer "B.Cu")
		(net "P1V0_NODE1")
	)
	(segment
		(start 128.305052 -150.9141)
		(end 128.305052 -150.14575)
		(width 0.508)
		(layer "B.Cu")
		(net "P1V0_NODE1")
	)
	(segment
		(start 136.255252 -150.8887)
		(end 136.255252 -150.151846)
		(width 0.4572)
		(layer "B.Cu")
		(net "P1V0_NODE1")
	)
	(segment
		(start 126.292102 -147.19935)
		(end 126.882652 -147.19935)
		(width 0.4064)
		(layer "B.Cu")
		(net "P1V0_NODE1")
	)
	(segment
		(start 134.705852 -150.6347)
		(end 134.705852 -149.94255)
		(width 0.4572)
		(layer "B.Cu")
		(net "P1V0_NODE1")
	)
	(segment
		(start 132.978652 -150.22957)
		(end 133.258052 -149.95017)
		(width 0.4572)
		(layer "B.Cu")
		(net "P1V0_NODE1")
	)
	(segment
		(start 132.775452 -136.271)
		(end 132.572252 -136.4742)
		(width 0.4572)
		(layer "B.Cu")
		(net "P1V0_NODE1")
	)
	(segment
		(start 132.978652 -150.9141)
		(end 132.978652 -150.22957)
		(width 0.4572)
		(layer "B.Cu")
		(net "P1V0_NODE1")
	)
	(segment
		(start 131.160012 -137.252456)
		(end 131.16052 -137.252456)
		(width 0.4572)
		(layer "B.Cu")
		(net "P1V0_NODE1")
	)
	(segment
		(start 135.747252 -135.4709)
		(end 135.747252 -134.518146)
		(width 0.4572)
		(layer "B.Cu")
		(net "P1V0_NODE1")
	)
	(segment
		(start 140.039852 -138.23315)
		(end 140.833602 -138.23315)
		(width 0.4572)
		(layer "B.Cu")
		(net "P1V0_NODE1")
	)
	(segment
		(start 126.882652 -147.19935)
		(end 127.106426 -146.975576)
		(width 0.4064)
		(layer "B.Cu")
		(net "P1V0_NODE1")
	)
	(segment
		(start 126.292102 -145.21815)
		(end 126.368302 -145.29435)
		(width 0.4064)
		(layer "B.Cu")
		(net "P1V0_NODE1")
	)
	(segment
		(start 134.985252 -150.9141)
		(end 134.705852 -150.6347)
		(width 0.4572)
		(layer "B.Cu")
		(net "P1V0_NODE1")
	)
	(segment
		(start 130.794252 -136.271)
		(end 130.794252 -136.886696)
		(width 0.4572)
		(layer "B.Cu")
		(net "P1V0_NODE1")
	)
	(segment
		(start 140.833602 -137.24255)
		(end 140.833602 -138.23315)
		(width 0.4572)
		(layer "B.Cu")
		(net "P1V0_NODE1")
	)
	(segment
		(start 141.005052 -148.3995)
		(end 140.071602 -148.3995)
		(width 0.4572)
		(layer "B.Cu")
		(net "P1V0_NODE1")
	)
	(segment
		(start 126.965202 -141.9606)
		(end 127.035052 -141.89075)
		(width 0.4572)
		(layer "B.Cu")
		(net "P1V0_NODE1")
	)
	(segment
		(start 133.258052 -149.95017)
		(end 133.258052 -149.91715)
		(width 0.4572)
		(layer "B.Cu")
		(net "P1V0_NODE1")
	)
	(segment
		(start 128.152652 -141.45895)
		(end 127.720852 -141.89075)
		(width 0.4572)
		(layer "B.Cu")
		(net "P1V0_NODE1")
	)
	(segment
		(start 140.262102 -143.4084)
		(end 140.065252 -143.21155)
		(width 0.4572)
		(layer "B.Cu")
		(net "P1V0_NODE1")
	)
	(segment
		(start 138.236452 -150.038054)
		(end 138.1379 -149.939502)
		(width 0.4572)
		(layer "B.Cu")
		(net "P1V0_NODE1")
	)
	(segment
		(start 126.368302 -145.29435)
		(end 127.136652 -145.29435)
		(width 0.4064)
		(layer "B.Cu")
		(net "P1V0_NODE1")
	)
	(segment
		(start 140.071602 -148.3995)
		(end 140.014452 -148.34235)
		(width 0.4572)
		(layer "B.Cu")
		(net "P1V0_NODE1")
	)
	(segment
		(start 126.069852 -141.9606)
		(end 126.965202 -141.9606)
		(width 0.4572)
		(layer "B.Cu")
		(net "P1V0_NODE1")
	)
	(segment
		(start 138.236452 -150.8887)
		(end 138.236452 -150.038054)
		(width 0.4572)
		(layer "B.Cu")
		(net "P1V0_NODE1")
	)
	(segment
		(start 136.255252 -150.151846)
		(end 136.087104 -149.983698)
		(width 0.4572)
		(layer "B.Cu")
		(net "P1V0_NODE1")
	)
	(segment
		(start 130.794252 -136.886696)
		(end 131.160012 -137.252456)
		(width 0.4572)
		(layer "B.Cu")
		(net "P1V0_NODE1")
	)
	(segment
		(start 132.572252 -136.4742)
		(end 132.572252 -137.24255)
		(width 0.4572)
		(layer "B.Cu")
		(net "P1V0_NODE1")
	)
	(segment
		(start 131.988052 -150.09495)
		(end 132.137912 -149.94509)
		(width 0.4572)
		(layer "B.Cu")
		(net "P1V0_NODE1")
	)
	(segment
		(start 128.305052 -150.14575)
		(end 128.457452 -149.99335)
		(width 0.508)
		(layer "B.Cu")
		(net "P1V0_NODE1")
	)
	(segment
		(start 135.747252 -134.518146)
		(end 135.737854 -134.508748)
		(width 0.4572)
		(layer "B.Cu")
		(net "P1V0_NODE1")
	)
	(segment
		(start 131.988052 -150.8887)
		(end 131.988052 -150.09495)
		(width 0.4572)
		(layer "B.Cu")
		(net "P1V0_NODE1")
	)
	(segment
		(start 137.550652 -135.4455)
		(end 137.550652 -134.52475)
		(width 0.4572)
		(layer "B.Cu")
		(net "P1V0_NODE1")
	)
	(segment
		(start 141.005052 -143.4084)
		(end 140.262102 -143.4084)
		(width 0.4572)
		(layer "B.Cu")
		(net "P1V0_NODE1")
	)
	(segment
		(start 159.91332 -113.106708)
		(end 161.402522 -111.617506)
		(width 0.1016)
		(layer "F.Cu")
		(net "FM_CPLD_NODE1_P1V26_BMC_EN")
	)
	(segment
		(start 86.91626 -144.213072)
		(end 86.458552 -144.67078)
		(width 0.1016)
		(layer "F.Cu")
		(net "FM_CPLD_NODE1_P1V26_BMC_EN")
	)
	(segment
		(start 173.976792 -111.533178)
		(end 177.010314 -114.5667)
		(width 0.1016)
		(layer "F.Cu")
		(net "FM_CPLD_NODE1_P1V26_BMC_EN")
	)
	(segment
		(start 160.16478 -114.113818)
		(end 159.91332 -113.862358)
		(width 0.1016)
		(layer "F.Cu")
		(net "FM_CPLD_NODE1_P1V26_BMC_EN")
	)
	(segment
		(start 177.010314 -114.5667)
		(end 177.010314 -116.365528)
		(width 0.1016)
		(layer "F.Cu")
		(net "FM_CPLD_NODE1_P1V26_BMC_EN")
	)
	(segment
		(start 84.927948 -143.222472)
		(end 85.411818 -143.706342)
		(width 0.1016)
		(layer "F.Cu")
		(net "FM_CPLD_NODE1_P1V26_BMC_EN")
	)
	(segment
		(start 170.65498 -111.533178)
		(end 173.976792 -111.533178)
		(width 0.1016)
		(layer "F.Cu")
		(net "FM_CPLD_NODE1_P1V26_BMC_EN")
	)
	(segment
		(start 84.927948 -142.851886)
		(end 84.927948 -143.222472)
		(width 0.1016)
		(layer "F.Cu")
		(net "FM_CPLD_NODE1_P1V26_BMC_EN")
	)
	(segment
		(start 170.570652 -111.617506)
		(end 170.65498 -111.533178)
		(width 0.1016)
		(layer "F.Cu")
		(net "FM_CPLD_NODE1_P1V26_BMC_EN")
	)
	(segment
		(start 159.91332 -113.862358)
		(end 159.91332 -113.106708)
		(width 0.1016)
		(layer "F.Cu")
		(net "FM_CPLD_NODE1_P1V26_BMC_EN")
	)
	(segment
		(start 161.402522 -111.617506)
		(end 170.570652 -111.617506)
		(width 0.1016)
		(layer "F.Cu")
		(net "FM_CPLD_NODE1_P1V26_BMC_EN")
	)
	(segment
		(start 85.411818 -143.706342)
		(end 85.411818 -144.659858)
		(width 0.1016)
		(layer "F.Cu")
		(net "FM_CPLD_NODE1_P1V26_BMC_EN")
	)
	(segment
		(start 86.44763 -144.659858)
		(end 85.411818 -144.659858)
		(width 0.1016)
		(layer "F.Cu")
		(net "FM_CPLD_NODE1_P1V26_BMC_EN")
	)
	(segment
		(start 86.91626 -143.725392)
		(end 86.91626 -144.213072)
		(width 0.1016)
		(layer "F.Cu")
		(net "FM_CPLD_NODE1_P1V26_BMC_EN")
	)
	(segment
		(start 160.16478 -114.6683)
		(end 160.16478 -114.113818)
		(width 0.1016)
		(layer "F.Cu")
		(net "FM_CPLD_NODE1_P1V26_BMC_EN")
	)
	(segment
		(start 86.458552 -144.67078)
		(end 86.44763 -144.659858)
		(width 0.1016)
		(layer "F.Cu")
		(net "FM_CPLD_NODE1_P1V26_BMC_EN")
	)
	(via
		(at 86.91626 -143.725392)
		(size 0.508)
		(drill 0.254)
		(layers "F.Cu" "B.Cu")
		(net "FM_CPLD_NODE1_P1V26_BMC_EN")
	)
	(via
		(at 160.70072 -118.533926)
		(size 0.508)
		(drill 0.254)
		(layers "F.Cu" "B.Cu")
		(net "FM_CPLD_NODE1_P1V26_BMC_EN")
	)
	(via
		(at 138.7475 -124.536708)
		(size 0.508)
		(drill 0.254)
		(layers "F.Cu" "B.Cu")
		(net "FM_CPLD_NODE1_P1V26_BMC_EN")
	)
	(via
		(at 160.16478 -114.6683)
		(size 0.508)
		(drill 0.254)
		(layers "F.Cu" "B.Cu")
		(net "FM_CPLD_NODE1_P1V26_BMC_EN")
	)
	(segment
		(start 160.16478 -114.6683)
		(end 160.39084 -114.89436)
		(width 0.1143)
		(layer "In2.Cu")
		(net "FM_CPLD_NODE1_P1V26_BMC_EN")
	)
	(segment
		(start 135.15848 -125.987556)
		(end 137.402062 -125.987556)
		(width 0.1143)
		(layer "In2.Cu")
		(net "FM_CPLD_NODE1_P1V26_BMC_EN")
	)
	(segment
		(start 118.26748 -142.797022)
		(end 118.26748 -138.799316)
		(width 0.1143)
		(layer "In2.Cu")
		(net "FM_CPLD_NODE1_P1V26_BMC_EN")
	)
	(segment
		(start 118.26748 -138.799316)
		(end 119.044974 -138.021822)
		(width 0.1143)
		(layer "In2.Cu")
		(net "FM_CPLD_NODE1_P1V26_BMC_EN")
	)
	(segment
		(start 119.044974 -137.282682)
		(end 127.63246 -128.695196)
		(width 0.1143)
		(layer "In2.Cu")
		(net "FM_CPLD_NODE1_P1V26_BMC_EN")
	)
	(segment
		(start 160.39084 -118.224046)
		(end 160.70072 -118.533926)
		(width 0.1143)
		(layer "In2.Cu")
		(net "FM_CPLD_NODE1_P1V26_BMC_EN")
	)
	(segment
		(start 119.044974 -138.021822)
		(end 119.044974 -137.282682)
		(width 0.1143)
		(layer "In2.Cu")
		(net "FM_CPLD_NODE1_P1V26_BMC_EN")
	)
	(segment
		(start 138.656314 -124.733304)
		(end 138.6586 -124.733304)
		(width 0.1143)
		(layer "In2.Cu")
		(net "FM_CPLD_NODE1_P1V26_BMC_EN")
	)
	(segment
		(start 137.402062 -125.987556)
		(end 138.656314 -124.733304)
		(width 0.1143)
		(layer "In2.Cu")
		(net "FM_CPLD_NODE1_P1V26_BMC_EN")
	)
	(segment
		(start 127.63246 -128.695196)
		(end 127.63246 -125.676152)
		(width 0.1143)
		(layer "In2.Cu")
		(net "FM_CPLD_NODE1_P1V26_BMC_EN")
	)
	(segment
		(start 129.03454 -124.274072)
		(end 133.444996 -124.274072)
		(width 0.1143)
		(layer "In2.Cu")
		(net "FM_CPLD_NODE1_P1V26_BMC_EN")
	)
	(segment
		(start 133.444996 -124.274072)
		(end 135.15848 -125.987556)
		(width 0.1143)
		(layer "In2.Cu")
		(net "FM_CPLD_NODE1_P1V26_BMC_EN")
	)
	(segment
		(start 94.983808 -145.3134)
		(end 94.987364 -145.316956)
		(width 0.1143)
		(layer "In2.Cu")
		(net "FM_CPLD_NODE1_P1V26_BMC_EN")
	)
	(segment
		(start 88.4936 -145.3134)
		(end 94.983808 -145.3134)
		(width 0.1143)
		(layer "In2.Cu")
		(net "FM_CPLD_NODE1_P1V26_BMC_EN")
	)
	(segment
		(start 138.7475 -124.644404)
		(end 138.7475 -124.536708)
		(width 0.1143)
		(layer "In2.Cu")
		(net "FM_CPLD_NODE1_P1V26_BMC_EN")
	)
	(segment
		(start 86.91626 -143.725392)
		(end 86.91626 -143.73606)
		(width 0.1143)
		(layer "In2.Cu")
		(net "FM_CPLD_NODE1_P1V26_BMC_EN")
	)
	(segment
		(start 127.63246 -125.676152)
		(end 129.03454 -124.274072)
		(width 0.1143)
		(layer "In2.Cu")
		(net "FM_CPLD_NODE1_P1V26_BMC_EN")
	)
	(segment
		(start 138.6586 -124.733304)
		(end 138.7475 -124.644404)
		(width 0.1143)
		(layer "In2.Cu")
		(net "FM_CPLD_NODE1_P1V26_BMC_EN")
	)
	(segment
		(start 86.91626 -143.73606)
		(end 88.4936 -145.3134)
		(width 0.1143)
		(layer "In2.Cu")
		(net "FM_CPLD_NODE1_P1V26_BMC_EN")
	)
	(segment
		(start 160.39084 -114.89436)
		(end 160.39084 -118.224046)
		(width 0.1143)
		(layer "In2.Cu")
		(net "FM_CPLD_NODE1_P1V26_BMC_EN")
	)
	(segment
		(start 94.987364 -145.316956)
		(end 115.747546 -145.316956)
		(width 0.1143)
		(layer "In2.Cu")
		(net "FM_CPLD_NODE1_P1V26_BMC_EN")
	)
	(segment
		(start 115.747546 -145.316956)
		(end 118.26748 -142.797022)
		(width 0.1143)
		(layer "In2.Cu")
		(net "FM_CPLD_NODE1_P1V26_BMC_EN")
	)
	(segment
		(start 138.7475 -124.536708)
		(end 138.7475 -124.537724)
		(width 0.1143)
		(layer "In6.Cu")
		(net "FM_CPLD_NODE1_P1V26_BMC_EN")
	)
	(segment
		(start 160.70072 -119.363998)
		(end 160.70072 -118.533926)
		(width 0.1143)
		(layer "In6.Cu")
		(net "FM_CPLD_NODE1_P1V26_BMC_EN")
	)
	(segment
		(start 159.33547 -120.729248)
		(end 160.70072 -119.363998)
		(width 0.1143)
		(layer "In6.Cu")
		(net "FM_CPLD_NODE1_P1V26_BMC_EN")
	)
	(segment
		(start 149.028404 -124.733304)
		(end 153.03246 -120.729248)
		(width 0.1143)
		(layer "In6.Cu")
		(net "FM_CPLD_NODE1_P1V26_BMC_EN")
	)
	(segment
		(start 153.03246 -120.729248)
		(end 159.33547 -120.729248)
		(width 0.1143)
		(layer "In6.Cu")
		(net "FM_CPLD_NODE1_P1V26_BMC_EN")
	)
	(segment
		(start 138.94308 -124.733304)
		(end 149.028404 -124.733304)
		(width 0.1143)
		(layer "In6.Cu")
		(net "FM_CPLD_NODE1_P1V26_BMC_EN")
	)
	(segment
		(start 138.7475 -124.537724)
		(end 138.94308 -124.733304)
		(width 0.1143)
		(layer "In6.Cu")
		(net "FM_CPLD_NODE1_P1V26_BMC_EN")
	)
	(segment
		(start 125.536452 -152.02535)
		(end 125.670818 -151.890984)
		(width 0.1016)
		(layer "F.Cu")
		(net "PCIE_SW_TRST")
	)
	(segment
		(start 125.536452 -153.2763)
		(end 125.536452 -152.512014)
		(width 0.1016)
		(layer "F.Cu")
		(net "PCIE_SW_TRST")
	)
	(segment
		(start 125.670818 -151.890984)
		(end 125.670818 -150.734776)
		(width 0.1016)
		(layer "F.Cu")
		(net "PCIE_SW_TRST")
	)
	(segment
		(start 125.787912 -150.617682)
		(end 125.787912 -149.775418)
		(width 0.1016)
		(layer "F.Cu")
		(net "PCIE_SW_TRST")
	)
	(segment
		(start 125.536452 -152.512014)
		(end 125.536452 -152.02535)
		(width 0.1016)
		(layer "F.Cu")
		(net "PCIE_SW_TRST")
	)
	(segment
		(start 125.670818 -150.734776)
		(end 125.787912 -150.617682)
		(width 0.1016)
		(layer "F.Cu")
		(net "PCIE_SW_TRST")
	)
	(via
		(at 125.536452 -152.512014)
		(size 0.508)
		(drill 0.254)
		(layers "F.Cu" "B.Cu")
		(net "PCIE_SW_TRST")
	)
	(segment
		(start 127.568452 -153.2763)
		(end 127.136652 -152.8445)
		(width 0.1016)
		(layer "F.Cu")
		(net "PCIE_SW_TMS")
	)
	(segment
		(start 127.136652 -152.8445)
		(end 127.136652 -152.63495)
		(width 0.1016)
		(layer "F.Cu")
		(net "PCIE_SW_TMS")
	)
	(segment
		(start 127.73787 -152.033732)
		(end 127.136652 -152.63495)
		(width 0.1016)
		(layer "F.Cu")
		(net "PCIE_SW_TMS")
	)
	(segment
		(start 127.73787 -151.32558)
		(end 127.73787 -152.033732)
		(width 0.1016)
		(layer "F.Cu")
		(net "PCIE_SW_TMS")
	)
	(via
		(at 127.136652 -152.63495)
		(size 0.508)
		(drill 0.254)
		(layers "F.Cu" "B.Cu")
		(net "PCIE_SW_TMS")
	)
	(segment
		(start 179.727352 -118.829328)
		(end 184.756806 -118.829328)
		(width 0.1016)
		(layer "F.Cu")
		(net "TP_FM_CPLD_NODE1_P3V3_STB_SW_EN")
	)
	(segment
		(start 179.010564 -118.365524)
		(end 179.263548 -118.365524)
		(width 0.1016)
		(layer "F.Cu")
		(net "TP_FM_CPLD_NODE1_P3V3_STB_SW_EN")
	)
	(segment
		(start 185.719212 -117.866922)
		(end 185.81878 -117.866922)
		(width 0.1016)
		(layer "F.Cu")
		(net "TP_FM_CPLD_NODE1_P3V3_STB_SW_EN")
	)
	(segment
		(start 184.756806 -118.829328)
		(end 185.719212 -117.866922)
		(width 0.1016)
		(layer "F.Cu")
		(net "TP_FM_CPLD_NODE1_P3V3_STB_SW_EN")
	)
	(segment
		(start 179.263548 -118.365524)
		(end 179.727352 -118.829328)
		(width 0.1016)
		(layer "F.Cu")
		(net "TP_FM_CPLD_NODE1_P3V3_STB_SW_EN")
	)
	(via
		(at 185.81878 -117.866922)
		(size 0.508)
		(drill 0.254)
		(layers "F.Cu" "B.Cu")
		(net "TP_FM_CPLD_NODE1_P3V3_STB_SW_EN")
	)
	(segment
		(start 154.48026 -115.74907)
		(end 154.48026 -117.037358)
		(width 0.1016)
		(layer "F.Cu")
		(net "FM_CPLD_NODE1_P1V538_BMC_EN")
	)
	(segment
		(start 170.44162 -111.025178)
		(end 170.357292 -111.109506)
		(width 0.1016)
		(layer "F.Cu")
		(net "FM_CPLD_NODE1_P1V538_BMC_EN")
	)
	(segment
		(start 28.45435 -123.662694)
		(end 28.466288 -123.674632)
		(width 0.1016)
		(layer "F.Cu")
		(net "FM_CPLD_NODE1_P1V538_BMC_EN")
	)
	(segment
		(start 29.641292 -125.254258)
		(end 29.228288 -125.254258)
		(width 0.1016)
		(layer "F.Cu")
		(net "FM_CPLD_NODE1_P1V538_BMC_EN")
	)
	(segment
		(start 159.547306 -111.109506)
		(end 155.151074 -115.505738)
		(width 0.1016)
		(layer "F.Cu")
		(net "FM_CPLD_NODE1_P1V538_BMC_EN")
	)
	(segment
		(start 155.151074 -115.505738)
		(end 154.723592 -115.505738)
		(width 0.1016)
		(layer "F.Cu")
		(net "FM_CPLD_NODE1_P1V538_BMC_EN")
	)
	(segment
		(start 170.357292 -111.109506)
		(end 159.547306 -111.109506)
		(width 0.1016)
		(layer "F.Cu")
		(net "FM_CPLD_NODE1_P1V538_BMC_EN")
	)
	(segment
		(start 27.438604 -123.662694)
		(end 28.45435 -123.662694)
		(width 0.1016)
		(layer "F.Cu")
		(net "FM_CPLD_NODE1_P1V538_BMC_EN")
	)
	(segment
		(start 27.438604 -125.095)
		(end 27.438604 -123.662694)
		(width 0.1016)
		(layer "F.Cu")
		(net "FM_CPLD_NODE1_P1V538_BMC_EN")
	)
	(segment
		(start 29.228288 -125.254258)
		(end 28.466288 -124.492258)
		(width 0.1016)
		(layer "F.Cu")
		(net "FM_CPLD_NODE1_P1V538_BMC_EN")
	)
	(segment
		(start 174.187612 -111.025178)
		(end 170.44162 -111.025178)
		(width 0.1016)
		(layer "F.Cu")
		(net "FM_CPLD_NODE1_P1V538_BMC_EN")
	)
	(segment
		(start 178.010566 -114.848132)
		(end 174.187612 -111.025178)
		(width 0.1016)
		(layer "F.Cu")
		(net "FM_CPLD_NODE1_P1V538_BMC_EN")
	)
	(segment
		(start 154.723592 -115.505738)
		(end 154.48026 -115.74907)
		(width 0.1016)
		(layer "F.Cu")
		(net "FM_CPLD_NODE1_P1V538_BMC_EN")
	)
	(segment
		(start 178.010566 -116.365528)
		(end 178.010566 -114.848132)
		(width 0.1016)
		(layer "F.Cu")
		(net "FM_CPLD_NODE1_P1V538_BMC_EN")
	)
	(segment
		(start 28.466288 -124.492258)
		(end 28.466288 -123.674632)
		(width 0.1016)
		(layer "F.Cu")
		(net "FM_CPLD_NODE1_P1V538_BMC_EN")
	)
	(segment
		(start 154.48026 -117.037358)
		(end 153.8732 -117.644418)
		(width 0.1016)
		(layer "F.Cu")
		(net "FM_CPLD_NODE1_P1V538_BMC_EN")
	)
	(via
		(at 27.438604 -125.095)
		(size 0.508)
		(drill 0.254)
		(layers "F.Cu" "B.Cu")
		(net "FM_CPLD_NODE1_P1V538_BMC_EN")
	)
	(via
		(at 153.8732 -117.644418)
		(size 0.508)
		(drill 0.254)
		(layers "F.Cu" "B.Cu")
		(net "FM_CPLD_NODE1_P1V538_BMC_EN")
	)
	(segment
		(start 50.784252 -116.334032)
		(end 80.632808 -116.334032)
		(width 0.1143)
		(layer "In6.Cu")
		(net "FM_CPLD_NODE1_P1V538_BMC_EN")
	)
	(segment
		(start 32.600138 -121.36755)
		(end 33.108646 -121.876058)
		(width 0.1143)
		(layer "In6.Cu")
		(net "FM_CPLD_NODE1_P1V538_BMC_EN")
	)
	(segment
		(start 134.89178 -122.833892)
		(end 138.202924 -122.833892)
		(width 0.1143)
		(layer "In6.Cu")
		(net "FM_CPLD_NODE1_P1V538_BMC_EN")
	)
	(segment
		(start 93.17228 -118.941342)
		(end 95.457772 -118.941342)
		(width 0.1143)
		(layer "In6.Cu")
		(net "FM_CPLD_NODE1_P1V538_BMC_EN")
	)
	(segment
		(start 138.53414 -122.502676)
		(end 149.014942 -122.502676)
		(width 0.1143)
		(layer "In6.Cu")
		(net "FM_CPLD_NODE1_P1V538_BMC_EN")
	)
	(segment
		(start 27.81554 -123.082304)
		(end 27.81554 -122.31624)
		(width 0.1143)
		(layer "In6.Cu")
		(net "FM_CPLD_NODE1_P1V538_BMC_EN")
	)
	(segment
		(start 119.067834 -111.77651)
		(end 126.235968 -118.944644)
		(width 0.1143)
		(layer "In6.Cu")
		(net "FM_CPLD_NODE1_P1V538_BMC_EN")
	)
	(segment
		(start 83.31708 -116.86667)
		(end 85.654388 -119.203978)
		(width 0.1143)
		(layer "In6.Cu")
		(net "FM_CPLD_NODE1_P1V538_BMC_EN")
	)
	(segment
		(start 107.22356 -111.77651)
		(end 119.067834 -111.77651)
		(width 0.1143)
		(layer "In6.Cu")
		(net "FM_CPLD_NODE1_P1V538_BMC_EN")
	)
	(segment
		(start 106.632502 -112.367568)
		(end 107.22356 -111.77651)
		(width 0.1143)
		(layer "In6.Cu")
		(net "FM_CPLD_NODE1_P1V538_BMC_EN")
	)
	(segment
		(start 28.76423 -121.36755)
		(end 32.600138 -121.36755)
		(width 0.1143)
		(layer "In6.Cu")
		(net "FM_CPLD_NODE1_P1V538_BMC_EN")
	)
	(segment
		(start 47.255176 -119.863108)
		(end 50.784252 -116.334032)
		(width 0.1143)
		(layer "In6.Cu")
		(net "FM_CPLD_NODE1_P1V538_BMC_EN")
	)
	(segment
		(start 133.881114 -123.844558)
		(end 134.89178 -122.833892)
		(width 0.1143)
		(layer "In6.Cu")
		(net "FM_CPLD_NODE1_P1V538_BMC_EN")
	)
	(segment
		(start 101.528372 -112.367568)
		(end 106.632502 -112.367568)
		(width 0.1143)
		(layer "In6.Cu")
		(net "FM_CPLD_NODE1_P1V538_BMC_EN")
	)
	(segment
		(start 96.61144 -117.2845)
		(end 101.528372 -112.367568)
		(width 0.1143)
		(layer "In6.Cu")
		(net "FM_CPLD_NODE1_P1V538_BMC_EN")
	)
	(segment
		(start 27.43708 -123.460764)
		(end 27.81554 -123.082304)
		(width 0.1143)
		(layer "In6.Cu")
		(net "FM_CPLD_NODE1_P1V538_BMC_EN")
	)
	(segment
		(start 27.438604 -125.095)
		(end 27.438604 -124.649484)
		(width 0.1143)
		(layer "In6.Cu")
		(net "FM_CPLD_NODE1_P1V538_BMC_EN")
	)
	(segment
		(start 126.70536 -118.944644)
		(end 127.2794 -119.518684)
		(width 0.1143)
		(layer "In6.Cu")
		(net "FM_CPLD_NODE1_P1V538_BMC_EN")
	)
	(segment
		(start 27.438604 -124.649484)
		(end 27.43708 -124.649484)
		(width 0.1143)
		(layer "In6.Cu")
		(net "FM_CPLD_NODE1_P1V538_BMC_EN")
	)
	(segment
		(start 92.909644 -119.203978)
		(end 93.17228 -118.941342)
		(width 0.1143)
		(layer "In6.Cu")
		(net "FM_CPLD_NODE1_P1V538_BMC_EN")
	)
	(segment
		(start 80.632808 -116.334032)
		(end 81.165446 -116.86667)
		(width 0.1143)
		(layer "In6.Cu")
		(net "FM_CPLD_NODE1_P1V538_BMC_EN")
	)
	(segment
		(start 130.06451 -123.844558)
		(end 133.881114 -123.844558)
		(width 0.1143)
		(layer "In6.Cu")
		(net "FM_CPLD_NODE1_P1V538_BMC_EN")
	)
	(segment
		(start 43.503088 -121.876058)
		(end 45.516038 -119.863108)
		(width 0.1143)
		(layer "In6.Cu")
		(net "FM_CPLD_NODE1_P1V538_BMC_EN")
	)
	(segment
		(start 138.202924 -122.833892)
		(end 138.53414 -122.502676)
		(width 0.1143)
		(layer "In6.Cu")
		(net "FM_CPLD_NODE1_P1V538_BMC_EN")
	)
	(segment
		(start 27.43708 -124.649484)
		(end 27.43708 -123.460764)
		(width 0.1143)
		(layer "In6.Cu")
		(net "FM_CPLD_NODE1_P1V538_BMC_EN")
	)
	(segment
		(start 127.2794 -119.518684)
		(end 127.2794 -121.059448)
		(width 0.1143)
		(layer "In6.Cu")
		(net "FM_CPLD_NODE1_P1V538_BMC_EN")
	)
	(segment
		(start 149.014942 -122.502676)
		(end 153.8732 -117.644418)
		(width 0.1143)
		(layer "In6.Cu")
		(net "FM_CPLD_NODE1_P1V538_BMC_EN")
	)
	(segment
		(start 127.2794 -121.059448)
		(end 130.06451 -123.844558)
		(width 0.1143)
		(layer "In6.Cu")
		(net "FM_CPLD_NODE1_P1V538_BMC_EN")
	)
	(segment
		(start 95.457772 -118.941342)
		(end 96.61144 -117.787674)
		(width 0.1143)
		(layer "In6.Cu")
		(net "FM_CPLD_NODE1_P1V538_BMC_EN")
	)
	(segment
		(start 85.654388 -119.203978)
		(end 92.909644 -119.203978)
		(width 0.1143)
		(layer "In6.Cu")
		(net "FM_CPLD_NODE1_P1V538_BMC_EN")
	)
	(segment
		(start 96.61144 -117.787674)
		(end 96.61144 -117.2845)
		(width 0.1143)
		(layer "In6.Cu")
		(net "FM_CPLD_NODE1_P1V538_BMC_EN")
	)
	(segment
		(start 27.81554 -122.31624)
		(end 28.76423 -121.36755)
		(width 0.1143)
		(layer "In6.Cu")
		(net "FM_CPLD_NODE1_P1V538_BMC_EN")
	)
	(segment
		(start 81.165446 -116.86667)
		(end 83.31708 -116.86667)
		(width 0.1143)
		(layer "In6.Cu")
		(net "FM_CPLD_NODE1_P1V538_BMC_EN")
	)
	(segment
		(start 45.516038 -119.863108)
		(end 47.255176 -119.863108)
		(width 0.1143)
		(layer "In6.Cu")
		(net "FM_CPLD_NODE1_P1V538_BMC_EN")
	)
	(segment
		(start 33.108646 -121.876058)
		(end 43.503088 -121.876058)
		(width 0.1143)
		(layer "In6.Cu")
		(net "FM_CPLD_NODE1_P1V538_BMC_EN")
	)
	(segment
		(start 126.235968 -118.944644)
		(end 126.70536 -118.944644)
		(width 0.1143)
		(layer "In6.Cu")
		(net "FM_CPLD_NODE1_P1V538_BMC_EN")
	)
	(segment
		(start 40.033194 -139.363704)
		(end 40.033448 -139.363704)
		(width 0.3556)
		(layer "F.Cu")
		(net "P1V538_BMC_NODE1")
	)
	(segment
		(start 46.668436 -131.128262)
		(end 47.6504 -131.128262)
		(width 0.3556)
		(layer "F.Cu")
		(net "P1V538_BMC_NODE1")
	)
	(segment
		(start 45.241718 -134.155688)
		(end 45.241718 -134.159498)
		(width 0.3556)
		(layer "F.Cu")
		(net "P1V538_BMC_NODE1")
	)
	(segment
		(start 40.033194 -131.36372)
		(end 39.109142 -131.36372)
		(width 0.381)
		(layer "F.Cu")
		(net "P1V538_BMC_NODE1")
	)
	(segment
		(start 40.83304 -135.363712)
		(end 40.83304 -135.36422)
		(width 0.3556)
		(layer "F.Cu")
		(net "P1V538_BMC_NODE1")
	)
	(segment
		(start 61.341762 -132.059426)
		(end 61.341762 -132.058918)
		(width 0.381)
		(layer "F.Cu")
		(net "P1V538_BMC_NODE1")
	)
	(segment
		(start 61.341762 -136.059418)
		(end 61.339476 -136.059418)
		(width 0.381)
		(layer "F.Cu")
		(net "P1V538_BMC_NODE1")
	)
	(segment
		(start 41.233598 -134.164324)
		(end 41.23309 -134.164324)
		(width 0.3556)
		(layer "F.Cu")
		(net "P1V538_BMC_NODE1")
	)
	(segment
		(start 46.896274 -137.300462)
		(end 47.29734 -137.300462)
		(width 0.3556)
		(layer "F.Cu")
		(net "P1V538_BMC_NODE1")
	)
	(segment
		(start 39.109142 -131.36372)
		(end 39.107618 -131.365244)
		(width 0.381)
		(layer "F.Cu")
		(net "P1V538_BMC_NODE1")
	)
	(segment
		(start 46.432978 -129.763774)
		(end 47.349918 -129.763774)
		(width 0.3556)
		(layer "F.Cu")
		(net "P1V538_BMC_NODE1")
	)
	(segment
		(start 46.432978 -138.563604)
		(end 46.434502 -138.563604)
		(width 0.3556)
		(layer "F.Cu")
		(net "P1V538_BMC_NODE1")
	)
	(segment
		(start 61.341762 -132.058918)
		(end 60.94095 -131.658106)
		(width 0.381)
		(layer "F.Cu")
		(net "P1V538_BMC_NODE1")
	)
	(segment
		(start 47.72025 -135.414512)
		(end 47.72025 -135.668512)
		(width 0.3556)
		(layer "F.Cu")
		(net "P1V538_BMC_NODE1")
	)
	(segment
		(start 40.033448 -139.363704)
		(end 40.43299 -138.964162)
		(width 0.3556)
		(layer "F.Cu")
		(net "P1V538_BMC_NODE1")
	)
	(segment
		(start 126.576328 -145.775426)
		(end 126.831852 -146.03095)
		(width 0.1778)
		(layer "F.Cu")
		(net "P1V538_BMC_NODE1")
	)
	(segment
		(start 46.432978 -137.763758)
		(end 46.896274 -137.300462)
		(width 0.3556)
		(layer "F.Cu")
		(net "P1V538_BMC_NODE1")
	)
	(segment
		(start 40.033194 -129.763774)
		(end 39.253922 -129.763774)
		(width 0.381)
		(layer "F.Cu")
		(net "P1V538_BMC_NODE1")
	)
	(segment
		(start 40.83304 -140.164312)
		(end 40.433244 -140.564108)
		(width 0.3556)
		(layer "F.Cu")
		(net "P1V538_BMC_NODE1")
	)
	(segment
		(start 39.253922 -129.763774)
		(end 39.125652 -129.892044)
		(width 0.381)
		(layer "F.Cu")
		(net "P1V538_BMC_NODE1")
	)
	(segment
		(start 134.537958 -134.692644)
		(end 134.731252 -134.49935)
		(width 0.1778)
		(layer "F.Cu")
		(net "P1V538_BMC_NODE1")
	)
	(segment
		(start 46.534324 -139.46505)
		(end 47.810166 -139.46505)
		(width 0.3556)
		(layer "F.Cu")
		(net "P1V538_BMC_NODE1")
	)
	(segment
		(start 61.341762 -132.859526)
		(end 61.341762 -132.859018)
		(width 0.381)
		(layer "F.Cu")
		(net "P1V538_BMC_NODE1")
	)
	(segment
		(start 47.603918 -129.509774)
		(end 47.603918 -129.224024)
		(width 0.3556)
		(layer "F.Cu")
		(net "P1V538_BMC_NODE1")
	)
	(segment
		(start 45.633132 -140.96365)
		(end 45.899578 -141.230096)
		(width 0.3556)
		(layer "F.Cu")
		(net "P1V538_BMC_NODE1")
	)
	(segment
		(start 45.899578 -141.389608)
		(end 46.098714 -141.588744)
		(width 0.3556)
		(layer "F.Cu")
		(net "P1V538_BMC_NODE1")
	)
	(segment
		(start 42.328084 -123.072652)
		(end 41.497758 -123.072652)
		(width 0.381)
		(layer "F.Cu")
		(net "P1V538_BMC_NODE1")
	)
	(segment
		(start 47.810166 -139.46505)
		(end 48.370236 -138.90498)
		(width 0.3556)
		(layer "F.Cu")
		(net "P1V538_BMC_NODE1")
	)
	(segment
		(start 132.137912 -135.825484)
		(end 132.137912 -136.71169)
		(width 0.1778)
		(layer "F.Cu")
		(net "P1V538_BMC_NODE1")
	)
	(segment
		(start 40.033194 -136.963658)
		(end 39.357554 -136.963658)
		(width 0.3556)
		(layer "F.Cu")
		(net "P1V538_BMC_NODE1")
	)
	(segment
		(start 40.033194 -140.96365)
		(end 40.033194 -141.596872)
		(width 0.381)
		(layer "F.Cu")
		(net "P1V538_BMC_NODE1")
	)
	(segment
		(start 47.380144 -135.074406)
		(end 47.72025 -135.414512)
		(width 0.3556)
		(layer "F.Cu")
		(net "P1V538_BMC_NODE1")
	)
	(segment
		(start 44.833032 -136.163558)
		(end 44.118784 -136.163558)
		(width 0.3556)
		(layer "F.Cu")
		(net "P1V538_BMC_NODE1")
	)
	(segment
		(start 40.83304 -138.563604)
		(end 40.83304 -138.564112)
		(width 0.3556)
		(layer "F.Cu")
		(net "P1V538_BMC_NODE1")
	)
	(segment
		(start 134.537958 -135.825484)
		(end 134.537958 -134.692644)
		(width 0.1778)
		(layer "F.Cu")
		(net "P1V538_BMC_NODE1")
	)
	(segment
		(start 131.810252 -137.03935)
		(end 131.810252 -137.26795)
		(width 0.1778)
		(layer "F.Cu")
		(net "P1V538_BMC_NODE1")
	)
	(segment
		(start 39.357554 -136.963658)
		(end 39.35603 -136.965182)
		(width 0.3556)
		(layer "F.Cu")
		(net "P1V538_BMC_NODE1")
	)
	(segment
		(start 39.346124 -139.363704)
		(end 40.033194 -139.363704)
		(width 0.3556)
		(layer "F.Cu")
		(net "P1V538_BMC_NODE1")
	)
	(segment
		(start 127.002286 -142.975584)
		(end 127.035052 -143.00835)
		(width 0.1778)
		(layer "F.Cu")
		(net "P1V538_BMC_NODE1")
	)
	(segment
		(start 46.722284 -135.074406)
		(end 47.380144 -135.074406)
		(width 0.3556)
		(layer "F.Cu")
		(net "P1V538_BMC_NODE1")
	)
	(segment
		(start 125.787912 -145.775426)
		(end 126.576328 -145.775426)
		(width 0.1778)
		(layer "F.Cu")
		(net "P1V538_BMC_NODE1")
	)
	(segment
		(start 40.83304 -135.36422)
		(end 40.433244 -135.764016)
		(width 0.3556)
		(layer "F.Cu")
		(net "P1V538_BMC_NODE1")
	)
	(segment
		(start 126.831852 -146.03095)
		(end 127.111252 -146.03095)
		(width 0.1778)
		(layer "F.Cu")
		(net "P1V538_BMC_NODE1")
	)
	(segment
		(start 46.432978 -139.363704)
		(end 46.534324 -139.46505)
		(width 0.3556)
		(layer "F.Cu")
		(net "P1V538_BMC_NODE1")
	)
	(segment
		(start 46.434502 -138.563604)
		(end 46.833536 -138.16457)
		(width 0.3556)
		(layer "F.Cu")
		(net "P1V538_BMC_NODE1")
	)
	(segment
		(start 61.341762 -132.859018)
		(end 60.94095 -132.458206)
		(width 0.381)
		(layer "F.Cu")
		(net "P1V538_BMC_NODE1")
	)
	(segment
		(start 39.3446 -139.365228)
		(end 39.346124 -139.363704)
		(width 0.3556)
		(layer "F.Cu")
		(net "P1V538_BMC_NODE1")
	)
	(segment
		(start 61.341762 -135.259572)
		(end 61.339476 -135.259572)
		(width 0.381)
		(layer "F.Cu")
		(net "P1V538_BMC_NODE1")
	)
	(segment
		(start 45.633132 -133.764274)
		(end 45.241718 -134.155688)
		(width 0.3556)
		(layer "F.Cu")
		(net "P1V538_BMC_NODE1")
	)
	(segment
		(start 40.83304 -140.16355)
		(end 40.83304 -140.164312)
		(width 0.3556)
		(layer "F.Cu")
		(net "P1V538_BMC_NODE1")
	)
	(segment
		(start 47.29734 -137.300462)
		(end 47.987458 -136.610344)
		(width 0.3556)
		(layer "F.Cu")
		(net "P1V538_BMC_NODE1")
	)
	(segment
		(start 61.339476 -136.059418)
		(end 60.94095 -136.457944)
		(width 0.381)
		(layer "F.Cu")
		(net "P1V538_BMC_NODE1")
	)
	(segment
		(start 47.349918 -129.763774)
		(end 47.603918 -129.509774)
		(width 0.3556)
		(layer "F.Cu")
		(net "P1V538_BMC_NODE1")
	)
	(segment
		(start 45.899578 -141.230096)
		(end 45.899578 -141.389608)
		(width 0.3556)
		(layer "F.Cu")
		(net "P1V538_BMC_NODE1")
	)
	(segment
		(start 46.432978 -135.363712)
		(end 46.722284 -135.074406)
		(width 0.3556)
		(layer "F.Cu")
		(net "P1V538_BMC_NODE1")
	)
	(segment
		(start 47.6504 -131.128262)
		(end 48.007778 -130.770884)
		(width 0.3556)
		(layer "F.Cu")
		(net "P1V538_BMC_NODE1")
	)
	(segment
		(start 40.83304 -138.564112)
		(end 40.43299 -138.964162)
		(width 0.3556)
		(layer "F.Cu")
		(net "P1V538_BMC_NODE1")
	)
	(segment
		(start 46.432978 -131.36372)
		(end 46.668436 -131.128262)
		(width 0.3556)
		(layer "F.Cu")
		(net "P1V538_BMC_NODE1")
	)
	(segment
		(start 125.787912 -142.975584)
		(end 127.002286 -142.975584)
		(width 0.1778)
		(layer "F.Cu")
		(net "P1V538_BMC_NODE1")
	)
	(segment
		(start 44.118784 -136.163558)
		(end 43.997118 -136.285224)
		(width 0.3556)
		(layer "F.Cu")
		(net "P1V538_BMC_NODE1")
	)
	(segment
		(start 45.633132 -133.763766)
		(end 45.633132 -133.764274)
		(width 0.3556)
		(layer "F.Cu")
		(net "P1V538_BMC_NODE1")
	)
	(segment
		(start 61.339476 -135.259572)
		(end 60.94095 -135.658098)
		(width 0.381)
		(layer "F.Cu")
		(net "P1V538_BMC_NODE1")
	)
	(segment
		(start 132.137912 -136.71169)
		(end 131.810252 -137.03935)
		(width 0.1778)
		(layer "F.Cu")
		(net "P1V538_BMC_NODE1")
	)
	(segment
		(start 40.83304 -133.763766)
		(end 41.233598 -134.164324)
		(width 0.3556)
		(layer "F.Cu")
		(net "P1V538_BMC_NODE1")
	)
	(via
		(at 49.456086 -141.567662)
		(size 0.6604)
		(drill 0.3302)
		(layers "F.Cu" "B.Cu")
		(net "P1V538_BMC_NODE1")
	)
	(via
		(at 40.433244 -135.764016)
		(size 0.49022)
		(drill 0.254)
		(layers "F.Cu" "B.Cu")
		(net "P1V538_BMC_NODE1")
	)
	(via
		(at 40.43299 -138.964162)
		(size 0.49022)
		(drill 0.254)
		(layers "F.Cu" "B.Cu")
		(net "P1V538_BMC_NODE1")
	)
	(via
		(at 46.34992 -143.972026)
		(size 0.508)
		(drill 0.254)
		(layers "F.Cu" "B.Cu")
		(net "P1V538_BMC_NODE1")
	)
	(via
		(at 46.098714 -141.588744)
		(size 0.49022)
		(drill 0.254)
		(layers "F.Cu" "B.Cu")
		(net "P1V538_BMC_NODE1")
	)
	(via
		(at 112.07242 -149.184614)
		(size 0.508)
		(drill 0.254)
		(layers "F.Cu" "B.Cu")
		(net "P1V538_BMC_NODE1")
	)
	(via
		(at 32.534098 -130.523996)
		(size 0.508)
		(drill 0.254)
		(layers "F.Cu" "B.Cu")
		(net "P1V538_BMC_NODE1")
	)
	(via
		(at 93.959172 -150.432262)
		(size 0.508)
		(drill 0.254)
		(layers "F.Cu" "B.Cu")
		(net "P1V538_BMC_NODE1")
	)
	(via
		(at 127.111252 -146.03095)
		(size 0.508)
		(drill 0.254)
		(layers "F.Cu" "B.Cu")
		(net "P1V538_BMC_NODE1")
	)
	(via
		(at 131.810252 -137.26795)
		(size 0.508)
		(drill 0.254)
		(layers "F.Cu" "B.Cu")
		(net "P1V538_BMC_NODE1")
	)
	(via
		(at 33.817052 -129.568956)
		(size 0.508)
		(drill 0.254)
		(layers "F.Cu" "B.Cu")
		(net "P1V538_BMC_NODE1")
	)
	(via
		(at 113.74882 -149.539706)
		(size 0.508)
		(drill 0.254)
		(layers "F.Cu" "B.Cu")
		(net "P1V538_BMC_NODE1")
	)
	(via
		(at 40.033194 -141.596872)
		(size 0.49022)
		(drill 0.254)
		(layers "F.Cu" "B.Cu")
		(net "P1V538_BMC_NODE1")
	)
	(via
		(at 47.987458 -136.610344)
		(size 0.49022)
		(drill 0.254)
		(layers "F.Cu" "B.Cu")
		(net "P1V538_BMC_NODE1")
	)
	(via
		(at 45.241718 -134.159498)
		(size 0.49022)
		(drill 0.254)
		(layers "F.Cu" "B.Cu")
		(net "P1V538_BMC_NODE1")
	)
	(via
		(at 48.370236 -138.90498)
		(size 0.49022)
		(drill 0.254)
		(layers "F.Cu" "B.Cu")
		(net "P1V538_BMC_NODE1")
	)
	(via
		(at 39.22014 -141.72946)
		(size 0.49022)
		(drill 0.254)
		(layers "F.Cu" "B.Cu")
		(net "P1V538_BMC_NODE1")
	)
	(via
		(at 39.125652 -129.892044)
		(size 0.49022)
		(drill 0.254)
		(layers "F.Cu" "B.Cu")
		(net "P1V538_BMC_NODE1")
	)
	(via
		(at 33.171384 -129.550668)
		(size 0.508)
		(drill 0.254)
		(layers "F.Cu" "B.Cu")
		(net "P1V538_BMC_NODE1")
	)
	(via
		(at 43.997118 -136.285224)
		(size 0.49022)
		(drill 0.254)
		(layers "F.Cu" "B.Cu")
		(net "P1V538_BMC_NODE1")
	)
	(via
		(at 60.94095 -136.457944)
		(size 0.49022)
		(drill 0.254)
		(layers "F.Cu" "B.Cu")
		(net "P1V538_BMC_NODE1")
	)
	(via
		(at 93.941392 -149.581362)
		(size 0.508)
		(drill 0.254)
		(layers "F.Cu" "B.Cu")
		(net "P1V538_BMC_NODE1")
	)
	(via
		(at 114.497612 -148.108924)
		(size 0.508)
		(drill 0.254)
		(layers "F.Cu" "B.Cu")
		(net "P1V538_BMC_NODE1")
	)
	(via
		(at 48.007778 -130.770884)
		(size 0.49022)
		(drill 0.254)
		(layers "F.Cu" "B.Cu")
		(net "P1V538_BMC_NODE1")
	)
	(via
		(at 30.897576 -129.387092)
		(size 0.508)
		(drill 0.254)
		(layers "F.Cu" "B.Cu")
		(net "P1V538_BMC_NODE1")
	)
	(via
		(at 40.433244 -140.564108)
		(size 0.49022)
		(drill 0.254)
		(layers "F.Cu" "B.Cu")
		(net "P1V538_BMC_NODE1")
	)
	(via
		(at 44.934886 -127.292862)
		(size 0.6604)
		(drill 0.3302)
		(layers "F.Cu" "B.Cu")
		(net "P1V538_BMC_NODE1")
	)
	(via
		(at 39.3446 -139.365228)
		(size 0.49022)
		(drill 0.254)
		(layers "F.Cu" "B.Cu")
		(net "P1V538_BMC_NODE1")
	)
	(via
		(at 38.748716 -125.482858)
		(size 0.508)
		(drill 0.254)
		(layers "F.Cu" "B.Cu")
		(net "P1V538_BMC_NODE1")
	)
	(via
		(at 39.35603 -136.965182)
		(size 0.49022)
		(drill 0.254)
		(layers "F.Cu" "B.Cu")
		(net "P1V538_BMC_NODE1")
	)
	(via
		(at 60.94095 -132.458206)
		(size 0.49022)
		(drill 0.254)
		(layers "F.Cu" "B.Cu")
		(net "P1V538_BMC_NODE1")
	)
	(via
		(at 57.172098 -135.726424)
		(size 0.6604)
		(drill 0.3302)
		(layers "F.Cu" "B.Cu")
		(net "P1V538_BMC_NODE1")
	)
	(via
		(at 134.731252 -134.49935)
		(size 0.508)
		(drill 0.254)
		(layers "F.Cu" "B.Cu")
		(net "P1V538_BMC_NODE1")
	)
	(via
		(at 47.72025 -135.668512)
		(size 0.49022)
		(drill 0.254)
		(layers "F.Cu" "B.Cu")
		(net "P1V538_BMC_NODE1")
	)
	(via
		(at 39.107618 -131.365244)
		(size 0.49022)
		(drill 0.254)
		(layers "F.Cu" "B.Cu")
		(net "P1V538_BMC_NODE1")
	)
	(via
		(at 94.855792 -149.619462)
		(size 0.508)
		(drill 0.254)
		(layers "F.Cu" "B.Cu")
		(net "P1V538_BMC_NODE1")
	)
	(via
		(at 46.833536 -138.16457)
		(size 0.49022)
		(drill 0.254)
		(layers "F.Cu" "B.Cu")
		(net "P1V538_BMC_NODE1")
	)
	(via
		(at 113.380012 -148.000974)
		(size 0.508)
		(drill 0.254)
		(layers "F.Cu" "B.Cu")
		(net "P1V538_BMC_NODE1")
	)
	(via
		(at 60.94095 -131.658106)
		(size 0.49022)
		(drill 0.254)
		(layers "F.Cu" "B.Cu")
		(net "P1V538_BMC_NODE1")
	)
	(via
		(at 42.15638 -126.397766)
		(size 0.6604)
		(drill 0.3302)
		(layers "F.Cu" "B.Cu")
		(net "P1V538_BMC_NODE1")
	)
	(via
		(at 33.198562 -130.187446)
		(size 0.508)
		(drill 0.254)
		(layers "F.Cu" "B.Cu")
		(net "P1V538_BMC_NODE1")
	)
	(via
		(at 47.603918 -129.224024)
		(size 0.49022)
		(drill 0.254)
		(layers "F.Cu" "B.Cu")
		(net "P1V538_BMC_NODE1")
	)
	(via
		(at 41.23309 -134.164324)
		(size 0.49022)
		(drill 0.254)
		(layers "F.Cu" "B.Cu")
		(net "P1V538_BMC_NODE1")
	)
	(via
		(at 31.661608 -129.387092)
		(size 0.508)
		(drill 0.254)
		(layers "F.Cu" "B.Cu")
		(net "P1V538_BMC_NODE1")
	)
	(via
		(at 33.234376 -130.842512)
		(size 0.508)
		(drill 0.254)
		(layers "F.Cu" "B.Cu")
		(net "P1V538_BMC_NODE1")
	)
	(via
		(at 60.94095 -135.658098)
		(size 0.49022)
		(drill 0.254)
		(layers "F.Cu" "B.Cu")
		(net "P1V538_BMC_NODE1")
	)
	(via
		(at 48.956214 -126.47422)
		(size 0.6604)
		(drill 0.3302)
		(layers "F.Cu" "B.Cu")
		(net "P1V538_BMC_NODE1")
	)
	(via
		(at 94.873572 -150.470362)
		(size 0.508)
		(drill 0.254)
		(layers "F.Cu" "B.Cu")
		(net "P1V538_BMC_NODE1")
	)
	(via
		(at 127.035052 -143.00835)
		(size 0.508)
		(drill 0.254)
		(layers "F.Cu" "B.Cu")
		(net "P1V538_BMC_NODE1")
	)
	(via
		(at 40.235124 -127.004064)
		(size 0.508)
		(drill 0.254)
		(layers "F.Cu" "B.Cu")
		(net "P1V538_BMC_NODE1")
	)
	(via
		(at 41.497758 -123.072652)
		(size 0.508)
		(drill 0.254)
		(layers "F.Cu" "B.Cu")
		(net "P1V538_BMC_NODE1")
	)
	(segment
		(start 60.429394 -136.855708)
		(end 58.092086 -136.855708)
		(width 0.1016)
		(layer "B.Cu")
		(net "P1V538_BMC_NODE1")
	)
	(segment
		(start 60.827158 -136.457944)
		(end 60.429394 -136.855708)
		(width 0.1016)
		(layer "B.Cu")
		(net "P1V538_BMC_NODE1")
	)
	(segment
		(start 58.092086 -136.855708)
		(end 58.083704 -136.86409)
		(width 0.1016)
		(layer "B.Cu")
		(net "P1V538_BMC_NODE1")
	)
	(segment
		(start 131.810252 -137.09015)
		(end 131.810252 -137.26795)
		(width 0.4572)
		(layer "B.Cu")
		(net "P1V538_BMC_NODE1")
	)
	(segment
		(start 131.784852 -136.271)
		(end 131.784852 -137.06475)
		(width 0.4572)
		(layer "B.Cu")
		(net "P1V538_BMC_NODE1")
	)
	(segment
		(start 60.94095 -136.457944)
		(end 60.827158 -136.457944)
		(width 0.1016)
		(layer "B.Cu")
		(net "P1V538_BMC_NODE1")
	)
	(segment
		(start 126.292102 -146.20875)
		(end 126.933452 -146.20875)
		(width 0.4064)
		(layer "B.Cu")
		(net "P1V538_BMC_NODE1")
	)
	(segment
		(start 131.784852 -137.06475)
		(end 131.810252 -137.09015)
		(width 0.4572)
		(layer "B.Cu")
		(net "P1V538_BMC_NODE1")
	)
	(segment
		(start 58.142886 -136.055862)
		(end 60.606686 -136.055862)
		(width 0.1016)
		(layer "B.Cu")
		(net "P1V538_BMC_NODE1")
	)
	(segment
		(start 134.756652 -135.4709)
		(end 134.756652 -134.52475)
		(width 0.4572)
		(layer "B.Cu")
		(net "P1V538_BMC_NODE1")
	)
	(segment
		(start 126.266702 -143.00835)
		(end 127.035052 -143.00835)
		(width 0.4572)
		(layer "B.Cu")
		(net "P1V538_BMC_NODE1")
	)
	(segment
		(start 126.933452 -146.20875)
		(end 127.111252 -146.03095)
		(width 0.4064)
		(layer "B.Cu")
		(net "P1V538_BMC_NODE1")
	)
	(segment
		(start 134.756652 -134.52475)
		(end 134.731252 -134.49935)
		(width 0.4572)
		(layer "B.Cu")
		(net "P1V538_BMC_NODE1")
	)
	(segment
		(start 57.88406 -132.059426)
		(end 60.717938 -132.059426)
		(width 0.1016)
		(layer "In6.Cu")
		(net "P1V538_BMC_NODE1")
	)
	(segment
		(start 57.88406 -133.659626)
		(end 61.237876 -133.659626)
		(width 0.1016)
		(layer "In6.Cu")
		(net "P1V538_BMC_NODE1")
	)
	(segment
		(start 57.88406 -131.259326)
		(end 60.717938 -131.259326)
		(width 0.1016)
		(layer "In6.Cu")
		(net "P1V538_BMC_NODE1")
	)
	(segment
		(start 57.88406 -136.859518)
		(end 60.717938 -136.859518)
		(width 0.1016)
		(layer "In6.Cu")
		(net "P1V538_BMC_NODE1")
	)
	(segment
		(start 57.88406 -132.859526)
		(end 60.717938 -132.859526)
		(width 0.1016)
		(layer "In6.Cu")
		(net "P1V538_BMC_NODE1")
	)
	(segment
		(start 57.88406 -137.659618)
		(end 61.237876 -137.659618)
		(width 0.1016)
		(layer "In6.Cu")
		(net "P1V538_BMC_NODE1")
	)
	(segment
		(start 57.88406 -136.059418)
		(end 60.717938 -136.059418)
		(width 0.1016)
		(layer "In6.Cu")
		(net "P1V538_BMC_NODE1")
	)
	(segment
		(start 102.519734 -173.467268)
		(end 102.145592 -173.093126)
		(width 0.1016)
		(layer "F.Cu")
		(net "FAN_PWM_BUF")
	)
	(segment
		(start 102.145592 -172.465492)
		(end 101.567742 -171.887642)
		(width 0.1016)
		(layer "F.Cu")
		(net "FAN_PWM_BUF")
	)
	(segment
		(start 103.214932 -173.467268)
		(end 102.519734 -173.467268)
		(width 0.1016)
		(layer "F.Cu")
		(net "FAN_PWM_BUF")
	)
	(segment
		(start 102.145592 -173.093126)
		(end 102.145592 -172.465492)
		(width 0.1016)
		(layer "F.Cu")
		(net "FAN_PWM_BUF")
	)
	(segment
		(start 101.567742 -171.887642)
		(end 101.567742 -169.268394)
		(width 0.1016)
		(layer "F.Cu")
		(net "FAN_PWM_BUF")
	)
	(via
		(at 105.902252 -170.166538)
		(size 0.6604)
		(drill 0.3302)
		(layers "F.Cu" "B.Cu")
		(net "FAN_PWM_BUF")
	)
	(via
		(at 101.567742 -169.268394)
		(size 0.508)
		(drill 0.254)
		(layers "F.Cu" "B.Cu")
		(net "FAN_PWM_BUF")
	)
	(segment
		(start 104.909112 -168.997122)
		(end 105.902252 -169.990262)
		(width 0.1016)
		(layer "B.Cu")
		(net "FAN_PWM_BUF")
	)
	(segment
		(start 105.902252 -170.241722)
		(end 105.902252 -170.166538)
		(width 0.1016)
		(layer "B.Cu")
		(net "FAN_PWM_BUF")
	)
	(segment
		(start 102.613206 -169.452798)
		(end 103.114856 -169.452798)
		(width 0.1016)
		(layer "B.Cu")
		(net "FAN_PWM_BUF")
	)
	(segment
		(start 103.114856 -169.452798)
		(end 103.570532 -168.997122)
		(width 0.1016)
		(layer "B.Cu")
		(net "FAN_PWM_BUF")
	)
	(segment
		(start 101.752146 -169.452798)
		(end 102.613206 -169.452798)
		(width 0.1016)
		(layer "B.Cu")
		(net "FAN_PWM_BUF")
	)
	(segment
		(start 103.570532 -168.997122)
		(end 104.909112 -168.997122)
		(width 0.1016)
		(layer "B.Cu")
		(net "FAN_PWM_BUF")
	)
	(segment
		(start 101.567742 -169.268394)
		(end 101.752146 -169.452798)
		(width 0.1016)
		(layer "B.Cu")
		(net "FAN_PWM_BUF")
	)
	(segment
		(start 102.957122 -171.750482)
		(end 104.393492 -171.750482)
		(width 0.1016)
		(layer "B.Cu")
		(net "FAN_PWM_BUF")
	)
	(segment
		(start 105.902252 -169.990262)
		(end 105.902252 -170.166538)
		(width 0.1016)
		(layer "B.Cu")
		(net "FAN_PWM_BUF")
	)
	(segment
		(start 104.393492 -171.750482)
		(end 105.902252 -170.241722)
		(width 0.1016)
		(layer "B.Cu")
		(net "FAN_PWM_BUF")
	)
	(segment
		(start 110.31601 -157.447742)
		(end 110.31601 -156.397452)
		(width 0.1016)
		(layer "F.Cu")
		(net "N52410978")
	)
	(segment
		(start 112.57026 -153.688034)
		(end 112.57026 -154.972512)
		(width 0.1016)
		(layer "F.Cu")
		(net "N52410978")
	)
	(segment
		(start 112.709706 -153.548588)
		(end 112.57026 -153.688034)
		(width 0.1016)
		(layer "F.Cu")
		(net "N52410978")
	)
	(segment
		(start 111.50092 -155.212542)
		(end 112.81029 -155.212542)
		(width 0.1016)
		(layer "F.Cu")
		(net "N52410978")
	)
	(segment
		(start 113.78565 -153.548588)
		(end 112.709706 -153.548588)
		(width 0.1016)
		(layer "F.Cu")
		(net "N52410978")
	)
	(segment
		(start 112.57026 -154.972512)
		(end 112.81029 -155.212542)
		(width 0.1016)
		(layer "F.Cu")
		(net "N52410978")
	)
	(segment
		(start 110.31601 -156.397452)
		(end 111.02848 -155.684982)
		(width 0.1016)
		(layer "F.Cu")
		(net "N52410978")
	)
	(segment
		(start 111.02848 -155.684982)
		(end 111.50092 -155.212542)
		(width 0.1016)
		(layer "F.Cu")
		(net "N52410978")
	)
	(via
		(at 111.02848 -155.684982)
		(size 0.508)
		(drill 0.254)
		(layers "F.Cu" "B.Cu")
		(net "N52410978")
	)
	(segment
		(start 134.782052 -155.2448)
		(end 133.766052 -155.2448)
		(width 0.1016)
		(layer "F.Cu")
		(net "PCIE_SW_P0_ERR")
	)
	(segment
		(start 68.814696 -86.951312)
		(end 69.177408 -86.5886)
		(width 0.1016)
		(layer "F.Cu")
		(net "PCIE_SW_P0_ERR")
	)
	(segment
		(start 133.05917 -155.2448)
		(end 133.766052 -155.2448)
		(width 0.1016)
		(layer "F.Cu")
		(net "PCIE_SW_P0_ERR")
	)
	(segment
		(start 68.814696 -87.00389)
		(end 68.814696 -86.951312)
		(width 0.1016)
		(layer "F.Cu")
		(net "PCIE_SW_P0_ERR")
	)
	(segment
		(start 133.0452 -155.23083)
		(end 133.05917 -155.2448)
		(width 0.1016)
		(layer "F.Cu")
		(net "PCIE_SW_P0_ERR")
	)
	(segment
		(start 134.807452 -155.2194)
		(end 134.782052 -155.2448)
		(width 0.1016)
		(layer "F.Cu")
		(net "PCIE_SW_P0_ERR")
	)
	(via
		(at 100.51796 -103.512112)
		(size 0.508)
		(drill 0.254)
		(layers "F.Cu" "B.Cu")
		(net "PCIE_SW_P0_ERR")
	)
	(via
		(at 133.0452 -155.23083)
		(size 0.508)
		(drill 0.254)
		(layers "F.Cu" "B.Cu")
		(net "PCIE_SW_P0_ERR")
	)
	(via
		(at 122.13082 -84.815934)
		(size 0.508)
		(drill 0.254)
		(layers "F.Cu" "B.Cu")
		(net "PCIE_SW_P0_ERR")
	)
	(via
		(at 73.20788 -98.96602)
		(size 0.508)
		(drill 0.254)
		(layers "F.Cu" "B.Cu")
		(net "PCIE_SW_P0_ERR")
	)
	(via
		(at 69.177408 -86.5886)
		(size 0.508)
		(drill 0.254)
		(layers "F.Cu" "B.Cu")
		(net "PCIE_SW_P0_ERR")
	)
	(via
		(at 147.266152 -90.104722)
		(size 0.508)
		(drill 0.254)
		(layers "F.Cu" "B.Cu")
		(net "PCIE_SW_P0_ERR")
	)
	(segment
		(start 73.20788 -98.525838)
		(end 70.999096 -96.3168)
		(width 0.1016)
		(layer "B.Cu")
		(net "PCIE_SW_P0_ERR")
	)
	(segment
		(start 70.999096 -96.3168)
		(end 70.403466 -96.3168)
		(width 0.1016)
		(layer "B.Cu")
		(net "PCIE_SW_P0_ERR")
	)
	(segment
		(start 69.51472 -93.310964)
		(end 69.51472 -86.925912)
		(width 0.1016)
		(layer "B.Cu")
		(net "PCIE_SW_P0_ERR")
	)
	(segment
		(start 69.82968 -95.743014)
		(end 69.82968 -93.625924)
		(width 0.1016)
		(layer "B.Cu")
		(net "PCIE_SW_P0_ERR")
	)
	(segment
		(start 69.82968 -93.625924)
		(end 69.51472 -93.310964)
		(width 0.1016)
		(layer "B.Cu")
		(net "PCIE_SW_P0_ERR")
	)
	(segment
		(start 69.51472 -86.925912)
		(end 69.177408 -86.5886)
		(width 0.1016)
		(layer "B.Cu")
		(net "PCIE_SW_P0_ERR")
	)
	(segment
		(start 70.403466 -96.3168)
		(end 69.82968 -95.743014)
		(width 0.1016)
		(layer "B.Cu")
		(net "PCIE_SW_P0_ERR")
	)
	(segment
		(start 73.20788 -98.96602)
		(end 73.20788 -98.525838)
		(width 0.1016)
		(layer "B.Cu")
		(net "PCIE_SW_P0_ERR")
	)
	(segment
		(start 113.19764 -94.446598)
		(end 113.19764 -96.38538)
		(width 0.1143)
		(layer "In2.Cu")
		(net "PCIE_SW_P0_ERR")
	)
	(segment
		(start 147.395692 -145.27911)
		(end 147.395692 -141.672818)
		(width 0.1143)
		(layer "In2.Cu")
		(net "PCIE_SW_P0_ERR")
	)
	(segment
		(start 147.39366 -149.355048)
		(end 147.39366 -145.281142)
		(width 0.1143)
		(layer "In2.Cu")
		(net "PCIE_SW_P0_ERR")
	)
	(segment
		(start 133.0452 -155.23083)
		(end 133.887718 -155.23083)
		(width 0.1143)
		(layer "In2.Cu")
		(net "PCIE_SW_P0_ERR")
	)
	(segment
		(start 157.33268 -124.331222)
		(end 158.45155 -123.212352)
		(width 0.1143)
		(layer "In2.Cu")
		(net "PCIE_SW_P0_ERR")
	)
	(segment
		(start 157.33268 -128.400556)
		(end 157.33268 -124.331222)
		(width 0.1143)
		(layer "In2.Cu")
		(net "PCIE_SW_P0_ERR")
	)
	(segment
		(start 147.460462 -138.272774)
		(end 157.33268 -128.400556)
		(width 0.1143)
		(layer "In2.Cu")
		(net "PCIE_SW_P0_ERR")
	)
	(segment
		(start 153.01087 -104.544114)
		(end 152.208992 -103.742236)
		(width 0.1143)
		(layer "In2.Cu")
		(net "PCIE_SW_P0_ERR")
	)
	(segment
		(start 122.13082 -85.513418)
		(end 113.19764 -94.446598)
		(width 0.1143)
		(layer "In2.Cu")
		(net "PCIE_SW_P0_ERR")
	)
	(segment
		(start 147.395692 -141.672818)
		(end 147.460462 -141.608048)
		(width 0.1143)
		(layer "In2.Cu")
		(net "PCIE_SW_P0_ERR")
	)
	(segment
		(start 113.19764 -96.38538)
		(end 107.199684 -102.383336)
		(width 0.1143)
		(layer "In2.Cu")
		(net "PCIE_SW_P0_ERR")
	)
	(segment
		(start 147.39366 -145.281142)
		(end 147.395692 -145.27911)
		(width 0.1143)
		(layer "In2.Cu")
		(net "PCIE_SW_P0_ERR")
	)
	(segment
		(start 158.45155 -123.212352)
		(end 158.45155 -113.850928)
		(width 0.1143)
		(layer "In2.Cu")
		(net "PCIE_SW_P0_ERR")
	)
	(segment
		(start 158.45155 -113.850928)
		(end 153.01087 -108.410248)
		(width 0.1143)
		(layer "In2.Cu")
		(net "PCIE_SW_P0_ERR")
	)
	(segment
		(start 122.13082 -84.815934)
		(end 122.13082 -85.513418)
		(width 0.1143)
		(layer "In2.Cu")
		(net "PCIE_SW_P0_ERR")
	)
	(segment
		(start 133.996938 -155.12161)
		(end 141.627098 -155.12161)
		(width 0.1143)
		(layer "In2.Cu")
		(net "PCIE_SW_P0_ERR")
	)
	(segment
		(start 147.460462 -141.608048)
		(end 147.460462 -138.272774)
		(width 0.1143)
		(layer "In2.Cu")
		(net "PCIE_SW_P0_ERR")
	)
	(segment
		(start 101.646482 -102.383336)
		(end 100.51796 -103.511858)
		(width 0.1143)
		(layer "In2.Cu")
		(net "PCIE_SW_P0_ERR")
	)
	(segment
		(start 152.208992 -103.742236)
		(end 152.208992 -95.047562)
		(width 0.1143)
		(layer "In2.Cu")
		(net "PCIE_SW_P0_ERR")
	)
	(segment
		(start 100.51796 -103.511858)
		(end 100.51796 -103.512112)
		(width 0.1143)
		(layer "In2.Cu")
		(net "PCIE_SW_P0_ERR")
	)
	(segment
		(start 141.627098 -155.12161)
		(end 147.39366 -149.355048)
		(width 0.1143)
		(layer "In2.Cu")
		(net "PCIE_SW_P0_ERR")
	)
	(segment
		(start 152.208992 -95.047562)
		(end 147.266152 -90.104722)
		(width 0.1143)
		(layer "In2.Cu")
		(net "PCIE_SW_P0_ERR")
	)
	(segment
		(start 107.199684 -102.383336)
		(end 101.646482 -102.383336)
		(width 0.1143)
		(layer "In2.Cu")
		(net "PCIE_SW_P0_ERR")
	)
	(segment
		(start 133.887718 -155.23083)
		(end 133.996938 -155.12161)
		(width 0.1143)
		(layer "In2.Cu")
		(net "PCIE_SW_P0_ERR")
	)
	(segment
		(start 153.01087 -108.410248)
		(end 153.01087 -104.544114)
		(width 0.1143)
		(layer "In2.Cu")
		(net "PCIE_SW_P0_ERR")
	)
	(segment
		(start 100.464112 -103.458264)
		(end 98.462338 -103.458264)
		(width 0.1143)
		(layer "In7.Cu")
		(net "PCIE_SW_P0_ERR")
	)
	(segment
		(start 76.389992 -102.148132)
		(end 73.20788 -98.96602)
		(width 0.1143)
		(layer "In7.Cu")
		(net "PCIE_SW_P0_ERR")
	)
	(segment
		(start 130.197606 -90.104722)
		(end 147.266152 -90.104722)
		(width 0.1143)
		(layer "In7.Cu")
		(net "PCIE_SW_P0_ERR")
	)
	(segment
		(start 100.51796 -103.512112)
		(end 100.464112 -103.458264)
		(width 0.1143)
		(layer "In7.Cu")
		(net "PCIE_SW_P0_ERR")
	)
	(segment
		(start 97.152206 -102.148132)
		(end 76.389992 -102.148132)
		(width 0.1143)
		(layer "In7.Cu")
		(net "PCIE_SW_P0_ERR")
	)
	(segment
		(start 130.02133 -89.928446)
		(end 130.197606 -90.104722)
		(width 0.1143)
		(layer "In7.Cu")
		(net "PCIE_SW_P0_ERR")
	)
	(segment
		(start 98.462338 -103.458264)
		(end 97.152206 -102.148132)
		(width 0.1143)
		(layer "In7.Cu")
		(net "PCIE_SW_P0_ERR")
	)
	(segment
		(start 122.13082 -84.815934)
		(end 127.243332 -89.928446)
		(width 0.1143)
		(layer "In7.Cu")
		(net "PCIE_SW_P0_ERR")
	)
	(segment
		(start 127.243332 -89.928446)
		(end 130.02133 -89.928446)
		(width 0.1143)
		(layer "In7.Cu")
		(net "PCIE_SW_P0_ERR")
	)
	(segment
		(start 125.787912 -149.375622)
		(end 127.026924 -149.375622)
		(width 0.1016)
		(layer "F.Cu")
		(net "PCIE_SW_TEST2")
	)
	(segment
		(start 126.552452 -150.50135)
		(end 127.136652 -149.91715)
		(width 0.1016)
		(layer "F.Cu")
		(net "PCIE_SW_TEST2")
	)
	(segment
		(start 127.136652 -149.91715)
		(end 127.136652 -149.48535)
		(width 0.1016)
		(layer "F.Cu")
		(net "PCIE_SW_TEST2")
	)
	(segment
		(start 126.552452 -153.2763)
		(end 126.552452 -150.50135)
		(width 0.1016)
		(layer "F.Cu")
		(net "PCIE_SW_TEST2")
	)
	(segment
		(start 127.026924 -149.375622)
		(end 127.136652 -149.48535)
		(width 0.1016)
		(layer "F.Cu")
		(net "PCIE_SW_TEST2")
	)
	(via
		(at 127.136652 -149.48535)
		(size 0.508)
		(drill 0.254)
		(layers "F.Cu" "B.Cu")
		(net "PCIE_SW_TEST2")
	)
	(segment
		(start 143.258032 -149.69617)
		(end 142.638272 -149.69617)
		(width 0.1016)
		(layer "F.Cu")
		(net "PCIE_SW_TEST1")
	)
	(segment
		(start 141.288008 -149.375622)
		(end 142.317724 -149.375622)
		(width 0.1016)
		(layer "F.Cu")
		(net "PCIE_SW_TEST1")
	)
	(segment
		(start 143.748252 -149.20595)
		(end 143.258032 -149.69617)
		(width 0.1016)
		(layer "F.Cu")
		(net "PCIE_SW_TEST1")
	)
	(segment
		(start 142.317724 -149.375622)
		(end 142.638272 -149.69617)
		(width 0.1016)
		(layer "F.Cu")
		(net "PCIE_SW_TEST1")
	)
	(segment
		(start 144.364202 -149.20595)
		(end 143.748252 -149.20595)
		(width 0.1016)
		(layer "F.Cu")
		(net "PCIE_SW_TEST1")
	)
	(via
		(at 142.638272 -149.69617)
		(size 0.508)
		(drill 0.254)
		(layers "F.Cu" "B.Cu")
		(net "PCIE_SW_TEST1")
	)
	(segment
		(start 137.779252 -153.25979)
		(end 137.883392 -153.15565)
		(width 0.1016)
		(layer "F.Cu")
		(net "PCIE_SW_TEST7")
	)
	(segment
		(start 137.779252 -154.3939)
		(end 137.779252 -153.25979)
		(width 0.1016)
		(layer "F.Cu")
		(net "PCIE_SW_TEST7")
	)
	(segment
		(start 137.73785 -153.010108)
		(end 137.883392 -153.15565)
		(width 0.1016)
		(layer "F.Cu")
		(net "PCIE_SW_TEST7")
	)
	(segment
		(start 137.73785 -151.32558)
		(end 137.73785 -153.010108)
		(width 0.1016)
		(layer "F.Cu")
		(net "PCIE_SW_TEST7")
	)
	(via
		(at 137.883392 -153.15565)
		(size 0.508)
		(drill 0.254)
		(layers "F.Cu" "B.Cu")
		(net "PCIE_SW_TEST7")
	)
	(segment
		(start 139.737846 -151.32558)
		(end 139.737846 -153.578306)
		(width 0.1016)
		(layer "F.Cu")
		(net "PCIE_SW_P2_CTCDIS")
	)
	(segment
		(start 139.17676 -153.578306)
		(end 138.922252 -153.832814)
		(width 0.1016)
		(layer "F.Cu")
		(net "PCIE_SW_P2_CTCDIS")
	)
	(segment
		(start 139.737846 -153.578306)
		(end 139.17676 -153.578306)
		(width 0.1016)
		(layer "F.Cu")
		(net "PCIE_SW_P2_CTCDIS")
	)
	(segment
		(start 138.922252 -153.832814)
		(end 138.922252 -154.3939)
		(width 0.1016)
		(layer "F.Cu")
		(net "PCIE_SW_P2_CTCDIS")
	)
	(via
		(at 139.737846 -153.578306)
		(size 0.508)
		(drill 0.254)
		(layers "F.Cu" "B.Cu")
		(net "PCIE_SW_P2_CTCDIS")
	)
	(segment
		(start 141.288008 -149.775418)
		(end 141.65072 -149.775418)
		(width 0.1016)
		(layer "F.Cu")
		(net "PCIE_SW_P1_CTCDIS")
	)
	(segment
		(start 144.389602 -150.19655)
		(end 144.389602 -151.08301)
		(width 0.1016)
		(layer "F.Cu")
		(net "PCIE_SW_P1_CTCDIS")
	)
	(segment
		(start 144.389602 -151.08301)
		(end 144.313402 -151.15921)
		(width 0.1016)
		(layer "F.Cu")
		(net "PCIE_SW_P1_CTCDIS")
	)
	(segment
		(start 141.65072 -149.775418)
		(end 143.034512 -151.15921)
		(width 0.1016)
		(layer "F.Cu")
		(net "PCIE_SW_P1_CTCDIS")
	)
	(segment
		(start 143.034512 -151.15921)
		(end 144.313402 -151.15921)
		(width 0.1016)
		(layer "F.Cu")
		(net "PCIE_SW_P1_CTCDIS")
	)
	(via
		(at 144.313402 -151.15921)
		(size 0.508)
		(drill 0.254)
		(layers "F.Cu" "B.Cu")
		(net "PCIE_SW_P1_CTCDIS")
	)
	(segment
		(start 141.288008 -144.17548)
		(end 142.095982 -144.17548)
		(width 0.1016)
		(layer "F.Cu")
		(net "PCIE_SW_P0_CTCDIS")
	)
	(segment
		(start 144.516602 -145.21815)
		(end 142.661132 -145.21815)
		(width 0.1016)
		(layer "F.Cu")
		(net "PCIE_SW_P0_CTCDIS")
	)
	(segment
		(start 142.661132 -145.21815)
		(end 142.648432 -145.23085)
		(width 0.1016)
		(layer "F.Cu")
		(net "PCIE_SW_P0_CTCDIS")
	)
	(segment
		(start 142.518892 -144.59839)
		(end 142.518892 -145.10131)
		(width 0.1016)
		(layer "F.Cu")
		(net "PCIE_SW_P0_CTCDIS")
	)
	(segment
		(start 142.095982 -144.17548)
		(end 142.518892 -144.59839)
		(width 0.1016)
		(layer "F.Cu")
		(net "PCIE_SW_P0_CTCDIS")
	)
	(segment
		(start 142.518892 -145.10131)
		(end 142.648432 -145.23085)
		(width 0.1016)
		(layer "F.Cu")
		(net "PCIE_SW_P0_CTCDIS")
	)
	(via
		(at 142.648432 -145.23085)
		(size 0.508)
		(drill 0.254)
		(layers "F.Cu" "B.Cu")
		(net "PCIE_SW_P0_CTCDIS")
	)
	(segment
		(start 146.704812 -143.607282)
		(end 147.033742 -143.936212)
		(width 0.1016)
		(layer "F.Cu")
		(net "PCIE_SW_PWR_SAV")
	)
	(segment
		(start 144.567402 -144.150842)
		(end 144.674082 -144.044162)
		(width 0.1016)
		(layer "F.Cu")
		(net "PCIE_SW_PWR_SAV")
	)
	(segment
		(start 144.567402 -144.15135)
		(end 144.567402 -144.150842)
		(width 0.1016)
		(layer "F.Cu")
		(net "PCIE_SW_PWR_SAV")
	)
	(segment
		(start 142.630652 -144.20215)
		(end 143.860012 -144.20215)
		(width 0.1016)
		(layer "F.Cu")
		(net "PCIE_SW_PWR_SAV")
	)
	(segment
		(start 147.033742 -143.936212)
		(end 147.033742 -144.082262)
		(width 0.1016)
		(layer "F.Cu")
		(net "PCIE_SW_PWR_SAV")
	)
	(segment
		(start 142.203932 -143.77543)
		(end 142.630652 -144.20215)
		(width 0.1016)
		(layer "F.Cu")
		(net "PCIE_SW_PWR_SAV")
	)
	(segment
		(start 144.739868 -144.044162)
		(end 145.176748 -143.607282)
		(width 0.1016)
		(layer "F.Cu")
		(net "PCIE_SW_PWR_SAV")
	)
	(segment
		(start 144.674082 -144.044162)
		(end 144.739868 -144.044162)
		(width 0.1016)
		(layer "F.Cu")
		(net "PCIE_SW_PWR_SAV")
	)
	(segment
		(start 145.176748 -143.607282)
		(end 146.704812 -143.607282)
		(width 0.1016)
		(layer "F.Cu")
		(net "PCIE_SW_PWR_SAV")
	)
	(segment
		(start 143.860012 -144.20215)
		(end 144.516602 -144.20215)
		(width 0.1016)
		(layer "F.Cu")
		(net "PCIE_SW_PWR_SAV")
	)
	(segment
		(start 141.288008 -143.77543)
		(end 142.203932 -143.77543)
		(width 0.1016)
		(layer "F.Cu")
		(net "PCIE_SW_PWR_SAV")
	)
	(segment
		(start 144.516602 -144.20215)
		(end 144.567402 -144.15135)
		(width 0.1016)
		(layer "F.Cu")
		(net "PCIE_SW_PWR_SAV")
	)
	(via
		(at 143.860012 -144.20215)
		(size 0.508)
		(drill 0.254)
		(layers "F.Cu" "B.Cu")
		(net "PCIE_SW_PWR_SAV")
	)
	(segment
		(start 109.770926 -154.02306)
		(end 109.770926 -153.54808)
		(width 0.1016)
		(layer "F.Cu")
		(net "N52411212")
	)
	(segment
		(start 109.30001 -154.493976)
		(end 109.60608 -154.187906)
		(width 0.1016)
		(layer "F.Cu")
		(net "N52411212")
	)
	(segment
		(start 109.30001 -155.212542)
		(end 109.30001 -154.493976)
		(width 0.1016)
		(layer "F.Cu")
		(net "N52411212")
	)
	(segment
		(start 109.60608 -154.187906)
		(end 109.770926 -154.02306)
		(width 0.1016)
		(layer "F.Cu")
		(net "N52411212")
	)
	(segment
		(start 108.788454 -153.54808)
		(end 109.770926 -153.54808)
		(width 0.1016)
		(layer "F.Cu")
		(net "N52411212")
	)
	(via
		(at 109.60608 -154.187906)
		(size 0.508)
		(drill 0.254)
		(layers "F.Cu" "B.Cu")
		(net "N52411212")
	)
	(segment
		(start 141.288008 -139.375642)
		(end 142.04696 -139.375642)
		(width 0.1016)
		(layer "F.Cu")
		(net "PCIE_SW_WAKE_N")
	)
	(segment
		(start 142.04696 -139.375642)
		(end 143.037052 -138.38555)
		(width 0.1016)
		(layer "F.Cu")
		(net "PCIE_SW_WAKE_N")
	)
	(segment
		(start 143.037052 -138.38555)
		(end 143.037052 -137.66165)
		(width 0.1016)
		(layer "F.Cu")
		(net "PCIE_SW_WAKE_N")
	)
	(segment
		(start 143.037052 -137.66165)
		(end 143.049752 -137.64895)
		(width 0.1016)
		(layer "F.Cu")
		(net "PCIE_SW_WAKE_N")
	)
	(segment
		(start 144.516602 -137.36955)
		(end 143.329152 -137.36955)
		(width 0.1016)
		(layer "F.Cu")
		(net "PCIE_SW_WAKE_N")
	)
	(segment
		(start 143.329152 -137.36955)
		(end 143.049752 -137.64895)
		(width 0.1016)
		(layer "F.Cu")
		(net "PCIE_SW_WAKE_N")
	)
	(via
		(at 143.049752 -137.64895)
		(size 0.508)
		(drill 0.254)
		(layers "F.Cu" "B.Cu")
		(net "PCIE_SW_WAKE_N")
	)
	(segment
		(start 98.161856 -161.827718)
		(end 97.250504 -161.827718)
		(width 0.1016)
		(layer "F.Cu")
		(net "N52411040")
	)
	(segment
		(start 97.250504 -161.827718)
		(end 97.17532 -161.902902)
		(width 0.1016)
		(layer "F.Cu")
		(net "N52411040")
	)
	(segment
		(start 99.182428 -161.827718)
		(end 98.161856 -161.827718)
		(width 0.1016)
		(layer "F.Cu")
		(net "N52411040")
	)
	(segment
		(start 95.813372 -162.254692)
		(end 96.82353 -162.254692)
		(width 0.1016)
		(layer "F.Cu")
		(net "N52411040")
	)
	(segment
		(start 96.82353 -162.254692)
		(end 97.17532 -161.902902)
		(width 0.1016)
		(layer "F.Cu")
		(net "N52411040")
	)
	(via
		(at 97.17532 -161.902902)
		(size 0.508)
		(drill 0.254)
		(layers "F.Cu" "B.Cu")
		(net "N52411040")
	)
	(segment
		(start 92.639896 -160.561782)
		(end 92.975176 -160.226502)
		(width 0.1016)
		(layer "F.Cu")
		(net "N52410998")
	)
	(segment
		(start 91.083892 -159.824928)
		(end 91.820746 -160.561782)
		(width 0.1016)
		(layer "F.Cu")
		(net "N52410998")
	)
	(segment
		(start 93.352874 -161.469578)
		(end 93.339158 -161.455862)
		(width 0.1016)
		(layer "F.Cu")
		(net "N52410998")
	)
	(segment
		(start 94.418912 -161.469578)
		(end 93.352874 -161.469578)
		(width 0.1016)
		(layer "F.Cu")
		(net "N52410998")
	)
	(segment
		(start 94.797372 -161.091118)
		(end 94.418912 -161.469578)
		(width 0.1016)
		(layer "F.Cu")
		(net "N52410998")
	)
	(segment
		(start 90.753692 -159.824928)
		(end 91.083892 -159.824928)
		(width 0.1016)
		(layer "F.Cu")
		(net "N52410998")
	)
	(segment
		(start 91.820746 -160.561782)
		(end 92.639896 -160.561782)
		(width 0.1016)
		(layer "F.Cu")
		(net "N52410998")
	)
	(segment
		(start 93.339158 -161.455862)
		(end 93.339158 -160.226502)
		(width 0.1016)
		(layer "F.Cu")
		(net "N52410998")
	)
	(segment
		(start 92.975176 -160.226502)
		(end 93.339158 -160.226502)
		(width 0.1016)
		(layer "F.Cu")
		(net "N52410998")
	)
	(segment
		(start 94.797372 -160.019492)
		(end 94.797372 -161.091118)
		(width 0.1016)
		(layer "F.Cu")
		(net "N52410998")
	)
	(via
		(at 94.797372 -161.091118)
		(size 0.508)
		(drill 0.254)
		(layers "F.Cu" "B.Cu")
		(net "N52410998")
	)
	(segment
		(start 144.542002 -142.19555)
		(end 144.332452 -142.19555)
		(width 0.1016)
		(layer "F.Cu")
		(net "PCIE_SW_I2C_SDA")
	)
	(segment
		(start 145.043652 -142.67815)
		(end 144.561052 -142.19555)
		(width 0.1016)
		(layer "F.Cu")
		(net "PCIE_SW_I2C_SDA")
	)
	(segment
		(start 144.561052 -142.19555)
		(end 144.542002 -142.19555)
		(width 0.1016)
		(layer "F.Cu")
		(net "PCIE_SW_I2C_SDA")
	)
	(segment
		(start 146.32686 -142.67815)
		(end 145.043652 -142.67815)
		(width 0.1016)
		(layer "F.Cu")
		(net "PCIE_SW_I2C_SDA")
	)
	(segment
		(start 144.332452 -142.19555)
		(end 143.205962 -143.32204)
		(width 0.1016)
		(layer "F.Cu")
		(net "PCIE_SW_I2C_SDA")
	)
	(segment
		(start 146.90598 -142.09903)
		(end 146.32686 -142.67815)
		(width 0.1016)
		(layer "F.Cu")
		(net "PCIE_SW_I2C_SDA")
	)
	(segment
		(start 143.205962 -143.32204)
		(end 142.59179 -143.32204)
		(width 0.1016)
		(layer "F.Cu")
		(net "PCIE_SW_I2C_SDA")
	)
	(segment
		(start 147.640802 -142.09903)
		(end 146.90598 -142.09903)
		(width 0.1016)
		(layer "F.Cu")
		(net "PCIE_SW_I2C_SDA")
	)
	(segment
		(start 142.538196 -143.375634)
		(end 141.288008 -143.375634)
		(width 0.1016)
		(layer "F.Cu")
		(net "PCIE_SW_I2C_SDA")
	)
	(segment
		(start 142.59179 -143.32204)
		(end 142.538196 -143.375634)
		(width 0.1016)
		(layer "F.Cu")
		(net "PCIE_SW_I2C_SDA")
	)
	(via
		(at 142.538196 -143.375634)
		(size 0.508)
		(drill 0.254)
		(layers "F.Cu" "B.Cu")
		(net "PCIE_SW_I2C_SDA")
	)
	(segment
		(start 144.999202 -141.68755)
		(end 144.516602 -141.20495)
		(width 0.1016)
		(layer "F.Cu")
		(net "PCIE_SW_I2C_SCL")
	)
	(segment
		(start 144.307052 -141.20495)
		(end 143.261842 -142.25016)
		(width 0.1016)
		(layer "F.Cu")
		(net "PCIE_SW_I2C_SCL")
	)
	(segment
		(start 143.261842 -142.25016)
		(end 142.272766 -142.25016)
		(width 0.1016)
		(layer "F.Cu")
		(net "PCIE_SW_I2C_SCL")
	)
	(segment
		(start 144.516602 -141.20495)
		(end 144.307052 -141.20495)
		(width 0.1016)
		(layer "F.Cu")
		(net "PCIE_SW_I2C_SCL")
	)
	(segment
		(start 142.272766 -142.25016)
		(end 142.19809 -142.175484)
		(width 0.1016)
		(layer "F.Cu")
		(net "PCIE_SW_I2C_SCL")
	)
	(segment
		(start 146.755612 -141.31417)
		(end 146.382232 -141.68755)
		(width 0.1016)
		(layer "F.Cu")
		(net "PCIE_SW_I2C_SCL")
	)
	(segment
		(start 147.658582 -141.02969)
		(end 147.040092 -141.02969)
		(width 0.1016)
		(layer "F.Cu")
		(net "PCIE_SW_I2C_SCL")
	)
	(segment
		(start 142.19809 -142.175484)
		(end 141.288008 -142.175484)
		(width 0.1016)
		(layer "F.Cu")
		(net "PCIE_SW_I2C_SCL")
	)
	(segment
		(start 146.382232 -141.68755)
		(end 144.999202 -141.68755)
		(width 0.1016)
		(layer "F.Cu")
		(net "PCIE_SW_I2C_SCL")
	)
	(segment
		(start 147.040092 -141.02969)
		(end 146.755612 -141.31417)
		(width 0.1016)
		(layer "F.Cu")
		(net "PCIE_SW_I2C_SCL")
	)
	(via
		(at 146.755612 -141.31417)
		(size 0.508)
		(drill 0.254)
		(layers "F.Cu" "B.Cu")
		(net "PCIE_SW_I2C_SCL")
	)
	(segment
		(start 136.862312 -152.42921)
		(end 136.862312 -153.14803)
		(width 0.1016)
		(layer "F.Cu")
		(net "PCIE_SW_EEPROM_DAT")
	)
	(segment
		(start 147.319746 -151.43226)
		(end 146.913346 -151.02586)
		(width 0.1016)
		(layer "F.Cu")
		(net "PCIE_SW_EEPROM_DAT")
	)
	(segment
		(start 146.913346 -151.02586)
		(end 146.913346 -150.644098)
		(width 0.1016)
		(layer "F.Cu")
		(net "PCIE_SW_EEPROM_DAT")
	)
	(segment
		(start 147.319746 -152.705816)
		(end 147.319746 -151.43226)
		(width 0.1016)
		(layer "F.Cu")
		(net "PCIE_SW_EEPROM_DAT")
	)
	(segment
		(start 136.537954 -152.104852)
		(end 136.862312 -152.42921)
		(width 0.1016)
		(layer "F.Cu")
		(net "PCIE_SW_EEPROM_DAT")
	)
	(segment
		(start 136.537954 -151.32558)
		(end 136.537954 -152.104852)
		(width 0.1016)
		(layer "F.Cu")
		(net "PCIE_SW_EEPROM_DAT")
	)
	(segment
		(start 144.50822 -154.369516)
		(end 146.17192 -152.705816)
		(width 0.1016)
		(layer "F.Cu")
		(net "PCIE_SW_EEPROM_DAT")
	)
	(segment
		(start 146.17192 -152.705816)
		(end 147.319746 -152.705816)
		(width 0.1016)
		(layer "F.Cu")
		(net "PCIE_SW_EEPROM_DAT")
	)
	(via
		(at 144.50822 -154.369516)
		(size 0.508)
		(drill 0.254)
		(layers "F.Cu" "B.Cu")
		(net "PCIE_SW_EEPROM_DAT")
	)
	(via
		(at 136.862312 -153.14803)
		(size 0.508)
		(drill 0.254)
		(layers "F.Cu" "B.Cu")
		(net "PCIE_SW_EEPROM_DAT")
	)
	(segment
		(start 136.862312 -153.14803)
		(end 136.862312 -153.212546)
		(width 0.1016)
		(layer "B.Cu")
		(net "PCIE_SW_EEPROM_DAT")
	)
	(segment
		(start 144.47901 -154.340306)
		(end 144.50822 -154.369516)
		(width 0.1016)
		(layer "B.Cu")
		(net "PCIE_SW_EEPROM_DAT")
	)
	(segment
		(start 137.990072 -154.340306)
		(end 144.47901 -154.340306)
		(width 0.1016)
		(layer "B.Cu")
		(net "PCIE_SW_EEPROM_DAT")
	)
	(segment
		(start 136.862312 -153.212546)
		(end 137.990072 -154.340306)
		(width 0.1016)
		(layer "B.Cu")
		(net "PCIE_SW_EEPROM_DAT")
	)
	(segment
		(start 142.544292 -147.775422)
		(end 141.288008 -147.775422)
		(width 0.1016)
		(layer "F.Cu")
		(net "PCIE_SW_GPIO6")
	)
	(segment
		(start 144.338802 -147.19935)
		(end 143.392652 -147.19935)
		(width 0.1016)
		(layer "F.Cu")
		(net "PCIE_SW_GPIO6")
	)
	(segment
		(start 143.392652 -147.19935)
		(end 142.81658 -147.775422)
		(width 0.1016)
		(layer "F.Cu")
		(net "PCIE_SW_GPIO6")
	)
	(segment
		(start 142.81658 -147.775422)
		(end 142.544292 -147.775422)
		(width 0.1016)
		(layer "F.Cu")
		(net "PCIE_SW_GPIO6")
	)
	(via
		(at 142.544292 -147.775422)
		(size 0.508)
		(drill 0.254)
		(layers "F.Cu" "B.Cu")
		(net "PCIE_SW_GPIO6")
	)
	(segment
		(start 142.125954 -148.175472)
		(end 142.480792 -148.53031)
		(width 0.1016)
		(layer "F.Cu")
		(net "PCIE_SW_GPIO7")
	)
	(segment
		(start 141.288008 -148.175472)
		(end 142.125954 -148.175472)
		(width 0.1016)
		(layer "F.Cu")
		(net "PCIE_SW_GPIO7")
	)
	(segment
		(start 143.926052 -148.21535)
		(end 143.611092 -148.53031)
		(width 0.1016)
		(layer "F.Cu")
		(net "PCIE_SW_GPIO7")
	)
	(segment
		(start 142.480792 -148.53031)
		(end 143.611092 -148.53031)
		(width 0.1016)
		(layer "F.Cu")
		(net "PCIE_SW_GPIO7")
	)
	(segment
		(start 144.364202 -148.21535)
		(end 143.926052 -148.21535)
		(width 0.1016)
		(layer "F.Cu")
		(net "PCIE_SW_GPIO7")
	)
	(via
		(at 143.611092 -148.53031)
		(size 0.508)
		(drill 0.254)
		(layers "F.Cu" "B.Cu")
		(net "PCIE_SW_GPIO7")
	)
	(segment
		(start 137.29716 -152.438354)
		(end 136.938004 -152.079198)
		(width 0.1016)
		(layer "F.Cu")
		(net "PCIE_SW_EEPROM_CLK")
	)
	(segment
		(start 147.319746 -153.975816)
		(end 145.814034 -153.975816)
		(width 0.1016)
		(layer "F.Cu")
		(net "PCIE_SW_EEPROM_CLK")
	)
	(segment
		(start 147.929346 -151.377396)
		(end 147.929346 -150.644098)
		(width 0.1016)
		(layer "F.Cu")
		(net "PCIE_SW_EEPROM_CLK")
	)
	(segment
		(start 148.47316 -153.699718)
		(end 148.47316 -151.92121)
		(width 0.1016)
		(layer "F.Cu")
		(net "PCIE_SW_EEPROM_CLK")
	)
	(segment
		(start 148.197062 -153.975816)
		(end 148.47316 -153.699718)
		(width 0.1016)
		(layer "F.Cu")
		(net "PCIE_SW_EEPROM_CLK")
	)
	(segment
		(start 137.29716 -152.656032)
		(end 137.29716 -152.438354)
		(width 0.1016)
		(layer "F.Cu")
		(net "PCIE_SW_EEPROM_CLK")
	)
	(segment
		(start 148.47316 -151.92121)
		(end 147.929346 -151.377396)
		(width 0.1016)
		(layer "F.Cu")
		(net "PCIE_SW_EEPROM_CLK")
	)
	(segment
		(start 147.319746 -153.975816)
		(end 148.197062 -153.975816)
		(width 0.1016)
		(layer "F.Cu")
		(net "PCIE_SW_EEPROM_CLK")
	)
	(segment
		(start 136.938004 -152.079198)
		(end 136.938004 -151.32558)
		(width 0.1016)
		(layer "F.Cu")
		(net "PCIE_SW_EEPROM_CLK")
	)
	(via
		(at 145.814034 -153.975816)
		(size 0.508)
		(drill 0.254)
		(layers "F.Cu" "B.Cu")
		(net "PCIE_SW_EEPROM_CLK")
	)
	(via
		(at 137.29716 -152.656032)
		(size 0.508)
		(drill 0.254)
		(layers "F.Cu" "B.Cu")
		(net "PCIE_SW_EEPROM_CLK")
	)
	(segment
		(start 145.699734 -153.861516)
		(end 143.69161 -153.861516)
		(width 0.1016)
		(layer "B.Cu")
		(net "PCIE_SW_EEPROM_CLK")
	)
	(segment
		(start 138.095482 -154.086306)
		(end 137.29716 -153.287984)
		(width 0.1016)
		(layer "B.Cu")
		(net "PCIE_SW_EEPROM_CLK")
	)
	(segment
		(start 143.69161 -153.861516)
		(end 143.46682 -154.086306)
		(width 0.1016)
		(layer "B.Cu")
		(net "PCIE_SW_EEPROM_CLK")
	)
	(segment
		(start 143.46682 -154.086306)
		(end 138.095482 -154.086306)
		(width 0.1016)
		(layer "B.Cu")
		(net "PCIE_SW_EEPROM_CLK")
	)
	(segment
		(start 145.814034 -153.975816)
		(end 145.699734 -153.861516)
		(width 0.1016)
		(layer "B.Cu")
		(net "PCIE_SW_EEPROM_CLK")
	)
	(segment
		(start 137.29716 -153.287984)
		(end 137.29716 -152.656032)
		(width 0.1016)
		(layer "B.Cu")
		(net "PCIE_SW_EEPROM_CLK")
	)
	(segment
		(start 143.872712 -146.20875)
		(end 143.727932 -146.35353)
		(width 0.1016)
		(layer "F.Cu")
		(net "PCIE_SW_GPIO5")
	)
	(segment
		(start 144.338802 -146.20875)
		(end 143.872712 -146.20875)
		(width 0.1016)
		(layer "F.Cu")
		(net "PCIE_SW_GPIO5")
	)
	(segment
		(start 142.108936 -147.375626)
		(end 142.478252 -147.00631)
		(width 0.1016)
		(layer "F.Cu")
		(net "PCIE_SW_GPIO5")
	)
	(segment
		(start 143.075152 -147.00631)
		(end 143.727932 -146.35353)
		(width 0.1016)
		(layer "F.Cu")
		(net "PCIE_SW_GPIO5")
	)
	(segment
		(start 141.288008 -147.375626)
		(end 142.108936 -147.375626)
		(width 0.1016)
		(layer "F.Cu")
		(net "PCIE_SW_GPIO5")
	)
	(segment
		(start 142.478252 -147.00631)
		(end 143.075152 -147.00631)
		(width 0.1016)
		(layer "F.Cu")
		(net "PCIE_SW_GPIO5")
	)
	(via
		(at 143.727932 -146.35353)
		(size 0.508)
		(drill 0.254)
		(layers "F.Cu" "B.Cu")
		(net "PCIE_SW_GPIO5")
	)
	(segment
		(start 130.537966 -151.32558)
		(end 130.537966 -153.651204)
		(width 0.1016)
		(layer "F.Cu")
		(net "PCIE_SW_SCAN_EN")
	)
	(segment
		(start 130.88112 -153.994358)
		(end 130.570732 -153.68397)
		(width 0.1016)
		(layer "F.Cu")
		(net "PCIE_SW_SCAN_EN")
	)
	(segment
		(start 130.88112 -154.696668)
		(end 130.88112 -153.994358)
		(width 0.1016)
		(layer "F.Cu")
		(net "PCIE_SW_SCAN_EN")
	)
	(segment
		(start 130.537966 -153.651204)
		(end 130.570732 -153.68397)
		(width 0.1016)
		(layer "F.Cu")
		(net "PCIE_SW_SCAN_EN")
	)
	(via
		(at 130.570732 -153.68397)
		(size 0.508)
		(drill 0.254)
		(layers "F.Cu" "B.Cu")
		(net "PCIE_SW_SCAN_EN")
	)
	(segment
		(start 70.141846 -128.753108)
		(end 70.438772 -128.456182)
		(width 0.1016)
		(layer "F.Cu")
		(net "PD_BMC_LPC")
	)
	(segment
		(start 74.141838 -127.259588)
		(end 75.724766 -127.259588)
		(width 0.1016)
		(layer "F.Cu")
		(net "PD_BMC_LPC")
	)
	(segment
		(start 72.912732 -128.471422)
		(end 74.873612 -128.471422)
		(width 0.1016)
		(layer "F.Cu")
		(net "PD_BMC_LPC")
	)
	(segment
		(start 70.537832 -130.05562)
		(end 70.537832 -129.401062)
		(width 0.1016)
		(layer "F.Cu")
		(net "PD_BMC_LPC")
	)
	(segment
		(start 72.13854 -128.456182)
		(end 72.541892 -128.859534)
		(width 0.1016)
		(layer "F.Cu")
		(net "PD_BMC_LPC")
	)
	(segment
		(start 72.541892 -128.842262)
		(end 72.912732 -128.471422)
		(width 0.1016)
		(layer "F.Cu")
		(net "PD_BMC_LPC")
	)
	(segment
		(start 77.505052 -127.031242)
		(end 77.649832 -127.176022)
		(width 0.1016)
		(layer "F.Cu")
		(net "PD_BMC_LPC")
	)
	(segment
		(start 74.873612 -128.471422)
		(end 75.259692 -128.085342)
		(width 0.1016)
		(layer "F.Cu")
		(net "PD_BMC_LPC")
	)
	(segment
		(start 73.341738 -127.259588)
		(end 74.141838 -126.459488)
		(width 0.1016)
		(layer "F.Cu")
		(net "PD_BMC_LPC")
	)
	(segment
		(start 72.541892 -128.859534)
		(end 72.541892 -128.842262)
		(width 0.1016)
		(layer "F.Cu")
		(net "PD_BMC_LPC")
	)
	(segment
		(start 74.141838 -126.459488)
		(end 74.141838 -127.259588)
		(width 0.1016)
		(layer "F.Cu")
		(net "PD_BMC_LPC")
	)
	(segment
		(start 70.537832 -129.401062)
		(end 70.271386 -129.134616)
		(width 0.1016)
		(layer "F.Cu")
		(net "PD_BMC_LPC")
	)
	(segment
		(start 70.271386 -128.989074)
		(end 70.141846 -128.859534)
		(width 0.1016)
		(layer "F.Cu")
		(net "PD_BMC_LPC")
	)
	(segment
		(start 70.141846 -128.859534)
		(end 70.141846 -128.753108)
		(width 0.1016)
		(layer "F.Cu")
		(net "PD_BMC_LPC")
	)
	(segment
		(start 75.953112 -127.031242)
		(end 77.505052 -127.031242)
		(width 0.1016)
		(layer "F.Cu")
		(net "PD_BMC_LPC")
	)
	(segment
		(start 75.724766 -127.259588)
		(end 75.953112 -127.031242)
		(width 0.1016)
		(layer "F.Cu")
		(net "PD_BMC_LPC")
	)
	(segment
		(start 70.438772 -128.456182)
		(end 72.13854 -128.456182)
		(width 0.1016)
		(layer "F.Cu")
		(net "PD_BMC_LPC")
	)
	(segment
		(start 70.941692 -130.45948)
		(end 70.537832 -130.05562)
		(width 0.1016)
		(layer "F.Cu")
		(net "PD_BMC_LPC")
	)
	(segment
		(start 70.271386 -129.134616)
		(end 70.271386 -128.989074)
		(width 0.1016)
		(layer "F.Cu")
		(net "PD_BMC_LPC")
	)
	(segment
		(start 77.649832 -127.176022)
		(end 77.649832 -127.772922)
		(width 0.1016)
		(layer "F.Cu")
		(net "PD_BMC_LPC")
	)
	(segment
		(start 77.337412 -128.085342)
		(end 77.649832 -127.772922)
		(width 0.1016)
		(layer "F.Cu")
		(net "PD_BMC_LPC")
	)
	(segment
		(start 75.259692 -128.085342)
		(end 77.337412 -128.085342)
		(width 0.1016)
		(layer "F.Cu")
		(net "PD_BMC_LPC")
	)
	(via
		(at 77.649832 -127.772922)
		(size 0.508)
		(drill 0.254)
		(layers "F.Cu" "B.Cu")
		(net "PD_BMC_LPC")
	)
	(segment
		(start 77.649832 -128.985772)
		(end 77.649832 -127.772922)
		(width 0.1016)
		(layer "B.Cu")
		(net "PD_BMC_LPC")
	)
	(segment
		(start 149.049486 -153.249376)
		(end 148.937726 -153.361136)
		(width 0.1016)
		(layer "F.Cu")
		(net "PCIE_SW_WP_N")
	)
	(segment
		(start 148.937726 -153.137616)
		(end 149.049486 -153.249376)
		(width 0.1016)
		(layer "F.Cu")
		(net "PCIE_SW_WP_N")
	)
	(segment
		(start 148.937726 -154.234388)
		(end 147.926298 -155.245816)
		(width 0.1016)
		(layer "F.Cu")
		(net "PCIE_SW_WP_N")
	)
	(segment
		(start 147.926298 -155.245816)
		(end 147.319746 -155.245816)
		(width 0.1016)
		(layer "F.Cu")
		(net "PCIE_SW_WP_N")
	)
	(segment
		(start 148.937726 -150.664418)
		(end 148.937726 -153.137616)
		(width 0.1016)
		(layer "F.Cu")
		(net "PCIE_SW_WP_N")
	)
	(segment
		(start 148.937726 -153.361136)
		(end 148.937726 -154.234388)
		(width 0.1016)
		(layer "F.Cu")
		(net "PCIE_SW_WP_N")
	)
	(segment
		(start 149.04974 -153.249376)
		(end 149.049486 -153.249376)
		(width 0.1016)
		(layer "F.Cu")
		(net "PCIE_SW_WP_N")
	)
	(via
		(at 149.04974 -153.249376)
		(size 0.508)
		(drill 0.254)
		(layers "F.Cu" "B.Cu")
		(net "PCIE_SW_WP_N")
	)
	(segment
		(start 134.807452 -153.62301)
		(end 134.469632 -153.28519)
		(width 0.1016)
		(layer "F.Cu")
		(net "PCIE_SW_P0_ERR_R")
	)
	(segment
		(start 134.807452 -154.4193)
		(end 134.807452 -153.62301)
		(width 0.1016)
		(layer "F.Cu")
		(net "PCIE_SW_P0_ERR_R")
	)
	(segment
		(start 134.938008 -152.816814)
		(end 134.469632 -153.28519)
		(width 0.1016)
		(layer "F.Cu")
		(net "PCIE_SW_P0_ERR_R")
	)
	(segment
		(start 134.938008 -151.32558)
		(end 134.938008 -152.816814)
		(width 0.1016)
		(layer "F.Cu")
		(net "PCIE_SW_P0_ERR_R")
	)
	(via
		(at 134.469632 -153.28519)
		(size 0.508)
		(drill 0.254)
		(layers "F.Cu" "B.Cu")
		(net "PCIE_SW_P0_ERR_R")
	)
	(segment
		(start 143.5989 -154.17292)
		(end 143.5989 -155.093416)
		(width 0.1016)
		(layer "F.Cu")
		(net "N49382752")
	)
	(segment
		(start 140.2969 -155.963112)
		(end 140.2969 -155.431744)
		(width 0.1016)
		(layer "F.Cu")
		(net "N49382752")
	)
	(segment
		(start 140.2969 -155.431744)
		(end 140.482828 -155.245816)
		(width 0.1016)
		(layer "F.Cu")
		(net "N49382752")
	)
	(segment
		(start 140.482828 -155.245816)
		(end 142.036546 -155.245816)
		(width 0.1016)
		(layer "F.Cu")
		(net "N49382752")
	)
	(segment
		(start 143.4465 -155.245816)
		(end 142.036546 -155.245816)
		(width 0.1016)
		(layer "F.Cu")
		(net "N49382752")
	)
	(segment
		(start 140.2969 -155.963112)
		(end 140.849604 -156.515816)
		(width 0.1016)
		(layer "F.Cu")
		(net "N49382752")
	)
	(segment
		(start 139.516104 -156.743908)
		(end 140.2969 -155.963112)
		(width 0.1016)
		(layer "F.Cu")
		(net "N49382752")
	)
	(segment
		(start 142.036546 -153.975816)
		(end 143.401796 -153.975816)
		(width 0.1016)
		(layer "F.Cu")
		(net "N49382752")
	)
	(segment
		(start 140.849604 -156.515816)
		(end 142.036546 -156.515816)
		(width 0.1016)
		(layer "F.Cu")
		(net "N49382752")
	)
	(segment
		(start 143.401796 -153.975816)
		(end 143.5989 -154.17292)
		(width 0.1016)
		(layer "F.Cu")
		(net "N49382752")
	)
	(segment
		(start 139.391136 -156.743908)
		(end 139.516104 -156.743908)
		(width 0.1016)
		(layer "F.Cu")
		(net "N49382752")
	)
	(segment
		(start 143.5989 -155.093416)
		(end 143.4465 -155.245816)
		(width 0.1016)
		(layer "F.Cu")
		(net "N49382752")
	)
	(via
		(at 140.2969 -155.963112)
		(size 0.508)
		(drill 0.254)
		(layers "F.Cu" "B.Cu")
		(net "N49382752")
	)
	(segment
		(start 143.955262 -140.77569)
		(end 143.849852 -140.77569)
		(width 0.1016)
		(layer "F.Cu")
		(net "PCIE_SW_TEST3")
	)
	(segment
		(start 142.27302 -141.76756)
		(end 142.675864 -141.76756)
		(width 0.1016)
		(layer "F.Cu")
		(net "PCIE_SW_TEST3")
	)
	(segment
		(start 142.265146 -141.775434)
		(end 142.27302 -141.76756)
		(width 0.1016)
		(layer "F.Cu")
		(net "PCIE_SW_TEST3")
	)
	(segment
		(start 143.667734 -140.77569)
		(end 143.849852 -140.77569)
		(width 0.1016)
		(layer "F.Cu")
		(net "PCIE_SW_TEST3")
	)
	(segment
		(start 142.675864 -141.76756)
		(end 143.667734 -140.77569)
		(width 0.1016)
		(layer "F.Cu")
		(net "PCIE_SW_TEST3")
	)
	(segment
		(start 144.516602 -140.21435)
		(end 143.955262 -140.77569)
		(width 0.1016)
		(layer "F.Cu")
		(net "PCIE_SW_TEST3")
	)
	(segment
		(start 141.288008 -141.775434)
		(end 142.265146 -141.775434)
		(width 0.1016)
		(layer "F.Cu")
		(net "PCIE_SW_TEST3")
	)
	(via
		(at 143.849852 -140.77569)
		(size 0.508)
		(drill 0.254)
		(layers "F.Cu" "B.Cu")
		(net "PCIE_SW_TEST3")
	)
	(segment
		(start 141.288008 -140.975588)
		(end 142.174214 -140.975588)
		(width 0.1016)
		(layer "F.Cu")
		(net "PCIE_SW_TEST5")
	)
	(segment
		(start 144.516602 -138.6332)
		(end 143.839692 -139.31011)
		(width 0.1016)
		(layer "F.Cu")
		(net "PCIE_SW_TEST5")
	)
	(segment
		(start 144.516602 -138.53795)
		(end 144.516602 -138.6332)
		(width 0.1016)
		(layer "F.Cu")
		(net "PCIE_SW_TEST5")
	)
	(segment
		(start 142.174214 -140.975588)
		(end 143.839692 -139.31011)
		(width 0.1016)
		(layer "F.Cu")
		(net "PCIE_SW_TEST5")
	)
	(via
		(at 143.839692 -139.31011)
		(size 0.508)
		(drill 0.254)
		(layers "F.Cu" "B.Cu")
		(net "PCIE_SW_TEST5")
	)
	(segment
		(start 147.793202 -138.48715)
		(end 147.205192 -138.48715)
		(width 0.1016)
		(layer "F.Cu")
		(net "PCIE_SW_TEST4")
	)
	(segment
		(start 146.059652 -139.63269)
		(end 146.262852 -139.42949)
		(width 0.1016)
		(layer "F.Cu")
		(net "PCIE_SW_TEST4")
	)
	(segment
		(start 141.288008 -141.375638)
		(end 142.386812 -141.375638)
		(width 0.1016)
		(layer "F.Cu")
		(net "PCIE_SW_TEST4")
	)
	(segment
		(start 144.12976 -139.63269)
		(end 146.059652 -139.63269)
		(width 0.1016)
		(layer "F.Cu")
		(net "PCIE_SW_TEST4")
	)
	(segment
		(start 147.205192 -138.48715)
		(end 146.262852 -139.42949)
		(width 0.1016)
		(layer "F.Cu")
		(net "PCIE_SW_TEST4")
	)
	(segment
		(start 142.386812 -141.375638)
		(end 144.12976 -139.63269)
		(width 0.1016)
		(layer "F.Cu")
		(net "PCIE_SW_TEST4")
	)
	(via
		(at 146.262852 -139.42949)
		(size 0.508)
		(drill 0.254)
		(layers "F.Cu" "B.Cu")
		(net "PCIE_SW_TEST4")
	)
	(segment
		(start 140.420598 -133.17855)
		(end 139.67968 -133.919468)
		(width 0.1016)
		(layer "F.Cu")
		(net "PCIE_SW_TEST6")
	)
	(segment
		(start 142.510002 -133.17855)
		(end 140.420598 -133.17855)
		(width 0.1016)
		(layer "F.Cu")
		(net "PCIE_SW_TEST6")
	)
	(segment
		(start 138.938 -134.661148)
		(end 139.67968 -133.919468)
		(width 0.1016)
		(layer "F.Cu")
		(net "PCIE_SW_TEST6")
	)
	(segment
		(start 138.938 -135.825484)
		(end 138.938 -134.661148)
		(width 0.1016)
		(layer "F.Cu")
		(net "PCIE_SW_TEST6")
	)
	(via
		(at 139.67968 -133.919468)
		(size 0.508)
		(drill 0.254)
		(layers "F.Cu" "B.Cu")
		(net "PCIE_SW_TEST6")
	)
	(segment
		(start 139.486386 -136.765284)
		(end 139.33805 -136.616948)
		(width 0.1016)
		(layer "F.Cu")
		(net "PCIE_SW_SLOTCLK")
	)
	(segment
		(start 139.943078 -136.765284)
		(end 139.486386 -136.765284)
		(width 0.1016)
		(layer "F.Cu")
		(net "PCIE_SW_SLOTCLK")
	)
	(segment
		(start 139.33805 -136.616948)
		(end 139.33805 -135.825484)
		(width 0.1016)
		(layer "F.Cu")
		(net "PCIE_SW_SLOTCLK")
	)
	(segment
		(start 142.510002 -136.0551)
		(end 142.826232 -136.37133)
		(width 0.1016)
		(layer "F.Cu")
		(net "PCIE_SW_SLOTCLK")
	)
	(segment
		(start 142.486888 -136.710674)
		(end 139.997688 -136.710674)
		(width 0.1016)
		(layer "F.Cu")
		(net "PCIE_SW_SLOTCLK")
	)
	(segment
		(start 142.826232 -136.37133)
		(end 142.486888 -136.710674)
		(width 0.1016)
		(layer "F.Cu")
		(net "PCIE_SW_SLOTCLK")
	)
	(segment
		(start 142.510002 -135.18515)
		(end 142.510002 -136.0551)
		(width 0.1016)
		(layer "F.Cu")
		(net "PCIE_SW_SLOTCLK")
	)
	(segment
		(start 139.997688 -136.710674)
		(end 139.943078 -136.765284)
		(width 0.1016)
		(layer "F.Cu")
		(net "PCIE_SW_SLOTCLK")
	)
	(via
		(at 142.826232 -136.37133)
		(size 0.508)
		(drill 0.254)
		(layers "F.Cu" "B.Cu")
		(net "PCIE_SW_SLOTCLK")
	)
	(segment
		(start 139.737846 -135.825484)
		(end 140.16101 -135.825484)
		(width 0.1016)
		(layer "F.Cu")
		(net "PCIE_SW_PRSNT1")
	)
	(segment
		(start 142.510002 -134.19455)
		(end 141.791944 -134.19455)
		(width 0.1016)
		(layer "F.Cu")
		(net "PCIE_SW_PRSNT1")
	)
	(segment
		(start 141.791944 -134.19455)
		(end 140.93444 -135.052054)
		(width 0.1016)
		(layer "F.Cu")
		(net "PCIE_SW_PRSNT1")
	)
	(segment
		(start 140.16101 -135.825484)
		(end 140.93444 -135.052054)
		(width 0.1016)
		(layer "F.Cu")
		(net "PCIE_SW_PRSNT1")
	)
	(via
		(at 140.93444 -135.052054)
		(size 0.508)
		(drill 0.254)
		(layers "F.Cu" "B.Cu")
		(net "PCIE_SW_PRSNT1")
	)
	(segment
		(start 146.257772 -137.86993)
		(end 146.356832 -137.77087)
		(width 0.1016)
		(layer "F.Cu")
		(net "PCIE_SW_PRSNT2")
	)
	(segment
		(start 146.808952 -137.31875)
		(end 146.356832 -137.77087)
		(width 0.1016)
		(layer "F.Cu")
		(net "PCIE_SW_PRSNT2")
	)
	(segment
		(start 142.104364 -139.775438)
		(end 144.009872 -137.86993)
		(width 0.1016)
		(layer "F.Cu")
		(net "PCIE_SW_PRSNT2")
	)
	(segment
		(start 144.009872 -137.86993)
		(end 146.257772 -137.86993)
		(width 0.1016)
		(layer "F.Cu")
		(net "PCIE_SW_PRSNT2")
	)
	(segment
		(start 141.288008 -139.775438)
		(end 142.104364 -139.775438)
		(width 0.1016)
		(layer "F.Cu")
		(net "PCIE_SW_PRSNT2")
	)
	(segment
		(start 147.793202 -137.31875)
		(end 146.808952 -137.31875)
		(width 0.1016)
		(layer "F.Cu")
		(net "PCIE_SW_PRSNT2")
	)
	(via
		(at 146.356832 -137.77087)
		(size 0.508)
		(drill 0.254)
		(layers "F.Cu" "B.Cu")
		(net "PCIE_SW_PRSNT2")
	)
	(segment
		(start 115.767358 -163.006532)
		(end 116.561362 -163.800536)
		(width 0.1016)
		(layer "F.Cu")
		(net "I2C_COM3_SDA_RC")
	)
	(segment
		(start 114.76736 -163.006532)
		(end 115.767358 -163.006532)
		(width 0.1016)
		(layer "F.Cu")
		(net "I2C_COM3_SDA_RC")
	)
	(via
		(at 116.561362 -163.800536)
		(size 0.508)
		(drill 0.254)
		(layers "F.Cu" "B.Cu")
		(net "I2C_COM3_SDA_RC")
	)
	(segment
		(start 116.002816 -163.24199)
		(end 116.561362 -163.800536)
		(width 0.1016)
		(layer "B.Cu")
		(net "I2C_COM3_SDA_RC")
	)
	(segment
		(start 115.410234 -163.24072)
		(end 115.411504 -163.24199)
		(width 0.1016)
		(layer "B.Cu")
		(net "I2C_COM3_SDA_RC")
	)
	(segment
		(start 115.411504 -163.24199)
		(end 116.002816 -163.24199)
		(width 0.1016)
		(layer "B.Cu")
		(net "I2C_COM3_SDA_RC")
	)
	(segment
		(start 115.410234 -162.251644)
		(end 115.410234 -163.24072)
		(width 0.1016)
		(layer "B.Cu")
		(net "I2C_COM3_SDA_RC")
	)
	(segment
		(start 160.98266 -73.530968)
		(end 160.98266 -76.219812)
		(width 0.254)
		(layer "F.Cu")
		(net "PWRGD_NODE1_P1V0")
	)
	(segment
		(start 161.12617 -76.363322)
		(end 161.632646 -76.363322)
		(width 0.254)
		(layer "F.Cu")
		(net "PWRGD_NODE1_P1V0")
	)
	(segment
		(start 179.010564 -121.365772)
		(end 179.510436 -121.865644)
		(width 0.1016)
		(layer "F.Cu")
		(net "PWRGD_NODE1_P1V0")
	)
	(segment
		(start 160.98266 -76.219812)
		(end 161.12617 -76.363322)
		(width 0.254)
		(layer "F.Cu")
		(net "PWRGD_NODE1_P1V0")
	)
	(segment
		(start 179.010564 -121.365518)
		(end 179.010564 -121.365772)
		(width 0.1016)
		(layer "F.Cu")
		(net "PWRGD_NODE1_P1V0")
	)
	(segment
		(start 161.089848 -71.54418)
		(end 161.089848 -72.400668)
		(width 0.254)
		(layer "F.Cu")
		(net "PWRGD_NODE1_P1V0")
	)
	(segment
		(start 161.085022 -72.405494)
		(end 161.085022 -73.428606)
		(width 0.254)
		(layer "F.Cu")
		(net "PWRGD_NODE1_P1V0")
	)
	(segment
		(start 161.085022 -73.428606)
		(end 160.98266 -73.530968)
		(width 0.254)
		(layer "F.Cu")
		(net "PWRGD_NODE1_P1V0")
	)
	(segment
		(start 161.089848 -72.400668)
		(end 161.085022 -72.405494)
		(width 0.254)
		(layer "F.Cu")
		(net "PWRGD_NODE1_P1V0")
	)
	(via
		(at 172.57522 -88.903302)
		(size 0.508)
		(drill 0.254)
		(layers "F.Cu" "B.Cu")
		(net "PWRGD_NODE1_P1V0")
	)
	(via
		(at 179.510436 -121.865644)
		(size 0.49022)
		(drill 0.254)
		(layers "F.Cu" "B.Cu")
		(net "PWRGD_NODE1_P1V0")
	)
	(via
		(at 161.089848 -71.54418)
		(size 0.508)
		(drill 0.254)
		(layers "F.Cu" "B.Cu")
		(net "PWRGD_NODE1_P1V0")
	)
	(segment
		(start 164.08654 -71.764144)
		(end 164.72662 -72.404224)
		(width 0.1016)
		(layer "B.Cu")
		(net "PWRGD_NODE1_P1V0")
	)
	(segment
		(start 161.089848 -71.54418)
		(end 161.309812 -71.764144)
		(width 0.1016)
		(layer "B.Cu")
		(net "PWRGD_NODE1_P1V0")
	)
	(segment
		(start 172.14088 -76.487782)
		(end 172.14088 -88.468962)
		(width 0.1016)
		(layer "B.Cu")
		(net "PWRGD_NODE1_P1V0")
	)
	(segment
		(start 161.309812 -71.764144)
		(end 164.08654 -71.764144)
		(width 0.1016)
		(layer "B.Cu")
		(net "PWRGD_NODE1_P1V0")
	)
	(segment
		(start 164.72662 -72.404224)
		(end 168.057322 -72.404224)
		(width 0.1016)
		(layer "B.Cu")
		(net "PWRGD_NODE1_P1V0")
	)
	(segment
		(start 168.057322 -72.404224)
		(end 172.14088 -76.487782)
		(width 0.1016)
		(layer "B.Cu")
		(net "PWRGD_NODE1_P1V0")
	)
	(segment
		(start 172.14088 -88.468962)
		(end 172.57522 -88.903302)
		(width 0.1016)
		(layer "B.Cu")
		(net "PWRGD_NODE1_P1V0")
	)
	(segment
		(start 178.20513 -88.903302)
		(end 186.25693 -96.955102)
		(width 0.1143)
		(layer "In2.Cu")
		(net "PWRGD_NODE1_P1V0")
	)
	(segment
		(start 181.375558 -121.766838)
		(end 180.847492 -122.294904)
		(width 0.1143)
		(layer "In2.Cu")
		(net "PWRGD_NODE1_P1V0")
	)
	(segment
		(start 186.25693 -96.955102)
		(end 186.25693 -121.291604)
		(width 0.1143)
		(layer "In2.Cu")
		(net "PWRGD_NODE1_P1V0")
	)
	(segment
		(start 180.118766 -122.294904)
		(end 179.689506 -121.865644)
		(width 0.1143)
		(layer "In2.Cu")
		(net "PWRGD_NODE1_P1V0")
	)
	(segment
		(start 172.57522 -88.903302)
		(end 178.20513 -88.903302)
		(width 0.1143)
		(layer "In2.Cu")
		(net "PWRGD_NODE1_P1V0")
	)
	(segment
		(start 182.640732 -121.934732)
		(end 182.472838 -121.766838)
		(width 0.1143)
		(layer "In2.Cu")
		(net "PWRGD_NODE1_P1V0")
	)
	(segment
		(start 180.847492 -122.294904)
		(end 180.118766 -122.294904)
		(width 0.1143)
		(layer "In2.Cu")
		(net "PWRGD_NODE1_P1V0")
	)
	(segment
		(start 186.25693 -121.291604)
		(end 185.613802 -121.934732)
		(width 0.1143)
		(layer "In2.Cu")
		(net "PWRGD_NODE1_P1V0")
	)
	(segment
		(start 182.472838 -121.766838)
		(end 181.375558 -121.766838)
		(width 0.1143)
		(layer "In2.Cu")
		(net "PWRGD_NODE1_P1V0")
	)
	(segment
		(start 185.613802 -121.934732)
		(end 182.640732 -121.934732)
		(width 0.1143)
		(layer "In2.Cu")
		(net "PWRGD_NODE1_P1V0")
	)
	(segment
		(start 179.689506 -121.865644)
		(end 179.510436 -121.865644)
		(width 0.1143)
		(layer "In2.Cu")
		(net "PWRGD_NODE1_P1V0")
	)
	(segment
		(start 160.052512 -74.318368)
		(end 160.052512 -75.31735)
		(width 0.254)
		(layer "F.Cu")
		(net "P1V0_ADJ")
	)
	(segment
		(start 160.052258 -74.318114)
		(end 160.052512 -74.318368)
		(width 0.254)
		(layer "F.Cu")
		(net "P1V0_ADJ")
	)
	(segment
		(start 160.052512 -75.31735)
		(end 160.052512 -76.078334)
		(width 0.254)
		(layer "F.Cu")
		(net "P1V0_ADJ")
	)
	(segment
		(start 160.052512 -76.078334)
		(end 160.444688 -76.470764)
		(width 0.254)
		(layer "F.Cu")
		(net "P1V0_ADJ")
	)
	(segment
		(start 160.836864 -76.863194)
		(end 160.444688 -76.470764)
		(width 0.254)
		(layer "F.Cu")
		(net "P1V0_ADJ")
	)
	(segment
		(start 161.632646 -76.863194)
		(end 160.836864 -76.863194)
		(width 0.254)
		(layer "F.Cu")
		(net "P1V0_ADJ")
	)
	(segment
		(start 160.052258 -73.271126)
		(end 160.052258 -74.318114)
		(width 0.254)
		(layer "F.Cu")
		(net "P1V0_ADJ")
	)
	(via
		(at 160.444688 -76.470764)
		(size 0.508)
		(drill 0.254)
		(layers "F.Cu" "B.Cu")
		(net "P1V0_ADJ")
	)
	(segment
		(start 159.252158 -73.271126)
		(end 159.252158 -74.318114)
		(width 0.254)
		(layer "F.Cu")
		(net "P1V0_ADJ_S")
	)
	(segment
		(start 157.5816 -74.318114)
		(end 158.593282 -74.318114)
		(width 0.254)
		(layer "F.Cu")
		(net "P1V0_ADJ_S")
	)
	(segment
		(start 159.252158 -74.318114)
		(end 158.593282 -74.318114)
		(width 0.254)
		(layer "F.Cu")
		(net "P1V0_ADJ_S")
	)
	(segment
		(start 157.572964 -74.32675)
		(end 157.5816 -74.318114)
		(width 0.254)
		(layer "F.Cu")
		(net "P1V0_ADJ_S")
	)
	(via
		(at 158.593282 -74.318114)
		(size 0.508)
		(drill 0.254)
		(layers "F.Cu" "B.Cu")
		(net "P1V0_ADJ_S")
	)
	(segment
		(start 165.351714 -75.546966)
		(end 165.09873 -75.293982)
		(width 0.254)
		(layer "F.Cu")
		(net "N47241340")
	)
	(segment
		(start 165.065964 -76.363322)
		(end 165.351714 -76.077572)
		(width 0.254)
		(layer "F.Cu")
		(net "N47241340")
	)
	(segment
		(start 164.784532 -73.331324)
		(end 164.784532 -72.319642)
		(width 0.254)
		(layer "F.Cu")
		(net "N47241340")
	)
	(segment
		(start 164.784532 -73.709784)
		(end 164.784532 -73.331324)
		(width 0.254)
		(layer "F.Cu")
		(net "N47241340")
	)
	(segment
		(start 165.828472 -72.313546)
		(end 165.951408 -72.436482)
		(width 0.254)
		(layer "F.Cu")
		(net "N47241340")
	)
	(segment
		(start 164.790628 -72.313546)
		(end 165.828472 -72.313546)
		(width 0.254)
		(layer "F.Cu")
		(net "N47241340")
	)
	(segment
		(start 164.73297 -76.363322)
		(end 165.065964 -76.363322)
		(width 0.254)
		(layer "F.Cu")
		(net "N47241340")
	)
	(segment
		(start 165.09873 -74.023982)
		(end 164.784532 -73.709784)
		(width 0.254)
		(layer "F.Cu")
		(net "N47241340")
	)
	(segment
		(start 165.351714 -76.077572)
		(end 165.351714 -75.546966)
		(width 0.254)
		(layer "F.Cu")
		(net "N47241340")
	)
	(segment
		(start 164.784532 -72.319642)
		(end 164.790628 -72.313546)
		(width 0.254)
		(layer "F.Cu")
		(net "N47241340")
	)
	(segment
		(start 165.09873 -75.293982)
		(end 165.09873 -74.023982)
		(width 0.254)
		(layer "F.Cu")
		(net "N47241340")
	)
	(via
		(at 165.09873 -75.293982)
		(size 0.508)
		(drill 0.254)
		(layers "F.Cu" "B.Cu")
		(net "N47241340")
	)
	(segment
		(start 171.472606 -133.075934)
		(end 172.252386 -132.296154)
		(width 0.1016)
		(layer "F.Cu")
		(net "N41777073")
	)
	(segment
		(start 171.472606 -133.232144)
		(end 171.472606 -133.075934)
		(width 0.1016)
		(layer "F.Cu")
		(net "N41777073")
	)
	(segment
		(start 172.252386 -132.296154)
		(end 172.252386 -131.92125)
		(width 0.1016)
		(layer "F.Cu")
		(net "N41777073")
	)
	(segment
		(start 171.461176 -133.243574)
		(end 171.472606 -133.232144)
		(width 0.1016)
		(layer "F.Cu")
		(net "N41777073")
	)
	(segment
		(start 171.472606 -133.232144)
		(end 172.961046 -133.232144)
		(width 0.1016)
		(layer "F.Cu")
		(net "N41777073")
	)
	(via
		(at 171.461176 -133.243574)
		(size 0.508)
		(drill 0.254)
		(layers "F.Cu" "B.Cu")
		(net "N41777073")
	)
	(segment
		(start 69.440044 -78.293214)
		(end 69.807328 -78.660498)
		(width 0.1016)
		(layer "F.Cu")
		(net "H_CPU_NODE1_PROCHOT_R")
	)
	(segment
		(start 69.440044 -78.255622)
		(end 69.440044 -78.293214)
		(width 0.1016)
		(layer "F.Cu")
		(net "H_CPU_NODE1_PROCHOT_R")
	)
	(via
		(at 69.807328 -78.660498)
		(size 0.508)
		(drill 0.254)
		(layers "F.Cu" "B.Cu")
		(net "H_CPU_NODE1_PROCHOT_R")
	)
	(via
		(at 70.175628 -77.959458)
		(size 0.6604)
		(drill 0.3302)
		(layers "F.Cu" "B.Cu")
		(net "H_CPU_NODE1_PROCHOT_R")
	)
	(segment
		(start 69.807328 -78.660498)
		(end 69.807328 -78.327758)
		(width 0.1016)
		(layer "B.Cu")
		(net "H_CPU_NODE1_PROCHOT_R")
	)
	(segment
		(start 71.900542 -77.151484)
		(end 71.4121 -77.639926)
		(width 0.1016)
		(layer "B.Cu")
		(net "H_CPU_NODE1_PROCHOT_R")
	)
	(segment
		(start 74.686922 -77.738224)
		(end 74.100182 -77.151484)
		(width 0.1016)
		(layer "B.Cu")
		(net "H_CPU_NODE1_PROCHOT_R")
	)
	(segment
		(start 74.100182 -77.151484)
		(end 71.900542 -77.151484)
		(width 0.1016)
		(layer "B.Cu")
		(net "H_CPU_NODE1_PROCHOT_R")
	)
	(segment
		(start 77.217778 -77.738224)
		(end 74.686922 -77.738224)
		(width 0.1016)
		(layer "B.Cu")
		(net "H_CPU_NODE1_PROCHOT_R")
	)
	(segment
		(start 77.670406 -76.800202)
		(end 77.503528 -76.96708)
		(width 0.1016)
		(layer "B.Cu")
		(net "H_CPU_NODE1_PROCHOT_R")
	)
	(segment
		(start 79.862172 -76.910692)
		(end 79.210662 -76.910692)
		(width 0.1016)
		(layer "B.Cu")
		(net "H_CPU_NODE1_PROCHOT_R")
	)
	(segment
		(start 77.503528 -77.452474)
		(end 77.217778 -77.738224)
		(width 0.1016)
		(layer "B.Cu")
		(net "H_CPU_NODE1_PROCHOT_R")
	)
	(segment
		(start 79.100172 -76.800202)
		(end 77.670406 -76.800202)
		(width 0.1016)
		(layer "B.Cu")
		(net "H_CPU_NODE1_PROCHOT_R")
	)
	(segment
		(start 69.807328 -78.327758)
		(end 70.175628 -77.959458)
		(width 0.1016)
		(layer "B.Cu")
		(net "H_CPU_NODE1_PROCHOT_R")
	)
	(segment
		(start 71.4121 -77.639926)
		(end 70.49516 -77.639926)
		(width 0.1016)
		(layer "B.Cu")
		(net "H_CPU_NODE1_PROCHOT_R")
	)
	(segment
		(start 77.503528 -76.96708)
		(end 77.503528 -77.452474)
		(width 0.1016)
		(layer "B.Cu")
		(net "H_CPU_NODE1_PROCHOT_R")
	)
	(segment
		(start 79.210662 -76.910692)
		(end 79.100172 -76.800202)
		(width 0.1016)
		(layer "B.Cu")
		(net "H_CPU_NODE1_PROCHOT_R")
	)
	(segment
		(start 70.49516 -77.639926)
		(end 70.175628 -77.959458)
		(width 0.1016)
		(layer "B.Cu")
		(net "H_CPU_NODE1_PROCHOT_R")
	)
	(segment
		(start 69.448426 -85.381846)
		(end 69.448426 -85.186012)
		(width 0.1016)
		(layer "F.Cu")
		(net "H_CPU_NODE1_ERR1")
	)
	(segment
		(start 69.448426 -85.186012)
		(end 69.154802 -84.892388)
		(width 0.1016)
		(layer "F.Cu")
		(net "H_CPU_NODE1_ERR1")
	)
	(via
		(at 69.563234 -85.512148)
		(size 0.6604)
		(drill 0.3302)
		(layers "F.Cu" "B.Cu")
		(net "H_CPU_NODE1_ERR1")
	)
	(via
		(at 69.154802 -84.892388)
		(size 0.508)
		(drill 0.254)
		(layers "F.Cu" "B.Cu")
		(net "H_CPU_NODE1_ERR1")
	)
	(segment
		(start 69.154802 -85.103716)
		(end 69.154802 -84.892388)
		(width 0.1016)
		(layer "B.Cu")
		(net "H_CPU_NODE1_ERR1")
	)
	(segment
		(start 71.366634 -88.83142)
		(end 71.366634 -88.29929)
		(width 0.1016)
		(layer "B.Cu")
		(net "H_CPU_NODE1_ERR1")
	)
	(segment
		(start 70.42404 -85.901276)
		(end 70.186042 -85.663278)
		(width 0.1016)
		(layer "B.Cu")
		(net "H_CPU_NODE1_ERR1")
	)
	(segment
		(start 70.616064 -86.35365)
		(end 70.42404 -86.161626)
		(width 0.1016)
		(layer "B.Cu")
		(net "H_CPU_NODE1_ERR1")
	)
	(segment
		(start 70.186042 -85.663278)
		(end 69.714364 -85.663278)
		(width 0.1016)
		(layer "B.Cu")
		(net "H_CPU_NODE1_ERR1")
	)
	(segment
		(start 69.563234 -85.512148)
		(end 69.154802 -85.103716)
		(width 0.1016)
		(layer "B.Cu")
		(net "H_CPU_NODE1_ERR1")
	)
	(segment
		(start 71.257922 -87.947754)
		(end 70.616064 -87.305896)
		(width 0.1016)
		(layer "B.Cu")
		(net "H_CPU_NODE1_ERR1")
	)
	(segment
		(start 71.366634 -88.29929)
		(end 71.257922 -88.190578)
		(width 0.1016)
		(layer "B.Cu")
		(net "H_CPU_NODE1_ERR1")
	)
	(segment
		(start 71.257922 -88.190578)
		(end 71.257922 -87.947754)
		(width 0.1016)
		(layer "B.Cu")
		(net "H_CPU_NODE1_ERR1")
	)
	(segment
		(start 69.714364 -85.663278)
		(end 69.563234 -85.512148)
		(width 0.1016)
		(layer "B.Cu")
		(net "H_CPU_NODE1_ERR1")
	)
	(segment
		(start 70.616064 -87.305896)
		(end 70.616064 -86.35365)
		(width 0.1016)
		(layer "B.Cu")
		(net "H_CPU_NODE1_ERR1")
	)
	(segment
		(start 70.42404 -86.161626)
		(end 70.42404 -85.901276)
		(width 0.1016)
		(layer "B.Cu")
		(net "H_CPU_NODE1_ERR1")
	)
	(segment
		(start 73.298558 -86.546436)
		(end 73.454514 -86.702392)
		(width 0.1016)
		(layer "F.Cu")
		(net "H_CPU_NODE1_ERR0")
	)
	(segment
		(start 73.298558 -86.117176)
		(end 73.298558 -86.546436)
		(width 0.1016)
		(layer "F.Cu")
		(net "H_CPU_NODE1_ERR0")
	)
	(via
		(at 73.454514 -86.702392)
		(size 0.508)
		(drill 0.254)
		(layers "F.Cu" "B.Cu")
		(net "H_CPU_NODE1_ERR0")
	)
	(segment
		(start 71.907146 -92.296234)
		(end 71.907146 -90.085926)
		(width 0.1016)
		(layer "B.Cu")
		(net "H_CPU_NODE1_ERR0")
	)
	(segment
		(start 73.454514 -88.37295)
		(end 73.454514 -86.702392)
		(width 0.1016)
		(layer "B.Cu")
		(net "H_CPU_NODE1_ERR0")
	)
	(segment
		(start 72.242172 -89.7509)
		(end 72.242172 -89.585292)
		(width 0.1016)
		(layer "B.Cu")
		(net "H_CPU_NODE1_ERR0")
	)
	(segment
		(start 72.008492 -92.39758)
		(end 71.907146 -92.296234)
		(width 0.1016)
		(layer "B.Cu")
		(net "H_CPU_NODE1_ERR0")
	)
	(segment
		(start 72.242172 -89.585292)
		(end 73.454514 -88.37295)
		(width 0.1016)
		(layer "B.Cu")
		(net "H_CPU_NODE1_ERR0")
	)
	(segment
		(start 71.907146 -90.085926)
		(end 72.242172 -89.7509)
		(width 0.1016)
		(layer "B.Cu")
		(net "H_CPU_NODE1_ERR0")
	)
	(segment
		(start 72.008492 -92.520008)
		(end 72.008492 -92.39758)
		(width 0.1016)
		(layer "B.Cu")
		(net "H_CPU_NODE1_ERR0")
	)
	(segment
		(start 68.16217 -84.238846)
		(end 68.2498 -84.238846)
		(width 0.1016)
		(layer "F.Cu")
		(net "H_CPU_NODE1_ERR2")
	)
	(segment
		(start 68.2498 -84.238846)
		(end 68.598034 -84.587334)
		(width 0.1016)
		(layer "F.Cu")
		(net "H_CPU_NODE1_ERR2")
	)
	(via
		(at 70.079108 -90.33891)
		(size 0.6604)
		(drill 0.3302)
		(layers "F.Cu" "B.Cu")
		(net "H_CPU_NODE1_ERR2")
	)
	(via
		(at 68.598034 -84.587334)
		(size 0.508)
		(drill 0.254)
		(layers "F.Cu" "B.Cu")
		(net "H_CPU_NODE1_ERR2")
	)
	(segment
		(start 68.598034 -84.781898)
		(end 68.256404 -85.123528)
		(width 0.1016)
		(layer "B.Cu")
		(net "H_CPU_NODE1_ERR2")
	)
	(segment
		(start 68.256404 -85.123528)
		(end 68.256404 -85.460332)
		(width 0.1016)
		(layer "B.Cu")
		(net "H_CPU_NODE1_ERR2")
	)
	(segment
		(start 70.079108 -91.950286)
		(end 70.079108 -90.33891)
		(width 0.1016)
		(layer "B.Cu")
		(net "H_CPU_NODE1_ERR2")
	)
	(segment
		(start 70.31355 -92.184728)
		(end 70.079108 -91.950286)
		(width 0.1016)
		(layer "B.Cu")
		(net "H_CPU_NODE1_ERR2")
	)
	(segment
		(start 68.494402 -85.69833)
		(end 68.948046 -85.69833)
		(width 0.1016)
		(layer "B.Cu")
		(net "H_CPU_NODE1_ERR2")
	)
	(segment
		(start 70.31355 -92.422218)
		(end 70.31355 -92.184728)
		(width 0.1016)
		(layer "B.Cu")
		(net "H_CPU_NODE1_ERR2")
	)
	(segment
		(start 70.409308 -87.159592)
		(end 70.409308 -88.2904)
		(width 0.1016)
		(layer "B.Cu")
		(net "H_CPU_NODE1_ERR2")
	)
	(segment
		(start 68.256404 -85.460332)
		(end 68.494402 -85.69833)
		(width 0.1016)
		(layer "B.Cu")
		(net "H_CPU_NODE1_ERR2")
	)
	(segment
		(start 68.598034 -84.587334)
		(end 68.598034 -84.781898)
		(width 0.1016)
		(layer "B.Cu")
		(net "H_CPU_NODE1_ERR2")
	)
	(segment
		(start 68.948046 -85.69833)
		(end 70.409308 -87.159592)
		(width 0.1016)
		(layer "B.Cu")
		(net "H_CPU_NODE1_ERR2")
	)
	(segment
		(start 70.409308 -88.2904)
		(end 70.079108 -88.6206)
		(width 0.1016)
		(layer "B.Cu")
		(net "H_CPU_NODE1_ERR2")
	)
	(segment
		(start 70.079108 -88.6206)
		(end 70.079108 -90.33891)
		(width 0.1016)
		(layer "B.Cu")
		(net "H_CPU_NODE1_ERR2")
	)
	(segment
		(start 162.487864 -99.189794)
		(end 162.20948 -99.189794)
		(width 0.1016)
		(layer "F.Cu")
		(net "USB_NODE1_PECREQ_L")
	)
	(segment
		(start 160.408112 -98.343212)
		(end 160.663382 -98.343212)
		(width 0.1016)
		(layer "F.Cu")
		(net "USB_NODE1_PECREQ_L")
	)
	(segment
		(start 162.164522 -99.144836)
		(end 161.465006 -99.144836)
		(width 0.1016)
		(layer "F.Cu")
		(net "USB_NODE1_PECREQ_L")
	)
	(segment
		(start 160.663382 -98.343212)
		(end 161.165794 -98.845624)
		(width 0.1016)
		(layer "F.Cu")
		(net "USB_NODE1_PECREQ_L")
	)
	(segment
		(start 161.465006 -99.144836)
		(end 161.165794 -98.845624)
		(width 0.1016)
		(layer "F.Cu")
		(net "USB_NODE1_PECREQ_L")
	)
	(segment
		(start 162.633914 -99.335844)
		(end 162.487864 -99.189794)
		(width 0.1016)
		(layer "F.Cu")
		(net "USB_NODE1_PECREQ_L")
	)
	(segment
		(start 162.20948 -99.189794)
		(end 162.164522 -99.144836)
		(width 0.1016)
		(layer "F.Cu")
		(net "USB_NODE1_PECREQ_L")
	)
	(segment
		(start 163.340034 -99.335844)
		(end 162.633914 -99.335844)
		(width 0.1016)
		(layer "F.Cu")
		(net "USB_NODE1_PECREQ_L")
	)
	(via
		(at 161.165794 -98.845624)
		(size 0.508)
		(drill 0.254)
		(layers "F.Cu" "B.Cu")
		(net "USB_NODE1_PECREQ_L")
	)
	(segment
		(start 129.0574 -52.2478)
		(end 129.06248 -52.2478)
		(width 0.1016)
		(layer "F.Cu")
		(net "UART_RX_P4_BUF")
	)
	(segment
		(start 129.064004 -52.286916)
		(end 129.064004 -53.05298)
		(width 0.1016)
		(layer "F.Cu")
		(net "UART_RX_P4_BUF")
	)
	(segment
		(start 128.524 -49.6316)
		(end 128.524 -51.7144)
		(width 0.1016)
		(layer "F.Cu")
		(net "UART_RX_P4_BUF")
	)
	(segment
		(start 128.524 -51.7144)
		(end 129.0574 -52.2478)
		(width 0.1016)
		(layer "F.Cu")
		(net "UART_RX_P4_BUF")
	)
	(segment
		(start 128.41732 -48.90897)
		(end 128.41732 -49.52492)
		(width 0.1016)
		(layer "F.Cu")
		(net "UART_RX_P4_BUF")
	)
	(segment
		(start 129.06248 -52.2478)
		(end 129.06248 -52.285392)
		(width 0.1016)
		(layer "F.Cu")
		(net "UART_RX_P4_BUF")
	)
	(segment
		(start 128.838452 -53.278532)
		(end 128.594866 -53.278532)
		(width 0.1016)
		(layer "F.Cu")
		(net "UART_RX_P4_BUF")
	)
	(segment
		(start 129.064004 -53.05298)
		(end 128.838452 -53.278532)
		(width 0.1016)
		(layer "F.Cu")
		(net "UART_RX_P4_BUF")
	)
	(segment
		(start 128.261618 -47.199804)
		(end 128.261618 -48.753268)
		(width 0.1016)
		(layer "F.Cu")
		(net "UART_RX_P4_BUF")
	)
	(segment
		(start 129.06248 -52.285392)
		(end 129.064004 -52.286916)
		(width 0.1016)
		(layer "F.Cu")
		(net "UART_RX_P4_BUF")
	)
	(segment
		(start 128.261618 -48.753268)
		(end 128.41732 -48.90897)
		(width 0.1016)
		(layer "F.Cu")
		(net "UART_RX_P4_BUF")
	)
	(segment
		(start 128.41732 -49.52492)
		(end 128.524 -49.6316)
		(width 0.1016)
		(layer "F.Cu")
		(net "UART_RX_P4_BUF")
	)
	(via
		(at 128.41732 -48.90897)
		(size 0.508)
		(drill 0.254)
		(layers "F.Cu" "B.Cu")
		(net "UART_RX_P4_BUF")
	)
	(segment
		(start 148.60016 -21.082)
		(end 148.60016 -26.973022)
		(width 0.1143)
		(layer "In7.Cu")
		(net "UART_RX_P4_BUF")
	)
	(segment
		(start 142.31874 -47.02048)
		(end 130.30581 -47.02048)
		(width 0.1143)
		(layer "In7.Cu")
		(net "UART_RX_P4_BUF")
	)
	(segment
		(start 150.113746 -19.568414)
		(end 148.60016 -21.082)
		(width 0.1143)
		(layer "In7.Cu")
		(net "UART_RX_P4_BUF")
	)
	(segment
		(start 143.9545 -45.38472)
		(end 142.31874 -47.02048)
		(width 0.1143)
		(layer "In7.Cu")
		(net "UART_RX_P4_BUF")
	)
	(segment
		(start 130.30581 -47.02048)
		(end 128.41732 -48.90897)
		(width 0.1143)
		(layer "In7.Cu")
		(net "UART_RX_P4_BUF")
	)
	(segment
		(start 143.9545 -31.618682)
		(end 143.9545 -45.38472)
		(width 0.1143)
		(layer "In7.Cu")
		(net "UART_RX_P4_BUF")
	)
	(segment
		(start 148.60016 -26.973022)
		(end 143.9545 -31.618682)
		(width 0.1143)
		(layer "In7.Cu")
		(net "UART_RX_P4_BUF")
	)
	(segment
		(start 129.13487 -53.76545)
		(end 129.413 -53.48732)
		(width 0.1016)
		(layer "F.Cu")
		(net "UART_TX_P4_BUF")
	)
	(segment
		(start 127.561594 -56.786526)
		(end 127.194056 -56.418988)
		(width 0.1016)
		(layer "F.Cu")
		(net "UART_TX_P4_BUF")
	)
	(segment
		(start 129.413 -51.8922)
		(end 129.1082 -51.5874)
		(width 0.1016)
		(layer "F.Cu")
		(net "UART_TX_P4_BUF")
	)
	(segment
		(start 129.1082 -51.5874)
		(end 129.1082 -51.27625)
		(width 0.1016)
		(layer "F.Cu")
		(net "UART_TX_P4_BUF")
	)
	(segment
		(start 126.930658 -57.854342)
		(end 127.561594 -57.223406)
		(width 0.1016)
		(layer "F.Cu")
		(net "UART_TX_P4_BUF")
	)
	(segment
		(start 126.689612 -56.418988)
		(end 127.194056 -56.418988)
		(width 0.1016)
		(layer "F.Cu")
		(net "UART_TX_P4_BUF")
	)
	(segment
		(start 126.815342 -58.62828)
		(end 126.815342 -58.26125)
		(width 0.1016)
		(layer "F.Cu")
		(net "UART_TX_P4_BUF")
	)
	(segment
		(start 127.713486 -55.899558)
		(end 127.713486 -54.26329)
		(width 0.1016)
		(layer "F.Cu")
		(net "UART_TX_P4_BUF")
	)
	(segment
		(start 129.413 -53.48732)
		(end 129.413 -51.8922)
		(width 0.1016)
		(layer "F.Cu")
		(net "UART_TX_P4_BUF")
	)
	(segment
		(start 127.194056 -56.418988)
		(end 127.713486 -55.899558)
		(width 0.1016)
		(layer "F.Cu")
		(net "UART_TX_P4_BUF")
	)
	(segment
		(start 127.713486 -54.26329)
		(end 128.211326 -53.76545)
		(width 0.1016)
		(layer "F.Cu")
		(net "UART_TX_P4_BUF")
	)
	(segment
		(start 126.712218 -58.158126)
		(end 126.712218 -57.854342)
		(width 0.1016)
		(layer "F.Cu")
		(net "UART_TX_P4_BUF")
	)
	(segment
		(start 126.815342 -58.26125)
		(end 126.712218 -58.158126)
		(width 0.1016)
		(layer "F.Cu")
		(net "UART_TX_P4_BUF")
	)
	(segment
		(start 128.211326 -53.76545)
		(end 129.13487 -53.76545)
		(width 0.1016)
		(layer "F.Cu")
		(net "UART_TX_P4_BUF")
	)
	(segment
		(start 127.561594 -57.223406)
		(end 127.561594 -56.786526)
		(width 0.1016)
		(layer "F.Cu")
		(net "UART_TX_P4_BUF")
	)
	(segment
		(start 126.712218 -57.854342)
		(end 126.930658 -57.854342)
		(width 0.1016)
		(layer "F.Cu")
		(net "UART_TX_P4_BUF")
	)
	(via
		(at 126.712218 -57.854342)
		(size 0.508)
		(drill 0.254)
		(layers "F.Cu" "B.Cu")
		(net "UART_TX_P4_BUF")
	)
	(segment
		(start 174.01032 -123.365768)
		(end 173.510448 -123.86564)
		(width 0.1016)
		(layer "F.Cu")
		(net "CPLD_THRMTRIP_LOG_N")
	)
	(via
		(at 173.510448 -123.86564)
		(size 0.49022)
		(drill 0.254)
		(layers "F.Cu" "B.Cu")
		(net "CPLD_THRMTRIP_LOG_N")
	)
	(via
		(at 44.567602 -182.94223)
		(size 0.508)
		(drill 0.254)
		(layers "F.Cu" "B.Cu")
		(net "CPLD_THRMTRIP_LOG_N")
	)
	(segment
		(start 48.232568 -177.279046)
		(end 47.21606 -178.295554)
		(width 0.1016)
		(layer "B.Cu")
		(net "CPLD_THRMTRIP_LOG_N")
	)
	(segment
		(start 49.038764 -176.640744)
		(end 48.400462 -177.279046)
		(width 0.1016)
		(layer "B.Cu")
		(net "CPLD_THRMTRIP_LOG_N")
	)
	(segment
		(start 47.21606 -178.295554)
		(end 47.21606 -179.886356)
		(width 0.1016)
		(layer "B.Cu")
		(net "CPLD_THRMTRIP_LOG_N")
	)
	(segment
		(start 47.21606 -179.886356)
		(end 46.57344 -180.528976)
		(width 0.1016)
		(layer "B.Cu")
		(net "CPLD_THRMTRIP_LOG_N")
	)
	(segment
		(start 52.30876 -176.640744)
		(end 49.038764 -176.640744)
		(width 0.1016)
		(layer "B.Cu")
		(net "CPLD_THRMTRIP_LOG_N")
	)
	(segment
		(start 46.57344 -180.528976)
		(end 46.57344 -180.936392)
		(width 0.1016)
		(layer "B.Cu")
		(net "CPLD_THRMTRIP_LOG_N")
	)
	(segment
		(start 46.57344 -180.936392)
		(end 44.567602 -182.94223)
		(width 0.1016)
		(layer "B.Cu")
		(net "CPLD_THRMTRIP_LOG_N")
	)
	(segment
		(start 48.400462 -177.279046)
		(end 48.232568 -177.279046)
		(width 0.1016)
		(layer "B.Cu")
		(net "CPLD_THRMTRIP_LOG_N")
	)
	(segment
		(start 166.35476 -130.401568)
		(end 166.32555 -130.431032)
		(width 0.1143)
		(layer "In2.Cu")
		(net "CPLD_THRMTRIP_LOG_N")
	)
	(segment
		(start 96.09582 -164.455856)
		(end 95.989902 -164.561774)
		(width 0.1143)
		(layer "In2.Cu")
		(net "CPLD_THRMTRIP_LOG_N")
	)
	(segment
		(start 47.203106 -178.533806)
		(end 47.203106 -179.786534)
		(width 0.1143)
		(layer "In2.Cu")
		(net "CPLD_THRMTRIP_LOG_N")
	)
	(segment
		(start 156.006038 -137.542778)
		(end 153.088848 -140.459968)
		(width 0.1143)
		(layer "In2.Cu")
		(net "CPLD_THRMTRIP_LOG_N")
	)
	(segment
		(start 67.089274 -167.555164)
		(end 59.99988 -167.555164)
		(width 0.1143)
		(layer "In2.Cu")
		(net "CPLD_THRMTRIP_LOG_N")
	)
	(segment
		(start 104.862376 -165.999668)
		(end 104.412542 -166.449502)
		(width 0.1143)
		(layer "In2.Cu")
		(net "CPLD_THRMTRIP_LOG_N")
	)
	(segment
		(start 120.07342 -165.2778)
		(end 119.25935 -166.09187)
		(width 0.1143)
		(layer "In2.Cu")
		(net "CPLD_THRMTRIP_LOG_N")
	)
	(segment
		(start 173.510448 -123.86564)
		(end 173.068742 -124.307346)
		(width 0.1143)
		(layer "In2.Cu")
		(net "CPLD_THRMTRIP_LOG_N")
	)
	(segment
		(start 95.989902 -164.561774)
		(end 94.485968 -164.561774)
		(width 0.1143)
		(layer "In2.Cu")
		(net "CPLD_THRMTRIP_LOG_N")
	)
	(segment
		(start 93.360494 -163.4363)
		(end 91.65336 -163.4363)
		(width 0.1143)
		(layer "In2.Cu")
		(net "CPLD_THRMTRIP_LOG_N")
	)
	(segment
		(start 120.67667 -160.959038)
		(end 120.37441 -161.261298)
		(width 0.1143)
		(layer "In2.Cu")
		(net "CPLD_THRMTRIP_LOG_N")
	)
	(segment
		(start 142.476474 -161.57321)
		(end 141.262608 -161.57321)
		(width 0.1143)
		(layer "In2.Cu")
		(net "CPLD_THRMTRIP_LOG_N")
	)
	(segment
		(start 153.369772 -144.508982)
		(end 152.85212 -145.026634)
		(width 0.1143)
		(layer "In2.Cu")
		(net "CPLD_THRMTRIP_LOG_N")
	)
	(segment
		(start 115.3414 -165.806628)
		(end 114.634772 -165.1)
		(width 0.1143)
		(layer "In2.Cu")
		(net "CPLD_THRMTRIP_LOG_N")
	)
	(segment
		(start 119.25935 -166.09187)
		(end 118.89486 -166.09187)
		(width 0.1143)
		(layer "In2.Cu")
		(net "CPLD_THRMTRIP_LOG_N")
	)
	(segment
		(start 87.341202 -163.84524)
		(end 86.84387 -163.347908)
		(width 0.1143)
		(layer "In2.Cu")
		(net "CPLD_THRMTRIP_LOG_N")
	)
	(segment
		(start 73.997566 -165.908736)
		(end 72.160892 -167.74541)
		(width 0.1143)
		(layer "In2.Cu")
		(net "CPLD_THRMTRIP_LOG_N")
	)
	(segment
		(start 118.609618 -165.806628)
		(end 115.3414 -165.806628)
		(width 0.1143)
		(layer "In2.Cu")
		(net "CPLD_THRMTRIP_LOG_N")
	)
	(segment
		(start 96.68637 -164.455856)
		(end 96.09582 -164.455856)
		(width 0.1143)
		(layer "In2.Cu")
		(net "CPLD_THRMTRIP_LOG_N")
	)
	(segment
		(start 172.448982 -124.307346)
		(end 166.35476 -130.401568)
		(width 0.1143)
		(layer "In2.Cu")
		(net "CPLD_THRMTRIP_LOG_N")
	)
	(segment
		(start 109.881162 -166.232078)
		(end 107.00766 -166.232078)
		(width 0.1143)
		(layer "In2.Cu")
		(net "CPLD_THRMTRIP_LOG_N")
	)
	(segment
		(start 152.85212 -145.026634)
		(end 152.85212 -151.477218)
		(width 0.1143)
		(layer "In2.Cu")
		(net "CPLD_THRMTRIP_LOG_N")
	)
	(segment
		(start 100.206556 -166.446962)
		(end 99.193858 -165.434264)
		(width 0.1143)
		(layer "In2.Cu")
		(net "CPLD_THRMTRIP_LOG_N")
	)
	(segment
		(start 120.07342 -162.517074)
		(end 120.07342 -165.2778)
		(width 0.1143)
		(layer "In2.Cu")
		(net "CPLD_THRMTRIP_LOG_N")
	)
	(segment
		(start 50.84953 -167.13454)
		(end 48.4378 -169.54627)
		(width 0.1143)
		(layer "In2.Cu")
		(net "CPLD_THRMTRIP_LOG_N")
	)
	(segment
		(start 164.39642 -134.9248)
		(end 160.531302 -134.9248)
		(width 0.1143)
		(layer "In2.Cu")
		(net "CPLD_THRMTRIP_LOG_N")
	)
	(segment
		(start 85.465412 -163.347908)
		(end 84.92363 -162.806126)
		(width 0.1143)
		(layer "In2.Cu")
		(net "CPLD_THRMTRIP_LOG_N")
	)
	(segment
		(start 47.9171 -175.86198)
		(end 47.9171 -177.819812)
		(width 0.1143)
		(layer "In2.Cu")
		(net "CPLD_THRMTRIP_LOG_N")
	)
	(segment
		(start 151.981916 -152.347422)
		(end 151.981916 -155.824682)
		(width 0.1143)
		(layer "In2.Cu")
		(net "CPLD_THRMTRIP_LOG_N")
	)
	(segment
		(start 97.664778 -165.434264)
		(end 96.68637 -164.455856)
		(width 0.1143)
		(layer "In2.Cu")
		(net "CPLD_THRMTRIP_LOG_N")
	)
	(segment
		(start 146.636232 -161.170366)
		(end 142.879318 -161.170366)
		(width 0.1143)
		(layer "In2.Cu")
		(net "CPLD_THRMTRIP_LOG_N")
	)
	(segment
		(start 91.24442 -163.84524)
		(end 87.341202 -163.84524)
		(width 0.1143)
		(layer "In2.Cu")
		(net "CPLD_THRMTRIP_LOG_N")
	)
	(segment
		(start 153.088848 -140.459968)
		(end 153.088848 -141.902942)
		(width 0.1143)
		(layer "In2.Cu")
		(net "CPLD_THRMTRIP_LOG_N")
	)
	(segment
		(start 48.4378 -175.34128)
		(end 47.9171 -175.86198)
		(width 0.1143)
		(layer "In2.Cu")
		(net "CPLD_THRMTRIP_LOG_N")
	)
	(segment
		(start 47.203106 -179.786534)
		(end 45.0215 -181.96814)
		(width 0.1143)
		(layer "In2.Cu")
		(net "CPLD_THRMTRIP_LOG_N")
	)
	(segment
		(start 101.117654 -166.446962)
		(end 100.206556 -166.446962)
		(width 0.1143)
		(layer "In2.Cu")
		(net "CPLD_THRMTRIP_LOG_N")
	)
	(segment
		(start 48.4378 -169.54627)
		(end 48.4378 -175.34128)
		(width 0.1143)
		(layer "In2.Cu")
		(net "CPLD_THRMTRIP_LOG_N")
	)
	(segment
		(start 112.539272 -165.1)
		(end 111.76 -165.879272)
		(width 0.1143)
		(layer "In2.Cu")
		(net "CPLD_THRMTRIP_LOG_N")
	)
	(segment
		(start 84.92363 -162.806126)
		(end 84.18068 -162.806126)
		(width 0.1143)
		(layer "In2.Cu")
		(net "CPLD_THRMTRIP_LOG_N")
	)
	(segment
		(start 72.160892 -167.74541)
		(end 67.27952 -167.74541)
		(width 0.1143)
		(layer "In2.Cu")
		(net "CPLD_THRMTRIP_LOG_N")
	)
	(segment
		(start 140.06576 -162.770058)
		(end 135.408162 -162.770058)
		(width 0.1143)
		(layer "In2.Cu")
		(net "CPLD_THRMTRIP_LOG_N")
	)
	(segment
		(start 157.913324 -137.542778)
		(end 156.006038 -137.542778)
		(width 0.1143)
		(layer "In2.Cu")
		(net "CPLD_THRMTRIP_LOG_N")
	)
	(segment
		(start 151.981916 -155.824682)
		(end 146.636232 -161.170366)
		(width 0.1143)
		(layer "In2.Cu")
		(net "CPLD_THRMTRIP_LOG_N")
	)
	(segment
		(start 59.99988 -167.555164)
		(end 59.579256 -167.13454)
		(width 0.1143)
		(layer "In2.Cu")
		(net "CPLD_THRMTRIP_LOG_N")
	)
	(segment
		(start 114.634772 -165.1)
		(end 112.539272 -165.1)
		(width 0.1143)
		(layer "In2.Cu")
		(net "CPLD_THRMTRIP_LOG_N")
	)
	(segment
		(start 91.65336 -163.4363)
		(end 91.24442 -163.84524)
		(width 0.1143)
		(layer "In2.Cu")
		(net "CPLD_THRMTRIP_LOG_N")
	)
	(segment
		(start 111.76 -165.879272)
		(end 110.233968 -165.879272)
		(width 0.1143)
		(layer "In2.Cu")
		(net "CPLD_THRMTRIP_LOG_N")
	)
	(segment
		(start 86.84387 -163.347908)
		(end 85.465412 -163.347908)
		(width 0.1143)
		(layer "In2.Cu")
		(net "CPLD_THRMTRIP_LOG_N")
	)
	(segment
		(start 81.125314 -164.005006)
		(end 76.53147 -164.005006)
		(width 0.1143)
		(layer "In2.Cu")
		(net "CPLD_THRMTRIP_LOG_N")
	)
	(segment
		(start 124.80671 -160.959038)
		(end 120.67667 -160.959038)
		(width 0.1143)
		(layer "In2.Cu")
		(net "CPLD_THRMTRIP_LOG_N")
	)
	(segment
		(start 94.485968 -164.561774)
		(end 93.360494 -163.4363)
		(width 0.1143)
		(layer "In2.Cu")
		(net "CPLD_THRMTRIP_LOG_N")
	)
	(segment
		(start 153.088848 -141.902942)
		(end 153.369772 -142.183866)
		(width 0.1143)
		(layer "In2.Cu")
		(net "CPLD_THRMTRIP_LOG_N")
	)
	(segment
		(start 84.18068 -162.806126)
		(end 84.11464 -162.872166)
		(width 0.1143)
		(layer "In2.Cu")
		(net "CPLD_THRMTRIP_LOG_N")
	)
	(segment
		(start 160.531302 -134.9248)
		(end 157.913324 -137.542778)
		(width 0.1143)
		(layer "In2.Cu")
		(net "CPLD_THRMTRIP_LOG_N")
	)
	(segment
		(start 47.9171 -177.819812)
		(end 47.203106 -178.533806)
		(width 0.1143)
		(layer "In2.Cu")
		(net "CPLD_THRMTRIP_LOG_N")
	)
	(segment
		(start 82.329274 -162.801046)
		(end 81.125314 -164.005006)
		(width 0.1143)
		(layer "In2.Cu")
		(net "CPLD_THRMTRIP_LOG_N")
	)
	(segment
		(start 76.53147 -164.005006)
		(end 74.62774 -165.908736)
		(width 0.1143)
		(layer "In2.Cu")
		(net "CPLD_THRMTRIP_LOG_N")
	)
	(segment
		(start 128.834642 -162.20186)
		(end 126.049532 -162.20186)
		(width 0.1143)
		(layer "In2.Cu")
		(net "CPLD_THRMTRIP_LOG_N")
	)
	(segment
		(start 59.579256 -167.13454)
		(end 50.84953 -167.13454)
		(width 0.1143)
		(layer "In2.Cu")
		(net "CPLD_THRMTRIP_LOG_N")
	)
	(segment
		(start 120.37441 -161.261298)
		(end 120.37441 -162.216084)
		(width 0.1143)
		(layer "In2.Cu")
		(net "CPLD_THRMTRIP_LOG_N")
	)
	(segment
		(start 166.32555 -132.99567)
		(end 164.39642 -134.9248)
		(width 0.1143)
		(layer "In2.Cu")
		(net "CPLD_THRMTRIP_LOG_N")
	)
	(segment
		(start 83.5025 -162.801046)
		(end 82.329274 -162.801046)
		(width 0.1143)
		(layer "In2.Cu")
		(net "CPLD_THRMTRIP_LOG_N")
	)
	(segment
		(start 110.233968 -165.879272)
		(end 109.881162 -166.232078)
		(width 0.1143)
		(layer "In2.Cu")
		(net "CPLD_THRMTRIP_LOG_N")
	)
	(segment
		(start 67.27952 -167.74541)
		(end 67.089274 -167.555164)
		(width 0.1143)
		(layer "In2.Cu")
		(net "CPLD_THRMTRIP_LOG_N")
	)
	(segment
		(start 152.85212 -151.477218)
		(end 151.981916 -152.347422)
		(width 0.1143)
		(layer "In2.Cu")
		(net "CPLD_THRMTRIP_LOG_N")
	)
	(segment
		(start 83.57362 -162.872166)
		(end 83.5025 -162.801046)
		(width 0.1143)
		(layer "In2.Cu")
		(net "CPLD_THRMTRIP_LOG_N")
	)
	(segment
		(start 130.173222 -163.54044)
		(end 128.834642 -162.20186)
		(width 0.1143)
		(layer "In2.Cu")
		(net "CPLD_THRMTRIP_LOG_N")
	)
	(segment
		(start 173.068742 -124.307346)
		(end 172.448982 -124.307346)
		(width 0.1143)
		(layer "In2.Cu")
		(net "CPLD_THRMTRIP_LOG_N")
	)
	(segment
		(start 104.412542 -166.449502)
		(end 101.120194 -166.449502)
		(width 0.1143)
		(layer "In2.Cu")
		(net "CPLD_THRMTRIP_LOG_N")
	)
	(segment
		(start 107.00766 -166.232078)
		(end 106.77525 -165.999668)
		(width 0.1143)
		(layer "In2.Cu")
		(net "CPLD_THRMTRIP_LOG_N")
	)
	(segment
		(start 106.77525 -165.999668)
		(end 104.862376 -165.999668)
		(width 0.1143)
		(layer "In2.Cu")
		(net "CPLD_THRMTRIP_LOG_N")
	)
	(segment
		(start 166.32555 -130.431032)
		(end 166.32555 -132.99567)
		(width 0.1143)
		(layer "In2.Cu")
		(net "CPLD_THRMTRIP_LOG_N")
	)
	(segment
		(start 118.89486 -166.09187)
		(end 118.609618 -165.806628)
		(width 0.1143)
		(layer "In2.Cu")
		(net "CPLD_THRMTRIP_LOG_N")
	)
	(segment
		(start 101.120194 -166.449502)
		(end 101.117654 -166.446962)
		(width 0.1143)
		(layer "In2.Cu")
		(net "CPLD_THRMTRIP_LOG_N")
	)
	(segment
		(start 120.37441 -162.216084)
		(end 120.07342 -162.517074)
		(width 0.1143)
		(layer "In2.Cu")
		(net "CPLD_THRMTRIP_LOG_N")
	)
	(segment
		(start 135.408162 -162.770058)
		(end 134.63778 -163.54044)
		(width 0.1143)
		(layer "In2.Cu")
		(net "CPLD_THRMTRIP_LOG_N")
	)
	(segment
		(start 141.262608 -161.57321)
		(end 140.06576 -162.770058)
		(width 0.1143)
		(layer "In2.Cu")
		(net "CPLD_THRMTRIP_LOG_N")
	)
	(segment
		(start 142.879318 -161.170366)
		(end 142.476474 -161.57321)
		(width 0.1143)
		(layer "In2.Cu")
		(net "CPLD_THRMTRIP_LOG_N")
	)
	(segment
		(start 126.049532 -162.20186)
		(end 124.80671 -160.959038)
		(width 0.1143)
		(layer "In2.Cu")
		(net "CPLD_THRMTRIP_LOG_N")
	)
	(segment
		(start 99.193858 -165.434264)
		(end 97.664778 -165.434264)
		(width 0.1143)
		(layer "In2.Cu")
		(net "CPLD_THRMTRIP_LOG_N")
	)
	(segment
		(start 153.369772 -142.183866)
		(end 153.369772 -144.508982)
		(width 0.1143)
		(layer "In2.Cu")
		(net "CPLD_THRMTRIP_LOG_N")
	)
	(segment
		(start 45.0215 -182.488332)
		(end 44.567602 -182.94223)
		(width 0.1143)
		(layer "In2.Cu")
		(net "CPLD_THRMTRIP_LOG_N")
	)
	(segment
		(start 84.11464 -162.872166)
		(end 83.57362 -162.872166)
		(width 0.1143)
		(layer "In2.Cu")
		(net "CPLD_THRMTRIP_LOG_N")
	)
	(segment
		(start 134.63778 -163.54044)
		(end 130.173222 -163.54044)
		(width 0.1143)
		(layer "In2.Cu")
		(net "CPLD_THRMTRIP_LOG_N")
	)
	(segment
		(start 45.0215 -181.96814)
		(end 45.0215 -182.488332)
		(width 0.1143)
		(layer "In2.Cu")
		(net "CPLD_THRMTRIP_LOG_N")
	)
	(segment
		(start 74.62774 -165.908736)
		(end 73.997566 -165.908736)
		(width 0.1143)
		(layer "In2.Cu")
		(net "CPLD_THRMTRIP_LOG_N")
	)
	(segment
		(start 69.51472 -87.00389)
		(end 69.678804 -87.00389)
		(width 0.1016)
		(layer "F.Cu")
		(net "CPU_NODE1_PROCHOT_N")
	)
	(segment
		(start 69.678804 -87.00389)
		(end 70.002908 -87.327994)
		(width 0.1016)
		(layer "F.Cu")
		(net "CPU_NODE1_PROCHOT_N")
	)
	(segment
		(start 94.913196 -84.370672)
		(end 94.50832 -83.965796)
		(width 0.1016)
		(layer "F.Cu")
		(net "CPU_NODE1_PROCHOT_N")
	)
	(segment
		(start 94.913196 -84.994242)
		(end 94.913196 -84.370672)
		(width 0.1016)
		(layer "F.Cu")
		(net "CPU_NODE1_PROCHOT_N")
	)
	(via
		(at 94.50832 -83.965796)
		(size 0.508)
		(drill 0.254)
		(layers "F.Cu" "B.Cu")
		(net "CPU_NODE1_PROCHOT_N")
	)
	(via
		(at 70.002908 -87.327994)
		(size 0.508)
		(drill 0.254)
		(layers "F.Cu" "B.Cu")
		(net "CPU_NODE1_PROCHOT_N")
	)
	(via
		(at 77.154786 -84.195412)
		(size 0.508)
		(drill 0.254)
		(layers "F.Cu" "B.Cu")
		(net "CPU_NODE1_PROCHOT_N")
	)
	(segment
		(start 77.841856 -83.923124)
		(end 77.427074 -83.923124)
		(width 0.1016)
		(layer "B.Cu")
		(net "CPU_NODE1_PROCHOT_N")
	)
	(segment
		(start 77.427074 -83.923124)
		(end 77.154786 -84.195412)
		(width 0.1016)
		(layer "B.Cu")
		(net "CPU_NODE1_PROCHOT_N")
	)
	(segment
		(start 76.777088 -84.195412)
		(end 73.644506 -87.327994)
		(width 0.1143)
		(layer "In7.Cu")
		(net "CPU_NODE1_PROCHOT_N")
	)
	(segment
		(start 78.7273 -84.91728)
		(end 77.876654 -84.91728)
		(width 0.1143)
		(layer "In7.Cu")
		(net "CPU_NODE1_PROCHOT_N")
	)
	(segment
		(start 94.50832 -83.965796)
		(end 93.073474 -83.965796)
		(width 0.1143)
		(layer "In7.Cu")
		(net "CPU_NODE1_PROCHOT_N")
	)
	(segment
		(start 93.073474 -83.965796)
		(end 92.269818 -83.16214)
		(width 0.1143)
		(layer "In7.Cu")
		(net "CPU_NODE1_PROCHOT_N")
	)
	(segment
		(start 80.256888 -86.446868)
		(end 78.7273 -84.91728)
		(width 0.1143)
		(layer "In7.Cu")
		(net "CPU_NODE1_PROCHOT_N")
	)
	(segment
		(start 73.644506 -87.327994)
		(end 70.002908 -87.327994)
		(width 0.1143)
		(layer "In7.Cu")
		(net "CPU_NODE1_PROCHOT_N")
	)
	(segment
		(start 77.876654 -84.91728)
		(end 77.154786 -84.195412)
		(width 0.1143)
		(layer "In7.Cu")
		(net "CPU_NODE1_PROCHOT_N")
	)
	(segment
		(start 92.269818 -83.16214)
		(end 90.32494 -83.16214)
		(width 0.1143)
		(layer "In7.Cu")
		(net "CPU_NODE1_PROCHOT_N")
	)
	(segment
		(start 89.11844 -84.36864)
		(end 88.503506 -84.36864)
		(width 0.1143)
		(layer "In7.Cu")
		(net "CPU_NODE1_PROCHOT_N")
	)
	(segment
		(start 77.154786 -84.195412)
		(end 76.777088 -84.195412)
		(width 0.1143)
		(layer "In7.Cu")
		(net "CPU_NODE1_PROCHOT_N")
	)
	(segment
		(start 88.503506 -84.36864)
		(end 85.65007 -87.222076)
		(width 0.1143)
		(layer "In7.Cu")
		(net "CPU_NODE1_PROCHOT_N")
	)
	(segment
		(start 90.32494 -83.16214)
		(end 89.11844 -84.36864)
		(width 0.1143)
		(layer "In7.Cu")
		(net "CPU_NODE1_PROCHOT_N")
	)
	(segment
		(start 85.65007 -87.222076)
		(end 82.801206 -87.222076)
		(width 0.1143)
		(layer "In7.Cu")
		(net "CPU_NODE1_PROCHOT_N")
	)
	(segment
		(start 82.801206 -87.222076)
		(end 82.025998 -86.446868)
		(width 0.1143)
		(layer "In7.Cu")
		(net "CPU_NODE1_PROCHOT_N")
	)
	(segment
		(start 82.025998 -86.446868)
		(end 80.256888 -86.446868)
		(width 0.1143)
		(layer "In7.Cu")
		(net "CPU_NODE1_PROCHOT_N")
	)
	(segment
		(start 93.2561 -82.994246)
		(end 93.185996 -82.924142)
		(width 0.1016)
		(layer "F.Cu")
		(net "N45787194")
	)
	(segment
		(start 93.185996 -82.924142)
		(end 92.716604 -82.924142)
		(width 0.1016)
		(layer "F.Cu")
		(net "N45787194")
	)
	(segment
		(start 93.963236 -82.028284)
		(end 93.963236 -82.994246)
		(width 0.1016)
		(layer "F.Cu")
		(net "N45787194")
	)
	(segment
		(start 93.963236 -82.994246)
		(end 93.2561 -82.994246)
		(width 0.1016)
		(layer "F.Cu")
		(net "N45787194")
	)
	(via
		(at 93.963236 -82.028284)
		(size 0.508)
		(drill 0.254)
		(layers "F.Cu" "B.Cu")
		(net "N45787194")
	)
	(segment
		(start 95.863156 -82.994246)
		(end 95.863156 -82.368644)
		(width 0.1016)
		(layer "F.Cu")
		(net "H_CPU_NODE1_PROCHOT_L")
	)
	(segment
		(start 95.863156 -82.368644)
		(end 97.165922 -81.065878)
		(width 0.1016)
		(layer "F.Cu")
		(net "H_CPU_NODE1_PROCHOT_L")
	)
	(segment
		(start 97.165922 -81.065878)
		(end 97.598992 -81.065878)
		(width 0.1016)
		(layer "F.Cu")
		(net "H_CPU_NODE1_PROCHOT_L")
	)
	(via
		(at 97.598992 -81.065878)
		(size 0.508)
		(drill 0.254)
		(layers "F.Cu" "B.Cu")
		(net "H_CPU_NODE1_PROCHOT_L")
	)
	(via
		(at 85.52688 -78.954884)
		(size 0.508)
		(drill 0.254)
		(layers "F.Cu" "B.Cu")
		(net "H_CPU_NODE1_PROCHOT_L")
	)
	(segment
		(start 85.27161 -78.699614)
		(end 85.52688 -78.954884)
		(width 0.1016)
		(layer "B.Cu")
		(net "H_CPU_NODE1_PROCHOT_L")
	)
	(segment
		(start 87.745824 -79.781908)
		(end 87.7443 -79.780384)
		(width 0.1016)
		(layer "B.Cu")
		(net "H_CPU_NODE1_PROCHOT_L")
	)
	(segment
		(start 87.3633 -79.780384)
		(end 86.84768 -79.264764)
		(width 0.1016)
		(layer "B.Cu")
		(net "H_CPU_NODE1_PROCHOT_L")
	)
	(segment
		(start 85.27161 -78.608936)
		(end 85.27161 -78.699614)
		(width 0.1016)
		(layer "B.Cu")
		(net "H_CPU_NODE1_PROCHOT_L")
	)
	(segment
		(start 86.84768 -79.264764)
		(end 85.83676 -79.264764)
		(width 0.1016)
		(layer "B.Cu")
		(net "H_CPU_NODE1_PROCHOT_L")
	)
	(segment
		(start 85.83676 -79.264764)
		(end 85.52688 -78.954884)
		(width 0.1016)
		(layer "B.Cu")
		(net "H_CPU_NODE1_PROCHOT_L")
	)
	(segment
		(start 83.573366 -76.910692)
		(end 85.27161 -78.608936)
		(width 0.1016)
		(layer "B.Cu")
		(net "H_CPU_NODE1_PROCHOT_L")
	)
	(segment
		(start 87.7443 -79.780384)
		(end 87.3633 -79.780384)
		(width 0.1016)
		(layer "B.Cu")
		(net "H_CPU_NODE1_PROCHOT_L")
	)
	(segment
		(start 80.662272 -76.910692)
		(end 83.573366 -76.910692)
		(width 0.1016)
		(layer "B.Cu")
		(net "H_CPU_NODE1_PROCHOT_L")
	)
	(segment
		(start 88.321388 -79.781908)
		(end 87.745824 -79.781908)
		(width 0.1016)
		(layer "B.Cu")
		(net "H_CPU_NODE1_PROCHOT_L")
	)
	(segment
		(start 93.720158 -79.025496)
		(end 95.55861 -79.025496)
		(width 0.1143)
		(layer "In7.Cu")
		(net "H_CPU_NODE1_PROCHOT_L")
	)
	(segment
		(start 87.339932 -78.954884)
		(end 88.95969 -77.335126)
		(width 0.1143)
		(layer "In7.Cu")
		(net "H_CPU_NODE1_PROCHOT_L")
	)
	(segment
		(start 95.55861 -79.025496)
		(end 97.598992 -81.065878)
		(width 0.1143)
		(layer "In7.Cu")
		(net "H_CPU_NODE1_PROCHOT_L")
	)
	(segment
		(start 88.95969 -77.335126)
		(end 92.029788 -77.335126)
		(width 0.1143)
		(layer "In7.Cu")
		(net "H_CPU_NODE1_PROCHOT_L")
	)
	(segment
		(start 92.029788 -77.335126)
		(end 93.720158 -79.025496)
		(width 0.1143)
		(layer "In7.Cu")
		(net "H_CPU_NODE1_PROCHOT_L")
	)
	(segment
		(start 85.52688 -78.954884)
		(end 87.339932 -78.954884)
		(width 0.1143)
		(layer "In7.Cu")
		(net "H_CPU_NODE1_PROCHOT_L")
	)
	(segment
		(start 97.728532 -166.430706)
		(end 98.685096 -166.430706)
		(width 0.1016)
		(layer "F.Cu")
		(net "PU_FAN_TACH")
	)
	(segment
		(start 103.214932 -163.890706)
		(end 102.535482 -163.890706)
		(width 0.1016)
		(layer "F.Cu")
		(net "PU_FAN_TACH")
	)
	(segment
		(start 101.10978 -163.35629)
		(end 100.367084 -164.098986)
		(width 0.1016)
		(layer "F.Cu")
		(net "PU_FAN_TACH")
	)
	(segment
		(start 104.434386 -163.890706)
		(end 103.214932 -163.890706)
		(width 0.1016)
		(layer "F.Cu")
		(net "PU_FAN_TACH")
	)
	(segment
		(start 98.685096 -166.430706)
		(end 99.023424 -166.092378)
		(width 0.1016)
		(layer "F.Cu")
		(net "PU_FAN_TACH")
	)
	(segment
		(start 102.535482 -163.890706)
		(end 102.001066 -163.35629)
		(width 0.1016)
		(layer "F.Cu")
		(net "PU_FAN_TACH")
	)
	(segment
		(start 105.792016 -163.767516)
		(end 104.557576 -163.767516)
		(width 0.1016)
		(layer "F.Cu")
		(net "PU_FAN_TACH")
	)
	(segment
		(start 102.001066 -163.35629)
		(end 101.10978 -163.35629)
		(width 0.1016)
		(layer "F.Cu")
		(net "PU_FAN_TACH")
	)
	(segment
		(start 99.11334 -164.098986)
		(end 99.023424 -164.00907)
		(width 0.1016)
		(layer "F.Cu")
		(net "PU_FAN_TACH")
	)
	(segment
		(start 99.023424 -166.092378)
		(end 99.023424 -164.00907)
		(width 0.1016)
		(layer "F.Cu")
		(net "PU_FAN_TACH")
	)
	(segment
		(start 104.557576 -163.767516)
		(end 104.434386 -163.890706)
		(width 0.1016)
		(layer "F.Cu")
		(net "PU_FAN_TACH")
	)
	(segment
		(start 100.367084 -164.098986)
		(end 99.11334 -164.098986)
		(width 0.1016)
		(layer "F.Cu")
		(net "PU_FAN_TACH")
	)
	(via
		(at 99.023424 -164.00907)
		(size 0.508)
		(drill 0.254)
		(layers "F.Cu" "B.Cu")
		(net "PU_FAN_TACH")
	)
	(segment
		(start 125.369574 -57.068974)
		(end 126.689612 -57.068974)
		(width 0.3048)
		(layer "F.Cu")
		(net "COM4_EN_N")
	)
	(segment
		(start 125.132084 -56.831484)
		(end 125.1458 -56.8452)
		(width 0.3048)
		(layer "F.Cu")
		(net "COM4_EN_N")
	)
	(segment
		(start 125.1458 -56.8452)
		(end 125.369574 -57.068974)
		(width 0.3048)
		(layer "F.Cu")
		(net "COM4_EN_N")
	)
	(segment
		(start 124.818902 -54.466236)
		(end 124.93117 -54.578504)
		(width 0.3048)
		(layer "F.Cu")
		(net "COM4_EN_N")
	)
	(segment
		(start 123.988068 -56.831484)
		(end 123.988068 -55.29707)
		(width 0.381)
		(layer "F.Cu")
		(net "COM4_EN_N")
	)
	(segment
		(start 123.991116 -56.834532)
		(end 123.988068 -56.831484)
		(width 0.381)
		(layer "F.Cu")
		(net "COM4_EN_N")
	)
	(segment
		(start 124.93117 -54.578504)
		(end 126.670054 -54.578504)
		(width 0.3048)
		(layer "F.Cu")
		(net "COM4_EN_N")
	)
	(segment
		(start 123.988068 -55.29707)
		(end 124.818902 -54.466236)
		(width 0.381)
		(layer "F.Cu")
		(net "COM4_EN_N")
	)
	(segment
		(start 123.988068 -56.831484)
		(end 125.132084 -56.831484)
		(width 0.3048)
		(layer "F.Cu")
		(net "COM4_EN_N")
	)
	(segment
		(start 123.991116 -57.900062)
		(end 123.991116 -56.834532)
		(width 0.381)
		(layer "F.Cu")
		(net "COM4_EN_N")
	)
	(via
		(at 125.1458 -56.8452)
		(size 0.508)
		(drill 0.254)
		(layers "F.Cu" "B.Cu")
		(net "COM4_EN_N")
	)
	(via
		(at 117.54866 -46.606206)
		(size 0.508)
		(drill 0.254)
		(layers "F.Cu" "B.Cu")
		(net "N46114787")
	)
	(segment
		(start 123.81992 -37.973762)
		(end 123.403868 -38.389814)
		(width 0.1016)
		(layer "F.Cu")
		(net "SIO_JTAG_CPLD3_TCK_R")
	)
	(segment
		(start 125.594618 -37.812218)
		(end 125.433074 -37.973762)
		(width 0.1016)
		(layer "F.Cu")
		(net "SIO_JTAG_CPLD3_TCK_R")
	)
	(segment
		(start 123.403868 -38.389814)
		(end 122.451622 -38.389814)
		(width 0.1016)
		(layer "F.Cu")
		(net "SIO_JTAG_CPLD3_TCK_R")
	)
	(segment
		(start 125.433074 -37.973762)
		(end 123.81992 -37.973762)
		(width 0.1016)
		(layer "F.Cu")
		(net "SIO_JTAG_CPLD3_TCK_R")
	)
	(via
		(at 125.594618 -37.812218)
		(size 0.508)
		(drill 0.254)
		(layers "F.Cu" "B.Cu")
		(net "SIO_JTAG_CPLD3_TCK_R")
	)
	(segment
		(start 123.43384 -38.137338)
		(end 123.124722 -38.446456)
		(width 0.1016)
		(layer "B.Cu")
		(net "SIO_JTAG_CPLD3_TCK_R")
	)
	(segment
		(start 128.301496 -38.274244)
		(end 126.989586 -38.274244)
		(width 0.1016)
		(layer "B.Cu")
		(net "SIO_JTAG_CPLD3_TCK_R")
	)
	(segment
		(start 125.269498 -38.137338)
		(end 123.43384 -38.137338)
		(width 0.1016)
		(layer "B.Cu")
		(net "SIO_JTAG_CPLD3_TCK_R")
	)
	(segment
		(start 126.989586 -38.274244)
		(end 126.52756 -37.812218)
		(width 0.1016)
		(layer "B.Cu")
		(net "SIO_JTAG_CPLD3_TCK_R")
	)
	(segment
		(start 125.594618 -37.812218)
		(end 125.269498 -38.137338)
		(width 0.1016)
		(layer "B.Cu")
		(net "SIO_JTAG_CPLD3_TCK_R")
	)
	(segment
		(start 123.124722 -38.446456)
		(end 122.12066 -38.446456)
		(width 0.1016)
		(layer "B.Cu")
		(net "SIO_JTAG_CPLD3_TCK_R")
	)
	(segment
		(start 126.52756 -37.812218)
		(end 125.594618 -37.812218)
		(width 0.1016)
		(layer "B.Cu")
		(net "SIO_JTAG_CPLD3_TCK_R")
	)
	(segment
		(start 127.05461 -34.658046)
		(end 127.05461 -34.759392)
		(width 0.1016)
		(layer "F.Cu")
		(net "SIO_JTAG_CPLD3_TMS_R")
	)
	(segment
		(start 125.254766 -36.559236)
		(end 124.375418 -36.559236)
		(width 0.1016)
		(layer "F.Cu")
		(net "SIO_JTAG_CPLD3_TMS_R")
	)
	(segment
		(start 124.206 -36.389818)
		(end 122.451622 -36.389818)
		(width 0.1016)
		(layer "F.Cu")
		(net "SIO_JTAG_CPLD3_TMS_R")
	)
	(segment
		(start 124.375418 -36.559236)
		(end 124.206 -36.389818)
		(width 0.1016)
		(layer "F.Cu")
		(net "SIO_JTAG_CPLD3_TMS_R")
	)
	(segment
		(start 127.05461 -34.759392)
		(end 125.254766 -36.559236)
		(width 0.1016)
		(layer "F.Cu")
		(net "SIO_JTAG_CPLD3_TMS_R")
	)
	(via
		(at 127.05461 -34.658046)
		(size 0.508)
		(drill 0.254)
		(layers "F.Cu" "B.Cu")
		(net "SIO_JTAG_CPLD3_TMS_R")
	)
	(segment
		(start 128.301496 -34.972244)
		(end 127.368808 -34.972244)
		(width 0.1016)
		(layer "B.Cu")
		(net "SIO_JTAG_CPLD3_TMS_R")
	)
	(segment
		(start 122.12066 -35.398456)
		(end 126.3142 -35.398456)
		(width 0.1016)
		(layer "B.Cu")
		(net "SIO_JTAG_CPLD3_TMS_R")
	)
	(segment
		(start 126.3142 -35.398456)
		(end 127.05461 -34.658046)
		(width 0.1016)
		(layer "B.Cu")
		(net "SIO_JTAG_CPLD3_TMS_R")
	)
	(segment
		(start 127.368808 -34.972244)
		(end 127.05461 -34.658046)
		(width 0.1016)
		(layer "B.Cu")
		(net "SIO_JTAG_CPLD3_TMS_R")
	)
	(segment
		(start 124.837952 -35.889692)
		(end 125.075696 -36.127436)
		(width 0.1016)
		(layer "F.Cu")
		(net "SIO_JTAG_CPLD3_TDI_R")
	)
	(segment
		(start 122.451622 -35.889692)
		(end 124.837952 -35.889692)
		(width 0.1016)
		(layer "F.Cu")
		(net "SIO_JTAG_CPLD3_TDI_R")
	)
	(via
		(at 125.075696 -36.127436)
		(size 0.508)
		(drill 0.254)
		(layers "F.Cu" "B.Cu")
		(net "SIO_JTAG_CPLD3_TDI_R")
	)
	(segment
		(start 124.49302 -36.414456)
		(end 124.78004 -36.127436)
		(width 0.1016)
		(layer "B.Cu")
		(net "SIO_JTAG_CPLD3_TDI_R")
	)
	(segment
		(start 125.087888 -36.115244)
		(end 125.075696 -36.127436)
		(width 0.1016)
		(layer "B.Cu")
		(net "SIO_JTAG_CPLD3_TDI_R")
	)
	(segment
		(start 128.301496 -36.115244)
		(end 125.087888 -36.115244)
		(width 0.1016)
		(layer "B.Cu")
		(net "SIO_JTAG_CPLD3_TDI_R")
	)
	(segment
		(start 122.12066 -36.414456)
		(end 124.49302 -36.414456)
		(width 0.1016)
		(layer "B.Cu")
		(net "SIO_JTAG_CPLD3_TDI_R")
	)
	(segment
		(start 124.78004 -36.127436)
		(end 125.075696 -36.127436)
		(width 0.1016)
		(layer "B.Cu")
		(net "SIO_JTAG_CPLD3_TDI_R")
	)
	(segment
		(start 162.549078 -12.87145)
		(end 162.549078 -13.677646)
		(width 0.1016)
		(layer "F.Cu")
		(net "SIO_JTAG_CPLD3_TDI")
	)
	(via
		(at 132.701792 -34.969196)
		(size 0.6604)
		(drill 0.3302)
		(layers "F.Cu" "B.Cu")
		(net "SIO_JTAG_CPLD3_TDI")
	)
	(via
		(at 162.549078 -13.677646)
		(size 0.508)
		(drill 0.254)
		(layers "F.Cu" "B.Cu")
		(net "SIO_JTAG_CPLD3_TDI")
	)
	(segment
		(start 130.7084 -36.6776)
		(end 131.6736 -36.6776)
		(width 0.1016)
		(layer "B.Cu")
		(net "SIO_JTAG_CPLD3_TDI")
	)
	(segment
		(start 157.9626 -4.445)
		(end 160.9598 -7.4422)
		(width 0.1016)
		(layer "B.Cu")
		(net "SIO_JTAG_CPLD3_TDI")
	)
	(segment
		(start 143.9672 -21.1074)
		(end 143.9672 -6.9596)
		(width 0.1016)
		(layer "B.Cu")
		(net "SIO_JTAG_CPLD3_TDI")
	)
	(segment
		(start 143.9672 -6.9596)
		(end 146.4818 -4.445)
		(width 0.1016)
		(layer "B.Cu")
		(net "SIO_JTAG_CPLD3_TDI")
	)
	(segment
		(start 145.9484 -23.0886)
		(end 143.9672 -21.1074)
		(width 0.1016)
		(layer "B.Cu")
		(net "SIO_JTAG_CPLD3_TDI")
	)
	(segment
		(start 132.701792 -34.969196)
		(end 132.701792 -34.557208)
		(width 0.1016)
		(layer "B.Cu")
		(net "SIO_JTAG_CPLD3_TDI")
	)
	(segment
		(start 142.9512 -32.385)
		(end 145.9484 -29.3878)
		(width 0.1016)
		(layer "B.Cu")
		(net "SIO_JTAG_CPLD3_TDI")
	)
	(segment
		(start 160.9598 -7.4422)
		(end 160.9598 -12.088368)
		(width 0.1016)
		(layer "B.Cu")
		(net "SIO_JTAG_CPLD3_TDI")
	)
	(segment
		(start 145.9484 -29.3878)
		(end 145.9484 -23.0886)
		(width 0.1016)
		(layer "B.Cu")
		(net "SIO_JTAG_CPLD3_TDI")
	)
	(segment
		(start 129.101596 -36.115244)
		(end 130.12547 -36.115244)
		(width 0.1016)
		(layer "B.Cu")
		(net "SIO_JTAG_CPLD3_TDI")
	)
	(segment
		(start 132.507736 -35.843464)
		(end 132.507736 -35.163252)
		(width 0.1016)
		(layer "B.Cu")
		(net "SIO_JTAG_CPLD3_TDI")
	)
	(segment
		(start 132.507736 -35.163252)
		(end 132.701792 -34.969196)
		(width 0.1016)
		(layer "B.Cu")
		(net "SIO_JTAG_CPLD3_TDI")
	)
	(segment
		(start 132.701792 -34.557208)
		(end 134.874 -32.385)
		(width 0.1016)
		(layer "B.Cu")
		(net "SIO_JTAG_CPLD3_TDI")
	)
	(segment
		(start 130.146806 -36.116006)
		(end 130.7084 -36.6776)
		(width 0.1016)
		(layer "B.Cu")
		(net "SIO_JTAG_CPLD3_TDI")
	)
	(segment
		(start 130.12547 -36.115244)
		(end 130.126232 -36.116006)
		(width 0.1016)
		(layer "B.Cu")
		(net "SIO_JTAG_CPLD3_TDI")
	)
	(segment
		(start 130.126232 -36.116006)
		(end 130.146806 -36.116006)
		(width 0.1016)
		(layer "B.Cu")
		(net "SIO_JTAG_CPLD3_TDI")
	)
	(segment
		(start 146.4818 -4.445)
		(end 157.9626 -4.445)
		(width 0.1016)
		(layer "B.Cu")
		(net "SIO_JTAG_CPLD3_TDI")
	)
	(segment
		(start 134.874 -32.385)
		(end 142.9512 -32.385)
		(width 0.1016)
		(layer "B.Cu")
		(net "SIO_JTAG_CPLD3_TDI")
	)
	(segment
		(start 131.6736 -36.6776)
		(end 132.507736 -35.843464)
		(width 0.1016)
		(layer "B.Cu")
		(net "SIO_JTAG_CPLD3_TDI")
	)
	(segment
		(start 160.9598 -12.088368)
		(end 162.549078 -13.677646)
		(width 0.1016)
		(layer "B.Cu")
		(net "SIO_JTAG_CPLD3_TDI")
	)
	(segment
		(start 124.025152 -37.389816)
		(end 124.09678 -37.461444)
		(width 0.1016)
		(layer "F.Cu")
		(net "SIO_JTAG_CPLD3_TDO")
	)
	(segment
		(start 170.176698 -12.874244)
		(end 170.176698 -13.632688)
		(width 0.1016)
		(layer "F.Cu")
		(net "SIO_JTAG_CPLD3_TDO")
	)
	(segment
		(start 122.451622 -37.389816)
		(end 124.025152 -37.389816)
		(width 0.1016)
		(layer "F.Cu")
		(net "SIO_JTAG_CPLD3_TDO")
	)
	(via
		(at 124.09678 -37.461444)
		(size 0.508)
		(drill 0.254)
		(layers "F.Cu" "B.Cu")
		(net "SIO_JTAG_CPLD3_TDO")
	)
	(via
		(at 170.176698 -13.632688)
		(size 0.508)
		(drill 0.254)
		(layers "F.Cu" "B.Cu")
		(net "SIO_JTAG_CPLD3_TDO")
	)
	(segment
		(start 133.384036 -34.408364)
		(end 135.0264 -32.766)
		(width 0.1016)
		(layer "B.Cu")
		(net "SIO_JTAG_CPLD3_TDO")
	)
	(segment
		(start 157.7594 -4.8768)
		(end 160.5788 -7.6962)
		(width 0.1016)
		(layer "B.Cu")
		(net "SIO_JTAG_CPLD3_TDO")
	)
	(segment
		(start 130.5306 -37.0332)
		(end 131.8006 -37.0332)
		(width 0.1016)
		(layer "B.Cu")
		(net "SIO_JTAG_CPLD3_TDO")
	)
	(segment
		(start 162.179 -14.1986)
		(end 169.610786 -14.1986)
		(width 0.1016)
		(layer "B.Cu")
		(net "SIO_JTAG_CPLD3_TDO")
	)
	(segment
		(start 135.0264 -32.766)
		(end 143.0782 -32.766)
		(width 0.1016)
		(layer "B.Cu")
		(net "SIO_JTAG_CPLD3_TDO")
	)
	(segment
		(start 126.783846 -37.001958)
		(end 127.133604 -36.6522)
		(width 0.1016)
		(layer "B.Cu")
		(net "SIO_JTAG_CPLD3_TDO")
	)
	(segment
		(start 122.12066 -37.430456)
		(end 124.065792 -37.430456)
		(width 0.1016)
		(layer "B.Cu")
		(net "SIO_JTAG_CPLD3_TDO")
	)
	(segment
		(start 124.09678 -37.461444)
		(end 124.556266 -37.001958)
		(width 0.1016)
		(layer "B.Cu")
		(net "SIO_JTAG_CPLD3_TDO")
	)
	(segment
		(start 144.2974 -7.112)
		(end 146.5326 -4.8768)
		(width 0.1016)
		(layer "B.Cu")
		(net "SIO_JTAG_CPLD3_TDO")
	)
	(segment
		(start 131.8006 -37.0332)
		(end 133.384036 -35.449764)
		(width 0.1016)
		(layer "B.Cu")
		(net "SIO_JTAG_CPLD3_TDO")
	)
	(segment
		(start 146.5326 -4.8768)
		(end 157.7594 -4.8768)
		(width 0.1016)
		(layer "B.Cu")
		(net "SIO_JTAG_CPLD3_TDO")
	)
	(segment
		(start 133.384036 -35.449764)
		(end 133.384036 -34.408364)
		(width 0.1016)
		(layer "B.Cu")
		(net "SIO_JTAG_CPLD3_TDO")
	)
	(segment
		(start 143.0782 -32.766)
		(end 146.31289 -29.53131)
		(width 0.1016)
		(layer "B.Cu")
		(net "SIO_JTAG_CPLD3_TDO")
	)
	(segment
		(start 160.5788 -12.5984)
		(end 162.179 -14.1986)
		(width 0.1016)
		(layer "B.Cu")
		(net "SIO_JTAG_CPLD3_TDO")
	)
	(segment
		(start 127.133604 -36.6522)
		(end 130.1496 -36.6522)
		(width 0.1016)
		(layer "B.Cu")
		(net "SIO_JTAG_CPLD3_TDO")
	)
	(segment
		(start 160.5788 -7.6962)
		(end 160.5788 -12.5984)
		(width 0.1016)
		(layer "B.Cu")
		(net "SIO_JTAG_CPLD3_TDO")
	)
	(segment
		(start 169.610786 -14.1986)
		(end 170.176698 -13.632688)
		(width 0.1016)
		(layer "B.Cu")
		(net "SIO_JTAG_CPLD3_TDO")
	)
	(segment
		(start 144.2974 -20.7518)
		(end 144.2974 -7.112)
		(width 0.1016)
		(layer "B.Cu")
		(net "SIO_JTAG_CPLD3_TDO")
	)
	(segment
		(start 130.1496 -36.6522)
		(end 130.5306 -37.0332)
		(width 0.1016)
		(layer "B.Cu")
		(net "SIO_JTAG_CPLD3_TDO")
	)
	(segment
		(start 146.31289 -29.53131)
		(end 146.31289 -22.76729)
		(width 0.1016)
		(layer "B.Cu")
		(net "SIO_JTAG_CPLD3_TDO")
	)
	(segment
		(start 124.065792 -37.430456)
		(end 124.09678 -37.461444)
		(width 0.1016)
		(layer "B.Cu")
		(net "SIO_JTAG_CPLD3_TDO")
	)
	(segment
		(start 146.31289 -22.76729)
		(end 144.2974 -20.7518)
		(width 0.1016)
		(layer "B.Cu")
		(net "SIO_JTAG_CPLD3_TDO")
	)
	(segment
		(start 124.556266 -37.001958)
		(end 126.783846 -37.001958)
		(width 0.1016)
		(layer "B.Cu")
		(net "SIO_JTAG_CPLD3_TDO")
	)
	(segment
		(start 132.52577 -178.858672)
		(end 132.52577 -179.884324)
		(width 0.1016)
		(layer "F.Cu")
		(net "JTAG_CPLD3_TDI")
	)
	(segment
		(start 132.130292 -180.279802)
		(end 132.130292 -182.031894)
		(width 0.1016)
		(layer "F.Cu")
		(net "JTAG_CPLD3_TDI")
	)
	(segment
		(start 132.52577 -179.884324)
		(end 132.130292 -180.279802)
		(width 0.1016)
		(layer "F.Cu")
		(net "JTAG_CPLD3_TDI")
	)
	(segment
		(start 131.609592 -182.552594)
		(end 131.250944 -182.552594)
		(width 0.1016)
		(layer "F.Cu")
		(net "JTAG_CPLD3_TDI")
	)
	(segment
		(start 132.130292 -182.031894)
		(end 131.609592 -182.552594)
		(width 0.1016)
		(layer "F.Cu")
		(net "JTAG_CPLD3_TDI")
	)
	(segment
		(start 163.565078 -10.870438)
		(end 163.565078 -12.07135)
		(width 0.1016)
		(layer "F.Cu")
		(net "JTAG_CPLD3_TDI")
	)
	(segment
		(start 131.250944 -182.552594)
		(end 130.682492 -181.984142)
		(width 0.1016)
		(layer "F.Cu")
		(net "JTAG_CPLD3_TDI")
	)
	(segment
		(start 162.550602 -9.855962)
		(end 163.565078 -10.870438)
		(width 0.1016)
		(layer "F.Cu")
		(net "JTAG_CPLD3_TDI")
	)
	(segment
		(start 162.549078 -12.07135)
		(end 163.565078 -12.07135)
		(width 0.1016)
		(layer "F.Cu")
		(net "JTAG_CPLD3_TDI")
	)
	(via
		(at 130.682492 -181.984142)
		(size 0.508)
		(drill 0.254)
		(layers "F.Cu" "B.Cu")
		(net "JTAG_CPLD3_TDI")
	)
	(via
		(at 166.624 -186.0296)
		(size 0.508)
		(drill 0.254)
		(layers "F.Cu" "B.Cu")
		(net "JTAG_CPLD3_TDI")
	)
	(via
		(at 191.32042 -83.378548)
		(size 0.508)
		(drill 0.254)
		(layers "F.Cu" "B.Cu")
		(net "JTAG_CPLD3_TDI")
	)
	(segment
		(start 167.288718 -186.0296)
		(end 170.18 -183.138318)
		(width 0.1143)
		(layer "In2.Cu")
		(net "JTAG_CPLD3_TDI")
	)
	(segment
		(start 197.5866 -154.497532)
		(end 197.5866 -91.1606)
		(width 0.1143)
		(layer "In2.Cu")
		(net "JTAG_CPLD3_TDI")
	)
	(segment
		(start 175.721264 -167.479726)
		(end 185.27776 -167.479726)
		(width 0.1143)
		(layer "In2.Cu")
		(net "JTAG_CPLD3_TDI")
	)
	(segment
		(start 174.01794 -170.761914)
		(end 174.01794 -169.18305)
		(width 0.1143)
		(layer "In2.Cu")
		(net "JTAG_CPLD3_TDI")
	)
	(segment
		(start 185.27776 -167.479726)
		(end 186.50331 -166.254176)
		(width 0.1143)
		(layer "In2.Cu")
		(net "JTAG_CPLD3_TDI")
	)
	(segment
		(start 174.01794 -169.18305)
		(end 175.721264 -167.479726)
		(width 0.1143)
		(layer "In2.Cu")
		(net "JTAG_CPLD3_TDI")
	)
	(segment
		(start 171.3357 -175.6791)
		(end 171.3357 -173.444154)
		(width 0.1143)
		(layer "In2.Cu")
		(net "JTAG_CPLD3_TDI")
	)
	(segment
		(start 191.29375 -85.815424)
		(end 191.29375 -84.124546)
		(width 0.1143)
		(layer "In2.Cu")
		(net "JTAG_CPLD3_TDI")
	)
	(segment
		(start 170.18 -183.138318)
		(end 170.18 -182.6006)
		(width 0.1143)
		(layer "In2.Cu")
		(net "JTAG_CPLD3_TDI")
	)
	(segment
		(start 170.7134 -182.0672)
		(end 170.7134 -176.3014)
		(width 0.1143)
		(layer "In2.Cu")
		(net "JTAG_CPLD3_TDI")
	)
	(segment
		(start 166.624 -186.0296)
		(end 167.288718 -186.0296)
		(width 0.1143)
		(layer "In2.Cu")
		(net "JTAG_CPLD3_TDI")
	)
	(segment
		(start 192.9638 -86.5378)
		(end 192.016126 -86.5378)
		(width 0.1143)
		(layer "In2.Cu")
		(net "JTAG_CPLD3_TDI")
	)
	(segment
		(start 186.50331 -166.254176)
		(end 186.50331 -165.580822)
		(width 0.1143)
		(layer "In2.Cu")
		(net "JTAG_CPLD3_TDI")
	)
	(segment
		(start 186.50331 -165.580822)
		(end 197.5866 -154.497532)
		(width 0.1143)
		(layer "In2.Cu")
		(net "JTAG_CPLD3_TDI")
	)
	(segment
		(start 197.5866 -91.1606)
		(end 192.9638 -86.5378)
		(width 0.1143)
		(layer "In2.Cu")
		(net "JTAG_CPLD3_TDI")
	)
	(segment
		(start 170.7134 -176.3014)
		(end 171.3357 -175.6791)
		(width 0.1143)
		(layer "In2.Cu")
		(net "JTAG_CPLD3_TDI")
	)
	(segment
		(start 170.18 -182.6006)
		(end 170.7134 -182.0672)
		(width 0.1143)
		(layer "In2.Cu")
		(net "JTAG_CPLD3_TDI")
	)
	(segment
		(start 191.32042 -84.097876)
		(end 191.32042 -83.378548)
		(width 0.1143)
		(layer "In2.Cu")
		(net "JTAG_CPLD3_TDI")
	)
	(segment
		(start 171.3357 -173.444154)
		(end 174.01794 -170.761914)
		(width 0.1143)
		(layer "In2.Cu")
		(net "JTAG_CPLD3_TDI")
	)
	(segment
		(start 191.29375 -84.124546)
		(end 191.32042 -84.097876)
		(width 0.1143)
		(layer "In2.Cu")
		(net "JTAG_CPLD3_TDI")
	)
	(segment
		(start 192.016126 -86.5378)
		(end 191.29375 -85.815424)
		(width 0.1143)
		(layer "In2.Cu")
		(net "JTAG_CPLD3_TDI")
	)
	(segment
		(start 135.39597 -187.352432)
		(end 161.694368 -187.352432)
		(width 0.1143)
		(layer "In6.Cu")
		(net "JTAG_CPLD3_TDI")
	)
	(segment
		(start 162.550602 -11.293602)
		(end 167.660574 -16.403574)
		(width 0.1143)
		(layer "In6.Cu")
		(net "JTAG_CPLD3_TDI")
	)
	(segment
		(start 171.93895 -67.16395)
		(end 188.33465 -83.55965)
		(width 0.1143)
		(layer "In6.Cu")
		(net "JTAG_CPLD3_TDI")
	)
	(segment
		(start 164.874956 -186.221116)
		(end 165.21684 -186.563)
		(width 0.1143)
		(layer "In6.Cu")
		(net "JTAG_CPLD3_TDI")
	)
	(segment
		(start 171.93895 -50.799492)
		(end 171.93895 -67.16395)
		(width 0.1143)
		(layer "In6.Cu")
		(net "JTAG_CPLD3_TDI")
	)
	(segment
		(start 161.8996 -187.1472)
		(end 162.472116 -187.1472)
		(width 0.1143)
		(layer "In6.Cu")
		(net "JTAG_CPLD3_TDI")
	)
	(segment
		(start 132.49656 -183.806592)
		(end 132.49656 -184.110884)
		(width 0.1143)
		(layer "In6.Cu")
		(net "JTAG_CPLD3_TDI")
	)
	(segment
		(start 169.349674 -35.701732)
		(end 169.349674 -44.56049)
		(width 0.1143)
		(layer "In6.Cu")
		(net "JTAG_CPLD3_TDI")
	)
	(segment
		(start 130.99034 -182.29199)
		(end 130.99034 -182.300372)
		(width 0.1143)
		(layer "In6.Cu")
		(net "JTAG_CPLD3_TDI")
	)
	(segment
		(start 169.349674 -44.56049)
		(end 172.29201 -47.502826)
		(width 0.1143)
		(layer "In6.Cu")
		(net "JTAG_CPLD3_TDI")
	)
	(segment
		(start 167.660574 -16.403574)
		(end 167.660574 -34.012632)
		(width 0.1143)
		(layer "In6.Cu")
		(net "JTAG_CPLD3_TDI")
	)
	(segment
		(start 166.624 -186.182)
		(end 166.624 -186.0296)
		(width 0.1143)
		(layer "In6.Cu")
		(net "JTAG_CPLD3_TDI")
	)
	(segment
		(start 191.139318 -83.55965)
		(end 191.32042 -83.378548)
		(width 0.1143)
		(layer "In6.Cu")
		(net "JTAG_CPLD3_TDI")
	)
	(segment
		(start 132.49656 -184.110884)
		(end 134.166864 -185.781188)
		(width 0.1143)
		(layer "In6.Cu")
		(net "JTAG_CPLD3_TDI")
	)
	(segment
		(start 163.3982 -186.221116)
		(end 164.874956 -186.221116)
		(width 0.1143)
		(layer "In6.Cu")
		(net "JTAG_CPLD3_TDI")
	)
	(segment
		(start 188.33465 -83.55965)
		(end 191.139318 -83.55965)
		(width 0.1143)
		(layer "In6.Cu")
		(net "JTAG_CPLD3_TDI")
	)
	(segment
		(start 130.682492 -181.984142)
		(end 130.99034 -182.29199)
		(width 0.1143)
		(layer "In6.Cu")
		(net "JTAG_CPLD3_TDI")
	)
	(segment
		(start 130.99034 -182.300372)
		(end 132.49656 -183.806592)
		(width 0.1143)
		(layer "In6.Cu")
		(net "JTAG_CPLD3_TDI")
	)
	(segment
		(start 167.660574 -34.012632)
		(end 169.349674 -35.701732)
		(width 0.1143)
		(layer "In6.Cu")
		(net "JTAG_CPLD3_TDI")
	)
	(segment
		(start 134.166864 -185.781188)
		(end 134.166864 -186.123326)
		(width 0.1143)
		(layer "In6.Cu")
		(net "JTAG_CPLD3_TDI")
	)
	(segment
		(start 172.29201 -47.502826)
		(end 172.29201 -50.446432)
		(width 0.1143)
		(layer "In6.Cu")
		(net "JTAG_CPLD3_TDI")
	)
	(segment
		(start 166.243 -186.563)
		(end 166.624 -186.182)
		(width 0.1143)
		(layer "In6.Cu")
		(net "JTAG_CPLD3_TDI")
	)
	(segment
		(start 134.166864 -186.123326)
		(end 135.39597 -187.352432)
		(width 0.1143)
		(layer "In6.Cu")
		(net "JTAG_CPLD3_TDI")
	)
	(segment
		(start 161.694368 -187.352432)
		(end 161.8996 -187.1472)
		(width 0.1143)
		(layer "In6.Cu")
		(net "JTAG_CPLD3_TDI")
	)
	(segment
		(start 165.21684 -186.563)
		(end 166.243 -186.563)
		(width 0.1143)
		(layer "In6.Cu")
		(net "JTAG_CPLD3_TDI")
	)
	(segment
		(start 162.472116 -187.1472)
		(end 163.3982 -186.221116)
		(width 0.1143)
		(layer "In6.Cu")
		(net "JTAG_CPLD3_TDI")
	)
	(segment
		(start 172.29201 -50.446432)
		(end 171.93895 -50.799492)
		(width 0.1143)
		(layer "In6.Cu")
		(net "JTAG_CPLD3_TDI")
	)
	(segment
		(start 162.550602 -9.855962)
		(end 162.550602 -11.293602)
		(width 0.1143)
		(layer "In6.Cu")
		(net "JTAG_CPLD3_TDI")
	)
	(segment
		(start 171.685458 -12.874244)
		(end 171.685458 -13.659866)
		(width 0.1016)
		(layer "F.Cu")
		(net "SIO_JTAG_CPLD3_TCK")
	)
	(via
		(at 171.685458 -13.659866)
		(size 0.508)
		(drill 0.254)
		(layers "F.Cu" "B.Cu")
		(net "SIO_JTAG_CPLD3_TCK")
	)
	(via
		(at 130.2004 -37.465)
		(size 0.6604)
		(drill 0.3302)
		(layers "F.Cu" "B.Cu")
		(net "SIO_JTAG_CPLD3_TCK")
	)
	(segment
		(start 146.6342 -5.2578)
		(end 157.3784 -5.2578)
		(width 0.1016)
		(layer "B.Cu")
		(net "SIO_JTAG_CPLD3_TCK")
	)
	(segment
		(start 129.101596 -37.258244)
		(end 129.993644 -37.258244)
		(width 0.1016)
		(layer "B.Cu")
		(net "SIO_JTAG_CPLD3_TCK")
	)
	(segment
		(start 133.9088 -35.4076)
		(end 133.9088 -34.3916)
		(width 0.1016)
		(layer "B.Cu")
		(net "SIO_JTAG_CPLD3_TCK")
	)
	(segment
		(start 133.9088 -34.3916)
		(end 135.129016 -33.171384)
		(width 0.1016)
		(layer "B.Cu")
		(net "SIO_JTAG_CPLD3_TCK")
	)
	(segment
		(start 144.6276 -19.9898)
		(end 144.6276 -7.2644)
		(width 0.1016)
		(layer "B.Cu")
		(net "SIO_JTAG_CPLD3_TCK")
	)
	(segment
		(start 130.2004 -37.465)
		(end 131.8514 -37.465)
		(width 0.1016)
		(layer "B.Cu")
		(net "SIO_JTAG_CPLD3_TCK")
	)
	(segment
		(start 143.333216 -33.171384)
		(end 147.574 -28.9306)
		(width 0.1016)
		(layer "B.Cu")
		(net "SIO_JTAG_CPLD3_TCK")
	)
	(segment
		(start 144.6276 -7.2644)
		(end 146.6342 -5.2578)
		(width 0.1016)
		(layer "B.Cu")
		(net "SIO_JTAG_CPLD3_TCK")
	)
	(segment
		(start 135.129016 -33.171384)
		(end 143.333216 -33.171384)
		(width 0.1016)
		(layer "B.Cu")
		(net "SIO_JTAG_CPLD3_TCK")
	)
	(segment
		(start 162.1536 -14.7066)
		(end 170.638724 -14.7066)
		(width 0.1016)
		(layer "B.Cu")
		(net "SIO_JTAG_CPLD3_TCK")
	)
	(segment
		(start 147.574 -28.9306)
		(end 147.574 -22.9362)
		(width 0.1016)
		(layer "B.Cu")
		(net "SIO_JTAG_CPLD3_TCK")
	)
	(segment
		(start 129.993644 -37.258244)
		(end 130.2004 -37.465)
		(width 0.1016)
		(layer "B.Cu")
		(net "SIO_JTAG_CPLD3_TCK")
	)
	(segment
		(start 131.8514 -37.465)
		(end 133.9088 -35.4076)
		(width 0.1016)
		(layer "B.Cu")
		(net "SIO_JTAG_CPLD3_TCK")
	)
	(segment
		(start 160.147 -12.7)
		(end 162.1536 -14.7066)
		(width 0.1016)
		(layer "B.Cu")
		(net "SIO_JTAG_CPLD3_TCK")
	)
	(segment
		(start 170.638724 -14.7066)
		(end 171.685458 -13.659866)
		(width 0.1016)
		(layer "B.Cu")
		(net "SIO_JTAG_CPLD3_TCK")
	)
	(segment
		(start 157.3784 -5.2578)
		(end 160.147 -8.0264)
		(width 0.1016)
		(layer "B.Cu")
		(net "SIO_JTAG_CPLD3_TCK")
	)
	(segment
		(start 129.101596 -38.274244)
		(end 129.101596 -37.258244)
		(width 0.1016)
		(layer "B.Cu")
		(net "SIO_JTAG_CPLD3_TCK")
	)
	(segment
		(start 147.574 -22.9362)
		(end 144.6276 -19.9898)
		(width 0.1016)
		(layer "B.Cu")
		(net "SIO_JTAG_CPLD3_TCK")
	)
	(segment
		(start 160.147 -8.0264)
		(end 160.147 -12.7)
		(width 0.1016)
		(layer "B.Cu")
		(net "SIO_JTAG_CPLD3_TCK")
	)
	(segment
		(start 132.80771 -180.639212)
		(end 133.025642 -180.42128)
		(width 0.1016)
		(layer "F.Cu")
		(net "JTAG_CPLD3_TMS")
	)
	(segment
		(start 133.025642 -180.42128)
		(end 133.025642 -178.858672)
		(width 0.1016)
		(layer "F.Cu")
		(net "JTAG_CPLD3_TMS")
	)
	(segment
		(start 166.610538 -12.091924)
		(end 167.626538 -12.091924)
		(width 0.1016)
		(layer "F.Cu")
		(net "JTAG_CPLD3_TMS")
	)
	(segment
		(start 167.630602 -9.855962)
		(end 167.626538 -9.860026)
		(width 0.1016)
		(layer "F.Cu")
		(net "JTAG_CPLD3_TMS")
	)
	(segment
		(start 167.626538 -9.860026)
		(end 167.626538 -12.091924)
		(width 0.1016)
		(layer "F.Cu")
		(net "JTAG_CPLD3_TMS")
	)
	(via
		(at 167.4368 -183.249316)
		(size 0.508)
		(drill 0.254)
		(layers "F.Cu" "B.Cu")
		(net "JTAG_CPLD3_TMS")
	)
	(via
		(at 189.28588 -83.1215)
		(size 0.508)
		(drill 0.254)
		(layers "F.Cu" "B.Cu")
		(net "JTAG_CPLD3_TMS")
	)
	(via
		(at 132.80771 -180.639212)
		(size 0.508)
		(drill 0.254)
		(layers "F.Cu" "B.Cu")
		(net "JTAG_CPLD3_TMS")
	)
	(segment
		(start 169.3672 -169.7228)
		(end 168.2496 -170.8404)
		(width 0.1143)
		(layer "In2.Cu")
		(net "JTAG_CPLD3_TMS")
	)
	(segment
		(start 168.2496 -175.895)
		(end 168.2496 -182.436516)
		(width 0.1143)
		(layer "In2.Cu")
		(net "JTAG_CPLD3_TMS")
	)
	(segment
		(start 170.7896 -168.021)
		(end 170.0022 -168.021)
		(width 0.1143)
		(layer "In2.Cu")
		(net "JTAG_CPLD3_TMS")
	)
	(segment
		(start 168.2496 -170.8404)
		(end 168.2496 -173.6852)
		(width 0.1143)
		(layer "In2.Cu")
		(net "JTAG_CPLD3_TMS")
	)
	(segment
		(start 194.818 -146.177)
		(end 194.818 -154.7876)
		(width 0.1143)
		(layer "In2.Cu")
		(net "JTAG_CPLD3_TMS")
	)
	(segment
		(start 192.2018 -88.5444)
		(end 192.659254 -88.5444)
		(width 0.1143)
		(layer "In2.Cu")
		(net "JTAG_CPLD3_TMS")
	)
	(segment
		(start 186.3344 -163.1696)
		(end 183.2864 -166.2176)
		(width 0.1143)
		(layer "In2.Cu")
		(net "JTAG_CPLD3_TMS")
	)
	(segment
		(start 189.28588 -85.62848)
		(end 192.2018 -88.5444)
		(width 0.1143)
		(layer "In2.Cu")
		(net "JTAG_CPLD3_TMS")
	)
	(segment
		(start 194.818 -154.7876)
		(end 186.436 -163.1696)
		(width 0.1143)
		(layer "In2.Cu")
		(net "JTAG_CPLD3_TMS")
	)
	(segment
		(start 189.28588 -83.1215)
		(end 189.28588 -85.62848)
		(width 0.1143)
		(layer "In2.Cu")
		(net "JTAG_CPLD3_TMS")
	)
	(segment
		(start 195.5038 -145.4912)
		(end 194.818 -146.177)
		(width 0.1143)
		(layer "In2.Cu")
		(net "JTAG_CPLD3_TMS")
	)
	(segment
		(start 186.436 -163.1696)
		(end 186.3344 -163.1696)
		(width 0.1143)
		(layer "In2.Cu")
		(net "JTAG_CPLD3_TMS")
	)
	(segment
		(start 168.2496 -173.6852)
		(end 168.91 -174.3456)
		(width 0.1143)
		(layer "In2.Cu")
		(net "JTAG_CPLD3_TMS")
	)
	(segment
		(start 172.593 -166.2176)
		(end 170.7896 -168.021)
		(width 0.1143)
		(layer "In2.Cu")
		(net "JTAG_CPLD3_TMS")
	)
	(segment
		(start 169.3672 -168.656)
		(end 169.3672 -169.7228)
		(width 0.1143)
		(layer "In2.Cu")
		(net "JTAG_CPLD3_TMS")
	)
	(segment
		(start 192.659254 -88.5444)
		(end 195.5038 -91.388946)
		(width 0.1143)
		(layer "In2.Cu")
		(net "JTAG_CPLD3_TMS")
	)
	(segment
		(start 168.91 -175.2346)
		(end 168.2496 -175.895)
		(width 0.1143)
		(layer "In2.Cu")
		(net "JTAG_CPLD3_TMS")
	)
	(segment
		(start 170.0022 -168.021)
		(end 169.3672 -168.656)
		(width 0.1143)
		(layer "In2.Cu")
		(net "JTAG_CPLD3_TMS")
	)
	(segment
		(start 195.5038 -91.388946)
		(end 195.5038 -145.4912)
		(width 0.1143)
		(layer "In2.Cu")
		(net "JTAG_CPLD3_TMS")
	)
	(segment
		(start 168.91 -174.3456)
		(end 168.91 -175.2346)
		(width 0.1143)
		(layer "In2.Cu")
		(net "JTAG_CPLD3_TMS")
	)
	(segment
		(start 183.2864 -166.2176)
		(end 172.593 -166.2176)
		(width 0.1143)
		(layer "In2.Cu")
		(net "JTAG_CPLD3_TMS")
	)
	(segment
		(start 168.2496 -182.436516)
		(end 167.4368 -183.249316)
		(width 0.1143)
		(layer "In2.Cu")
		(net "JTAG_CPLD3_TMS")
	)
	(segment
		(start 167.348916 -183.3372)
		(end 167.4368 -183.249316)
		(width 0.1143)
		(layer "In6.Cu")
		(net "JTAG_CPLD3_TMS")
	)
	(segment
		(start 159.004 -185.2422)
		(end 160.1216 -184.1246)
		(width 0.1143)
		(layer "In6.Cu")
		(net "JTAG_CPLD3_TMS")
	)
	(segment
		(start 169.78884 -44.195238)
		(end 169.78884 -35.519614)
		(width 0.1143)
		(layer "In6.Cu")
		(net "JTAG_CPLD3_TMS")
	)
	(segment
		(start 133.1468 -180.6194)
		(end 137.4394 -184.912)
		(width 0.1143)
		(layer "In6.Cu")
		(net "JTAG_CPLD3_TMS")
	)
	(segment
		(start 189.28588 -83.1215)
		(end 188.5061 -83.1215)
		(width 0.1143)
		(layer "In6.Cu")
		(net "JTAG_CPLD3_TMS")
	)
	(segment
		(start 132.80771 -180.6194)
		(end 133.1468 -180.6194)
		(width 0.1143)
		(layer "In6.Cu")
		(net "JTAG_CPLD3_TMS")
	)
	(segment
		(start 165.9128 -184.1246)
		(end 166.7002 -183.3372)
		(width 0.1143)
		(layer "In6.Cu")
		(net "JTAG_CPLD3_TMS")
	)
	(segment
		(start 132.80771 -180.639212)
		(end 132.80771 -180.6194)
		(width 0.1143)
		(layer "In6.Cu")
		(net "JTAG_CPLD3_TMS")
	)
	(segment
		(start 173.70171 -68.31711)
		(end 173.70171 -48.108108)
		(width 0.1143)
		(layer "In6.Cu")
		(net "JTAG_CPLD3_TMS")
	)
	(segment
		(start 168.712388 -34.443162)
		(end 168.712388 -10.937748)
		(width 0.1143)
		(layer "In6.Cu")
		(net "JTAG_CPLD3_TMS")
	)
	(segment
		(start 166.7002 -183.3372)
		(end 167.348916 -183.3372)
		(width 0.1143)
		(layer "In6.Cu")
		(net "JTAG_CPLD3_TMS")
	)
	(segment
		(start 173.70171 -48.108108)
		(end 169.78884 -44.195238)
		(width 0.1143)
		(layer "In6.Cu")
		(net "JTAG_CPLD3_TMS")
	)
	(segment
		(start 188.5061 -83.1215)
		(end 173.70171 -68.31711)
		(width 0.1143)
		(layer "In6.Cu")
		(net "JTAG_CPLD3_TMS")
	)
	(segment
		(start 169.78884 -35.519614)
		(end 168.712388 -34.443162)
		(width 0.1143)
		(layer "In6.Cu")
		(net "JTAG_CPLD3_TMS")
	)
	(segment
		(start 147.6756 -184.912)
		(end 148.0058 -185.2422)
		(width 0.1143)
		(layer "In6.Cu")
		(net "JTAG_CPLD3_TMS")
	)
	(segment
		(start 160.1216 -184.1246)
		(end 165.9128 -184.1246)
		(width 0.1143)
		(layer "In6.Cu")
		(net "JTAG_CPLD3_TMS")
	)
	(segment
		(start 148.0058 -185.2422)
		(end 159.004 -185.2422)
		(width 0.1143)
		(layer "In6.Cu")
		(net "JTAG_CPLD3_TMS")
	)
	(segment
		(start 137.4394 -184.912)
		(end 147.6756 -184.912)
		(width 0.1143)
		(layer "In6.Cu")
		(net "JTAG_CPLD3_TMS")
	)
	(segment
		(start 168.712388 -10.937748)
		(end 167.630602 -9.855962)
		(width 0.1143)
		(layer "In6.Cu")
		(net "JTAG_CPLD3_TMS")
	)
	(segment
		(start 131.51485 -180.326538)
		(end 132.025644 -179.815744)
		(width 0.1016)
		(layer "F.Cu")
		(net "JTAG_CPLD3_TCK")
	)
	(segment
		(start 172.710602 -9.855962)
		(end 172.701458 -9.865106)
		(width 0.1016)
		(layer "F.Cu")
		(net "JTAG_CPLD3_TCK")
	)
	(segment
		(start 171.685458 -12.074144)
		(end 172.701458 -12.074144)
		(width 0.1016)
		(layer "F.Cu")
		(net "JTAG_CPLD3_TCK")
	)
	(segment
		(start 172.701458 -9.865106)
		(end 172.701458 -12.074144)
		(width 0.1016)
		(layer "F.Cu")
		(net "JTAG_CPLD3_TCK")
	)
	(segment
		(start 132.025644 -179.815744)
		(end 132.025644 -178.858672)
		(width 0.1016)
		(layer "F.Cu")
		(net "JTAG_CPLD3_TCK")
	)
	(segment
		(start 131.51485 -180.645562)
		(end 131.51485 -180.326538)
		(width 0.1016)
		(layer "F.Cu")
		(net "JTAG_CPLD3_TCK")
	)
	(via
		(at 189.8904 -82.175858)
		(size 0.508)
		(drill 0.254)
		(layers "F.Cu" "B.Cu")
		(net "JTAG_CPLD3_TCK")
	)
	(via
		(at 167.35044 -184.755282)
		(size 0.508)
		(drill 0.254)
		(layers "F.Cu" "B.Cu")
		(net "JTAG_CPLD3_TCK")
	)
	(via
		(at 131.51485 -180.645562)
		(size 0.508)
		(drill 0.254)
		(layers "F.Cu" "B.Cu")
		(net "JTAG_CPLD3_TCK")
	)
	(segment
		(start 171.196 -168.4782)
		(end 170.3324 -168.4782)
		(width 0.1143)
		(layer "In2.Cu")
		(net "JTAG_CPLD3_TCK")
	)
	(segment
		(start 189.8904 -82.175858)
		(end 189.8904 -85.6234)
		(width 0.1143)
		(layer "In2.Cu")
		(net "JTAG_CPLD3_TCK")
	)
	(segment
		(start 169.1132 -182.992522)
		(end 167.35044 -184.755282)
		(width 0.1143)
		(layer "In2.Cu")
		(net "JTAG_CPLD3_TCK")
	)
	(segment
		(start 169.9006 -168.91)
		(end 169.9006 -170.6118)
		(width 0.1143)
		(layer "In2.Cu")
		(net "JTAG_CPLD3_TCK")
	)
	(segment
		(start 170.3324 -168.4782)
		(end 169.9006 -168.91)
		(width 0.1143)
		(layer "In2.Cu")
		(net "JTAG_CPLD3_TCK")
	)
	(segment
		(start 184.25414 -166.641526)
		(end 173.058074 -166.641526)
		(width 0.1143)
		(layer "In2.Cu")
		(net "JTAG_CPLD3_TCK")
	)
	(segment
		(start 196.723 -154.172666)
		(end 184.25414 -166.641526)
		(width 0.1143)
		(layer "In2.Cu")
		(net "JTAG_CPLD3_TCK")
	)
	(segment
		(start 171.57827 -168.12133)
		(end 171.55287 -168.12133)
		(width 0.1143)
		(layer "In2.Cu")
		(net "JTAG_CPLD3_TCK")
	)
	(segment
		(start 192.913 -87.884)
		(end 196.723 -91.694)
		(width 0.1143)
		(layer "In2.Cu")
		(net "JTAG_CPLD3_TCK")
	)
	(segment
		(start 173.058074 -166.641526)
		(end 171.57827 -168.12133)
		(width 0.1143)
		(layer "In2.Cu")
		(net "JTAG_CPLD3_TCK")
	)
	(segment
		(start 192.151 -87.884)
		(end 192.913 -87.884)
		(width 0.1143)
		(layer "In2.Cu")
		(net "JTAG_CPLD3_TCK")
	)
	(segment
		(start 169.9006 -170.6118)
		(end 170.2562 -170.9674)
		(width 0.1143)
		(layer "In2.Cu")
		(net "JTAG_CPLD3_TCK")
	)
	(segment
		(start 196.723 -91.694)
		(end 196.723 -154.172666)
		(width 0.1143)
		(layer "In2.Cu")
		(net "JTAG_CPLD3_TCK")
	)
	(segment
		(start 170.2562 -174.879)
		(end 169.1132 -176.022)
		(width 0.1143)
		(layer "In2.Cu")
		(net "JTAG_CPLD3_TCK")
	)
	(segment
		(start 170.2562 -170.9674)
		(end 170.2562 -174.879)
		(width 0.1143)
		(layer "In2.Cu")
		(net "JTAG_CPLD3_TCK")
	)
	(segment
		(start 171.55287 -168.12133)
		(end 171.196 -168.4782)
		(width 0.1143)
		(layer "In2.Cu")
		(net "JTAG_CPLD3_TCK")
	)
	(segment
		(start 169.1132 -176.022)
		(end 169.1132 -182.992522)
		(width 0.1143)
		(layer "In2.Cu")
		(net "JTAG_CPLD3_TCK")
	)
	(segment
		(start 189.8904 -85.6234)
		(end 192.151 -87.884)
		(width 0.1143)
		(layer "In2.Cu")
		(net "JTAG_CPLD3_TCK")
	)
	(segment
		(start 170.62704 -43.492674)
		(end 170.62704 -35.172142)
		(width 0.1143)
		(layer "In6.Cu")
		(net "JTAG_CPLD3_TCK")
	)
	(segment
		(start 137.245852 -185.3438)
		(end 134.553706 -182.651654)
		(width 0.1143)
		(layer "In6.Cu")
		(net "JTAG_CPLD3_TCK")
	)
	(segment
		(start 188.779658 -82.175858)
		(end 175.7553 -69.1515)
		(width 0.1143)
		(layer "In6.Cu")
		(net "JTAG_CPLD3_TCK")
	)
	(segment
		(start 167.35044 -184.755282)
		(end 166.807642 -184.755282)
		(width 0.1143)
		(layer "In6.Cu")
		(net "JTAG_CPLD3_TCK")
	)
	(segment
		(start 189.8904 -82.175858)
		(end 188.779658 -82.175858)
		(width 0.1143)
		(layer "In6.Cu")
		(net "JTAG_CPLD3_TCK")
	)
	(segment
		(start 170.62704 -35.172142)
		(end 169.6212 -34.166302)
		(width 0.1143)
		(layer "In6.Cu")
		(net "JTAG_CPLD3_TCK")
	)
	(segment
		(start 169.6212 -34.166302)
		(end 169.6212 -12.945364)
		(width 0.1143)
		(layer "In6.Cu")
		(net "JTAG_CPLD3_TCK")
	)
	(segment
		(start 134.553706 -182.651654)
		(end 133.520942 -182.651654)
		(width 0.1143)
		(layer "In6.Cu")
		(net "JTAG_CPLD3_TCK")
	)
	(segment
		(start 174.53991 -56.595772)
		(end 174.53991 -47.405544)
		(width 0.1143)
		(layer "In6.Cu")
		(net "JTAG_CPLD3_TCK")
	)
	(segment
		(start 147.3454 -185.3438)
		(end 137.245852 -185.3438)
		(width 0.1143)
		(layer "In6.Cu")
		(net "JTAG_CPLD3_TCK")
	)
	(segment
		(start 133.520942 -182.651654)
		(end 131.51485 -180.645562)
		(width 0.1143)
		(layer "In6.Cu")
		(net "JTAG_CPLD3_TCK")
	)
	(segment
		(start 174.53991 -47.405544)
		(end 170.62704 -43.492674)
		(width 0.1143)
		(layer "In6.Cu")
		(net "JTAG_CPLD3_TCK")
	)
	(segment
		(start 159.1818 -185.6994)
		(end 147.701 -185.6994)
		(width 0.1143)
		(layer "In6.Cu")
		(net "JTAG_CPLD3_TCK")
	)
	(segment
		(start 160.274 -184.6072)
		(end 159.1818 -185.6994)
		(width 0.1143)
		(layer "In6.Cu")
		(net "JTAG_CPLD3_TCK")
	)
	(segment
		(start 175.7553 -57.811162)
		(end 174.53991 -56.595772)
		(width 0.1143)
		(layer "In6.Cu")
		(net "JTAG_CPLD3_TCK")
	)
	(segment
		(start 166.807642 -184.755282)
		(end 166.65956 -184.6072)
		(width 0.1143)
		(layer "In6.Cu")
		(net "JTAG_CPLD3_TCK")
	)
	(segment
		(start 175.7553 -69.1515)
		(end 175.7553 -57.811162)
		(width 0.1143)
		(layer "In6.Cu")
		(net "JTAG_CPLD3_TCK")
	)
	(segment
		(start 169.6212 -12.945364)
		(end 172.710602 -9.855962)
		(width 0.1143)
		(layer "In6.Cu")
		(net "JTAG_CPLD3_TCK")
	)
	(segment
		(start 166.65956 -184.6072)
		(end 160.274 -184.6072)
		(width 0.1143)
		(layer "In6.Cu")
		(net "JTAG_CPLD3_TCK")
	)
	(segment
		(start 147.701 -185.6994)
		(end 147.3454 -185.3438)
		(width 0.1143)
		(layer "In6.Cu")
		(net "JTAG_CPLD3_TCK")
	)
	(segment
		(start 167.626538 -12.892024)
		(end 167.626538 -13.645388)
		(width 0.1016)
		(layer "F.Cu")
		(net "SIO_JTAG_CPLD3_TMS")
	)
	(via
		(at 167.626538 -13.645388)
		(size 0.508)
		(drill 0.254)
		(layers "F.Cu" "B.Cu")
		(net "SIO_JTAG_CPLD3_TMS")
	)
	(via
		(at 130.68554 -33.805622)
		(size 0.6604)
		(drill 0.3302)
		(layers "F.Cu" "B.Cu")
		(net "SIO_JTAG_CPLD3_TMS")
	)
	(segment
		(start 145.5928 -29.1592)
		(end 145.5928 -23.908766)
		(width 0.1016)
		(layer "B.Cu")
		(net "SIO_JTAG_CPLD3_TMS")
	)
	(segment
		(start 143.637 -6.8072)
		(end 146.4056 -4.0386)
		(width 0.1016)
		(layer "B.Cu")
		(net "SIO_JTAG_CPLD3_TMS")
	)
	(segment
		(start 161.3662 -7.239)
		(end 161.3662 -10.6172)
		(width 0.1016)
		(layer "B.Cu")
		(net "SIO_JTAG_CPLD3_TMS")
	)
	(segment
		(start 132.716778 -33.805622)
		(end 134.493 -32.0294)
		(width 0.1016)
		(layer "B.Cu")
		(net "SIO_JTAG_CPLD3_TMS")
	)
	(segment
		(start 130.68554 -33.805622)
		(end 132.716778 -33.805622)
		(width 0.1016)
		(layer "B.Cu")
		(net "SIO_JTAG_CPLD3_TMS")
	)
	(segment
		(start 130.121152 -34.37001)
		(end 130.68554 -33.805622)
		(width 0.1016)
		(layer "B.Cu")
		(net "SIO_JTAG_CPLD3_TMS")
	)
	(segment
		(start 163.7792 -13.0302)
		(end 167.01135 -13.0302)
		(width 0.1016)
		(layer "B.Cu")
		(net "SIO_JTAG_CPLD3_TMS")
	)
	(segment
		(start 158.1658 -4.0386)
		(end 161.3662 -7.239)
		(width 0.1016)
		(layer "B.Cu")
		(net "SIO_JTAG_CPLD3_TMS")
	)
	(segment
		(start 146.4056 -4.0386)
		(end 158.1658 -4.0386)
		(width 0.1016)
		(layer "B.Cu")
		(net "SIO_JTAG_CPLD3_TMS")
	)
	(segment
		(start 134.493 -32.0294)
		(end 142.7226 -32.0294)
		(width 0.1016)
		(layer "B.Cu")
		(net "SIO_JTAG_CPLD3_TMS")
	)
	(segment
		(start 142.7226 -32.0294)
		(end 145.5928 -29.1592)
		(width 0.1016)
		(layer "B.Cu")
		(net "SIO_JTAG_CPLD3_TMS")
	)
	(segment
		(start 167.01135 -13.0302)
		(end 167.626538 -13.645388)
		(width 0.1016)
		(layer "B.Cu")
		(net "SIO_JTAG_CPLD3_TMS")
	)
	(segment
		(start 145.5928 -23.908766)
		(end 143.637 -21.952966)
		(width 0.1016)
		(layer "B.Cu")
		(net "SIO_JTAG_CPLD3_TMS")
	)
	(segment
		(start 161.3662 -10.6172)
		(end 163.7792 -13.0302)
		(width 0.1016)
		(layer "B.Cu")
		(net "SIO_JTAG_CPLD3_TMS")
	)
	(segment
		(start 130.119628 -34.972244)
		(end 130.121152 -34.973768)
		(width 0.1016)
		(layer "B.Cu")
		(net "SIO_JTAG_CPLD3_TMS")
	)
	(segment
		(start 129.101596 -34.972244)
		(end 130.119628 -34.972244)
		(width 0.1016)
		(layer "B.Cu")
		(net "SIO_JTAG_CPLD3_TMS")
	)
	(segment
		(start 130.121152 -34.973768)
		(end 130.121152 -34.37001)
		(width 0.1016)
		(layer "B.Cu")
		(net "SIO_JTAG_CPLD3_TMS")
	)
	(segment
		(start 143.637 -21.952966)
		(end 143.637 -6.8072)
		(width 0.1016)
		(layer "B.Cu")
		(net "SIO_JTAG_CPLD3_TMS")
	)
	(segment
		(start 88.385142 -167.124634)
		(end 87.744808 -167.124634)
		(width 0.1016)
		(layer "F.Cu")
		(net "CPLD_FAN_MAX_CTRL")
	)
	(segment
		(start 108.82376 -166.453566)
		(end 109.17428 -166.804086)
		(width 0.1016)
		(layer "F.Cu")
		(net "CPLD_FAN_MAX_CTRL")
	)
	(segment
		(start 104.318816 -172.197268)
		(end 104.431846 -172.310298)
		(width 0.1016)
		(layer "F.Cu")
		(net "CPLD_FAN_MAX_CTRL")
	)
	(segment
		(start 88.671908 -166.837868)
		(end 88.385142 -167.124634)
		(width 0.1016)
		(layer "F.Cu")
		(net "CPLD_FAN_MAX_CTRL")
	)
	(segment
		(start 88.671908 -165.567868)
		(end 88.671908 -166.837868)
		(width 0.1016)
		(layer "F.Cu")
		(net "CPLD_FAN_MAX_CTRL")
	)
	(segment
		(start 89.33942 -164.900356)
		(end 88.671908 -165.567868)
		(width 0.1016)
		(layer "F.Cu")
		(net "CPLD_FAN_MAX_CTRL")
	)
	(segment
		(start 89.33942 -164.898324)
		(end 89.33942 -164.900356)
		(width 0.1016)
		(layer "F.Cu")
		(net "CPLD_FAN_MAX_CTRL")
	)
	(segment
		(start 103.214932 -172.197268)
		(end 104.318816 -172.197268)
		(width 0.1016)
		(layer "F.Cu")
		(net "CPLD_FAN_MAX_CTRL")
	)
	(segment
		(start 108.82376 -165.565582)
		(end 108.82376 -166.453566)
		(width 0.1016)
		(layer "F.Cu")
		(net "CPLD_FAN_MAX_CTRL")
	)
	(via
		(at 109.17428 -166.804086)
		(size 0.508)
		(drill 0.254)
		(layers "F.Cu" "B.Cu")
		(net "CPLD_FAN_MAX_CTRL")
	)
	(via
		(at 104.431846 -172.310298)
		(size 0.508)
		(drill 0.254)
		(layers "F.Cu" "B.Cu")
		(net "CPLD_FAN_MAX_CTRL")
	)
	(via
		(at 89.33942 -164.898324)
		(size 0.508)
		(drill 0.254)
		(layers "F.Cu" "B.Cu")
		(net "CPLD_FAN_MAX_CTRL")
	)
	(segment
		(start 106.68508 -170.68165)
		(end 105.153714 -172.213016)
		(width 0.1016)
		(layer "B.Cu")
		(net "CPLD_FAN_MAX_CTRL")
	)
	(segment
		(start 108.82376 -167.154606)
		(end 108.82376 -167.99941)
		(width 0.1016)
		(layer "B.Cu")
		(net "CPLD_FAN_MAX_CTRL")
	)
	(segment
		(start 108.82376 -167.99941)
		(end 106.68508 -170.13809)
		(width 0.1016)
		(layer "B.Cu")
		(net "CPLD_FAN_MAX_CTRL")
	)
	(segment
		(start 104.529128 -172.213016)
		(end 104.431846 -172.310298)
		(width 0.1016)
		(layer "B.Cu")
		(net "CPLD_FAN_MAX_CTRL")
	)
	(segment
		(start 105.153714 -172.213016)
		(end 104.529128 -172.213016)
		(width 0.1016)
		(layer "B.Cu")
		(net "CPLD_FAN_MAX_CTRL")
	)
	(segment
		(start 109.17428 -166.804086)
		(end 108.82376 -167.154606)
		(width 0.1016)
		(layer "B.Cu")
		(net "CPLD_FAN_MAX_CTRL")
	)
	(segment
		(start 106.68508 -170.13809)
		(end 106.68508 -170.68165)
		(width 0.1016)
		(layer "B.Cu")
		(net "CPLD_FAN_MAX_CTRL")
	)
	(segment
		(start 100.087684 -166.713662)
		(end 99.12096 -165.746938)
		(width 0.1143)
		(layer "In2.Cu")
		(net "CPLD_FAN_MAX_CTRL")
	)
	(segment
		(start 101.00564 -166.713662)
		(end 100.087684 -166.713662)
		(width 0.1143)
		(layer "In2.Cu")
		(net "CPLD_FAN_MAX_CTRL")
	)
	(segment
		(start 94.050612 -164.828474)
		(end 93.645736 -164.423598)
		(width 0.1143)
		(layer "In2.Cu")
		(net "CPLD_FAN_MAX_CTRL")
	)
	(segment
		(start 96.101662 -164.828474)
		(end 94.050612 -164.828474)
		(width 0.1143)
		(layer "In2.Cu")
		(net "CPLD_FAN_MAX_CTRL")
	)
	(segment
		(start 99.12096 -165.746938)
		(end 97.59696 -165.746938)
		(width 0.1143)
		(layer "In2.Cu")
		(net "CPLD_FAN_MAX_CTRL")
	)
	(segment
		(start 106.632248 -166.90594)
		(end 101.197918 -166.90594)
		(width 0.1143)
		(layer "In2.Cu")
		(net "CPLD_FAN_MAX_CTRL")
	)
	(segment
		(start 109.17428 -166.804086)
		(end 108.70565 -166.804086)
		(width 0.1143)
		(layer "In2.Cu")
		(net "CPLD_FAN_MAX_CTRL")
	)
	(segment
		(start 96.20758 -164.722556)
		(end 96.101662 -164.828474)
		(width 0.1143)
		(layer "In2.Cu")
		(net "CPLD_FAN_MAX_CTRL")
	)
	(segment
		(start 93.645736 -164.423598)
		(end 89.816178 -164.423598)
		(width 0.1143)
		(layer "In2.Cu")
		(net "CPLD_FAN_MAX_CTRL")
	)
	(segment
		(start 107.01274 -167.286432)
		(end 106.632248 -166.90594)
		(width 0.1143)
		(layer "In2.Cu")
		(net "CPLD_FAN_MAX_CTRL")
	)
	(segment
		(start 108.223304 -167.286432)
		(end 107.01274 -167.286432)
		(width 0.1143)
		(layer "In2.Cu")
		(net "CPLD_FAN_MAX_CTRL")
	)
	(segment
		(start 108.70565 -166.804086)
		(end 108.223304 -167.286432)
		(width 0.1143)
		(layer "In2.Cu")
		(net "CPLD_FAN_MAX_CTRL")
	)
	(segment
		(start 97.59696 -165.746938)
		(end 96.572578 -164.722556)
		(width 0.1143)
		(layer "In2.Cu")
		(net "CPLD_FAN_MAX_CTRL")
	)
	(segment
		(start 89.816178 -164.423598)
		(end 89.341452 -164.898324)
		(width 0.1143)
		(layer "In2.Cu")
		(net "CPLD_FAN_MAX_CTRL")
	)
	(segment
		(start 101.197918 -166.90594)
		(end 101.00564 -166.713662)
		(width 0.1143)
		(layer "In2.Cu")
		(net "CPLD_FAN_MAX_CTRL")
	)
	(segment
		(start 89.341452 -164.898324)
		(end 89.33942 -164.898324)
		(width 0.1143)
		(layer "In2.Cu")
		(net "CPLD_FAN_MAX_CTRL")
	)
	(segment
		(start 96.572578 -164.722556)
		(end 96.20758 -164.722556)
		(width 0.1143)
		(layer "In2.Cu")
		(net "CPLD_FAN_MAX_CTRL")
	)
	(via
		(at 99.51466 -181.672992)
		(size 0.6604)
		(drill 0.3302)
		(layers "F.Cu" "B.Cu")
		(net "PCA_CPLD_WDT2")
	)
	(segment
		(start 94.072202 -182.526432)
		(end 93.70568 -182.892954)
		(width 0.1016)
		(layer "B.Cu")
		(net "PCA_CPLD_WDT2")
	)
	(segment
		(start 102.111048 -179.494688)
		(end 99.932744 -181.672992)
		(width 0.1016)
		(layer "B.Cu")
		(net "PCA_CPLD_WDT2")
	)
	(segment
		(start 98.050096 -182.526432)
		(end 94.072202 -182.526432)
		(width 0.1016)
		(layer "B.Cu")
		(net "PCA_CPLD_WDT2")
	)
	(segment
		(start 99.932744 -181.672992)
		(end 99.51466 -181.672992)
		(width 0.1016)
		(layer "B.Cu")
		(net "PCA_CPLD_WDT2")
	)
	(segment
		(start 98.420682 -181.672992)
		(end 98.420682 -182.155846)
		(width 0.1016)
		(layer "B.Cu")
		(net "PCA_CPLD_WDT2")
	)
	(segment
		(start 98.420682 -181.672992)
		(end 99.51466 -181.672992)
		(width 0.1016)
		(layer "B.Cu")
		(net "PCA_CPLD_WDT2")
	)
	(segment
		(start 103.36276 -179.494688)
		(end 102.111048 -179.494688)
		(width 0.1016)
		(layer "B.Cu")
		(net "PCA_CPLD_WDT2")
	)
	(segment
		(start 98.420682 -182.155846)
		(end 98.050096 -182.526432)
		(width 0.1016)
		(layer "B.Cu")
		(net "PCA_CPLD_WDT2")
	)
	(segment
		(start 93.70568 -182.892954)
		(end 93.70568 -182.894986)
		(width 0.1016)
		(layer "B.Cu")
		(net "PCA_CPLD_WDT2")
	)
	(segment
		(start 77.494638 -163.31946)
		(end 77.494638 -164.374576)
		(width 0.1016)
		(layer "F.Cu")
		(net "TACKOVER_EN_N")
	)
	(segment
		(start 135.025638 -162.095688)
		(end 134.817866 -161.887916)
		(width 0.1016)
		(layer "F.Cu")
		(net "TACKOVER_EN_N")
	)
	(segment
		(start 75.63358 -171.37888)
		(end 75.63358 -170.382692)
		(width 0.1016)
		(layer "F.Cu")
		(net "TACKOVER_EN_N")
	)
	(segment
		(start 77.9526 -166.66083)
		(end 77.9526 -165.601904)
		(width 0.1016)
		(layer "F.Cu")
		(net "TACKOVER_EN_N")
	)
	(segment
		(start 76.98994 -162.814762)
		(end 77.494638 -163.31946)
		(width 0.1016)
		(layer "F.Cu")
		(net "TACKOVER_EN_N")
	)
	(segment
		(start 76.98994 -162.402774)
		(end 76.98994 -162.814762)
		(width 0.1016)
		(layer "F.Cu")
		(net "TACKOVER_EN_N")
	)
	(segment
		(start 77.33792 -168.678352)
		(end 77.33792 -167.27551)
		(width 0.1016)
		(layer "F.Cu")
		(net "TACKOVER_EN_N")
	)
	(segment
		(start 77.9526 -165.601904)
		(end 77.494638 -165.143942)
		(width 0.1016)
		(layer "F.Cu")
		(net "TACKOVER_EN_N")
	)
	(segment
		(start 75.63358 -170.382692)
		(end 77.33792 -168.678352)
		(width 0.1016)
		(layer "F.Cu")
		(net "TACKOVER_EN_N")
	)
	(segment
		(start 135.025638 -163.358576)
		(end 135.025638 -162.095688)
		(width 0.1016)
		(layer "F.Cu")
		(net "TACKOVER_EN_N")
	)
	(segment
		(start 77.33792 -167.27551)
		(end 77.9526 -166.66083)
		(width 0.1016)
		(layer "F.Cu")
		(net "TACKOVER_EN_N")
	)
	(segment
		(start 77.494638 -165.143942)
		(end 77.494638 -164.374576)
		(width 0.1016)
		(layer "F.Cu")
		(net "TACKOVER_EN_N")
	)
	(via
		(at 75.63358 -171.37888)
		(size 0.508)
		(drill 0.254)
		(layers "F.Cu" "B.Cu")
		(net "TACKOVER_EN_N")
	)
	(via
		(at 134.817866 -161.887916)
		(size 0.508)
		(drill 0.254)
		(layers "F.Cu" "B.Cu")
		(net "TACKOVER_EN_N")
	)
	(via
		(at 76.98994 -162.402774)
		(size 0.508)
		(drill 0.254)
		(layers "F.Cu" "B.Cu")
		(net "TACKOVER_EN_N")
	)
	(via
		(at 95.744284 -175.25619)
		(size 0.508)
		(drill 0.254)
		(layers "F.Cu" "B.Cu")
		(net "TACKOVER_EN_N")
	)
	(via
		(at 156.54528 -136.414764)
		(size 0.508)
		(drill 0.254)
		(layers "F.Cu" "B.Cu")
		(net "TACKOVER_EN_N")
	)
	(segment
		(start 103.36276 -180.144674)
		(end 102.65156 -180.144674)
		(width 0.1016)
		(layer "B.Cu")
		(net "TACKOVER_EN_N")
	)
	(segment
		(start 98.575876 -183.390032)
		(end 94.072964 -183.390032)
		(width 0.1016)
		(layer "B.Cu")
		(net "TACKOVER_EN_N")
	)
	(segment
		(start 134.310628 -161.380678)
		(end 134.817866 -161.887916)
		(width 0.1016)
		(layer "B.Cu")
		(net "TACKOVER_EN_N")
	)
	(segment
		(start 91.94292 -181.725824)
		(end 91.94292 -182.148226)
		(width 0.1016)
		(layer "B.Cu")
		(net "TACKOVER_EN_N")
	)
	(segment
		(start 93.366082 -180.302662)
		(end 91.94292 -181.725824)
		(width 0.1016)
		(layer "B.Cu")
		(net "TACKOVER_EN_N")
	)
	(segment
		(start 93.81744 -179.379626)
		(end 93.366082 -179.830984)
		(width 0.1016)
		(layer "B.Cu")
		(net "TACKOVER_EN_N")
	)
	(segment
		(start 91.94292 -182.148226)
		(end 92.68968 -182.894986)
		(width 0.1016)
		(layer "B.Cu")
		(net "TACKOVER_EN_N")
	)
	(segment
		(start 101.892862 -180.073046)
		(end 98.575876 -183.390032)
		(width 0.1016)
		(layer "B.Cu")
		(net "TACKOVER_EN_N")
	)
	(segment
		(start 93.96222 -178.548792)
		(end 93.81744 -178.693572)
		(width 0.1016)
		(layer "B.Cu")
		(net "TACKOVER_EN_N")
	)
	(segment
		(start 102.579932 -180.073046)
		(end 101.892862 -180.073046)
		(width 0.1016)
		(layer "B.Cu")
		(net "TACKOVER_EN_N")
	)
	(segment
		(start 94.072964 -183.390032)
		(end 94.02572 -183.342788)
		(width 0.1016)
		(layer "B.Cu")
		(net "TACKOVER_EN_N")
	)
	(segment
		(start 94.02572 -183.342788)
		(end 92.822522 -183.342788)
		(width 0.1016)
		(layer "B.Cu")
		(net "TACKOVER_EN_N")
	)
	(segment
		(start 93.96222 -177.038254)
		(end 93.96222 -178.548792)
		(width 0.1016)
		(layer "B.Cu")
		(net "TACKOVER_EN_N")
	)
	(segment
		(start 134.310628 -159.917892)
		(end 134.310628 -161.380678)
		(width 0.1016)
		(layer "B.Cu")
		(net "TACKOVER_EN_N")
	)
	(segment
		(start 92.822522 -183.342788)
		(end 92.68968 -183.209946)
		(width 0.1016)
		(layer "B.Cu")
		(net "TACKOVER_EN_N")
	)
	(segment
		(start 92.68968 -183.209946)
		(end 92.68968 -182.894986)
		(width 0.1016)
		(layer "B.Cu")
		(net "TACKOVER_EN_N")
	)
	(segment
		(start 95.744284 -175.25619)
		(end 93.96222 -177.038254)
		(width 0.1016)
		(layer "B.Cu")
		(net "TACKOVER_EN_N")
	)
	(segment
		(start 102.65156 -180.144674)
		(end 102.579932 -180.073046)
		(width 0.1016)
		(layer "B.Cu")
		(net "TACKOVER_EN_N")
	)
	(segment
		(start 93.366082 -179.830984)
		(end 93.366082 -180.302662)
		(width 0.1016)
		(layer "B.Cu")
		(net "TACKOVER_EN_N")
	)
	(segment
		(start 93.81744 -178.693572)
		(end 93.81744 -179.379626)
		(width 0.1016)
		(layer "B.Cu")
		(net "TACKOVER_EN_N")
	)
	(segment
		(start 119.365776 -162.52444)
		(end 119.00154 -162.52444)
		(width 0.1143)
		(layer "In2.Cu")
		(net "TACKOVER_EN_N")
	)
	(segment
		(start 86.431374 -162.67176)
		(end 85.20938 -161.449766)
		(width 0.1143)
		(layer "In2.Cu")
		(net "TACKOVER_EN_N")
	)
	(segment
		(start 126.161292 -161.934398)
		(end 124.919232 -160.692338)
		(width 0.1143)
		(layer "In2.Cu")
		(net "TACKOVER_EN_N")
	)
	(segment
		(start 153.103072 -144.398492)
		(end 153.103072 -144.034256)
		(width 0.1143)
		(layer "In2.Cu")
		(net "TACKOVER_EN_N")
	)
	(segment
		(start 148.9202 -156.563314)
		(end 148.9202 -154.887676)
		(width 0.1143)
		(layer "In2.Cu")
		(net "TACKOVER_EN_N")
	)
	(segment
		(start 142.362428 -161.30651)
		(end 143.469614 -160.199324)
		(width 0.1143)
		(layer "In2.Cu")
		(net "TACKOVER_EN_N")
	)
	(segment
		(start 77.716888 -162.701478)
		(end 77.418184 -162.402774)
		(width 0.1143)
		(layer "In2.Cu")
		(net "TACKOVER_EN_N")
	)
	(segment
		(start 152.822148 -143.753332)
		(end 152.822148 -140.142722)
		(width 0.1143)
		(layer "In2.Cu")
		(net "TACKOVER_EN_N")
	)
	(segment
		(start 151.5491 -152.296876)
		(end 152.58542 -151.260556)
		(width 0.1143)
		(layer "In2.Cu")
		(net "TACKOVER_EN_N")
	)
	(segment
		(start 120.10771 -161.782506)
		(end 119.365776 -162.52444)
		(width 0.1143)
		(layer "In2.Cu")
		(net "TACKOVER_EN_N")
	)
	(segment
		(start 108.8009 -165.089078)
		(end 105.218992 -165.089078)
		(width 0.1143)
		(layer "In2.Cu")
		(net "TACKOVER_EN_N")
	)
	(segment
		(start 148.9202 -154.887676)
		(end 150.127208 -153.680668)
		(width 0.1143)
		(layer "In2.Cu")
		(net "TACKOVER_EN_N")
	)
	(segment
		(start 93.4466 -162.67176)
		(end 86.431374 -162.67176)
		(width 0.1143)
		(layer "In2.Cu")
		(net "TACKOVER_EN_N")
	)
	(segment
		(start 152.58542 -151.260556)
		(end 152.58542 -144.916144)
		(width 0.1143)
		(layer "In2.Cu")
		(net "TACKOVER_EN_N")
	)
	(segment
		(start 133.432042 -163.27374)
		(end 130.286252 -163.27374)
		(width 0.1143)
		(layer "In2.Cu")
		(net "TACKOVER_EN_N")
	)
	(segment
		(start 85.20938 -161.449766)
		(end 81.936844 -161.449766)
		(width 0.1143)
		(layer "In2.Cu")
		(net "TACKOVER_EN_N")
	)
	(segment
		(start 96.200214 -163.797488)
		(end 95.8215 -163.418774)
		(width 0.1143)
		(layer "In2.Cu")
		(net "TACKOVER_EN_N")
	)
	(segment
		(start 117.197886 -162.481768)
		(end 115.367054 -164.3126)
		(width 0.1143)
		(layer "In2.Cu")
		(net "TACKOVER_EN_N")
	)
	(segment
		(start 151.5491 -152.866598)
		(end 151.5491 -152.296876)
		(width 0.1143)
		(layer "In2.Cu")
		(net "TACKOVER_EN_N")
	)
	(segment
		(start 105.218992 -165.089078)
		(end 104.629966 -164.500052)
		(width 0.1143)
		(layer "In2.Cu")
		(net "TACKOVER_EN_N")
	)
	(segment
		(start 150.127208 -153.680668)
		(end 150.73503 -153.680668)
		(width 0.1143)
		(layer "In2.Cu")
		(net "TACKOVER_EN_N")
	)
	(segment
		(start 115.367054 -164.3126)
		(end 112.280954 -164.3126)
		(width 0.1143)
		(layer "In2.Cu")
		(net "TACKOVER_EN_N")
	)
	(segment
		(start 128.94691 -161.934398)
		(end 126.161292 -161.934398)
		(width 0.1143)
		(layer "In2.Cu")
		(net "TACKOVER_EN_N")
	)
	(segment
		(start 138.663172 -161.887916)
		(end 139.184888 -161.3662)
		(width 0.1143)
		(layer "In2.Cu")
		(net "TACKOVER_EN_N")
	)
	(segment
		(start 94.193614 -163.418774)
		(end 93.4466 -162.67176)
		(width 0.1143)
		(layer "In2.Cu")
		(net "TACKOVER_EN_N")
	)
	(segment
		(start 112.280954 -164.3126)
		(end 111.31042 -165.283134)
		(width 0.1143)
		(layer "In2.Cu")
		(net "TACKOVER_EN_N")
	)
	(segment
		(start 153.103072 -144.034256)
		(end 152.822148 -143.753332)
		(width 0.1143)
		(layer "In2.Cu")
		(net "TACKOVER_EN_N")
	)
	(segment
		(start 134.817866 -161.887916)
		(end 133.432042 -163.27374)
		(width 0.1143)
		(layer "In2.Cu")
		(net "TACKOVER_EN_N")
	)
	(segment
		(start 97.50679 -163.797488)
		(end 96.200214 -163.797488)
		(width 0.1143)
		(layer "In2.Cu")
		(net "TACKOVER_EN_N")
	)
	(segment
		(start 80.739742 -162.646868)
		(end 79.81188 -162.646868)
		(width 0.1143)
		(layer "In2.Cu")
		(net "TACKOVER_EN_N")
	)
	(segment
		(start 130.286252 -163.27374)
		(end 128.94691 -161.934398)
		(width 0.1143)
		(layer "In2.Cu")
		(net "TACKOVER_EN_N")
	)
	(segment
		(start 79.75727 -162.701478)
		(end 77.716888 -162.701478)
		(width 0.1143)
		(layer "In2.Cu")
		(net "TACKOVER_EN_N")
	)
	(segment
		(start 81.936844 -161.449766)
		(end 80.739742 -162.646868)
		(width 0.1143)
		(layer "In2.Cu")
		(net "TACKOVER_EN_N")
	)
	(segment
		(start 124.919232 -160.692338)
		(end 120.56618 -160.692338)
		(width 0.1143)
		(layer "In2.Cu")
		(net "TACKOVER_EN_N")
	)
	(segment
		(start 103.805482 -164.88537)
		(end 98.594672 -164.88537)
		(width 0.1143)
		(layer "In2.Cu")
		(net "TACKOVER_EN_N")
	)
	(segment
		(start 156.2608 -136.699244)
		(end 156.54528 -136.414764)
		(width 0.1143)
		(layer "In2.Cu")
		(net "TACKOVER_EN_N")
	)
	(segment
		(start 79.81188 -162.646868)
		(end 79.75727 -162.701478)
		(width 0.1143)
		(layer "In2.Cu")
		(net "TACKOVER_EN_N")
	)
	(segment
		(start 145.28419 -160.199324)
		(end 148.9202 -156.563314)
		(width 0.1143)
		(layer "In2.Cu")
		(net "TACKOVER_EN_N")
	)
	(segment
		(start 104.629966 -164.500052)
		(end 104.1908 -164.500052)
		(width 0.1143)
		(layer "In2.Cu")
		(net "TACKOVER_EN_N")
	)
	(segment
		(start 77.418184 -162.402774)
		(end 76.98994 -162.402774)
		(width 0.1143)
		(layer "In2.Cu")
		(net "TACKOVER_EN_N")
	)
	(segment
		(start 98.594672 -164.88537)
		(end 97.50679 -163.797488)
		(width 0.1143)
		(layer "In2.Cu")
		(net "TACKOVER_EN_N")
	)
	(segment
		(start 152.822148 -140.142722)
		(end 156.2608 -136.70407)
		(width 0.1143)
		(layer "In2.Cu")
		(net "TACKOVER_EN_N")
	)
	(segment
		(start 108.994956 -165.283134)
		(end 108.8009 -165.089078)
		(width 0.1143)
		(layer "In2.Cu")
		(net "TACKOVER_EN_N")
	)
	(segment
		(start 152.58542 -144.916144)
		(end 153.103072 -144.398492)
		(width 0.1143)
		(layer "In2.Cu")
		(net "TACKOVER_EN_N")
	)
	(segment
		(start 141.09065 -161.3662)
		(end 141.15034 -161.30651)
		(width 0.1143)
		(layer "In2.Cu")
		(net "TACKOVER_EN_N")
	)
	(segment
		(start 156.2608 -136.70407)
		(end 156.2608 -136.699244)
		(width 0.1143)
		(layer "In2.Cu")
		(net "TACKOVER_EN_N")
	)
	(segment
		(start 141.15034 -161.30651)
		(end 142.362428 -161.30651)
		(width 0.1143)
		(layer "In2.Cu")
		(net "TACKOVER_EN_N")
	)
	(segment
		(start 111.31042 -165.283134)
		(end 108.994956 -165.283134)
		(width 0.1143)
		(layer "In2.Cu")
		(net "TACKOVER_EN_N")
	)
	(segment
		(start 134.817866 -161.887916)
		(end 138.663172 -161.887916)
		(width 0.1143)
		(layer "In2.Cu")
		(net "TACKOVER_EN_N")
	)
	(segment
		(start 118.958868 -162.481768)
		(end 117.197886 -162.481768)
		(width 0.1143)
		(layer "In2.Cu")
		(net "TACKOVER_EN_N")
	)
	(segment
		(start 119.00154 -162.52444)
		(end 118.958868 -162.481768)
		(width 0.1143)
		(layer "In2.Cu")
		(net "TACKOVER_EN_N")
	)
	(segment
		(start 150.73503 -153.680668)
		(end 151.5491 -152.866598)
		(width 0.1143)
		(layer "In2.Cu")
		(net "TACKOVER_EN_N")
	)
	(segment
		(start 139.184888 -161.3662)
		(end 141.09065 -161.3662)
		(width 0.1143)
		(layer "In2.Cu")
		(net "TACKOVER_EN_N")
	)
	(segment
		(start 143.469614 -160.199324)
		(end 145.28419 -160.199324)
		(width 0.1143)
		(layer "In2.Cu")
		(net "TACKOVER_EN_N")
	)
	(segment
		(start 120.56618 -160.692338)
		(end 120.10771 -161.150808)
		(width 0.1143)
		(layer "In2.Cu")
		(net "TACKOVER_EN_N")
	)
	(segment
		(start 104.1908 -164.500052)
		(end 103.805482 -164.88537)
		(width 0.1143)
		(layer "In2.Cu")
		(net "TACKOVER_EN_N")
	)
	(segment
		(start 95.8215 -163.418774)
		(end 94.193614 -163.418774)
		(width 0.1143)
		(layer "In2.Cu")
		(net "TACKOVER_EN_N")
	)
	(segment
		(start 120.10771 -161.150808)
		(end 120.10771 -161.782506)
		(width 0.1143)
		(layer "In2.Cu")
		(net "TACKOVER_EN_N")
	)
	(segment
		(start 83.016344 -174.636938)
		(end 85.084412 -174.636938)
		(width 0.1143)
		(layer "In6.Cu")
		(net "TACKOVER_EN_N")
	)
	(segment
		(start 175.66386 -47.85741)
		(end 175.66386 -52.754784)
		(width 0.1143)
		(layer "In6.Cu")
		(net "TACKOVER_EN_N")
	)
	(segment
		(start 75.63358 -171.37888)
		(end 76.976986 -170.035474)
		(width 0.1143)
		(layer "In6.Cu")
		(net "TACKOVER_EN_N")
	)
	(segment
		(start 193.933826 -83.680046)
		(end 193.933826 -120.336564)
		(width 0.1143)
		(layer "In6.Cu")
		(net "TACKOVER_EN_N")
	)
	(segment
		(start 88.938862 -174.884842)
		(end 89.556082 -175.502062)
		(width 0.1143)
		(layer "In6.Cu")
		(net "TACKOVER_EN_N")
	)
	(segment
		(start 93.162374 -174.884842)
		(end 94.284546 -174.884842)
		(width 0.1143)
		(layer "In6.Cu")
		(net "TACKOVER_EN_N")
	)
	(segment
		(start 159.554418 -136.414764)
		(end 156.54528 -136.414764)
		(width 0.1143)
		(layer "In6.Cu")
		(net "TACKOVER_EN_N")
	)
	(segment
		(start 78.41488 -170.035474)
		(end 83.016344 -174.636938)
		(width 0.1143)
		(layer "In6.Cu")
		(net "TACKOVER_EN_N")
	)
	(segment
		(start 191.921892 -81.668112)
		(end 193.933826 -83.680046)
		(width 0.1143)
		(layer "In6.Cu")
		(net "TACKOVER_EN_N")
	)
	(segment
		(start 176.12741 -54.08549)
		(end 175.32223 -54.89067)
		(width 0.1143)
		(layer "In6.Cu")
		(net "TACKOVER_EN_N")
	)
	(segment
		(start 188.631068 -125.639322)
		(end 186.85002 -127.42037)
		(width 0.1143)
		(layer "In6.Cu")
		(net "TACKOVER_EN_N")
	)
	(segment
		(start 175.32223 -56.345582)
		(end 176.1744 -57.197752)
		(width 0.1143)
		(layer "In6.Cu")
		(net "TACKOVER_EN_N")
	)
	(segment
		(start 162.001454 -138.8618)
		(end 159.554418 -136.414764)
		(width 0.1143)
		(layer "In6.Cu")
		(net "TACKOVER_EN_N")
	)
	(segment
		(start 176.12741 -53.218334)
		(end 176.12741 -54.08549)
		(width 0.1143)
		(layer "In6.Cu")
		(net "TACKOVER_EN_N")
	)
	(segment
		(start 85.332316 -174.884842)
		(end 88.938862 -174.884842)
		(width 0.1143)
		(layer "In6.Cu")
		(net "TACKOVER_EN_N")
	)
	(segment
		(start 94.284546 -174.884842)
		(end 94.655894 -175.25619)
		(width 0.1143)
		(layer "In6.Cu")
		(net "TACKOVER_EN_N")
	)
	(segment
		(start 76.976986 -170.035474)
		(end 78.41488 -170.035474)
		(width 0.1143)
		(layer "In6.Cu")
		(net "TACKOVER_EN_N")
	)
	(segment
		(start 176.1744 -57.197752)
		(end 176.1744 -68.977764)
		(width 0.1143)
		(layer "In6.Cu")
		(net "TACKOVER_EN_N")
	)
	(segment
		(start 92.545154 -175.502062)
		(end 93.162374 -174.884842)
		(width 0.1143)
		(layer "In6.Cu")
		(net "TACKOVER_EN_N")
	)
	(segment
		(start 176.1744 -68.977764)
		(end 188.864748 -81.668112)
		(width 0.1143)
		(layer "In6.Cu")
		(net "TACKOVER_EN_N")
	)
	(segment
		(start 175.113442 -34.144966)
		(end 175.113442 -47.306992)
		(width 0.1143)
		(layer "In6.Cu")
		(net "TACKOVER_EN_N")
	)
	(segment
		(start 177.783744 -4.86791)
		(end 177.783744 -11.62685)
		(width 0.1143)
		(layer "In6.Cu")
		(net "TACKOVER_EN_N")
	)
	(segment
		(start 186.85002 -127.42037)
		(end 186.85002 -128.297178)
		(width 0.1143)
		(layer "In6.Cu")
		(net "TACKOVER_EN_N")
	)
	(segment
		(start 189.964568 -125.122432)
		(end 189.447678 -125.639322)
		(width 0.1143)
		(layer "In6.Cu")
		(net "TACKOVER_EN_N")
	)
	(segment
		(start 89.556082 -175.502062)
		(end 92.545154 -175.502062)
		(width 0.1143)
		(layer "In6.Cu")
		(net "TACKOVER_EN_N")
	)
	(segment
		(start 187.951872 -7.457694)
		(end 184.80786 -4.313682)
		(width 0.1143)
		(layer "In6.Cu")
		(net "TACKOVER_EN_N")
	)
	(segment
		(start 188.864748 -81.668112)
		(end 191.921892 -81.668112)
		(width 0.1143)
		(layer "In6.Cu")
		(net "TACKOVER_EN_N")
	)
	(segment
		(start 175.66386 -52.754784)
		(end 176.12741 -53.218334)
		(width 0.1143)
		(layer "In6.Cu")
		(net "TACKOVER_EN_N")
	)
	(segment
		(start 179.85867 -26.409396)
		(end 179.42687 -26.841196)
		(width 0.1143)
		(layer "In6.Cu")
		(net "TACKOVER_EN_N")
	)
	(segment
		(start 184.80786 -4.313682)
		(end 178.337972 -4.313682)
		(width 0.1143)
		(layer "In6.Cu")
		(net "TACKOVER_EN_N")
	)
	(segment
		(start 178.337972 -4.313682)
		(end 177.783744 -4.86791)
		(width 0.1143)
		(layer "In6.Cu")
		(net "TACKOVER_EN_N")
	)
	(segment
		(start 175.113442 -47.306992)
		(end 175.66386 -47.85741)
		(width 0.1143)
		(layer "In6.Cu")
		(net "TACKOVER_EN_N")
	)
	(segment
		(start 179.42687 -26.841196)
		(end 179.42687 -29.831538)
		(width 0.1143)
		(layer "In6.Cu")
		(net "TACKOVER_EN_N")
	)
	(segment
		(start 182.36819 -132.779008)
		(end 182.36819 -133.974078)
		(width 0.1143)
		(layer "In6.Cu")
		(net "TACKOVER_EN_N")
	)
	(segment
		(start 175.32223 -54.89067)
		(end 175.32223 -56.345582)
		(width 0.1143)
		(layer "In6.Cu")
		(net "TACKOVER_EN_N")
	)
	(segment
		(start 94.655894 -175.25619)
		(end 95.744284 -175.25619)
		(width 0.1143)
		(layer "In6.Cu")
		(net "TACKOVER_EN_N")
	)
	(segment
		(start 179.42687 -29.831538)
		(end 175.113442 -34.144966)
		(width 0.1143)
		(layer "In6.Cu")
		(net "TACKOVER_EN_N")
	)
	(segment
		(start 189.447678 -125.639322)
		(end 188.631068 -125.639322)
		(width 0.1143)
		(layer "In6.Cu")
		(net "TACKOVER_EN_N")
	)
	(segment
		(start 182.36819 -133.974078)
		(end 177.480468 -138.8618)
		(width 0.1143)
		(layer "In6.Cu")
		(net "TACKOVER_EN_N")
	)
	(segment
		(start 193.933826 -120.336564)
		(end 189.964568 -124.305822)
		(width 0.1143)
		(layer "In6.Cu")
		(net "TACKOVER_EN_N")
	)
	(segment
		(start 177.783744 -11.62685)
		(end 179.85867 -13.701776)
		(width 0.1143)
		(layer "In6.Cu")
		(net "TACKOVER_EN_N")
	)
	(segment
		(start 179.85867 -13.701776)
		(end 179.85867 -26.409396)
		(width 0.1143)
		(layer "In6.Cu")
		(net "TACKOVER_EN_N")
	)
	(segment
		(start 186.85002 -128.297178)
		(end 182.36819 -132.779008)
		(width 0.1143)
		(layer "In6.Cu")
		(net "TACKOVER_EN_N")
	)
	(segment
		(start 85.084412 -174.636938)
		(end 85.332316 -174.884842)
		(width 0.1143)
		(layer "In6.Cu")
		(net "TACKOVER_EN_N")
	)
	(segment
		(start 177.480468 -138.8618)
		(end 162.001454 -138.8618)
		(width 0.1143)
		(layer "In6.Cu")
		(net "TACKOVER_EN_N")
	)
	(segment
		(start 189.964568 -124.305822)
		(end 189.964568 -125.122432)
		(width 0.1143)
		(layer "In6.Cu")
		(net "TACKOVER_EN_N")
	)
	(segment
		(start 125.21057 -26.969466)
		(end 125.21057 -27.247596)
		(width 0.1016)
		(layer "F.Cu")
		(net "SIO_GPIO47")
	)
	(segment
		(start 126.69774 -28.182062)
		(end 126.145036 -28.182062)
		(width 0.1016)
		(layer "F.Cu")
		(net "SIO_GPIO47")
	)
	(segment
		(start 127.761746 -30.079696)
		(end 127.761746 -29.246068)
		(width 0.1016)
		(layer "F.Cu")
		(net "SIO_GPIO47")
	)
	(segment
		(start 125.21057 -27.247596)
		(end 125.56617 -27.603196)
		(width 0.1016)
		(layer "F.Cu")
		(net "SIO_GPIO47")
	)
	(segment
		(start 126.145036 -28.182062)
		(end 125.56617 -27.603196)
		(width 0.1016)
		(layer "F.Cu")
		(net "SIO_GPIO47")
	)
	(segment
		(start 127.761746 -29.246068)
		(end 126.69774 -28.182062)
		(width 0.1016)
		(layer "F.Cu")
		(net "SIO_GPIO47")
	)
	(via
		(at 125.56617 -27.603196)
		(size 0.508)
		(drill 0.254)
		(layers "F.Cu" "B.Cu")
		(net "SIO_GPIO47")
	)
	(segment
		(start 77.72146 -178.12258)
		(end 76.994766 -178.849274)
		(width 0.1016)
		(layer "F.Cu")
		(net "UART_RI_P4_N")
	)
	(segment
		(start 77.72146 -177.086006)
		(end 77.72146 -178.12258)
		(width 0.1016)
		(layer "F.Cu")
		(net "UART_RI_P4_N")
	)
	(segment
		(start 76.994766 -178.849274)
		(end 76.994766 -179.874672)
		(width 0.1016)
		(layer "F.Cu")
		(net "UART_RI_P4_N")
	)
	(via
		(at 132.41528 -45.258736)
		(size 0.508)
		(drill 0.254)
		(layers "F.Cu" "B.Cu")
		(net "UART_RI_P4_N")
	)
	(via
		(at 77.72146 -177.086006)
		(size 0.508)
		(drill 0.254)
		(layers "F.Cu" "B.Cu")
		(net "UART_RI_P4_N")
	)
	(segment
		(start 133.7818 -55.372)
		(end 133.7818 -53.9496)
		(width 0.1016)
		(layer "B.Cu")
		(net "UART_RI_P4_N")
	)
	(segment
		(start 133.7818 -53.9496)
		(end 132.969 -53.1368)
		(width 0.1016)
		(layer "B.Cu")
		(net "UART_RI_P4_N")
	)
	(segment
		(start 132.969 -53.1368)
		(end 132.969 -51.435)
		(width 0.1016)
		(layer "B.Cu")
		(net "UART_RI_P4_N")
	)
	(segment
		(start 132.3594 -50.165)
		(end 132.6642 -49.8602)
		(width 0.1016)
		(layer "B.Cu")
		(net "UART_RI_P4_N")
	)
	(segment
		(start 132.41528 -44.11345)
		(end 132.41528 -45.258736)
		(width 0.1016)
		(layer "B.Cu")
		(net "UART_RI_P4_N")
	)
	(segment
		(start 132.6642 -48.6664)
		(end 131.9022 -47.9044)
		(width 0.1016)
		(layer "B.Cu")
		(net "UART_RI_P4_N")
	)
	(segment
		(start 131.9022 -47.9044)
		(end 131.9022 -47.09795)
		(width 0.1016)
		(layer "B.Cu")
		(net "UART_RI_P4_N")
	)
	(segment
		(start 132.997194 -55.6006)
		(end 133.5532 -55.6006)
		(width 0.1016)
		(layer "B.Cu")
		(net "UART_RI_P4_N")
	)
	(segment
		(start 132.4356 -46.56455)
		(end 132.4356 -45.279056)
		(width 0.1016)
		(layer "B.Cu")
		(net "UART_RI_P4_N")
	)
	(segment
		(start 132.3594 -50.8254)
		(end 132.3594 -50.165)
		(width 0.1016)
		(layer "B.Cu")
		(net "UART_RI_P4_N")
	)
	(segment
		(start 132.969 -51.435)
		(end 132.3594 -50.8254)
		(width 0.1016)
		(layer "B.Cu")
		(net "UART_RI_P4_N")
	)
	(segment
		(start 132.6642 -49.8602)
		(end 132.6642 -48.6664)
		(width 0.1016)
		(layer "B.Cu")
		(net "UART_RI_P4_N")
	)
	(segment
		(start 133.5532 -55.6006)
		(end 133.7818 -55.372)
		(width 0.1016)
		(layer "B.Cu")
		(net "UART_RI_P4_N")
	)
	(segment
		(start 131.9022 -47.09795)
		(end 132.4356 -46.56455)
		(width 0.1016)
		(layer "B.Cu")
		(net "UART_RI_P4_N")
	)
	(segment
		(start 132.4356 -45.279056)
		(end 132.41528 -45.258736)
		(width 0.1016)
		(layer "B.Cu")
		(net "UART_RI_P4_N")
	)
	(segment
		(start 188.754004 -120.225058)
		(end 188.754004 -98.033078)
		(width 0.1143)
		(layer "In2.Cu")
		(net "UART_RI_P4_N")
	)
	(segment
		(start 87.319358 -177.000662)
		(end 92.05976 -177.000662)
		(width 0.1143)
		(layer "In2.Cu")
		(net "UART_RI_P4_N")
	)
	(segment
		(start 133.48208 -70.552564)
		(end 129.65049 -66.720974)
		(width 0.1143)
		(layer "In2.Cu")
		(net "UART_RI_P4_N")
	)
	(segment
		(start 157.42793 -161.976308)
		(end 158.419038 -161.976308)
		(width 0.1143)
		(layer "In2.Cu")
		(net "UART_RI_P4_N")
	)
	(segment
		(start 98.068384 -174.81804)
		(end 98.87839 -175.628046)
		(width 0.1143)
		(layer "In2.Cu")
		(net "UART_RI_P4_N")
	)
	(segment
		(start 161.828988 -88.021922)
		(end 149.012656 -88.021922)
		(width 0.1143)
		(layer "In2.Cu")
		(net "UART_RI_P4_N")
	)
	(segment
		(start 113.009426 -175.572166)
		(end 114.752374 -177.315114)
		(width 0.1143)
		(layer "In2.Cu")
		(net "UART_RI_P4_N")
	)
	(segment
		(start 95.562674 -174.81804)
		(end 98.068384 -174.81804)
		(width 0.1143)
		(layer "In2.Cu")
		(net "UART_RI_P4_N")
	)
	(segment
		(start 92.31503 -176.745392)
		(end 93.753686 -176.745392)
		(width 0.1143)
		(layer "In2.Cu")
		(net "UART_RI_P4_N")
	)
	(segment
		(start 188.55817 -141.896338)
		(end 188.55817 -125.415802)
		(width 0.1143)
		(layer "In2.Cu")
		(net "UART_RI_P4_N")
	)
	(segment
		(start 135.47344 -170.23207)
		(end 135.47344 -169.627804)
		(width 0.1143)
		(layer "In2.Cu")
		(net "UART_RI_P4_N")
	)
	(segment
		(start 105.951528 -175.5648)
		(end 107.053126 -174.463202)
		(width 0.1143)
		(layer "In2.Cu")
		(net "UART_RI_P4_N")
	)
	(segment
		(start 95.30588 -175.193198)
		(end 95.30588 -175.074834)
		(width 0.1143)
		(layer "In2.Cu")
		(net "UART_RI_P4_N")
	)
	(segment
		(start 176.205134 -158.924244)
		(end 187.6298 -147.499578)
		(width 0.1143)
		(layer "In2.Cu")
		(net "UART_RI_P4_N")
	)
	(segment
		(start 139.147296 -167.756332)
		(end 141.65834 -165.245288)
		(width 0.1143)
		(layer "In2.Cu")
		(net "UART_RI_P4_N")
	)
	(segment
		(start 93.753686 -176.745392)
		(end 95.30588 -175.193198)
		(width 0.1143)
		(layer "In2.Cu")
		(net "UART_RI_P4_N")
	)
	(segment
		(start 187.6298 -142.824708)
		(end 188.55817 -141.896338)
		(width 0.1143)
		(layer "In2.Cu")
		(net "UART_RI_P4_N")
	)
	(segment
		(start 109.244892 -174.975774)
		(end 110.0709 -174.975774)
		(width 0.1143)
		(layer "In2.Cu")
		(net "UART_RI_P4_N")
	)
	(segment
		(start 86.11362 -176.160684)
		(end 86.47938 -176.160684)
		(width 0.1143)
		(layer "In2.Cu")
		(net "UART_RI_P4_N")
	)
	(segment
		(start 156.588714 -162.815524)
		(end 157.42793 -161.976308)
		(width 0.1143)
		(layer "In2.Cu")
		(net "UART_RI_P4_N")
	)
	(segment
		(start 155.1432 -163.49726)
		(end 155.824936 -162.815524)
		(width 0.1143)
		(layer "In2.Cu")
		(net "UART_RI_P4_N")
	)
	(segment
		(start 110.667292 -175.572166)
		(end 113.009426 -175.572166)
		(width 0.1143)
		(layer "In2.Cu")
		(net "UART_RI_P4_N")
	)
	(segment
		(start 158.419038 -161.976308)
		(end 158.93034 -161.465006)
		(width 0.1143)
		(layer "In2.Cu")
		(net "UART_RI_P4_N")
	)
	(segment
		(start 135.01243 -170.69308)
		(end 135.47344 -170.23207)
		(width 0.1143)
		(layer "In2.Cu")
		(net "UART_RI_P4_N")
	)
	(segment
		(start 178.493166 -87.77224)
		(end 162.07867 -87.77224)
		(width 0.1143)
		(layer "In2.Cu")
		(net "UART_RI_P4_N")
	)
	(segment
		(start 131.392422 -53.00091)
		(end 131.392422 -49.495964)
		(width 0.1143)
		(layer "In2.Cu")
		(net "UART_RI_P4_N")
	)
	(segment
		(start 85.394038 -176.880266)
		(end 86.11362 -176.160684)
		(width 0.1143)
		(layer "In2.Cu")
		(net "UART_RI_P4_N")
	)
	(segment
		(start 126.630176 -176.632616)
		(end 134.232142 -176.632616)
		(width 0.1143)
		(layer "In2.Cu")
		(net "UART_RI_P4_N")
	)
	(segment
		(start 149.012656 -88.021922)
		(end 135.84428 -74.853546)
		(width 0.1143)
		(layer "In2.Cu")
		(net "UART_RI_P4_N")
	)
	(segment
		(start 108.73232 -174.463202)
		(end 109.244892 -174.975774)
		(width 0.1143)
		(layer "In2.Cu")
		(net "UART_RI_P4_N")
	)
	(segment
		(start 188.227716 -125.085348)
		(end 188.227716 -120.751346)
		(width 0.1143)
		(layer "In2.Cu")
		(net "UART_RI_P4_N")
	)
	(segment
		(start 77.72146 -177.086006)
		(end 77.9272 -176.880266)
		(width 0.1143)
		(layer "In2.Cu")
		(net "UART_RI_P4_N")
	)
	(segment
		(start 129.65049 -66.720974)
		(end 129.65049 -54.742842)
		(width 0.1143)
		(layer "In2.Cu")
		(net "UART_RI_P4_N")
	)
	(segment
		(start 155.824936 -162.815524)
		(end 156.588714 -162.815524)
		(width 0.1143)
		(layer "In2.Cu")
		(net "UART_RI_P4_N")
	)
	(segment
		(start 126.128018 -177.134774)
		(end 126.630176 -176.632616)
		(width 0.1143)
		(layer "In2.Cu")
		(net "UART_RI_P4_N")
	)
	(segment
		(start 158.93034 -161.465006)
		(end 169.1005 -161.465006)
		(width 0.1143)
		(layer "In2.Cu")
		(net "UART_RI_P4_N")
	)
	(segment
		(start 86.47938 -176.160684)
		(end 87.319358 -177.000662)
		(width 0.1143)
		(layer "In2.Cu")
		(net "UART_RI_P4_N")
	)
	(segment
		(start 135.514334 -175.350424)
		(end 135.514334 -173.238668)
		(width 0.1143)
		(layer "In2.Cu")
		(net "UART_RI_P4_N")
	)
	(segment
		(start 188.55817 -125.415802)
		(end 188.227716 -125.085348)
		(width 0.1143)
		(layer "In2.Cu")
		(net "UART_RI_P4_N")
	)
	(segment
		(start 141.91615 -164.856668)
		(end 145.38071 -164.856668)
		(width 0.1143)
		(layer "In2.Cu")
		(net "UART_RI_P4_N")
	)
	(segment
		(start 77.9272 -176.880266)
		(end 85.394038 -176.880266)
		(width 0.1143)
		(layer "In2.Cu")
		(net "UART_RI_P4_N")
	)
	(segment
		(start 132.41782 -45.260514)
		(end 132.41782 -45.258736)
		(width 0.1143)
		(layer "In2.Cu")
		(net "UART_RI_P4_N")
	)
	(segment
		(start 98.87839 -175.628046)
		(end 99.24288 -175.628046)
		(width 0.1143)
		(layer "In2.Cu")
		(net "UART_RI_P4_N")
	)
	(segment
		(start 135.84428 -74.085196)
		(end 133.48208 -71.722996)
		(width 0.1143)
		(layer "In2.Cu")
		(net "UART_RI_P4_N")
	)
	(segment
		(start 169.1005 -161.465006)
		(end 171.641262 -158.924244)
		(width 0.1143)
		(layer "In2.Cu")
		(net "UART_RI_P4_N")
	)
	(segment
		(start 133.48208 -71.722996)
		(end 133.48208 -70.552564)
		(width 0.1143)
		(layer "In2.Cu")
		(net "UART_RI_P4_N")
	)
	(segment
		(start 145.38071 -164.856668)
		(end 146.01952 -164.217858)
		(width 0.1143)
		(layer "In2.Cu")
		(net "UART_RI_P4_N")
	)
	(segment
		(start 146.01952 -164.217858)
		(end 148.800312 -164.217858)
		(width 0.1143)
		(layer "In2.Cu")
		(net "UART_RI_P4_N")
	)
	(segment
		(start 135.84428 -74.853546)
		(end 135.84428 -74.085196)
		(width 0.1143)
		(layer "In2.Cu")
		(net "UART_RI_P4_N")
	)
	(segment
		(start 92.05976 -177.000662)
		(end 92.31503 -176.745392)
		(width 0.1143)
		(layer "In2.Cu")
		(net "UART_RI_P4_N")
	)
	(segment
		(start 101.37394 -175.746664)
		(end 104.038146 -175.746664)
		(width 0.1143)
		(layer "In2.Cu")
		(net "UART_RI_P4_N")
	)
	(segment
		(start 137.344912 -167.756332)
		(end 139.147296 -167.756332)
		(width 0.1143)
		(layer "In2.Cu")
		(net "UART_RI_P4_N")
	)
	(segment
		(start 124.6886 -177.134774)
		(end 126.128018 -177.134774)
		(width 0.1143)
		(layer "In2.Cu")
		(net "UART_RI_P4_N")
	)
	(segment
		(start 104.038146 -175.746664)
		(end 104.22001 -175.5648)
		(width 0.1143)
		(layer "In2.Cu")
		(net "UART_RI_P4_N")
	)
	(segment
		(start 107.053126 -174.463202)
		(end 108.73232 -174.463202)
		(width 0.1143)
		(layer "In2.Cu")
		(net "UART_RI_P4_N")
	)
	(segment
		(start 141.65834 -165.245288)
		(end 141.65834 -165.114478)
		(width 0.1143)
		(layer "In2.Cu")
		(net "UART_RI_P4_N")
	)
	(segment
		(start 124.50826 -177.315114)
		(end 124.6886 -177.134774)
		(width 0.1143)
		(layer "In2.Cu")
		(net "UART_RI_P4_N")
	)
	(segment
		(start 114.752374 -177.315114)
		(end 124.50826 -177.315114)
		(width 0.1143)
		(layer "In2.Cu")
		(net "UART_RI_P4_N")
	)
	(segment
		(start 188.227716 -120.751346)
		(end 188.754004 -120.225058)
		(width 0.1143)
		(layer "In2.Cu")
		(net "UART_RI_P4_N")
	)
	(segment
		(start 101.15931 -175.532034)
		(end 101.37394 -175.746664)
		(width 0.1143)
		(layer "In2.Cu")
		(net "UART_RI_P4_N")
	)
	(segment
		(start 131.392422 -49.495964)
		(end 132.4102 -48.478186)
		(width 0.1143)
		(layer "In2.Cu")
		(net "UART_RI_P4_N")
	)
	(segment
		(start 188.754004 -98.033078)
		(end 178.493166 -87.77224)
		(width 0.1143)
		(layer "In2.Cu")
		(net "UART_RI_P4_N")
	)
	(segment
		(start 162.07867 -87.77224)
		(end 161.828988 -88.021922)
		(width 0.1143)
		(layer "In2.Cu")
		(net "UART_RI_P4_N")
	)
	(segment
		(start 135.47344 -169.627804)
		(end 137.344912 -167.756332)
		(width 0.1143)
		(layer "In2.Cu")
		(net "UART_RI_P4_N")
	)
	(segment
		(start 148.800312 -164.217858)
		(end 149.52091 -163.49726)
		(width 0.1143)
		(layer "In2.Cu")
		(net "UART_RI_P4_N")
	)
	(segment
		(start 95.30588 -175.074834)
		(end 95.562674 -174.81804)
		(width 0.1143)
		(layer "In2.Cu")
		(net "UART_RI_P4_N")
	)
	(segment
		(start 134.232142 -176.632616)
		(end 135.514334 -175.350424)
		(width 0.1143)
		(layer "In2.Cu")
		(net "UART_RI_P4_N")
	)
	(segment
		(start 132.4102 -48.478186)
		(end 132.4102 -45.267118)
		(width 0.1143)
		(layer "In2.Cu")
		(net "UART_RI_P4_N")
	)
	(segment
		(start 135.01243 -172.736764)
		(end 135.01243 -170.69308)
		(width 0.1143)
		(layer "In2.Cu")
		(net "UART_RI_P4_N")
	)
	(segment
		(start 104.22001 -175.5648)
		(end 105.951528 -175.5648)
		(width 0.1143)
		(layer "In2.Cu")
		(net "UART_RI_P4_N")
	)
	(segment
		(start 141.65834 -165.114478)
		(end 141.91615 -164.856668)
		(width 0.1143)
		(layer "In2.Cu")
		(net "UART_RI_P4_N")
	)
	(segment
		(start 132.4102 -45.267118)
		(end 132.416804 -45.260514)
		(width 0.1143)
		(layer "In2.Cu")
		(net "UART_RI_P4_N")
	)
	(segment
		(start 171.641262 -158.924244)
		(end 176.205134 -158.924244)
		(width 0.1143)
		(layer "In2.Cu")
		(net "UART_RI_P4_N")
	)
	(segment
		(start 132.416804 -45.260514)
		(end 132.41782 -45.260514)
		(width 0.1143)
		(layer "In2.Cu")
		(net "UART_RI_P4_N")
	)
	(segment
		(start 187.6298 -147.499578)
		(end 187.6298 -142.824708)
		(width 0.1143)
		(layer "In2.Cu")
		(net "UART_RI_P4_N")
	)
	(segment
		(start 135.514334 -173.238668)
		(end 135.01243 -172.736764)
		(width 0.1143)
		(layer "In2.Cu")
		(net "UART_RI_P4_N")
	)
	(segment
		(start 99.24288 -175.628046)
		(end 99.338638 -175.532034)
		(width 0.1143)
		(layer "In2.Cu")
		(net "UART_RI_P4_N")
	)
	(segment
		(start 149.52091 -163.49726)
		(end 155.1432 -163.49726)
		(width 0.1143)
		(layer "In2.Cu")
		(net "UART_RI_P4_N")
	)
	(segment
		(start 132.41782 -45.258736)
		(end 132.41528 -45.258736)
		(width 0.1143)
		(layer "In2.Cu")
		(net "UART_RI_P4_N")
	)
	(segment
		(start 110.0709 -174.975774)
		(end 110.667292 -175.572166)
		(width 0.1143)
		(layer "In2.Cu")
		(net "UART_RI_P4_N")
	)
	(segment
		(start 129.65049 -54.742842)
		(end 131.392422 -53.00091)
		(width 0.1143)
		(layer "In2.Cu")
		(net "UART_RI_P4_N")
	)
	(segment
		(start 99.338638 -175.532034)
		(end 101.15931 -175.532034)
		(width 0.1143)
		(layer "In2.Cu")
		(net "UART_RI_P4_N")
	)
	(segment
		(start 138.176 -43.7388)
		(end 138.176 -45.9232)
		(width 0.1016)
		(layer "F.Cu")
		(net "UART_RI_P3_N")
	)
	(segment
		(start 130.9624 -43.1546)
		(end 131.7244 -42.3926)
		(width 0.1016)
		(layer "F.Cu")
		(net "UART_RI_P3_N")
	)
	(segment
		(start 138.176 -45.9232)
		(end 137.761726 -46.337474)
		(width 0.1016)
		(layer "F.Cu")
		(net "UART_RI_P3_N")
	)
	(segment
		(start 136.8298 -42.3926)
		(end 138.176 -43.7388)
		(width 0.1016)
		(layer "F.Cu")
		(net "UART_RI_P3_N")
	)
	(segment
		(start 137.761726 -46.337474)
		(end 137.761726 -47.199804)
		(width 0.1016)
		(layer "F.Cu")
		(net "UART_RI_P3_N")
	)
	(segment
		(start 130.9624 -43.8912)
		(end 130.9624 -43.1546)
		(width 0.1016)
		(layer "F.Cu")
		(net "UART_RI_P3_N")
	)
	(segment
		(start 131.7244 -42.3926)
		(end 136.8298 -42.3926)
		(width 0.1016)
		(layer "F.Cu")
		(net "UART_RI_P3_N")
	)
	(via
		(at 128.255014 -57.876186)
		(size 0.508)
		(drill 0.254)
		(layers "F.Cu" "B.Cu")
		(net "UART_RI_P3_N")
	)
	(via
		(at 130.9624 -43.8912)
		(size 0.508)
		(drill 0.254)
		(layers "F.Cu" "B.Cu")
		(net "UART_RI_P3_N")
	)
	(segment
		(start 128.255014 -57.876186)
		(end 124.1044 -53.725572)
		(width 0.1016)
		(layer "B.Cu")
		(net "UART_RI_P3_N")
	)
	(segment
		(start 124.1044 -52.451)
		(end 124.6124 -51.943)
		(width 0.1016)
		(layer "B.Cu")
		(net "UART_RI_P3_N")
	)
	(segment
		(start 124.6124 -51.943)
		(end 125.984 -51.943)
		(width 0.1016)
		(layer "B.Cu")
		(net "UART_RI_P3_N")
	)
	(segment
		(start 125.984 -51.943)
		(end 126.6698 -51.2572)
		(width 0.1016)
		(layer "B.Cu")
		(net "UART_RI_P3_N")
	)
	(segment
		(start 124.1044 -53.725572)
		(end 124.1044 -52.451)
		(width 0.1016)
		(layer "B.Cu")
		(net "UART_RI_P3_N")
	)
	(segment
		(start 128.524 -59.03595)
		(end 128.524 -58.145172)
		(width 0.1016)
		(layer "B.Cu")
		(net "UART_RI_P3_N")
	)
	(segment
		(start 128.524 -58.145172)
		(end 128.255014 -57.876186)
		(width 0.1016)
		(layer "B.Cu")
		(net "UART_RI_P3_N")
	)
	(segment
		(start 127.508 -59.03595)
		(end 128.524 -59.03595)
		(width 0.1016)
		(layer "B.Cu")
		(net "UART_RI_P3_N")
	)
	(segment
		(start 128.255014 -56.207406)
		(end 128.255014 -57.876186)
		(width 0.1016)
		(layer "B.Cu")
		(net "UART_RI_P3_N")
	)
	(segment
		(start 126.6698 -51.2572)
		(end 128.1557 -51.2572)
		(width 0.1016)
		(layer "B.Cu")
		(net "UART_RI_P3_N")
	)
	(segment
		(start 129.921 -49.1998)
		(end 129.3114 -49.8094)
		(width 0.1143)
		(layer "In2.Cu")
		(net "UART_RI_P3_N")
	)
	(segment
		(start 131.699 -46.609)
		(end 129.921 -48.387)
		(width 0.1143)
		(layer "In2.Cu")
		(net "UART_RI_P3_N")
	)
	(segment
		(start 130.9624 -43.8912)
		(end 131.699 -44.6278)
		(width 0.1143)
		(layer "In2.Cu")
		(net "UART_RI_P3_N")
	)
	(segment
		(start 129.3114 -51.2318)
		(end 128.016 -52.5272)
		(width 0.1143)
		(layer "In2.Cu")
		(net "UART_RI_P3_N")
	)
	(segment
		(start 129.3114 -49.8094)
		(end 129.3114 -51.2318)
		(width 0.1143)
		(layer "In2.Cu")
		(net "UART_RI_P3_N")
	)
	(segment
		(start 128.016 -57.637172)
		(end 128.255014 -57.876186)
		(width 0.1143)
		(layer "In2.Cu")
		(net "UART_RI_P3_N")
	)
	(segment
		(start 129.921 -48.387)
		(end 129.921 -49.1998)
		(width 0.1143)
		(layer "In2.Cu")
		(net "UART_RI_P3_N")
	)
	(segment
		(start 131.699 -44.6278)
		(end 131.699 -46.609)
		(width 0.1143)
		(layer "In2.Cu")
		(net "UART_RI_P3_N")
	)
	(segment
		(start 128.016 -52.5272)
		(end 128.016 -57.637172)
		(width 0.1143)
		(layer "In2.Cu")
		(net "UART_RI_P3_N")
	)
	(via
		(at 160.66262 -182.064152)
		(size 0.6604)
		(drill 0.3302)
		(layers "F.Cu" "B.Cu")
		(net "CPLD_UART_DTR_P4_R_N")
	)
	(segment
		(start 160.82518 -179.246784)
		(end 160.82518 -181.901592)
		(width 0.1016)
		(layer "B.Cu")
		(net "CPLD_UART_DTR_P4_R_N")
	)
	(segment
		(start 159.375602 -178.7525)
		(end 160.330896 -178.7525)
		(width 0.1016)
		(layer "B.Cu")
		(net "CPLD_UART_DTR_P4_R_N")
	)
	(segment
		(start 160.330896 -178.7525)
		(end 160.82518 -179.246784)
		(width 0.1016)
		(layer "B.Cu")
		(net "CPLD_UART_DTR_P4_R_N")
	)
	(segment
		(start 159.726884 -181.595268)
		(end 160.195768 -182.064152)
		(width 0.1016)
		(layer "B.Cu")
		(net "CPLD_UART_DTR_P4_R_N")
	)
	(segment
		(start 160.82518 -181.901592)
		(end 160.66262 -182.064152)
		(width 0.1016)
		(layer "B.Cu")
		(net "CPLD_UART_DTR_P4_R_N")
	)
	(segment
		(start 159.501078 -181.595268)
		(end 159.726884 -181.595268)
		(width 0.1016)
		(layer "B.Cu")
		(net "CPLD_UART_DTR_P4_R_N")
	)
	(segment
		(start 160.195768 -182.064152)
		(end 160.66262 -182.064152)
		(width 0.1016)
		(layer "B.Cu")
		(net "CPLD_UART_DTR_P4_R_N")
	)
	(via
		(at 157.04058 -181.189376)
		(size 0.6604)
		(drill 0.3302)
		(layers "F.Cu" "B.Cu")
		(net "CPLD_UART_RTS_P4_R_N")
	)
	(segment
		(start 157.36062 -181.788308)
		(end 157.04058 -181.468268)
		(width 0.1016)
		(layer "B.Cu")
		(net "CPLD_UART_RTS_P4_R_N")
	)
	(segment
		(start 158.485078 -181.595268)
		(end 158.2674 -181.595268)
		(width 0.1016)
		(layer "B.Cu")
		(net "CPLD_UART_RTS_P4_R_N")
	)
	(segment
		(start 158.2674 -181.595268)
		(end 158.07436 -181.788308)
		(width 0.1016)
		(layer "B.Cu")
		(net "CPLD_UART_RTS_P4_R_N")
	)
	(segment
		(start 159.375602 -180.052472)
		(end 158.626302 -180.052472)
		(width 0.1016)
		(layer "B.Cu")
		(net "CPLD_UART_RTS_P4_R_N")
	)
	(segment
		(start 157.977332 -180.701442)
		(end 157.528514 -180.701442)
		(width 0.1016)
		(layer "B.Cu")
		(net "CPLD_UART_RTS_P4_R_N")
	)
	(segment
		(start 157.04058 -181.468268)
		(end 157.04058 -181.189376)
		(width 0.1016)
		(layer "B.Cu")
		(net "CPLD_UART_RTS_P4_R_N")
	)
	(segment
		(start 158.626302 -180.052472)
		(end 157.977332 -180.701442)
		(width 0.1016)
		(layer "B.Cu")
		(net "CPLD_UART_RTS_P4_R_N")
	)
	(segment
		(start 157.528514 -180.701442)
		(end 157.04058 -181.189376)
		(width 0.1016)
		(layer "B.Cu")
		(net "CPLD_UART_RTS_P4_R_N")
	)
	(segment
		(start 158.07436 -181.788308)
		(end 157.36062 -181.788308)
		(width 0.1016)
		(layer "B.Cu")
		(net "CPLD_UART_RTS_P4_R_N")
	)
	(via
		(at 163.50996 -181.865016)
		(size 0.6604)
		(drill 0.3302)
		(layers "F.Cu" "B.Cu")
		(net "CPLD_UART_RX_P4_R")
	)
	(segment
		(start 163.49472 -181.849776)
		(end 163.50996 -181.865016)
		(width 0.1016)
		(layer "B.Cu")
		(net "CPLD_UART_RX_P4_R")
	)
	(segment
		(start 165.217602 -177.452528)
		(end 164.355018 -177.452528)
		(width 0.1016)
		(layer "B.Cu")
		(net "CPLD_UART_RX_P4_R")
	)
	(segment
		(start 164.611558 -183.051196)
		(end 164.611558 -182.836566)
		(width 0.1016)
		(layer "B.Cu")
		(net "CPLD_UART_RX_P4_R")
	)
	(segment
		(start 163.640008 -181.865016)
		(end 163.50996 -181.865016)
		(width 0.1016)
		(layer "B.Cu")
		(net "CPLD_UART_RX_P4_R")
	)
	(segment
		(start 164.355018 -177.452528)
		(end 163.49472 -178.312826)
		(width 0.1016)
		(layer "B.Cu")
		(net "CPLD_UART_RX_P4_R")
	)
	(segment
		(start 163.49472 -178.312826)
		(end 163.49472 -181.849776)
		(width 0.1016)
		(layer "B.Cu")
		(net "CPLD_UART_RX_P4_R")
	)
	(segment
		(start 164.611558 -182.836566)
		(end 163.640008 -181.865016)
		(width 0.1016)
		(layer "B.Cu")
		(net "CPLD_UART_RX_P4_R")
	)
	(segment
		(start 144.013936 -35.38982)
		(end 143.344646 -34.72053)
		(width 0.1016)
		(layer "F.Cu")
		(net "SIO_CPLD_RSV3_R")
	)
	(segment
		(start 140.891006 -34.72053)
		(end 139.852146 -33.68167)
		(width 0.1016)
		(layer "F.Cu")
		(net "SIO_CPLD_RSV3_R")
	)
	(segment
		(start 143.344646 -34.72053)
		(end 140.891006 -34.72053)
		(width 0.1016)
		(layer "F.Cu")
		(net "SIO_CPLD_RSV3_R")
	)
	(segment
		(start 145.571718 -35.38982)
		(end 144.013936 -35.38982)
		(width 0.1016)
		(layer "F.Cu")
		(net "SIO_CPLD_RSV3_R")
	)
	(segment
		(start 139.852146 -33.68167)
		(end 139.852146 -33.679384)
		(width 0.1016)
		(layer "F.Cu")
		(net "SIO_CPLD_RSV3_R")
	)
	(via
		(at 139.852146 -33.679384)
		(size 0.508)
		(drill 0.254)
		(layers "F.Cu" "B.Cu")
		(net "SIO_CPLD_RSV3_R")
	)
	(segment
		(start 137.901426 -33.679384)
		(end 137.569956 -34.010854)
		(width 0.1016)
		(layer "B.Cu")
		(net "SIO_CPLD_RSV3_R")
	)
	(segment
		(start 142.280386 -34.646616)
		(end 141.313154 -33.679384)
		(width 0.1016)
		(layer "B.Cu")
		(net "SIO_CPLD_RSV3_R")
	)
	(segment
		(start 136.656826 -34.39541)
		(end 136.5885 -34.327084)
		(width 0.1016)
		(layer "B.Cu")
		(net "SIO_CPLD_RSV3_R")
	)
	(segment
		(start 144.508982 -34.646616)
		(end 142.280386 -34.646616)
		(width 0.1016)
		(layer "B.Cu")
		(net "SIO_CPLD_RSV3_R")
	)
	(segment
		(start 137.569956 -34.39541)
		(end 136.656826 -34.39541)
		(width 0.1016)
		(layer "B.Cu")
		(net "SIO_CPLD_RSV3_R")
	)
	(segment
		(start 139.852146 -33.679384)
		(end 137.901426 -33.679384)
		(width 0.1016)
		(layer "B.Cu")
		(net "SIO_CPLD_RSV3_R")
	)
	(segment
		(start 141.313154 -33.679384)
		(end 139.852146 -33.679384)
		(width 0.1016)
		(layer "B.Cu")
		(net "SIO_CPLD_RSV3_R")
	)
	(segment
		(start 136.5885 -34.327084)
		(end 135.596884 -34.327084)
		(width 0.1016)
		(layer "B.Cu")
		(net "SIO_CPLD_RSV3_R")
	)
	(segment
		(start 137.569956 -34.010854)
		(end 137.569956 -34.39541)
		(width 0.1016)
		(layer "B.Cu")
		(net "SIO_CPLD_RSV3_R")
	)
	(segment
		(start 143.304514 -35.186112)
		(end 140.251942 -35.186112)
		(width 0.1016)
		(layer "F.Cu")
		(net "SIO_CPLD_RSV2_R")
	)
	(segment
		(start 144.008094 -35.889692)
		(end 143.304514 -35.186112)
		(width 0.1016)
		(layer "F.Cu")
		(net "SIO_CPLD_RSV2_R")
	)
	(segment
		(start 145.571718 -35.889692)
		(end 144.008094 -35.889692)
		(width 0.1016)
		(layer "F.Cu")
		(net "SIO_CPLD_RSV2_R")
	)
	(via
		(at 140.251942 -35.186112)
		(size 0.508)
		(drill 0.254)
		(layers "F.Cu" "B.Cu")
		(net "SIO_CPLD_RSV2_R")
	)
	(segment
		(start 144.508982 -35.662616)
		(end 144.2593 -35.412934)
		(width 0.1016)
		(layer "B.Cu")
		(net "SIO_CPLD_RSV2_R")
	)
	(segment
		(start 137.978896 -35.948874)
		(end 139.48918 -35.948874)
		(width 0.1016)
		(layer "B.Cu")
		(net "SIO_CPLD_RSV2_R")
	)
	(segment
		(start 137.569956 -35.41141)
		(end 137.569956 -35.539934)
		(width 0.1016)
		(layer "B.Cu")
		(net "SIO_CPLD_RSV2_R")
	)
	(segment
		(start 135.596884 -35.343084)
		(end 137.524236 -35.36569)
		(width 0.1016)
		(layer "B.Cu")
		(net "SIO_CPLD_RSV2_R")
	)
	(segment
		(start 144.2593 -35.412934)
		(end 140.478764 -35.412934)
		(width 0.1016)
		(layer "B.Cu")
		(net "SIO_CPLD_RSV2_R")
	)
	(segment
		(start 137.524236 -35.36569)
		(end 137.569956 -35.41141)
		(width 0.1016)
		(layer "B.Cu")
		(net "SIO_CPLD_RSV2_R")
	)
	(segment
		(start 137.569956 -35.539934)
		(end 137.978896 -35.948874)
		(width 0.1016)
		(layer "B.Cu")
		(net "SIO_CPLD_RSV2_R")
	)
	(segment
		(start 139.48918 -35.948874)
		(end 140.251942 -35.186112)
		(width 0.1016)
		(layer "B.Cu")
		(net "SIO_CPLD_RSV2_R")
	)
	(segment
		(start 140.478764 -35.412934)
		(end 140.251942 -35.186112)
		(width 0.1016)
		(layer "B.Cu")
		(net "SIO_CPLD_RSV2_R")
	)
	(segment
		(start 143.285464 -35.765994)
		(end 143.909288 -36.389818)
		(width 0.1016)
		(layer "F.Cu")
		(net "SIO_CPLD_RSV1_R")
	)
	(segment
		(start 140.071856 -36.540948)
		(end 140.257784 -36.540948)
		(width 0.1016)
		(layer "F.Cu")
		(net "SIO_CPLD_RSV1_R")
	)
	(segment
		(start 141.032738 -35.765994)
		(end 143.285464 -35.765994)
		(width 0.1016)
		(layer "F.Cu")
		(net "SIO_CPLD_RSV1_R")
	)
	(segment
		(start 140.257784 -36.540948)
		(end 141.032738 -35.765994)
		(width 0.1016)
		(layer "F.Cu")
		(net "SIO_CPLD_RSV1_R")
	)
	(segment
		(start 143.909288 -36.389818)
		(end 145.571718 -36.389818)
		(width 0.1016)
		(layer "F.Cu")
		(net "SIO_CPLD_RSV1_R")
	)
	(via
		(at 140.071856 -36.540948)
		(size 0.508)
		(drill 0.254)
		(layers "F.Cu" "B.Cu")
		(net "SIO_CPLD_RSV1_R")
	)
	(segment
		(start 137.50163 -36.359084)
		(end 137.569956 -36.42741)
		(width 0.1016)
		(layer "B.Cu")
		(net "SIO_CPLD_RSV1_R")
	)
	(segment
		(start 140.071856 -36.540948)
		(end 139.74191 -36.870894)
		(width 0.1016)
		(layer "B.Cu")
		(net "SIO_CPLD_RSV1_R")
	)
	(segment
		(start 137.569956 -36.596828)
		(end 137.569956 -36.42741)
		(width 0.1016)
		(layer "B.Cu")
		(net "SIO_CPLD_RSV1_R")
	)
	(segment
		(start 141.164818 -35.674554)
		(end 140.298424 -36.540948)
		(width 0.1016)
		(layer "B.Cu")
		(net "SIO_CPLD_RSV1_R")
	)
	(segment
		(start 139.74191 -36.870894)
		(end 137.844022 -36.870894)
		(width 0.1016)
		(layer "B.Cu")
		(net "SIO_CPLD_RSV1_R")
	)
	(segment
		(start 143.50492 -35.674554)
		(end 141.164818 -35.674554)
		(width 0.1016)
		(layer "B.Cu")
		(net "SIO_CPLD_RSV1_R")
	)
	(segment
		(start 135.596884 -36.359084)
		(end 137.50163 -36.359084)
		(width 0.1016)
		(layer "B.Cu")
		(net "SIO_CPLD_RSV1_R")
	)
	(segment
		(start 144.508982 -36.678616)
		(end 143.50492 -35.674554)
		(width 0.1016)
		(layer "B.Cu")
		(net "SIO_CPLD_RSV1_R")
	)
	(segment
		(start 137.844022 -36.870894)
		(end 137.569956 -36.596828)
		(width 0.1016)
		(layer "B.Cu")
		(net "SIO_CPLD_RSV1_R")
	)
	(segment
		(start 140.298424 -36.540948)
		(end 140.071856 -36.540948)
		(width 0.1016)
		(layer "B.Cu")
		(net "SIO_CPLD_RSV1_R")
	)
	(segment
		(start 159.375602 -177.452528)
		(end 158.195772 -177.452528)
		(width 0.1016)
		(layer "F.Cu")
		(net "CPLD_UART_RX_P3_R")
	)
	(segment
		(start 155.999688 -178.289204)
		(end 156.549344 -178.289204)
		(width 0.1016)
		(layer "F.Cu")
		(net "CPLD_UART_RX_P3_R")
	)
	(segment
		(start 156.549344 -178.289204)
		(end 156.95422 -178.69408)
		(width 0.1016)
		(layer "F.Cu")
		(net "CPLD_UART_RX_P3_R")
	)
	(segment
		(start 158.195772 -177.452528)
		(end 156.95422 -178.69408)
		(width 0.1016)
		(layer "F.Cu")
		(net "CPLD_UART_RX_P3_R")
	)
	(via
		(at 156.95422 -178.69408)
		(size 0.508)
		(drill 0.254)
		(layers "F.Cu" "B.Cu")
		(net "CPLD_UART_RX_P3_R")
	)
	(segment
		(start 163.626038 -184.067196)
		(end 163.47694 -183.918098)
		(width 0.1016)
		(layer "F.Cu")
		(net "CPLD_UART_DTR_P3_R_N")
	)
	(segment
		(start 163.22294 -179.946808)
		(end 163.22294 -183.664098)
		(width 0.1016)
		(layer "F.Cu")
		(net "CPLD_UART_DTR_P3_R_N")
	)
	(segment
		(start 163.22294 -183.664098)
		(end 163.47694 -183.918098)
		(width 0.1016)
		(layer "F.Cu")
		(net "CPLD_UART_DTR_P3_R_N")
	)
	(segment
		(start 164.417248 -178.7525)
		(end 163.22294 -179.946808)
		(width 0.1016)
		(layer "F.Cu")
		(net "CPLD_UART_DTR_P3_R_N")
	)
	(segment
		(start 165.217602 -178.7525)
		(end 164.417248 -178.7525)
		(width 0.1016)
		(layer "F.Cu")
		(net "CPLD_UART_DTR_P3_R_N")
	)
	(segment
		(start 164.611304 -184.067196)
		(end 163.626038 -184.067196)
		(width 0.1016)
		(layer "F.Cu")
		(net "CPLD_UART_DTR_P3_R_N")
	)
	(via
		(at 163.47694 -183.918098)
		(size 0.762)
		(drill 0.381)
		(layers "F.Cu" "B.Cu")
		(net "CPLD_UART_DTR_P3_R_N")
	)
	(segment
		(start 167.393366 -180.198268)
		(end 167.393366 -180.352192)
		(width 0.1016)
		(layer "F.Cu")
		(net "CPLD_UART_RTS_P3_R_N")
	)
	(segment
		(start 165.217602 -180.052472)
		(end 167.24757 -180.052472)
		(width 0.1016)
		(layer "F.Cu")
		(net "CPLD_UART_RTS_P3_R_N")
	)
	(segment
		(start 165.25748 -181.38902)
		(end 165.25748 -181.04485)
		(width 0.1016)
		(layer "F.Cu")
		(net "CPLD_UART_RTS_P3_R_N")
	)
	(segment
		(start 165.25748 -181.04485)
		(end 165.660832 -180.641498)
		(width 0.1016)
		(layer "F.Cu")
		(net "CPLD_UART_RTS_P3_R_N")
	)
	(segment
		(start 164.611304 -182.035196)
		(end 165.25748 -181.38902)
		(width 0.1016)
		(layer "F.Cu")
		(net "CPLD_UART_RTS_P3_R_N")
	)
	(segment
		(start 165.660832 -180.641498)
		(end 167.207946 -180.641498)
		(width 0.1016)
		(layer "F.Cu")
		(net "CPLD_UART_RTS_P3_R_N")
	)
	(segment
		(start 167.24757 -180.052472)
		(end 167.393366 -180.198268)
		(width 0.1016)
		(layer "F.Cu")
		(net "CPLD_UART_RTS_P3_R_N")
	)
	(segment
		(start 167.393366 -180.456078)
		(end 167.393366 -180.352192)
		(width 0.1016)
		(layer "F.Cu")
		(net "CPLD_UART_RTS_P3_R_N")
	)
	(segment
		(start 167.207946 -180.641498)
		(end 167.393366 -180.456078)
		(width 0.1016)
		(layer "F.Cu")
		(net "CPLD_UART_RTS_P3_R_N")
	)
	(via
		(at 167.393366 -180.352192)
		(size 0.762)
		(drill 0.381)
		(layers "F.Cu" "B.Cu")
		(net "CPLD_UART_RTS_P3_R_N")
	)
	(segment
		(start 132.616194 -28.78074)
		(end 132.61594 -28.78074)
		(width 0.1016)
		(layer "F.Cu")
		(net "SIO_PIN81")
	)
	(segment
		(start 132.761736 -30.079696)
		(end 132.761736 -28.926282)
		(width 0.1016)
		(layer "F.Cu")
		(net "SIO_PIN81")
	)
	(segment
		(start 132.61594 -28.78074)
		(end 132.61594 -27.476704)
		(width 0.1016)
		(layer "F.Cu")
		(net "SIO_PIN81")
	)
	(segment
		(start 132.61594 -27.476704)
		(end 132.32257 -27.183334)
		(width 0.1016)
		(layer "F.Cu")
		(net "SIO_PIN81")
	)
	(segment
		(start 132.761736 -28.926282)
		(end 132.616194 -28.78074)
		(width 0.1016)
		(layer "F.Cu")
		(net "SIO_PIN81")
	)
	(segment
		(start 132.32257 -27.183334)
		(end 132.32257 -26.969466)
		(width 0.1016)
		(layer "F.Cu")
		(net "SIO_PIN81")
	)
	(via
		(at 132.616194 -28.78074)
		(size 0.508)
		(drill 0.254)
		(layers "F.Cu" "B.Cu")
		(net "SIO_PIN81")
	)
	(segment
		(start 133.33857 -27.034236)
		(end 133.81609 -27.511756)
		(width 0.1016)
		(layer "F.Cu")
		(net "SIO_PIN82")
	)
	(segment
		(start 133.33857 -26.969466)
		(end 133.33857 -27.034236)
		(width 0.1016)
		(layer "F.Cu")
		(net "SIO_PIN82")
	)
	(segment
		(start 133.261608 -30.079696)
		(end 133.261608 -28.066238)
		(width 0.1016)
		(layer "F.Cu")
		(net "SIO_PIN82")
	)
	(segment
		(start 133.261608 -28.066238)
		(end 133.81609 -27.511756)
		(width 0.1016)
		(layer "F.Cu")
		(net "SIO_PIN82")
	)
	(via
		(at 133.81609 -27.511756)
		(size 0.508)
		(drill 0.254)
		(layers "F.Cu" "B.Cu")
		(net "SIO_PIN82")
	)
	(segment
		(start 134.3533 -26.970736)
		(end 134.3533 -27.968702)
		(width 0.1016)
		(layer "F.Cu")
		(net "SIO_PIN83")
	)
	(segment
		(start 133.761734 -29.04871)
		(end 134.013702 -28.796742)
		(width 0.1016)
		(layer "F.Cu")
		(net "SIO_PIN83")
	)
	(segment
		(start 134.35457 -26.969466)
		(end 134.3533 -26.970736)
		(width 0.1016)
		(layer "F.Cu")
		(net "SIO_PIN83")
	)
	(segment
		(start 133.761734 -30.079696)
		(end 133.761734 -29.04871)
		(width 0.1016)
		(layer "F.Cu")
		(net "SIO_PIN83")
	)
	(segment
		(start 134.3533 -27.968702)
		(end 134.013702 -28.3083)
		(width 0.1016)
		(layer "F.Cu")
		(net "SIO_PIN83")
	)
	(segment
		(start 134.013702 -28.3083)
		(end 134.013702 -28.796742)
		(width 0.1016)
		(layer "F.Cu")
		(net "SIO_PIN83")
	)
	(via
		(at 134.013702 -28.796742)
		(size 0.508)
		(drill 0.254)
		(layers "F.Cu" "B.Cu")
		(net "SIO_PIN83")
	)
	(segment
		(start 131.98348 -27.569922)
		(end 131.56057 -27.569922)
		(width 0.1016)
		(layer "F.Cu")
		(net "SIO_PIN80")
	)
	(segment
		(start 131.30657 -27.315922)
		(end 131.30657 -26.969466)
		(width 0.1016)
		(layer "F.Cu")
		(net "SIO_PIN80")
	)
	(segment
		(start 131.56057 -27.569922)
		(end 131.30657 -27.315922)
		(width 0.1016)
		(layer "F.Cu")
		(net "SIO_PIN80")
	)
	(segment
		(start 132.26161 -29.13507)
		(end 132.26161 -30.079696)
		(width 0.1016)
		(layer "F.Cu")
		(net "SIO_PIN80")
	)
	(segment
		(start 131.98475 -27.569922)
		(end 131.98348 -27.569922)
		(width 0.1016)
		(layer "F.Cu")
		(net "SIO_PIN80")
	)
	(segment
		(start 131.98348 -27.569922)
		(end 131.98348 -28.85694)
		(width 0.1016)
		(layer "F.Cu")
		(net "SIO_PIN80")
	)
	(segment
		(start 131.98348 -28.85694)
		(end 132.26161 -29.13507)
		(width 0.1016)
		(layer "F.Cu")
		(net "SIO_PIN80")
	)
	(via
		(at 131.98475 -27.569922)
		(size 0.508)
		(drill 0.254)
		(layers "F.Cu" "B.Cu")
		(net "SIO_PIN80")
	)
	(segment
		(start 132.26161 -49.246536)
		(end 132.08381 -49.424336)
		(width 0.1016)
		(layer "F.Cu")
		(net "UART_DTR_P4_R_N")
	)
	(segment
		(start 132.26161 -47.199804)
		(end 132.26161 -49.246536)
		(width 0.1016)
		(layer "F.Cu")
		(net "UART_DTR_P4_R_N")
	)
	(segment
		(start 132.207 -50.48758)
		(end 132.08381 -50.36439)
		(width 0.1016)
		(layer "F.Cu")
		(net "UART_DTR_P4_R_N")
	)
	(segment
		(start 132.207 -51.03495)
		(end 132.207 -50.48758)
		(width 0.1016)
		(layer "F.Cu")
		(net "UART_DTR_P4_R_N")
	)
	(segment
		(start 132.08381 -50.36439)
		(end 132.08381 -49.424336)
		(width 0.1016)
		(layer "F.Cu")
		(net "UART_DTR_P4_R_N")
	)
	(via
		(at 132.08381 -49.424336)
		(size 0.508)
		(drill 0.254)
		(layers "F.Cu" "B.Cu")
		(net "UART_DTR_P4_R_N")
	)
	(segment
		(start 129.1082 -48.9458)
		(end 129.1082 -50.47615)
		(width 0.1016)
		(layer "F.Cu")
		(net "UART_TX_P4_R")
	)
	(segment
		(start 129.7432 -48.3108)
		(end 129.761742 -48.3108)
		(width 0.1016)
		(layer "F.Cu")
		(net "UART_TX_P4_R")
	)
	(segment
		(start 129.761742 -48.3108)
		(end 129.761742 -47.199804)
		(width 0.1016)
		(layer "F.Cu")
		(net "UART_TX_P4_R")
	)
	(segment
		(start 129.3114 -48.7426)
		(end 129.7432 -48.3108)
		(width 0.1016)
		(layer "F.Cu")
		(net "UART_TX_P4_R")
	)
	(segment
		(start 129.3114 -48.7426)
		(end 129.1082 -48.9458)
		(width 0.1016)
		(layer "F.Cu")
		(net "UART_TX_P4_R")
	)
	(via
		(at 129.3114 -48.7426)
		(size 0.508)
		(drill 0.254)
		(layers "F.Cu" "B.Cu")
		(net "UART_TX_P4_R")
	)
	(segment
		(start 130.76174 -47.199804)
		(end 130.76174 -48.491902)
		(width 0.1016)
		(layer "F.Cu")
		(net "UART_RTS_P4_R_N")
	)
	(segment
		(start 131.230878 -51.05146)
		(end 131.230878 -48.955198)
		(width 0.1016)
		(layer "F.Cu")
		(net "UART_RTS_P4_R_N")
	)
	(segment
		(start 130.76174 -48.491902)
		(end 130.868674 -48.598836)
		(width 0.1016)
		(layer "F.Cu")
		(net "UART_RTS_P4_R_N")
	)
	(segment
		(start 131.230878 -48.955198)
		(end 130.874516 -48.598836)
		(width 0.1016)
		(layer "F.Cu")
		(net "UART_RTS_P4_R_N")
	)
	(segment
		(start 130.874516 -48.598836)
		(end 130.868674 -48.598836)
		(width 0.1016)
		(layer "F.Cu")
		(net "UART_RTS_P4_R_N")
	)
	(via
		(at 130.868674 -48.598836)
		(size 0.508)
		(drill 0.254)
		(layers "F.Cu" "B.Cu")
		(net "UART_RTS_P4_R_N")
	)
	(segment
		(start 136.525762 -163.358576)
		(end 136.525762 -166.256208)
		(width 0.1016)
		(layer "F.Cu")
		(net "CMC_CPU_RST_N")
	)
	(segment
		(start 136.525762 -166.256208)
		(end 136.285478 -166.496492)
		(width 0.1016)
		(layer "F.Cu")
		(net "CMC_CPU_RST_N")
	)
	(segment
		(start 118.64594 -165.47465)
		(end 118.99392 -165.12667)
		(width 0.1016)
		(layer "F.Cu")
		(net "CMC_CPU_RST_N")
	)
	(segment
		(start 119.301514 -163.656518)
		(end 120.60936 -163.656518)
		(width 0.1016)
		(layer "F.Cu")
		(net "CMC_CPU_RST_N")
	)
	(segment
		(start 119.00916 -166.572946)
		(end 118.64594 -166.209726)
		(width 0.1016)
		(layer "F.Cu")
		(net "CMC_CPU_RST_N")
	)
	(segment
		(start 118.64594 -166.209726)
		(end 118.64594 -165.47465)
		(width 0.1016)
		(layer "F.Cu")
		(net "CMC_CPU_RST_N")
	)
	(segment
		(start 118.99392 -165.12667)
		(end 118.99392 -163.964112)
		(width 0.1016)
		(layer "F.Cu")
		(net "CMC_CPU_RST_N")
	)
	(segment
		(start 118.99392 -163.964112)
		(end 119.301514 -163.656518)
		(width 0.1016)
		(layer "F.Cu")
		(net "CMC_CPU_RST_N")
	)
	(via
		(at 136.285478 -166.496492)
		(size 0.508)
		(drill 0.254)
		(layers "F.Cu" "B.Cu")
		(net "CMC_CPU_RST_N")
	)
	(via
		(at 119.00916 -166.572946)
		(size 0.508)
		(drill 0.254)
		(layers "F.Cu" "B.Cu")
		(net "CMC_CPU_RST_N")
	)
	(segment
		(start 135.839454 -166.942516)
		(end 136.285478 -166.496492)
		(width 0.1143)
		(layer "In6.Cu")
		(net "CMC_CPU_RST_N")
	)
	(segment
		(start 119.07266 -166.636446)
		(end 121.924318 -166.636446)
		(width 0.1143)
		(layer "In6.Cu")
		(net "CMC_CPU_RST_N")
	)
	(segment
		(start 127.488696 -165.784276)
		(end 129.953766 -165.784276)
		(width 0.1143)
		(layer "In6.Cu")
		(net "CMC_CPU_RST_N")
	)
	(segment
		(start 129.953766 -165.784276)
		(end 131.112006 -166.942516)
		(width 0.1143)
		(layer "In6.Cu")
		(net "CMC_CPU_RST_N")
	)
	(segment
		(start 122.05462 -166.766748)
		(end 122.42038 -166.766748)
		(width 0.1143)
		(layer "In6.Cu")
		(net "CMC_CPU_RST_N")
	)
	(segment
		(start 122.550682 -166.636446)
		(end 126.636526 -166.636446)
		(width 0.1143)
		(layer "In6.Cu")
		(net "CMC_CPU_RST_N")
	)
	(segment
		(start 119.00916 -166.572946)
		(end 119.07266 -166.636446)
		(width 0.1143)
		(layer "In6.Cu")
		(net "CMC_CPU_RST_N")
	)
	(segment
		(start 122.42038 -166.766748)
		(end 122.550682 -166.636446)
		(width 0.1143)
		(layer "In6.Cu")
		(net "CMC_CPU_RST_N")
	)
	(segment
		(start 121.924318 -166.636446)
		(end 122.05462 -166.766748)
		(width 0.1143)
		(layer "In6.Cu")
		(net "CMC_CPU_RST_N")
	)
	(segment
		(start 126.636526 -166.636446)
		(end 127.488696 -165.784276)
		(width 0.1143)
		(layer "In6.Cu")
		(net "CMC_CPU_RST_N")
	)
	(segment
		(start 131.112006 -166.942516)
		(end 135.839454 -166.942516)
		(width 0.1143)
		(layer "In6.Cu")
		(net "CMC_CPU_RST_N")
	)
	(segment
		(start 131.261612 -28.893262)
		(end 131.101084 -28.732734)
		(width 0.1016)
		(layer "F.Cu")
		(net "SIO_PIN78")
	)
	(segment
		(start 130.851148 -28.482798)
		(end 131.101084 -28.732734)
		(width 0.1016)
		(layer "F.Cu")
		(net "SIO_PIN78")
	)
	(segment
		(start 130.851148 -27.268424)
		(end 130.851148 -28.482798)
		(width 0.1016)
		(layer "F.Cu")
		(net "SIO_PIN78")
	)
	(segment
		(start 130.29057 -26.969466)
		(end 130.55219 -26.969466)
		(width 0.1016)
		(layer "F.Cu")
		(net "SIO_PIN78")
	)
	(segment
		(start 131.261612 -30.079696)
		(end 131.261612 -28.893262)
		(width 0.1016)
		(layer "F.Cu")
		(net "SIO_PIN78")
	)
	(segment
		(start 130.55219 -26.969466)
		(end 130.851148 -27.268424)
		(width 0.1016)
		(layer "F.Cu")
		(net "SIO_PIN78")
	)
	(via
		(at 131.101084 -28.732734)
		(size 0.508)
		(drill 0.254)
		(layers "F.Cu" "B.Cu")
		(net "SIO_PIN78")
	)
	(segment
		(start 130.261614 -27.602688)
		(end 130.271012 -27.59329)
		(width 0.1016)
		(layer "F.Cu")
		(net "SIO_PIN76")
	)
	(segment
		(start 129.27457 -27.218386)
		(end 129.649474 -27.59329)
		(width 0.1016)
		(layer "F.Cu")
		(net "SIO_PIN76")
	)
	(segment
		(start 129.27457 -26.969466)
		(end 129.27457 -27.218386)
		(width 0.1016)
		(layer "F.Cu")
		(net "SIO_PIN76")
	)
	(segment
		(start 129.649474 -27.59329)
		(end 130.271012 -27.59329)
		(width 0.1016)
		(layer "F.Cu")
		(net "SIO_PIN76")
	)
	(segment
		(start 130.261614 -30.079696)
		(end 130.261614 -27.602688)
		(width 0.1016)
		(layer "F.Cu")
		(net "SIO_PIN76")
	)
	(via
		(at 130.271012 -27.59329)
		(size 0.508)
		(drill 0.254)
		(layers "F.Cu" "B.Cu")
		(net "SIO_PIN76")
	)
	(segment
		(start 128.25857 -26.969466)
		(end 128.25857 -27.483308)
		(width 0.1016)
		(layer "F.Cu")
		(net "SIO_PIN75")
	)
	(segment
		(start 129.761742 -30.079696)
		(end 129.761742 -28.98648)
		(width 0.1016)
		(layer "F.Cu")
		(net "SIO_PIN75")
	)
	(segment
		(start 129.761742 -28.98648)
		(end 129.461514 -28.686252)
		(width 0.1016)
		(layer "F.Cu")
		(net "SIO_PIN75")
	)
	(segment
		(start 128.25857 -27.483308)
		(end 129.461514 -28.686252)
		(width 0.1016)
		(layer "F.Cu")
		(net "SIO_PIN75")
	)
	(via
		(at 129.461514 -28.686252)
		(size 0.508)
		(drill 0.254)
		(layers "F.Cu" "B.Cu")
		(net "SIO_PIN75")
	)
	(segment
		(start 134.6708 -51.46675)
		(end 134.6708 -54.594252)
		(width 0.1016)
		(layer "F.Cu")
		(net "UART_TX_P3_R")
	)
	(segment
		(start 134.516368 -49.021746)
		(end 134.516368 -49.739296)
		(width 0.1016)
		(layer "F.Cu")
		(net "UART_TX_P3_R")
	)
	(segment
		(start 134.761732 -48.48987)
		(end 134.516368 -48.735234)
		(width 0.1016)
		(layer "F.Cu")
		(net "UART_TX_P3_R")
	)
	(segment
		(start 134.516368 -49.739296)
		(end 134.239 -50.016664)
		(width 0.1016)
		(layer "F.Cu")
		(net "UART_TX_P3_R")
	)
	(segment
		(start 136.125966 -54.924452)
		(end 135.109966 -54.924452)
		(width 0.1016)
		(layer "F.Cu")
		(net "UART_TX_P3_R")
	)
	(segment
		(start 134.516368 -48.735234)
		(end 134.516368 -49.021746)
		(width 0.1016)
		(layer "F.Cu")
		(net "UART_TX_P3_R")
	)
	(segment
		(start 134.239 -51.03495)
		(end 134.6708 -51.46675)
		(width 0.1016)
		(layer "F.Cu")
		(net "UART_TX_P3_R")
	)
	(segment
		(start 135.001 -54.924452)
		(end 135.109966 -54.924452)
		(width 0.1016)
		(layer "F.Cu")
		(net "UART_TX_P3_R")
	)
	(segment
		(start 134.239 -50.016664)
		(end 134.239 -51.03495)
		(width 0.1016)
		(layer "F.Cu")
		(net "UART_TX_P3_R")
	)
	(segment
		(start 134.6708 -54.594252)
		(end 135.001 -54.924452)
		(width 0.1016)
		(layer "F.Cu")
		(net "UART_TX_P3_R")
	)
	(segment
		(start 134.761732 -47.199804)
		(end 134.761732 -48.48987)
		(width 0.1016)
		(layer "F.Cu")
		(net "UART_TX_P3_R")
	)
	(via
		(at 134.516368 -49.021746)
		(size 0.508)
		(drill 0.254)
		(layers "F.Cu" "B.Cu")
		(net "UART_TX_P3_R")
	)
	(segment
		(start 139.895834 -85.4202)
		(end 138.117834 -83.6422)
		(width 0.1016)
		(layer "F.Cu")
		(net "CLK_48M_SIO")
	)
	(segment
		(start 139.895834 -96.855788)
		(end 139.895834 -85.4202)
		(width 0.1016)
		(layer "F.Cu")
		(net "CLK_48M_SIO")
	)
	(segment
		(start 118.097046 -38.251384)
		(end 117.31752 -38.251384)
		(width 0.1016)
		(layer "F.Cu")
		(net "CLK_48M_SIO")
	)
	(segment
		(start 130.81 -71.4248)
		(end 129.286 -69.9008)
		(width 0.1016)
		(layer "F.Cu")
		(net "CLK_48M_SIO")
	)
	(segment
		(start 113.96599 -53.16474)
		(end 111.96828 -51.16703)
		(width 0.1016)
		(layer "F.Cu")
		(net "CLK_48M_SIO")
	)
	(segment
		(start 113.96599 -55.618634)
		(end 113.96599 -53.16474)
		(width 0.1016)
		(layer "F.Cu")
		(net "CLK_48M_SIO")
	)
	(segment
		(start 112.933734 -38.227)
		(end 117.31752 -38.227)
		(width 0.1016)
		(layer "F.Cu")
		(net "CLK_48M_SIO")
	)
	(segment
		(start 145.14068 -102.100634)
		(end 139.895834 -96.855788)
		(width 0.1016)
		(layer "F.Cu")
		(net "CLK_48M_SIO")
	)
	(segment
		(start 112.38484 -38.775894)
		(end 112.933734 -38.227)
		(width 0.1016)
		(layer "F.Cu")
		(net "CLK_48M_SIO")
	)
	(segment
		(start 119.538242 -39.13759)
		(end 118.983252 -39.13759)
		(width 0.1016)
		(layer "F.Cu")
		(net "CLK_48M_SIO")
	)
	(segment
		(start 135.6106 -82.3976)
		(end 135.6106 -78.3336)
		(width 0.1016)
		(layer "F.Cu")
		(net "CLK_48M_SIO")
	)
	(segment
		(start 129.286 -69.9008)
		(end 124.5362 -69.9008)
		(width 0.1016)
		(layer "F.Cu")
		(net "CLK_48M_SIO")
	)
	(segment
		(start 135.6106 -78.3336)
		(end 130.81 -73.533)
		(width 0.1016)
		(layer "F.Cu")
		(net "CLK_48M_SIO")
	)
	(segment
		(start 111.96828 -51.16703)
		(end 111.96828 -43.466512)
		(width 0.1016)
		(layer "F.Cu")
		(net "CLK_48M_SIO")
	)
	(segment
		(start 111.96828 -43.466512)
		(end 112.38484 -43.049952)
		(width 0.1016)
		(layer "F.Cu")
		(net "CLK_48M_SIO")
	)
	(segment
		(start 117.7798 -59.432444)
		(end 113.96599 -55.618634)
		(width 0.1016)
		(layer "F.Cu")
		(net "CLK_48M_SIO")
	)
	(segment
		(start 138.117834 -83.6422)
		(end 136.8552 -83.6422)
		(width 0.1016)
		(layer "F.Cu")
		(net "CLK_48M_SIO")
	)
	(segment
		(start 142.02156 -113.397792)
		(end 145.14068 -110.278672)
		(width 0.1016)
		(layer "F.Cu")
		(net "CLK_48M_SIO")
	)
	(segment
		(start 130.81 -73.533)
		(end 130.81 -71.4248)
		(width 0.1016)
		(layer "F.Cu")
		(net "CLK_48M_SIO")
	)
	(segment
		(start 136.8552 -83.6422)
		(end 135.6106 -82.3976)
		(width 0.1016)
		(layer "F.Cu")
		(net "CLK_48M_SIO")
	)
	(segment
		(start 124.5362 -69.9008)
		(end 117.7798 -63.1444)
		(width 0.1016)
		(layer "F.Cu")
		(net "CLK_48M_SIO")
	)
	(segment
		(start 145.14068 -110.278672)
		(end 145.14068 -102.100634)
		(width 0.1016)
		(layer "F.Cu")
		(net "CLK_48M_SIO")
	)
	(segment
		(start 118.983252 -39.13759)
		(end 118.097046 -38.251384)
		(width 0.1016)
		(layer "F.Cu")
		(net "CLK_48M_SIO")
	)
	(segment
		(start 142.02156 -113.983008)
		(end 142.02156 -113.397792)
		(width 0.1016)
		(layer "F.Cu")
		(net "CLK_48M_SIO")
	)
	(segment
		(start 117.7798 -63.1444)
		(end 117.7798 -59.432444)
		(width 0.1016)
		(layer "F.Cu")
		(net "CLK_48M_SIO")
	)
	(segment
		(start 112.38484 -43.049952)
		(end 112.38484 -38.775894)
		(width 0.1016)
		(layer "F.Cu")
		(net "CLK_48M_SIO")
	)
	(segment
		(start 117.31752 -38.227)
		(end 117.31752 -38.251384)
		(width 0.1016)
		(layer "F.Cu")
		(net "CLK_48M_SIO")
	)
	(via
		(at 117.31752 -38.251384)
		(size 0.508)
		(drill 0.254)
		(layers "F.Cu" "B.Cu")
		(net "CLK_48M_SIO")
	)
	(segment
		(start 127.24257 -26.969466)
		(end 127.24257 -27.263852)
		(width 0.1016)
		(layer "F.Cu")
		(net "SIO_PIN73")
	)
	(segment
		(start 127.24257 -27.263852)
		(end 128.2065 -28.227782)
		(width 0.1016)
		(layer "F.Cu")
		(net "SIO_PIN73")
	)
	(segment
		(start 128.761744 -28.93949)
		(end 128.2065 -28.384246)
		(width 0.1016)
		(layer "F.Cu")
		(net "SIO_PIN73")
	)
	(segment
		(start 128.761744 -30.079696)
		(end 128.761744 -28.93949)
		(width 0.1016)
		(layer "F.Cu")
		(net "SIO_PIN73")
	)
	(segment
		(start 128.2065 -28.227782)
		(end 128.2065 -28.384246)
		(width 0.1016)
		(layer "F.Cu")
		(net "SIO_PIN73")
	)
	(via
		(at 128.2065 -28.384246)
		(size 0.508)
		(drill 0.254)
		(layers "F.Cu" "B.Cu")
		(net "SIO_PIN73")
	)
	(segment
		(start 135.76173 -48.348646)
		(end 136.202928 -48.789844)
		(width 0.1016)
		(layer "F.Cu")
		(net "UART_RTS_P3_R_N")
	)
	(segment
		(start 136.310878 -51.05146)
		(end 136.310878 -48.897794)
		(width 0.1016)
		(layer "F.Cu")
		(net "UART_RTS_P3_R_N")
	)
	(segment
		(start 136.310878 -48.897794)
		(end 136.202928 -48.789844)
		(width 0.1016)
		(layer "F.Cu")
		(net "UART_RTS_P3_R_N")
	)
	(segment
		(start 135.76173 -47.199804)
		(end 135.76173 -48.348646)
		(width 0.1016)
		(layer "F.Cu")
		(net "UART_RTS_P3_R_N")
	)
	(via
		(at 136.202928 -48.789844)
		(size 0.508)
		(drill 0.254)
		(layers "F.Cu" "B.Cu")
		(net "UART_RTS_P3_R_N")
	)
	(segment
		(start 136.202928 -48.789844)
		(end 135.577072 -48.163988)
		(width 0.1016)
		(layer "B.Cu")
		(net "UART_RTS_P3_R_N")
	)
	(segment
		(start 135.566912 -47.360586)
		(end 135.577072 -47.350426)
		(width 0.1016)
		(layer "B.Cu")
		(net "UART_RTS_P3_R_N")
	)
	(segment
		(start 135.577072 -48.163988)
		(end 135.577072 -47.350426)
		(width 0.1016)
		(layer "B.Cu")
		(net "UART_RTS_P3_R_N")
	)
	(segment
		(start 134.435088 -47.360586)
		(end 135.566912 -47.360586)
		(width 0.1016)
		(layer "B.Cu")
		(net "UART_RTS_P3_R_N")
	)
	(segment
		(start 126.22657 -27.492198)
		(end 126.473966 -27.739594)
		(width 0.1016)
		(layer "F.Cu")
		(net "SIO_PIN72")
	)
	(segment
		(start 126.22657 -26.969466)
		(end 126.22657 -27.492198)
		(width 0.1016)
		(layer "F.Cu")
		(net "SIO_PIN72")
	)
	(segment
		(start 128.261618 -30.079696)
		(end 128.261618 -29.18587)
		(width 0.1016)
		(layer "F.Cu")
		(net "SIO_PIN72")
	)
	(segment
		(start 128.261618 -29.18587)
		(end 127.07874 -28.002992)
		(width 0.1016)
		(layer "F.Cu")
		(net "SIO_PIN72")
	)
	(segment
		(start 127.07874 -28.002992)
		(end 127.07874 -27.739594)
		(width 0.1016)
		(layer "F.Cu")
		(net "SIO_PIN72")
	)
	(segment
		(start 126.473966 -27.739594)
		(end 127.07874 -27.739594)
		(width 0.1016)
		(layer "F.Cu")
		(net "SIO_PIN72")
	)
	(via
		(at 127.07874 -27.739594)
		(size 0.508)
		(drill 0.254)
		(layers "F.Cu" "B.Cu")
		(net "SIO_PIN72")
	)
	(segment
		(start 176.485042 -126.728728)
		(end 176.485042 -127.327152)
		(width 0.1016)
		(layer "F.Cu")
		(net "CPLD_CPU_THRMTRIP_N")
	)
	(segment
		(start 176.267364 -129.273554)
		(end 176.267364 -132.222748)
		(width 0.1016)
		(layer "F.Cu")
		(net "CPLD_CPU_THRMTRIP_N")
	)
	(segment
		(start 176.49317 -127.33528)
		(end 176.49317 -129.047748)
		(width 0.1016)
		(layer "F.Cu")
		(net "CPLD_CPU_THRMTRIP_N")
	)
	(segment
		(start 176.485042 -127.327152)
		(end 176.49317 -127.33528)
		(width 0.1016)
		(layer "F.Cu")
		(net "CPLD_CPU_THRMTRIP_N")
	)
	(segment
		(start 176.49317 -124.118878)
		(end 176.49317 -126.7206)
		(width 0.1016)
		(layer "F.Cu")
		(net "CPLD_CPU_THRMTRIP_N")
	)
	(segment
		(start 176.267364 -132.222748)
		(end 176.153064 -132.337048)
		(width 0.1016)
		(layer "F.Cu")
		(net "CPLD_CPU_THRMTRIP_N")
	)
	(segment
		(start 176.49317 -126.7206)
		(end 176.485042 -126.728728)
		(width 0.1016)
		(layer "F.Cu")
		(net "CPLD_CPU_THRMTRIP_N")
	)
	(segment
		(start 174.961042 -133.338824)
		(end 174.961042 -134.182104)
		(width 0.1016)
		(layer "F.Cu")
		(net "CPLD_CPU_THRMTRIP_N")
	)
	(segment
		(start 176.49317 -129.047748)
		(end 176.267364 -129.273554)
		(width 0.1016)
		(layer "F.Cu")
		(net "CPLD_CPU_THRMTRIP_N")
	)
	(segment
		(start 177.010314 -123.365768)
		(end 177.010314 -123.601734)
		(width 0.1016)
		(layer "F.Cu")
		(net "CPLD_CPU_THRMTRIP_N")
	)
	(segment
		(start 177.010314 -123.601734)
		(end 176.49317 -124.118878)
		(width 0.1016)
		(layer "F.Cu")
		(net "CPLD_CPU_THRMTRIP_N")
	)
	(segment
		(start 176.153064 -132.337048)
		(end 175.962818 -132.337048)
		(width 0.1016)
		(layer "F.Cu")
		(net "CPLD_CPU_THRMTRIP_N")
	)
	(segment
		(start 175.962818 -132.337048)
		(end 174.961042 -133.338824)
		(width 0.1016)
		(layer "F.Cu")
		(net "CPLD_CPU_THRMTRIP_N")
	)
	(via
		(at 176.485042 -126.728728)
		(size 0.508)
		(drill 0.254)
		(layers "F.Cu" "B.Cu")
		(net "CPLD_CPU_THRMTRIP_N")
	)
	(segment
		(start 171.99864 -134.473188)
		(end 171.551092 -134.920736)
		(width 0.1016)
		(layer "F.Cu")
		(net "N41777080")
	)
	(segment
		(start 172.657516 -135.132064)
		(end 171.99864 -134.473188)
		(width 0.1016)
		(layer "F.Cu")
		(net "N41777080")
	)
	(segment
		(start 171.551092 -134.920736)
		(end 171.551092 -135.24738)
		(width 0.1016)
		(layer "F.Cu")
		(net "N41777080")
	)
	(segment
		(start 172.961046 -135.132064)
		(end 172.657516 -135.132064)
		(width 0.1016)
		(layer "F.Cu")
		(net "N41777080")
	)
	(via
		(at 171.99864 -134.473188)
		(size 0.508)
		(drill 0.254)
		(layers "F.Cu" "B.Cu")
		(net "N41777080")
	)
	(segment
		(start 146.487642 -44.389802)
		(end 147.80641 -45.70857)
		(width 0.1016)
		(layer "F.Cu")
		(net "UART_RI_P2_N")
	)
	(segment
		(start 147.80641 -45.70857)
		(end 148.992844 -45.70857)
		(width 0.1016)
		(layer "F.Cu")
		(net "UART_RI_P2_N")
	)
	(segment
		(start 145.571718 -44.389802)
		(end 146.487642 -44.389802)
		(width 0.1016)
		(layer "F.Cu")
		(net "UART_RI_P2_N")
	)
	(via
		(at 147.80641 -45.70857)
		(size 0.508)
		(drill 0.254)
		(layers "F.Cu" "B.Cu")
		(net "UART_RI_P2_N")
	)
	(segment
		(start 145.571718 -40.38981)
		(end 142.79753 -40.38981)
		(width 0.1016)
		(layer "F.Cu")
		(net "UART_RI_P1_N")
	)
	(via
		(at 142.79753 -40.38981)
		(size 0.508)
		(drill 0.254)
		(layers "F.Cu" "B.Cu")
		(net "UART_RI_P1_N")
	)
	(segment
		(start 144.508982 -40.742616)
		(end 143.76146 -40.742616)
		(width 0.1016)
		(layer "B.Cu")
		(net "UART_RI_P1_N")
	)
	(segment
		(start 143.408654 -40.38981)
		(end 142.79753 -40.38981)
		(width 0.1016)
		(layer "B.Cu")
		(net "UART_RI_P1_N")
	)
	(segment
		(start 143.76146 -40.742616)
		(end 143.408654 -40.38981)
		(width 0.1016)
		(layer "B.Cu")
		(net "UART_RI_P1_N")
	)
	(segment
		(start 25.641554 -101.259132)
		(end 26.818844 -100.081842)
		(width 0.1016)
		(layer "F.Cu")
		(net "FRU_SYS_A0")
	)
	(segment
		(start 26.818844 -100.081842)
		(end 27.312874 -100.081842)
		(width 0.1016)
		(layer "F.Cu")
		(net "FRU_SYS_A0")
	)
	(segment
		(start 27.820874 -99.573842)
		(end 27.312874 -100.081842)
		(width 0.1016)
		(layer "F.Cu")
		(net "FRU_SYS_A0")
	)
	(segment
		(start 25.641554 -102.709472)
		(end 25.641554 -101.259132)
		(width 0.1016)
		(layer "F.Cu")
		(net "FRU_SYS_A0")
	)
	(segment
		(start 28.098496 -98.546412)
		(end 28.098496 -99.573842)
		(width 0.1016)
		(layer "F.Cu")
		(net "FRU_SYS_A0")
	)
	(segment
		(start 28.098496 -99.573842)
		(end 27.820874 -99.573842)
		(width 0.1016)
		(layer "F.Cu")
		(net "FRU_SYS_A0")
	)
	(via
		(at 27.312874 -100.081842)
		(size 0.508)
		(drill 0.254)
		(layers "F.Cu" "B.Cu")
		(net "FRU_SYS_A0")
	)
	(segment
		(start 124.027184 -41.88968)
		(end 124.49302 -41.423844)
		(width 0.1016)
		(layer "F.Cu")
		(net "SIO_PIN45")
	)
	(segment
		(start 122.451622 -41.88968)
		(end 124.027184 -41.88968)
		(width 0.1016)
		(layer "F.Cu")
		(net "SIO_PIN45")
	)
	(via
		(at 124.49302 -41.423844)
		(size 0.508)
		(drill 0.254)
		(layers "F.Cu" "B.Cu")
		(net "SIO_PIN45")
	)
	(segment
		(start 124.982986 -41.423844)
		(end 124.49302 -41.423844)
		(width 0.1016)
		(layer "B.Cu")
		(net "SIO_PIN45")
	)
	(segment
		(start 125.639576 -41.214294)
		(end 125.192536 -41.214294)
		(width 0.1016)
		(layer "B.Cu")
		(net "SIO_PIN45")
	)
	(segment
		(start 125.192536 -41.214294)
		(end 124.982986 -41.423844)
		(width 0.1016)
		(layer "B.Cu")
		(net "SIO_PIN45")
	)
	(segment
		(start 123.53798 -48.076866)
		(end 123.986798 -48.525684)
		(width 0.1016)
		(layer "F.Cu")
		(net "SIO_PIN38")
	)
	(segment
		(start 123.00712 -48.607726)
		(end 123.53798 -48.076866)
		(width 0.1016)
		(layer "F.Cu")
		(net "SIO_PIN38")
	)
	(segment
		(start 124.48032 -48.525684)
		(end 124.761752 -48.244252)
		(width 0.1016)
		(layer "F.Cu")
		(net "SIO_PIN38")
	)
	(segment
		(start 124.761752 -48.244252)
		(end 124.761752 -47.199804)
		(width 0.1016)
		(layer "F.Cu")
		(net "SIO_PIN38")
	)
	(segment
		(start 123.986798 -48.525684)
		(end 124.48032 -48.525684)
		(width 0.1016)
		(layer "F.Cu")
		(net "SIO_PIN38")
	)
	(segment
		(start 123.00712 -49.635664)
		(end 123.00712 -48.607726)
		(width 0.1016)
		(layer "F.Cu")
		(net "SIO_PIN38")
	)
	(via
		(at 123.53798 -48.076866)
		(size 0.508)
		(drill 0.254)
		(layers "F.Cu" "B.Cu")
		(net "SIO_PIN38")
	)
	(segment
		(start 24.375872 -95.061278)
		(end 24.375872 -95.667576)
		(width 0.1016)
		(layer "F.Cu")
		(net "N43448372")
	)
	(segment
		(start 24.375872 -95.667576)
		(end 24.371554 -95.671894)
		(width 0.1016)
		(layer "F.Cu")
		(net "N43448372")
	)
	(segment
		(start 24.371554 -97.426272)
		(end 24.371554 -95.671894)
		(width 0.1016)
		(layer "F.Cu")
		(net "N43448372")
	)
	(via
		(at 24.371554 -95.671894)
		(size 0.508)
		(drill 0.254)
		(layers "F.Cu" "B.Cu")
		(net "N43448372")
	)
	(segment
		(start 141.820392 -36.311332)
		(end 141.820392 -36.197794)
		(width 0.1016)
		(layer "F.Cu")
		(net "SIO_JTAG_CPLD2_TDI_R")
	)
	(segment
		(start 145.571718 -37.389816)
		(end 142.898876 -37.389816)
		(width 0.1016)
		(layer "F.Cu")
		(net "SIO_JTAG_CPLD2_TDI_R")
	)
	(segment
		(start 142.898876 -37.389816)
		(end 141.820392 -36.311332)
		(width 0.1016)
		(layer "F.Cu")
		(net "SIO_JTAG_CPLD2_TDI_R")
	)
	(via
		(at 141.820392 -36.197794)
		(size 0.508)
		(drill 0.254)
		(layers "F.Cu" "B.Cu")
		(net "SIO_JTAG_CPLD2_TDI_R")
	)
	(segment
		(start 141.517116 -36.197794)
		(end 141.820392 -36.197794)
		(width 0.1016)
		(layer "B.Cu")
		(net "SIO_JTAG_CPLD2_TDI_R")
	)
	(segment
		(start 144.508982 -37.694616)
		(end 144.508982 -37.431472)
		(width 0.1016)
		(layer "B.Cu")
		(net "SIO_JTAG_CPLD2_TDI_R")
	)
	(segment
		(start 140.45311 -37.2618)
		(end 141.517116 -36.197794)
		(width 0.1016)
		(layer "B.Cu")
		(net "SIO_JTAG_CPLD2_TDI_R")
	)
	(segment
		(start 144.508982 -37.431472)
		(end 143.275304 -36.197794)
		(width 0.1016)
		(layer "B.Cu")
		(net "SIO_JTAG_CPLD2_TDI_R")
	)
	(segment
		(start 143.275304 -36.197794)
		(end 141.820392 -36.197794)
		(width 0.1016)
		(layer "B.Cu")
		(net "SIO_JTAG_CPLD2_TDI_R")
	)
	(segment
		(start 139.612624 -37.44341)
		(end 139.794234 -37.2618)
		(width 0.1016)
		(layer "B.Cu")
		(net "SIO_JTAG_CPLD2_TDI_R")
	)
	(segment
		(start 139.794234 -37.2618)
		(end 140.45311 -37.2618)
		(width 0.1016)
		(layer "B.Cu")
		(net "SIO_JTAG_CPLD2_TDI_R")
	)
	(segment
		(start 138.370056 -37.44341)
		(end 139.612624 -37.44341)
		(width 0.1016)
		(layer "B.Cu")
		(net "SIO_JTAG_CPLD2_TDI_R")
	)
	(segment
		(start 141.746986 -39.180516)
		(end 143.902684 -39.180516)
		(width 0.1016)
		(layer "F.Cu")
		(net "SIO_JTAG_CPLD2_TCK_R")
	)
	(segment
		(start 143.902684 -39.180516)
		(end 144.193514 -38.889686)
		(width 0.1016)
		(layer "F.Cu")
		(net "SIO_JTAG_CPLD2_TCK_R")
	)
	(segment
		(start 144.193514 -38.889686)
		(end 145.571718 -38.889686)
		(width 0.1016)
		(layer "F.Cu")
		(net "SIO_JTAG_CPLD2_TCK_R")
	)
	(via
		(at 141.746986 -39.180516)
		(size 0.508)
		(drill 0.254)
		(layers "F.Cu" "B.Cu")
		(net "SIO_JTAG_CPLD2_TCK_R")
	)
	(segment
		(start 143.439134 -39.726616)
		(end 142.893034 -39.180516)
		(width 0.1016)
		(layer "B.Cu")
		(net "SIO_JTAG_CPLD2_TCK_R")
	)
	(segment
		(start 140.907516 -40.019986)
		(end 141.746986 -39.180516)
		(width 0.1016)
		(layer "B.Cu")
		(net "SIO_JTAG_CPLD2_TCK_R")
	)
	(segment
		(start 144.508982 -39.726616)
		(end 143.439134 -39.726616)
		(width 0.1016)
		(layer "B.Cu")
		(net "SIO_JTAG_CPLD2_TCK_R")
	)
	(segment
		(start 140.907516 -41.285414)
		(end 140.907516 -40.019986)
		(width 0.1016)
		(layer "B.Cu")
		(net "SIO_JTAG_CPLD2_TCK_R")
	)
	(segment
		(start 142.893034 -39.180516)
		(end 141.746986 -39.180516)
		(width 0.1016)
		(layer "B.Cu")
		(net "SIO_JTAG_CPLD2_TCK_R")
	)
	(segment
		(start 137.287 -50.165)
		(end 137.033 -49.911)
		(width 0.1016)
		(layer "F.Cu")
		(net "UART_DTR_P3_R_N")
	)
	(segment
		(start 137.287 -51.03495)
		(end 137.287 -50.165)
		(width 0.1016)
		(layer "F.Cu")
		(net "UART_DTR_P3_R_N")
	)
	(segment
		(start 137.033 -49.911)
		(end 136.761728 -49.639728)
		(width 0.1016)
		(layer "F.Cu")
		(net "UART_DTR_P3_R_N")
	)
	(segment
		(start 136.761728 -49.639728)
		(end 136.761728 -47.199804)
		(width 0.1016)
		(layer "F.Cu")
		(net "UART_DTR_P3_R_N")
	)
	(via
		(at 137.033 -49.911)
		(size 0.508)
		(drill 0.254)
		(layers "F.Cu" "B.Cu")
		(net "UART_DTR_P3_R_N")
	)
	(segment
		(start 137.668508 -47.352204)
		(end 137.668508 -49.275492)
		(width 0.1016)
		(layer "B.Cu")
		(net "UART_DTR_P3_R_N")
	)
	(segment
		(start 137.668508 -49.275492)
		(end 137.033 -49.911)
		(width 0.1016)
		(layer "B.Cu")
		(net "UART_DTR_P3_R_N")
	)
	(segment
		(start 137.66673 -47.353982)
		(end 136.633712 -47.353982)
		(width 0.1016)
		(layer "B.Cu")
		(net "UART_DTR_P3_R_N")
	)
	(segment
		(start 137.668508 -47.352204)
		(end 137.66673 -47.353982)
		(width 0.1016)
		(layer "B.Cu")
		(net "UART_DTR_P3_R_N")
	)
	(segment
		(start 139.8397 -38.527228)
		(end 140.64234 -37.724588)
		(width 0.1016)
		(layer "F.Cu")
		(net "SIO_JTAG_CPLD2_TMS_R")
	)
	(segment
		(start 140.64234 -37.724588)
		(end 143.60398 -37.724588)
		(width 0.1016)
		(layer "F.Cu")
		(net "SIO_JTAG_CPLD2_TMS_R")
	)
	(segment
		(start 143.60398 -37.724588)
		(end 143.76908 -37.889688)
		(width 0.1016)
		(layer "F.Cu")
		(net "SIO_JTAG_CPLD2_TMS_R")
	)
	(segment
		(start 143.76908 -37.889688)
		(end 145.571718 -37.889688)
		(width 0.1016)
		(layer "F.Cu")
		(net "SIO_JTAG_CPLD2_TMS_R")
	)
	(via
		(at 139.8397 -38.527228)
		(size 0.508)
		(drill 0.254)
		(layers "F.Cu" "B.Cu")
		(net "SIO_JTAG_CPLD2_TMS_R")
	)
	(segment
		(start 138.891518 -39.47541)
		(end 139.8397 -38.527228)
		(width 0.1016)
		(layer "B.Cu")
		(net "SIO_JTAG_CPLD2_TMS_R")
	)
	(segment
		(start 138.370056 -40.49141)
		(end 138.370056 -39.47541)
		(width 0.1016)
		(layer "B.Cu")
		(net "SIO_JTAG_CPLD2_TMS_R")
	)
	(segment
		(start 138.370056 -39.47541)
		(end 138.891518 -39.47541)
		(width 0.1016)
		(layer "B.Cu")
		(net "SIO_JTAG_CPLD2_TMS_R")
	)
	(segment
		(start 60.954666 -142.846552)
		(end 60.954666 -143.434562)
		(width 0.1016)
		(layer "F.Cu")
		(net "BMC_NODE1_GFX_VSYNC_R")
	)
	(segment
		(start 60.53455 -143.854678)
		(end 59.767978 -143.854678)
		(width 0.1016)
		(layer "F.Cu")
		(net "BMC_NODE1_GFX_VSYNC_R")
	)
	(segment
		(start 60.954666 -143.434562)
		(end 60.53455 -143.854678)
		(width 0.1016)
		(layer "F.Cu")
		(net "BMC_NODE1_GFX_VSYNC_R")
	)
	(segment
		(start 61.341762 -142.459456)
		(end 60.954666 -142.846552)
		(width 0.1016)
		(layer "F.Cu")
		(net "BMC_NODE1_GFX_VSYNC_R")
	)
	(via
		(at 59.767978 -143.854678)
		(size 0.49022)
		(drill 0.254)
		(layers "F.Cu" "B.Cu")
		(net "BMC_NODE1_GFX_VSYNC_R")
	)
	(segment
		(start 59.217814 -144.404842)
		(end 58.498232 -144.404842)
		(width 0.1016)
		(layer "B.Cu")
		(net "BMC_NODE1_GFX_VSYNC_R")
	)
	(segment
		(start 58.498232 -144.404842)
		(end 57.0484 -145.854674)
		(width 0.1016)
		(layer "B.Cu")
		(net "BMC_NODE1_GFX_VSYNC_R")
	)
	(segment
		(start 59.767978 -143.854678)
		(end 59.217814 -144.404842)
		(width 0.1016)
		(layer "B.Cu")
		(net "BMC_NODE1_GFX_VSYNC_R")
	)
	(segment
		(start 57.0484 -145.854674)
		(end 56.60009 -145.854674)
		(width 0.1016)
		(layer "B.Cu")
		(net "BMC_NODE1_GFX_VSYNC_R")
	)
	(segment
		(start 62.141862 -140.858748)
		(end 61.74105 -140.457936)
		(width 0.1016)
		(layer "F.Cu")
		(net "BMC_NODE1_GFX_HSYNC_R")
	)
	(segment
		(start 62.141862 -140.85951)
		(end 62.141862 -140.858748)
		(width 0.1016)
		(layer "F.Cu")
		(net "BMC_NODE1_GFX_HSYNC_R")
	)
	(via
		(at 61.74105 -140.457936)
		(size 0.49022)
		(drill 0.254)
		(layers "F.Cu" "B.Cu")
		(net "BMC_NODE1_GFX_HSYNC_R")
	)
	(via
		(at 57.870852 -143.995902)
		(size 0.6604)
		(drill 0.3302)
		(layers "F.Cu" "B.Cu")
		(net "BMC_NODE1_GFX_HSYNC_R")
	)
	(segment
		(start 57.05729 -144.809464)
		(end 57.870852 -143.995902)
		(width 0.1016)
		(layer "B.Cu")
		(net "BMC_NODE1_GFX_HSYNC_R")
	)
	(segment
		(start 59.049666 -142.817088)
		(end 59.381898 -142.817088)
		(width 0.1016)
		(layer "B.Cu")
		(net "BMC_NODE1_GFX_HSYNC_R")
	)
	(segment
		(start 59.381898 -142.817088)
		(end 61.74105 -140.457936)
		(width 0.1016)
		(layer "B.Cu")
		(net "BMC_NODE1_GFX_HSYNC_R")
	)
	(segment
		(start 57.870852 -143.995902)
		(end 59.049666 -142.817088)
		(width 0.1016)
		(layer "B.Cu")
		(net "BMC_NODE1_GFX_HSYNC_R")
	)
	(segment
		(start 56.602376 -144.809464)
		(end 57.05729 -144.809464)
		(width 0.1016)
		(layer "B.Cu")
		(net "BMC_NODE1_GFX_HSYNC_R")
	)
	(segment
		(start 125.3109 -162.713162)
		(end 125.3109 -164.178234)
		(width 0.1016)
		(layer "F.Cu")
		(net "UART_CMC_TX_P")
	)
	(segment
		(start 124.99594 -161.817812)
		(end 125.41504 -162.236912)
		(width 0.1016)
		(layer "F.Cu")
		(net "UART_CMC_TX_P")
	)
	(segment
		(start 125.3109 -164.178234)
		(end 125.22708 -164.262054)
		(width 0.1016)
		(layer "F.Cu")
		(net "UART_CMC_TX_P")
	)
	(segment
		(start 121.539 -162.356546)
		(end 122.07748 -161.818066)
		(width 0.1016)
		(layer "F.Cu")
		(net "UART_CMC_TX_P")
	)
	(segment
		(start 134.02564 -178.858672)
		(end 134.02564 -174.396654)
		(width 0.1016)
		(layer "F.Cu")
		(net "UART_CMC_TX_P")
	)
	(segment
		(start 120.60936 -162.356546)
		(end 121.539 -162.356546)
		(width 0.1016)
		(layer "F.Cu")
		(net "UART_CMC_TX_P")
	)
	(segment
		(start 125.41504 -162.236912)
		(end 125.41504 -162.609022)
		(width 0.1016)
		(layer "F.Cu")
		(net "UART_CMC_TX_P")
	)
	(segment
		(start 124.62256 -161.817812)
		(end 124.99594 -161.817812)
		(width 0.1016)
		(layer "F.Cu")
		(net "UART_CMC_TX_P")
	)
	(segment
		(start 134.02564 -174.396654)
		(end 133.886194 -174.257208)
		(width 0.1016)
		(layer "F.Cu")
		(net "UART_CMC_TX_P")
	)
	(segment
		(start 125.41504 -162.609022)
		(end 125.3109 -162.713162)
		(width 0.1016)
		(layer "F.Cu")
		(net "UART_CMC_TX_P")
	)
	(segment
		(start 124.622306 -161.818066)
		(end 124.62256 -161.817812)
		(width 0.1016)
		(layer "F.Cu")
		(net "UART_CMC_TX_P")
	)
	(segment
		(start 122.07748 -161.818066)
		(end 124.622306 -161.818066)
		(width 0.1016)
		(layer "F.Cu")
		(net "UART_CMC_TX_P")
	)
	(via
		(at 133.886194 -174.257208)
		(size 0.508)
		(drill 0.254)
		(layers "F.Cu" "B.Cu")
		(net "UART_CMC_TX_P")
	)
	(via
		(at 125.22708 -164.262054)
		(size 0.508)
		(drill 0.254)
		(layers "F.Cu" "B.Cu")
		(net "UART_CMC_TX_P")
	)
	(segment
		(start 128.88341 -166.935658)
		(end 132.63118 -170.683428)
		(width 0.1143)
		(layer "In2.Cu")
		(net "UART_CMC_TX_P")
	)
	(segment
		(start 132.63118 -170.683428)
		(end 132.63118 -173.002194)
		(width 0.1143)
		(layer "In2.Cu")
		(net "UART_CMC_TX_P")
	)
	(segment
		(start 132.63118 -173.002194)
		(end 133.886194 -174.257208)
		(width 0.1143)
		(layer "In2.Cu")
		(net "UART_CMC_TX_P")
	)
	(segment
		(start 127.628396 -165.784276)
		(end 128.62687 -165.784276)
		(width 0.1143)
		(layer "In2.Cu")
		(net "UART_CMC_TX_P")
	)
	(segment
		(start 125.22708 -164.262054)
		(end 126.106174 -164.262054)
		(width 0.1143)
		(layer "In2.Cu")
		(net "UART_CMC_TX_P")
	)
	(segment
		(start 128.62687 -165.784276)
		(end 128.88341 -166.040816)
		(width 0.1143)
		(layer "In2.Cu")
		(net "UART_CMC_TX_P")
	)
	(segment
		(start 126.106174 -164.262054)
		(end 127.628396 -165.784276)
		(width 0.1143)
		(layer "In2.Cu")
		(net "UART_CMC_TX_P")
	)
	(segment
		(start 128.88341 -166.040816)
		(end 128.88341 -166.935658)
		(width 0.1143)
		(layer "In2.Cu")
		(net "UART_CMC_TX_P")
	)
	(segment
		(start 123.282202 -162.464242)
		(end 122.659394 -162.464242)
		(width 0.1016)
		(layer "F.Cu")
		(net "UART_CMC_RX_P")
	)
	(segment
		(start 122.659394 -162.464242)
		(end 121.99874 -163.124896)
		(width 0.1016)
		(layer "F.Cu")
		(net "UART_CMC_RX_P")
	)
	(segment
		(start 120.60936 -163.006532)
		(end 121.880376 -163.006532)
		(width 0.1016)
		(layer "F.Cu")
		(net "UART_CMC_RX_P")
	)
	(segment
		(start 133.525768 -175.734218)
		(end 131.812538 -174.020988)
		(width 0.1016)
		(layer "F.Cu")
		(net "UART_CMC_RX_P")
	)
	(segment
		(start 133.525768 -178.858672)
		(end 133.525768 -175.734218)
		(width 0.1016)
		(layer "F.Cu")
		(net "UART_CMC_RX_P")
	)
	(segment
		(start 121.880376 -163.006532)
		(end 121.99874 -163.124896)
		(width 0.1016)
		(layer "F.Cu")
		(net "UART_CMC_RX_P")
	)
	(via
		(at 121.99874 -163.124896)
		(size 0.508)
		(drill 0.254)
		(layers "F.Cu" "B.Cu")
		(net "UART_CMC_RX_P")
	)
	(via
		(at 131.812538 -174.020988)
		(size 0.508)
		(drill 0.254)
		(layers "F.Cu" "B.Cu")
		(net "UART_CMC_RX_P")
	)
	(segment
		(start 126.223014 -165.33495)
		(end 126.223014 -166.463218)
		(width 0.1143)
		(layer "In2.Cu")
		(net "UART_CMC_RX_P")
	)
	(segment
		(start 125.65888 -164.770816)
		(end 126.223014 -165.33495)
		(width 0.1143)
		(layer "In2.Cu")
		(net "UART_CMC_RX_P")
	)
	(segment
		(start 124.313188 -164.770816)
		(end 125.65888 -164.770816)
		(width 0.1143)
		(layer "In2.Cu")
		(net "UART_CMC_RX_P")
	)
	(segment
		(start 122.667268 -163.124896)
		(end 124.313188 -164.770816)
		(width 0.1143)
		(layer "In2.Cu")
		(net "UART_CMC_RX_P")
	)
	(segment
		(start 132.107178 -171.287948)
		(end 132.107178 -173.726348)
		(width 0.1143)
		(layer "In2.Cu")
		(net "UART_CMC_RX_P")
	)
	(segment
		(start 126.223014 -166.463218)
		(end 130.403854 -170.644058)
		(width 0.1143)
		(layer "In2.Cu")
		(net "UART_CMC_RX_P")
	)
	(segment
		(start 130.403854 -170.644058)
		(end 131.463288 -170.644058)
		(width 0.1143)
		(layer "In2.Cu")
		(net "UART_CMC_RX_P")
	)
	(segment
		(start 132.107178 -173.726348)
		(end 131.812538 -174.020988)
		(width 0.1143)
		(layer "In2.Cu")
		(net "UART_CMC_RX_P")
	)
	(segment
		(start 131.463288 -170.644058)
		(end 132.107178 -171.287948)
		(width 0.1143)
		(layer "In2.Cu")
		(net "UART_CMC_RX_P")
	)
	(segment
		(start 121.99874 -163.124896)
		(end 122.667268 -163.124896)
		(width 0.1143)
		(layer "In2.Cu")
		(net "UART_CMC_RX_P")
	)
	(segment
		(start 65.819528 -84.963508)
		(end 66.610738 -84.963508)
		(width 0.1016)
		(layer "F.Cu")
		(net "CPLD_ROW_LATCH")
	)
	(segment
		(start 178.00193 -124.365766)
		(end 177.465482 -123.829318)
		(width 0.1016)
		(layer "F.Cu")
		(net "CPLD_ROW_LATCH")
	)
	(segment
		(start 65.475866 -84.619846)
		(end 65.819528 -84.963508)
		(width 0.1016)
		(layer "F.Cu")
		(net "CPLD_ROW_LATCH")
	)
	(segment
		(start 178.010566 -124.365766)
		(end 178.00193 -124.365766)
		(width 0.1016)
		(layer "F.Cu")
		(net "CPLD_ROW_LATCH")
	)
	(via
		(at 153.370026 -123.274328)
		(size 0.508)
		(drill 0.254)
		(layers "F.Cu" "B.Cu")
		(net "CPLD_ROW_LATCH")
	)
	(via
		(at 177.465482 -123.829318)
		(size 0.49022)
		(drill 0.254)
		(layers "F.Cu" "B.Cu")
		(net "CPLD_ROW_LATCH")
	)
	(via
		(at 66.610738 -84.963508)
		(size 0.508)
		(drill 0.254)
		(layers "F.Cu" "B.Cu")
		(net "CPLD_ROW_LATCH")
	)
	(segment
		(start 108.73994 -88.185244)
		(end 99.12096 -88.185244)
		(width 0.1143)
		(layer "In7.Cu")
		(net "CPLD_ROW_LATCH")
	)
	(segment
		(start 68.290694 -88.514428)
		(end 66.231516 -86.45525)
		(width 0.1143)
		(layer "In7.Cu")
		(net "CPLD_ROW_LATCH")
	)
	(segment
		(start 137.312908 -104.629712)
		(end 125.184408 -104.629712)
		(width 0.1143)
		(layer "In7.Cu")
		(net "CPLD_ROW_LATCH")
	)
	(segment
		(start 68.926964 -88.514428)
		(end 68.290694 -88.514428)
		(width 0.1143)
		(layer "In7.Cu")
		(net "CPLD_ROW_LATCH")
	)
	(segment
		(start 176.151032 -131.307586)
		(end 171.079922 -131.307586)
		(width 0.1143)
		(layer "In7.Cu")
		(net "CPLD_ROW_LATCH")
	)
	(segment
		(start 178.215798 -131.744466)
		(end 176.587912 -131.744466)
		(width 0.1143)
		(layer "In7.Cu")
		(net "CPLD_ROW_LATCH")
	)
	(segment
		(start 75.073002 -89.078562)
		(end 69.491098 -89.078562)
		(width 0.1143)
		(layer "In7.Cu")
		(net "CPLD_ROW_LATCH")
	)
	(segment
		(start 66.610738 -84.96935)
		(end 66.610738 -84.963508)
		(width 0.1143)
		(layer "In7.Cu")
		(net "CPLD_ROW_LATCH")
	)
	(segment
		(start 171.079922 -131.307586)
		(end 170.699938 -131.68757)
		(width 0.1143)
		(layer "In7.Cu")
		(net "CPLD_ROW_LATCH")
	)
	(segment
		(start 75.428094 -89.433654)
		(end 75.073002 -89.078562)
		(width 0.1143)
		(layer "In7.Cu")
		(net "CPLD_ROW_LATCH")
	)
	(segment
		(start 97.143316 -86.2076)
		(end 88.874346 -86.2076)
		(width 0.1143)
		(layer "In7.Cu")
		(net "CPLD_ROW_LATCH")
	)
	(segment
		(start 99.12096 -88.185244)
		(end 97.143316 -86.2076)
		(width 0.1143)
		(layer "In7.Cu")
		(net "CPLD_ROW_LATCH")
	)
	(segment
		(start 142.310866 -108.131864)
		(end 140.81506 -108.131864)
		(width 0.1143)
		(layer "In7.Cu")
		(net "CPLD_ROW_LATCH")
	)
	(segment
		(start 160.951418 -130.430524)
		(end 160.526222 -130.430524)
		(width 0.1143)
		(layer "In7.Cu")
		(net "CPLD_ROW_LATCH")
	)
	(segment
		(start 170.699938 -131.68757)
		(end 162.208464 -131.68757)
		(width 0.1143)
		(layer "In7.Cu")
		(net "CPLD_ROW_LATCH")
	)
	(segment
		(start 160.526222 -130.430524)
		(end 153.370026 -123.274328)
		(width 0.1143)
		(layer "In7.Cu")
		(net "CPLD_ROW_LATCH")
	)
	(segment
		(start 140.81506 -108.131864)
		(end 137.312908 -104.629712)
		(width 0.1143)
		(layer "In7.Cu")
		(net "CPLD_ROW_LATCH")
	)
	(segment
		(start 88.874346 -86.2076)
		(end 86.223602 -88.858344)
		(width 0.1143)
		(layer "In7.Cu")
		(net "CPLD_ROW_LATCH")
	)
	(segment
		(start 125.184408 -104.629712)
		(end 108.73994 -88.185244)
		(width 0.1143)
		(layer "In7.Cu")
		(net "CPLD_ROW_LATCH")
	)
	(segment
		(start 83.161124 -89.433654)
		(end 75.428094 -89.433654)
		(width 0.1143)
		(layer "In7.Cu")
		(net "CPLD_ROW_LATCH")
	)
	(segment
		(start 84.99602 -89.369138)
		(end 83.22564 -89.369138)
		(width 0.1143)
		(layer "In7.Cu")
		(net "CPLD_ROW_LATCH")
	)
	(segment
		(start 147.75053 -113.571528)
		(end 142.310866 -108.131864)
		(width 0.1143)
		(layer "In7.Cu")
		(net "CPLD_ROW_LATCH")
	)
	(segment
		(start 176.587912 -131.744466)
		(end 176.151032 -131.307586)
		(width 0.1143)
		(layer "In7.Cu")
		(net "CPLD_ROW_LATCH")
	)
	(segment
		(start 66.231516 -85.348572)
		(end 66.610738 -84.96935)
		(width 0.1143)
		(layer "In7.Cu")
		(net "CPLD_ROW_LATCH")
	)
	(segment
		(start 69.491098 -89.078562)
		(end 68.926964 -88.514428)
		(width 0.1143)
		(layer "In7.Cu")
		(net "CPLD_ROW_LATCH")
	)
	(segment
		(start 66.231516 -86.45525)
		(end 66.231516 -85.348572)
		(width 0.1143)
		(layer "In7.Cu")
		(net "CPLD_ROW_LATCH")
	)
	(segment
		(start 180.30698 -129.653284)
		(end 178.215798 -131.744466)
		(width 0.1143)
		(layer "In7.Cu")
		(net "CPLD_ROW_LATCH")
	)
	(segment
		(start 177.465482 -123.829318)
		(end 180.30698 -126.670816)
		(width 0.1143)
		(layer "In7.Cu")
		(net "CPLD_ROW_LATCH")
	)
	(segment
		(start 83.22564 -89.369138)
		(end 83.161124 -89.433654)
		(width 0.1143)
		(layer "In7.Cu")
		(net "CPLD_ROW_LATCH")
	)
	(segment
		(start 147.75053 -117.654832)
		(end 147.75053 -113.571528)
		(width 0.1143)
		(layer "In7.Cu")
		(net "CPLD_ROW_LATCH")
	)
	(segment
		(start 85.506814 -88.858344)
		(end 84.99602 -89.369138)
		(width 0.1143)
		(layer "In7.Cu")
		(net "CPLD_ROW_LATCH")
	)
	(segment
		(start 180.30698 -126.670816)
		(end 180.30698 -129.653284)
		(width 0.1143)
		(layer "In7.Cu")
		(net "CPLD_ROW_LATCH")
	)
	(segment
		(start 162.208464 -131.68757)
		(end 160.951418 -130.430524)
		(width 0.1143)
		(layer "In7.Cu")
		(net "CPLD_ROW_LATCH")
	)
	(segment
		(start 86.223602 -88.858344)
		(end 85.506814 -88.858344)
		(width 0.1143)
		(layer "In7.Cu")
		(net "CPLD_ROW_LATCH")
	)
	(segment
		(start 153.370026 -123.274328)
		(end 147.75053 -117.654832)
		(width 0.1143)
		(layer "In7.Cu")
		(net "CPLD_ROW_LATCH")
	)
	(segment
		(start 66.17589 -84.318856)
		(end 66.637408 -83.857338)
		(width 0.1016)
		(layer "F.Cu")
		(net "CPLD_ROW_EN")
	)
	(segment
		(start 66.17589 -84.619846)
		(end 66.17589 -84.318856)
		(width 0.1016)
		(layer "F.Cu")
		(net "CPLD_ROW_EN")
	)
	(segment
		(start 179.5272 -124.882402)
		(end 179.5272 -128.13157)
		(width 0.1016)
		(layer "F.Cu")
		(net "CPLD_ROW_EN")
	)
	(segment
		(start 66.637408 -83.857338)
		(end 67.82562 -83.857338)
		(width 0.1016)
		(layer "F.Cu")
		(net "CPLD_ROW_EN")
	)
	(segment
		(start 179.010564 -124.365766)
		(end 179.5272 -124.882402)
		(width 0.1016)
		(layer "F.Cu")
		(net "CPLD_ROW_EN")
	)
	(segment
		(start 179.5272 -128.13157)
		(end 179.81168 -128.41605)
		(width 0.1016)
		(layer "F.Cu")
		(net "CPLD_ROW_EN")
	)
	(via
		(at 67.82562 -83.857338)
		(size 0.508)
		(drill 0.254)
		(layers "F.Cu" "B.Cu")
		(net "CPLD_ROW_EN")
	)
	(via
		(at 179.81168 -128.41605)
		(size 0.508)
		(drill 0.254)
		(layers "F.Cu" "B.Cu")
		(net "CPLD_ROW_EN")
	)
	(segment
		(start 148.2471 -117.414802)
		(end 160.246568 -129.41427)
		(width 0.1143)
		(layer "In7.Cu")
		(net "CPLD_ROW_EN")
	)
	(segment
		(start 68.220082 -87.009224)
		(end 68.585334 -87.009224)
		(width 0.1143)
		(layer "In7.Cu")
		(net "CPLD_ROW_EN")
	)
	(segment
		(start 176.727866 -130.912108)
		(end 177.315622 -130.912108)
		(width 0.1143)
		(layer "In7.Cu")
		(net "CPLD_ROW_EN")
	)
	(segment
		(start 67.644772 -84.038186)
		(end 67.644772 -86.433914)
		(width 0.1143)
		(layer "In7.Cu")
		(net "CPLD_ROW_EN")
	)
	(segment
		(start 73.398888 -88.026748)
		(end 75.280012 -88.026748)
		(width 0.1143)
		(layer "In7.Cu")
		(net "CPLD_ROW_EN")
	)
	(segment
		(start 160.246568 -129.41427)
		(end 160.749488 -129.41427)
		(width 0.1143)
		(layer "In7.Cu")
		(net "CPLD_ROW_EN")
	)
	(segment
		(start 160.749488 -129.41427)
		(end 162.146488 -130.81127)
		(width 0.1143)
		(layer "In7.Cu")
		(net "CPLD_ROW_EN")
	)
	(segment
		(start 88.627712 -85.6996)
		(end 97.456244 -85.6996)
		(width 0.1143)
		(layer "In7.Cu")
		(net "CPLD_ROW_EN")
	)
	(segment
		(start 86.070186 -88.257126)
		(end 88.627712 -85.6996)
		(width 0.1143)
		(layer "In7.Cu")
		(net "CPLD_ROW_EN")
	)
	(segment
		(start 81.604104 -88.469978)
		(end 81.816956 -88.257126)
		(width 0.1143)
		(layer "In7.Cu")
		(net "CPLD_ROW_EN")
	)
	(segment
		(start 162.146488 -130.81127)
		(end 163.21024 -130.81127)
		(width 0.1143)
		(layer "In7.Cu")
		(net "CPLD_ROW_EN")
	)
	(segment
		(start 142.51813 -107.636564)
		(end 148.2471 -113.365534)
		(width 0.1143)
		(layer "In7.Cu")
		(net "CPLD_ROW_EN")
	)
	(segment
		(start 75.280012 -88.026748)
		(end 76.179934 -88.92667)
		(width 0.1143)
		(layer "In7.Cu")
		(net "CPLD_ROW_EN")
	)
	(segment
		(start 70.105016 -88.528906)
		(end 72.89673 -88.528906)
		(width 0.1143)
		(layer "In7.Cu")
		(net "CPLD_ROW_EN")
	)
	(segment
		(start 170.220894 -130.812286)
		(end 176.628044 -130.812286)
		(width 0.1143)
		(layer "In7.Cu")
		(net "CPLD_ROW_EN")
	)
	(segment
		(start 79.895192 -88.92667)
		(end 80.351884 -88.469978)
		(width 0.1143)
		(layer "In7.Cu")
		(net "CPLD_ROW_EN")
	)
	(segment
		(start 108.946696 -87.689944)
		(end 125.391164 -104.134412)
		(width 0.1143)
		(layer "In7.Cu")
		(net "CPLD_ROW_EN")
	)
	(segment
		(start 163.21024 -130.81127)
		(end 163.43249 -131.03352)
		(width 0.1143)
		(layer "In7.Cu")
		(net "CPLD_ROW_EN")
	)
	(segment
		(start 176.628044 -130.812286)
		(end 176.727866 -130.912108)
		(width 0.1143)
		(layer "In7.Cu")
		(net "CPLD_ROW_EN")
	)
	(segment
		(start 80.351884 -88.469978)
		(end 81.604104 -88.469978)
		(width 0.1143)
		(layer "In7.Cu")
		(net "CPLD_ROW_EN")
	)
	(segment
		(start 177.315622 -130.912108)
		(end 179.81168 -128.41605)
		(width 0.1143)
		(layer "In7.Cu")
		(net "CPLD_ROW_EN")
	)
	(segment
		(start 99.446588 -87.689944)
		(end 108.946696 -87.689944)
		(width 0.1143)
		(layer "In7.Cu")
		(net "CPLD_ROW_EN")
	)
	(segment
		(start 76.179934 -88.92667)
		(end 79.895192 -88.92667)
		(width 0.1143)
		(layer "In7.Cu")
		(net "CPLD_ROW_EN")
	)
	(segment
		(start 68.585334 -87.009224)
		(end 70.105016 -88.528906)
		(width 0.1143)
		(layer "In7.Cu")
		(net "CPLD_ROW_EN")
	)
	(segment
		(start 67.82562 -83.857338)
		(end 67.644772 -84.038186)
		(width 0.1143)
		(layer "In7.Cu")
		(net "CPLD_ROW_EN")
	)
	(segment
		(start 72.89673 -88.528906)
		(end 73.398888 -88.026748)
		(width 0.1143)
		(layer "In7.Cu")
		(net "CPLD_ROW_EN")
	)
	(segment
		(start 137.520426 -104.134412)
		(end 141.022578 -107.636564)
		(width 0.1143)
		(layer "In7.Cu")
		(net "CPLD_ROW_EN")
	)
	(segment
		(start 67.644772 -86.433914)
		(end 68.220082 -87.009224)
		(width 0.1143)
		(layer "In7.Cu")
		(net "CPLD_ROW_EN")
	)
	(segment
		(start 81.816956 -88.257126)
		(end 86.070186 -88.257126)
		(width 0.1143)
		(layer "In7.Cu")
		(net "CPLD_ROW_EN")
	)
	(segment
		(start 141.022578 -107.636564)
		(end 142.51813 -107.636564)
		(width 0.1143)
		(layer "In7.Cu")
		(net "CPLD_ROW_EN")
	)
	(segment
		(start 97.456244 -85.6996)
		(end 99.446588 -87.689944)
		(width 0.1143)
		(layer "In7.Cu")
		(net "CPLD_ROW_EN")
	)
	(segment
		(start 125.391164 -104.134412)
		(end 137.520426 -104.134412)
		(width 0.1143)
		(layer "In7.Cu")
		(net "CPLD_ROW_EN")
	)
	(segment
		(start 148.2471 -113.365534)
		(end 148.2471 -117.414802)
		(width 0.1143)
		(layer "In7.Cu")
		(net "CPLD_ROW_EN")
	)
	(segment
		(start 163.43249 -131.03352)
		(end 169.99966 -131.03352)
		(width 0.1143)
		(layer "In7.Cu")
		(net "CPLD_ROW_EN")
	)
	(segment
		(start 169.99966 -131.03352)
		(end 170.220894 -130.812286)
		(width 0.1143)
		(layer "In7.Cu")
		(net "CPLD_ROW_EN")
	)
	(segment
		(start 69.341746 -143.259556)
		(end 69.341746 -143.470122)
		(width 0.1016)
		(layer "F.Cu")
		(net "BMC_DEBUG_RXD")
	)
	(segment
		(start 69.364098 -143.492474)
		(end 69.364098 -143.833342)
		(width 0.1016)
		(layer "F.Cu")
		(net "BMC_DEBUG_RXD")
	)
	(segment
		(start 69.364098 -143.833342)
		(end 68.175378 -145.022062)
		(width 0.1016)
		(layer "F.Cu")
		(net "BMC_DEBUG_RXD")
	)
	(segment
		(start 69.341746 -143.470122)
		(end 69.364098 -143.492474)
		(width 0.1016)
		(layer "F.Cu")
		(net "BMC_DEBUG_RXD")
	)
	(segment
		(start 68.175378 -145.022062)
		(end 68.074286 -145.022062)
		(width 0.1016)
		(layer "F.Cu")
		(net "BMC_DEBUG_RXD")
	)
	(via
		(at 68.074286 -145.022062)
		(size 0.508)
		(drill 0.254)
		(layers "F.Cu" "B.Cu")
		(net "BMC_DEBUG_RXD")
	)
	(segment
		(start 67.670172 -145.426176)
		(end 68.074286 -145.022062)
		(width 0.1016)
		(layer "B.Cu")
		(net "BMC_DEBUG_RXD")
	)
	(segment
		(start 67.670172 -147.480782)
		(end 67.670172 -145.426176)
		(width 0.1016)
		(layer "B.Cu")
		(net "BMC_DEBUG_RXD")
	)
	(segment
		(start 68.5419 -140.05941)
		(end 68.542154 -140.05941)
		(width 0.1016)
		(layer "F.Cu")
		(net "BMC_DEBUG_TXD")
	)
	(segment
		(start 68.542154 -140.05941)
		(end 68.940934 -140.45819)
		(width 0.1016)
		(layer "F.Cu")
		(net "BMC_DEBUG_TXD")
	)
	(via
		(at 68.940934 -140.45819)
		(size 0.49022)
		(drill 0.254)
		(layers "F.Cu" "B.Cu")
		(net "BMC_DEBUG_TXD")
	)
	(via
		(at 67.588892 -142.738602)
		(size 0.6604)
		(drill 0.3302)
		(layers "F.Cu" "B.Cu")
		(net "BMC_DEBUG_TXD")
	)
	(segment
		(start 70.316852 -146.551142)
		(end 70.316852 -145.695162)
		(width 0.1016)
		(layer "B.Cu")
		(net "BMC_DEBUG_TXD")
	)
	(segment
		(start 70.50786 -146.741642)
		(end 70.31736 -146.551142)
		(width 0.1016)
		(layer "B.Cu")
		(net "BMC_DEBUG_TXD")
	)
	(segment
		(start 70.316852 -145.695162)
		(end 67.588892 -142.967202)
		(width 0.1016)
		(layer "B.Cu")
		(net "BMC_DEBUG_TXD")
	)
	(segment
		(start 70.31736 -146.551142)
		(end 70.316852 -146.551142)
		(width 0.1016)
		(layer "B.Cu")
		(net "BMC_DEBUG_TXD")
	)
	(segment
		(start 68.940934 -140.45819)
		(end 67.588892 -141.810232)
		(width 0.1016)
		(layer "B.Cu")
		(net "BMC_DEBUG_TXD")
	)
	(segment
		(start 67.588892 -142.967202)
		(end 67.588892 -142.738602)
		(width 0.1016)
		(layer "B.Cu")
		(net "BMC_DEBUG_TXD")
	)
	(segment
		(start 67.588892 -141.810232)
		(end 67.588892 -142.738602)
		(width 0.1016)
		(layer "B.Cu")
		(net "BMC_DEBUG_TXD")
	)
	(segment
		(start 70.50786 -147.252436)
		(end 70.50786 -146.741642)
		(width 0.1016)
		(layer "B.Cu")
		(net "BMC_DEBUG_TXD")
	)
	(segment
		(start 66.9417 -127.259588)
		(end 67.337686 -126.863602)
		(width 0.1016)
		(layer "F.Cu")
		(net "PU_I2C_BMC_SCL")
	)
	(segment
		(start 67.337686 -126.302262)
		(end 66.507868 -125.472444)
		(width 0.1016)
		(layer "F.Cu")
		(net "PU_I2C_BMC_SCL")
	)
	(segment
		(start 67.337686 -126.863602)
		(end 67.337686 -126.302262)
		(width 0.1016)
		(layer "F.Cu")
		(net "PU_I2C_BMC_SCL")
	)
	(segment
		(start 66.507868 -125.472444)
		(end 66.507868 -123.15698)
		(width 0.1016)
		(layer "F.Cu")
		(net "PU_I2C_BMC_SCL")
	)
	(segment
		(start 66.194686 -121.444512)
		(end 66.884296 -122.134122)
		(width 0.1016)
		(layer "F.Cu")
		(net "PU_I2C_BMC_SCL")
	)
	(segment
		(start 66.884296 -122.134122)
		(end 66.884296 -122.780552)
		(width 0.1016)
		(layer "F.Cu")
		(net "PU_I2C_BMC_SCL")
	)
	(segment
		(start 66.507868 -123.15698)
		(end 66.884296 -122.780552)
		(width 0.1016)
		(layer "F.Cu")
		(net "PU_I2C_BMC_SCL")
	)
	(via
		(at 66.884296 -122.780552)
		(size 0.762)
		(drill 0.381)
		(layers "F.Cu" "B.Cu")
		(net "PU_I2C_BMC_SCL")
	)
	(segment
		(start 66.056002 -122.118374)
		(end 65.73266 -121.795032)
		(width 0.1016)
		(layer "F.Cu")
		(net "PU_I2C_BMC_SDA")
	)
	(segment
		(start 65.73266 -121.795032)
		(end 65.73266 -118.885462)
		(width 0.1016)
		(layer "F.Cu")
		(net "PU_I2C_BMC_SDA")
	)
	(segment
		(start 66.9417 -126.459488)
		(end 66.9417 -126.338076)
		(width 0.1016)
		(layer "F.Cu")
		(net "PU_I2C_BMC_SDA")
	)
	(segment
		(start 65.73266 -118.885462)
		(end 65.74282 -118.875302)
		(width 0.1016)
		(layer "F.Cu")
		(net "PU_I2C_BMC_SDA")
	)
	(segment
		(start 66.194686 -118.358412)
		(end 66.194686 -117.965728)
		(width 0.1016)
		(layer "F.Cu")
		(net "PU_I2C_BMC_SDA")
	)
	(segment
		(start 66.9417 -126.338076)
		(end 66.056002 -125.452378)
		(width 0.1016)
		(layer "F.Cu")
		(net "PU_I2C_BMC_SDA")
	)
	(segment
		(start 66.194686 -117.965728)
		(end 67.006978 -117.153436)
		(width 0.1016)
		(layer "F.Cu")
		(net "PU_I2C_BMC_SDA")
	)
	(segment
		(start 65.74282 -118.875302)
		(end 65.74282 -118.810278)
		(width 0.1016)
		(layer "F.Cu")
		(net "PU_I2C_BMC_SDA")
	)
	(segment
		(start 66.056002 -125.452378)
		(end 66.056002 -122.118374)
		(width 0.1016)
		(layer "F.Cu")
		(net "PU_I2C_BMC_SDA")
	)
	(segment
		(start 65.74282 -118.810278)
		(end 66.194686 -118.358412)
		(width 0.1016)
		(layer "F.Cu")
		(net "PU_I2C_BMC_SDA")
	)
	(via
		(at 67.006978 -117.153436)
		(size 0.508)
		(drill 0.254)
		(layers "F.Cu" "B.Cu")
		(net "PU_I2C_BMC_SDA")
	)
	(segment
		(start 79.281782 -162.92068)
		(end 79.091028 -162.729926)
		(width 0.1016)
		(layer "F.Cu")
		(net "CMC_CPLD_RSV1")
	)
	(segment
		(start 79.091028 -162.729926)
		(end 79.091028 -161.399728)
		(width 0.1016)
		(layer "F.Cu")
		(net "CMC_CPLD_RSV1")
	)
	(segment
		(start 118.39194 -165.367716)
		(end 118.73992 -165.019736)
		(width 0.1016)
		(layer "F.Cu")
		(net "CMC_CPLD_RSV1")
	)
	(segment
		(start 79.494888 -164.374576)
		(end 79.494888 -163.237926)
		(width 0.1016)
		(layer "F.Cu")
		(net "CMC_CPLD_RSV1")
	)
	(segment
		(start 79.281782 -163.02482)
		(end 79.281782 -162.92068)
		(width 0.1016)
		(layer "F.Cu")
		(net "CMC_CPLD_RSV1")
	)
	(segment
		(start 118.39194 -166.566596)
		(end 118.39194 -165.367716)
		(width 0.1016)
		(layer "F.Cu")
		(net "CMC_CPLD_RSV1")
	)
	(segment
		(start 119.184166 -163.412932)
		(end 119.184166 -162.08629)
		(width 0.1016)
		(layer "F.Cu")
		(net "CMC_CPLD_RSV1")
	)
	(segment
		(start 79.494888 -163.237926)
		(end 79.281782 -163.02482)
		(width 0.1016)
		(layer "F.Cu")
		(net "CMC_CPLD_RSV1")
	)
	(segment
		(start 120.60936 -166.906702)
		(end 119.59336 -166.906702)
		(width 0.1016)
		(layer "F.Cu")
		(net "CMC_CPLD_RSV1")
	)
	(segment
		(start 119.495316 -167.004746)
		(end 118.83009 -167.004746)
		(width 0.1016)
		(layer "F.Cu")
		(net "CMC_CPLD_RSV1")
	)
	(segment
		(start 119.59336 -166.906702)
		(end 119.495316 -167.004746)
		(width 0.1016)
		(layer "F.Cu")
		(net "CMC_CPLD_RSV1")
	)
	(segment
		(start 118.73992 -165.019736)
		(end 118.73992 -163.857178)
		(width 0.1016)
		(layer "F.Cu")
		(net "CMC_CPLD_RSV1")
	)
	(segment
		(start 118.73992 -163.857178)
		(end 119.184166 -163.412932)
		(width 0.1016)
		(layer "F.Cu")
		(net "CMC_CPLD_RSV1")
	)
	(segment
		(start 118.83009 -167.004746)
		(end 118.39194 -166.566596)
		(width 0.1016)
		(layer "F.Cu")
		(net "CMC_CPLD_RSV1")
	)
	(via
		(at 79.091028 -161.399728)
		(size 0.508)
		(drill 0.254)
		(layers "F.Cu" "B.Cu")
		(net "CMC_CPLD_RSV1")
	)
	(via
		(at 119.184166 -162.08629)
		(size 0.508)
		(drill 0.254)
		(layers "F.Cu" "B.Cu")
		(net "CMC_CPLD_RSV1")
	)
	(segment
		(start 101.934264 -164.44722)
		(end 97.95256 -164.44722)
		(width 0.1143)
		(layer "In6.Cu")
		(net "CMC_CPLD_RSV1")
	)
	(segment
		(start 102.561644 -163.81984)
		(end 101.934264 -164.44722)
		(width 0.1143)
		(layer "In6.Cu")
		(net "CMC_CPLD_RSV1")
	)
	(segment
		(start 80.93202 -163.31819)
		(end 80.93202 -163.24072)
		(width 0.1143)
		(layer "In6.Cu")
		(net "CMC_CPLD_RSV1")
	)
	(segment
		(start 97.190814 -163.685474)
		(end 95.005652 -163.685474)
		(width 0.1143)
		(layer "In6.Cu")
		(net "CMC_CPLD_RSV1")
	)
	(segment
		(start 109.32287 -160.971992)
		(end 106.475022 -163.81984)
		(width 0.1143)
		(layer "In6.Cu")
		(net "CMC_CPLD_RSV1")
	)
	(segment
		(start 117.505988 -161.596324)
		(end 116.67363 -160.763966)
		(width 0.1143)
		(layer "In6.Cu")
		(net "CMC_CPLD_RSV1")
	)
	(segment
		(start 119.184166 -162.084004)
		(end 118.696486 -161.596324)
		(width 0.1143)
		(layer "In6.Cu")
		(net "CMC_CPLD_RSV1")
	)
	(segment
		(start 97.95256 -164.44722)
		(end 97.190814 -163.685474)
		(width 0.1143)
		(layer "In6.Cu")
		(net "CMC_CPLD_RSV1")
	)
	(segment
		(start 80.93202 -163.24072)
		(end 79.091028 -161.399728)
		(width 0.1143)
		(layer "In6.Cu")
		(net "CMC_CPLD_RSV1")
	)
	(segment
		(start 94.353888 -164.337238)
		(end 81.951068 -164.337238)
		(width 0.1143)
		(layer "In6.Cu")
		(net "CMC_CPLD_RSV1")
	)
	(segment
		(start 106.475022 -163.81984)
		(end 102.561644 -163.81984)
		(width 0.1143)
		(layer "In6.Cu")
		(net "CMC_CPLD_RSV1")
	)
	(segment
		(start 95.005652 -163.685474)
		(end 94.353888 -164.337238)
		(width 0.1143)
		(layer "In6.Cu")
		(net "CMC_CPLD_RSV1")
	)
	(segment
		(start 116.67363 -160.763966)
		(end 112.072166 -160.763966)
		(width 0.1143)
		(layer "In6.Cu")
		(net "CMC_CPLD_RSV1")
	)
	(segment
		(start 81.951068 -164.337238)
		(end 80.93202 -163.31819)
		(width 0.1143)
		(layer "In6.Cu")
		(net "CMC_CPLD_RSV1")
	)
	(segment
		(start 112.072166 -160.763966)
		(end 111.86414 -160.971992)
		(width 0.1143)
		(layer "In6.Cu")
		(net "CMC_CPLD_RSV1")
	)
	(segment
		(start 118.696486 -161.596324)
		(end 117.505988 -161.596324)
		(width 0.1143)
		(layer "In6.Cu")
		(net "CMC_CPLD_RSV1")
	)
	(segment
		(start 119.184166 -162.08629)
		(end 119.184166 -162.084004)
		(width 0.1143)
		(layer "In6.Cu")
		(net "CMC_CPLD_RSV1")
	)
	(segment
		(start 111.86414 -160.971992)
		(end 109.32287 -160.971992)
		(width 0.1143)
		(layer "In6.Cu")
		(net "CMC_CPLD_RSV1")
	)
	(segment
		(start 59.330336 -164.934646)
		(end 59.330336 -165.739826)
		(width 0.508)
		(layer "F.Cu")
		(net "P3V3_STB_NODE1")
	)
	(segment
		(start 157.47238 -138.87577)
		(end 157.474666 -138.878056)
		(width 0.508)
		(layer "F.Cu")
		(net "P3V3_STB_NODE1")
	)
	(segment
		(start 88.85936 -163.14039)
		(end 89.337134 -163.618164)
		(width 0.508)
		(layer "F.Cu")
		(net "P3V3_STB_NODE1")
	)
	(segment
		(start 32.07004 -119.448072)
		(end 32.07004 -119.447818)
		(width 0.508)
		(layer "F.Cu")
		(net "P3V3_STB_NODE1")
	)
	(segment
		(start 70.55485 -100.256848)
		(end 70.55485 -100.254562)
		(width 0.508)
		(layer "F.Cu")
		(net "P3V3_STB_NODE1")
	)
	(segment
		(start 133.33857 -25.237186)
		(end 133.33857 -26.169366)
		(width 0.508)
		(layer "F.Cu")
		(net "P3V3_STB_NODE1")
	)
	(segment
		(start 157.212284 -138.119358)
		(end 157.47238 -138.379454)
		(width 0.508)
		(layer "F.Cu")
		(net "P3V3_STB_NODE1")
	)
	(segment
		(start 130.29057 -26.169366)
		(end 130.29057 -25.508712)
		(width 0.508)
		(layer "F.Cu")
		(net "P3V3_STB_NODE1")
	)
	(segment
		(start 175.010318 -121.365518)
		(end 175.010318 -121.365772)
		(width 0.508)
		(layer "F.Cu")
		(net "P3V3_STB_NODE1")
	)
	(segment
		(start 42.2402 -115.80241)
		(end 43.51274 -117.07495)
		(width 0.254)
		(layer "F.Cu")
		(net "P3V3_STB_NODE1")
	)
	(segment
		(start 175.010318 -120.36552)
		(end 174.510446 -119.865648)
		(width 0.508)
		(layer "F.Cu")
		(net "P3V3_STB_NODE1")
	)
	(segment
		(start 70.55485 -101.397562)
		(end 70.55485 -100.256848)
		(width 0.508)
		(layer "F.Cu")
		(net "P3V3_STB_NODE1")
	)
	(segment
		(start 157.212284 -137.668762)
		(end 157.212284 -138.119358)
		(width 0.508)
		(layer "F.Cu")
		(net "P3V3_STB_NODE1")
	)
	(segment
		(start 95.55226 -180.659786)
		(end 97.441766 -182.549292)
		(width 0.508)
		(layer "F.Cu")
		(net "P3V3_STB_NODE1")
	)
	(segment
		(start 178.010566 -122.365516)
		(end 178.510438 -121.865644)
		(width 0.4572)
		(layer "F.Cu")
		(net "P3V3_STB_NODE1")
	)
	(segment
		(start 53.319172 -113.68405)
		(end 59.261248 -113.68405)
		(width 0.254)
		(layer "F.Cu")
		(net "P3V3_STB_NODE1")
	)
	(segment
		(start 176.010316 -122.36577)
		(end 175.510444 -122.865642)
		(width 0.508)
		(layer "F.Cu")
		(net "P3V3_STB_NODE1")
	)
	(segment
		(start 178.010566 -120.36552)
		(end 178.510438 -119.865648)
		(width 0.508)
		(layer "F.Cu")
		(net "P3V3_STB_NODE1")
	)
	(segment
		(start 187.992004 -121.65965)
		(end 188.814456 -121.65965)
		(width 0.4572)
		(layer "F.Cu")
		(net "P3V3_STB_NODE1")
	)
	(segment
		(start 59.671458 -111.743744)
		(end 59.652408 -111.762794)
		(width 0.254)
		(layer "F.Cu")
		(net "P3V3_STB_NODE1")
	)
	(segment
		(start 42.652696 -113.355628)
		(end 42.2402 -113.768124)
		(width 0.254)
		(layer "F.Cu")
		(net "P3V3_STB_NODE1")
	)
	(segment
		(start 188.7601 -122.811794)
		(end 188.7601 -122.809508)
		(width 0.4572)
		(layer "F.Cu")
		(net "P3V3_STB_NODE1")
	)
	(segment
		(start 178.010566 -120.365774)
		(end 178.010566 -120.36552)
		(width 0.508)
		(layer "F.Cu")
		(net "P3V3_STB_NODE1")
	)
	(segment
		(start 32.099758 -118.551452)
		(end 32.944054 -118.551452)
		(width 0.508)
		(layer "F.Cu")
		(net "P3V3_STB_NODE1")
	)
	(segment
		(start 59.261248 -113.68405)
		(end 59.652408 -113.29289)
		(width 0.254)
		(layer "F.Cu")
		(net "P3V3_STB_NODE1")
	)
	(segment
		(start 129.27457 -26.169366)
		(end 129.27457 -25.394412)
		(width 0.508)
		(layer "F.Cu")
		(net "P3V3_STB_NODE1")
	)
	(segment
		(start 179.764944 -130.36042)
		(end 179.764944 -129.57556)
		(width 0.508)
		(layer "F.Cu")
		(net "P3V3_STB_NODE1")
	)
	(segment
		(start 91.803982 -137.981944)
		(end 90.899234 -137.981944)
		(width 0.4572)
		(layer "F.Cu")
		(net "P3V3_STB_NODE1")
	)
	(segment
		(start 176.010316 -119.365522)
		(end 175.510444 -118.86565)
		(width 0.508)
		(layer "F.Cu")
		(net "P3V3_STB_NODE1")
	)
	(segment
		(start 176.01057 -119.365522)
		(end 176.010316 -119.365522)
		(width 0.508)
		(layer "F.Cu")
		(net "P3V3_STB_NODE1")
	)
	(segment
		(start 65.734692 -106.915966)
		(end 65.734692 -106.068876)
		(width 0.508)
		(layer "F.Cu")
		(net "P3V3_STB_NODE1")
	)
	(segment
		(start 71.089774 -100.256848)
		(end 70.55485 -100.256848)
		(width 0.508)
		(layer "F.Cu")
		(net "P3V3_STB_NODE1")
	)
	(segment
		(start 157.47238 -138.379454)
		(end 157.47238 -138.87577)
		(width 0.508)
		(layer "F.Cu")
		(net "P3V3_STB_NODE1")
	)
	(segment
		(start 32.773112 -107.26928)
		(end 32.773112 -108.100622)
		(width 0.508)
		(layer "F.Cu")
		(net "P3V3_STB_NODE1")
	)
	(segment
		(start 34.63544 -122.426476)
		(end 34.63544 -122.209814)
		(width 0.508)
		(layer "F.Cu")
		(net "P3V3_STB_NODE1")
	)
	(segment
		(start 32.18942 -119.567452)
		(end 32.07004 -119.448072)
		(width 0.508)
		(layer "F.Cu")
		(net "P3V3_STB_NODE1")
	)
	(segment
		(start 42.652696 -112.033558)
		(end 44.873418 -112.033558)
		(width 0.254)
		(layer "F.Cu")
		(net "P3V3_STB_NODE1")
	)
	(segment
		(start 34.66338 -122.426476)
		(end 34.63544 -122.426476)
		(width 0.508)
		(layer "F.Cu")
		(net "P3V3_STB_NODE1")
	)
	(segment
		(start 166.30777 -123.76531)
		(end 165.45433 -123.76531)
		(width 0.508)
		(layer "F.Cu")
		(net "P3V3_STB_NODE1")
	)
	(segment
		(start 44.873418 -112.033558)
		(end 45.108622 -111.798354)
		(width 0.254)
		(layer "F.Cu")
		(net "P3V3_STB_NODE1")
	)
	(segment
		(start 178.859942 -139.65301)
		(end 179.897532 -139.65301)
		(width 0.508)
		(layer "F.Cu")
		(net "P3V3_STB_NODE1")
	)
	(segment
		(start 71.30542 -100.041202)
		(end 71.089774 -100.256848)
		(width 0.508)
		(layer "F.Cu")
		(net "P3V3_STB_NODE1")
	)
	(segment
		(start 119.377968 -155.754578)
		(end 120.216676 -155.754578)
		(width 0.508)
		(layer "F.Cu")
		(net "P3V3_STB_NODE1")
	)
	(segment
		(start 176.01057 -122.36577)
		(end 176.010316 -122.36577)
		(width 0.508)
		(layer "F.Cu")
		(net "P3V3_STB_NODE1")
	)
	(segment
		(start 88.30818 -163.14039)
		(end 88.85936 -163.14039)
		(width 0.508)
		(layer "F.Cu")
		(net "P3V3_STB_NODE1")
	)
	(segment
		(start 132.32257 -26.169366)
		(end 132.32257 -25.512776)
		(width 0.508)
		(layer "F.Cu")
		(net "P3V3_STB_NODE1")
	)
	(segment
		(start 116.929154 -63.422784)
		(end 116.929154 -62.557914)
		(width 0.508)
		(layer "F.Cu")
		(net "P3V3_STB_NODE1")
	)
	(segment
		(start 161.889948 -72.400668)
		(end 162.588448 -72.400668)
		(width 0.4064)
		(layer "F.Cu")
		(net "P3V3_STB_NODE1")
	)
	(segment
		(start 116.929154 -62.557914)
		(end 116.83746 -62.46622)
		(width 0.508)
		(layer "F.Cu")
		(net "P3V3_STB_NODE1")
	)
	(segment
		(start 42.2402 -113.768124)
		(end 42.2402 -115.80241)
		(width 0.254)
		(layer "F.Cu")
		(net "P3V3_STB_NODE1")
	)
	(segment
		(start 71.30542 -100.039424)
		(end 71.30542 -100.041202)
		(width 0.508)
		(layer "F.Cu")
		(net "P3V3_STB_NODE1")
	)
	(segment
		(start 187.986416 -122.844814)
		(end 188.72708 -122.844814)
		(width 0.4572)
		(layer "F.Cu")
		(net "P3V3_STB_NODE1")
	)
	(segment
		(start 27.932888 -130.989832)
		(end 27.932888 -131.955032)
		(width 0.508)
		(layer "F.Cu")
		(net "P3V3_STB_NODE1")
	)
	(segment
		(start 84.62264 -109.19968)
		(end 84.94268 -108.87964)
		(width 0.508)
		(layer "F.Cu")
		(net "P3V3_STB_NODE1")
	)
	(segment
		(start 178.010566 -121.365518)
		(end 178.010566 -121.365772)
		(width 0.508)
		(layer "F.Cu")
		(net "P3V3_STB_NODE1")
	)
	(segment
		(start 181.05628 -130.412236)
		(end 181.05628 -131.990338)
		(width 0.508)
		(layer "F.Cu")
		(net "P3V3_STB_NODE1")
	)
	(segment
		(start 152.355804 -136.171432)
		(end 151.52624 -136.171432)
		(width 0.508)
		(layer "F.Cu")
		(net "P3V3_STB_NODE1")
	)
	(segment
		(start 84.150708 -109.19968)
		(end 84.62264 -109.19968)
		(width 0.508)
		(layer "F.Cu")
		(net "P3V3_STB_NODE1")
	)
	(segment
		(start 119.83593 -69.308218)
		(end 119.83593 -68.057014)
		(width 0.508)
		(layer "F.Cu")
		(net "P3V3_STB_NODE1")
	)
	(segment
		(start 178.010566 -121.365772)
		(end 178.510438 -121.865644)
		(width 0.508)
		(layer "F.Cu")
		(net "P3V3_STB_NODE1")
	)
	(segment
		(start 61.38418 -164.910262)
		(end 61.38418 -165.749732)
		(width 0.508)
		(layer "F.Cu")
		(net "P3V3_STB_NODE1")
	)
	(segment
		(start 178.010566 -119.365522)
		(end 178.510438 -118.86565)
		(width 0.508)
		(layer "F.Cu")
		(net "P3V3_STB_NODE1")
	)
	(segment
		(start 83.06054 -108.09859)
		(end 83.38566 -107.77347)
		(width 0.508)
		(layer "F.Cu")
		(net "P3V3_STB_NODE1")
	)
	(segment
		(start 128.25857 -26.169366)
		(end 128.25857 -25.35682)
		(width 0.508)
		(layer "F.Cu")
		(net "P3V3_STB_NODE1")
	)
	(segment
		(start 89.337134 -163.618164)
		(end 89.831418 -163.618164)
		(width 0.508)
		(layer "F.Cu")
		(net "P3V3_STB_NODE1")
	)
	(segment
		(start 32.944054 -119.567452)
		(end 32.18942 -119.567452)
		(width 0.508)
		(layer "F.Cu")
		(net "P3V3_STB_NODE1")
	)
	(segment
		(start 162.162744 -131.24942)
		(end 163.027868 -131.24942)
		(width 0.508)
		(layer "F.Cu")
		(net "P3V3_STB_NODE1")
	)
	(segment
		(start 127.24257 -26.169366)
		(end 127.24257 -25.435306)
		(width 0.508)
		(layer "F.Cu")
		(net "P3V3_STB_NODE1")
	)
	(segment
		(start 32.099758 -118.551452)
		(end 32.099758 -119.4181)
		(width 0.508)
		(layer "F.Cu")
		(net "P3V3_STB_NODE1")
	)
	(segment
		(start 90.705686 -137.788396)
		(end 90.705686 -135.959088)
		(width 0.4572)
		(layer "F.Cu")
		(net "P3V3_STB_NODE1")
	)
	(segment
		(start 45.108622 -111.798354)
		(end 45.108622 -111.452914)
		(width 0.254)
		(layer "F.Cu")
		(net "P3V3_STB_NODE1")
	)
	(segment
		(start 34.63544 -122.209814)
		(end 32.944054 -120.518428)
		(width 0.508)
		(layer "F.Cu")
		(net "P3V3_STB_NODE1")
	)
	(segment
		(start 176.267364 -133.022848)
		(end 177.10404 -133.022848)
		(width 0.508)
		(layer "F.Cu")
		(net "P3V3_STB_NODE1")
	)
	(segment
		(start 83.38566 -107.77347)
		(end 83.38566 -107.773216)
		(width 0.508)
		(layer "F.Cu")
		(net "P3V3_STB_NODE1")
	)
	(segment
		(start 43.51274 -117.07495)
		(end 48.57242 -117.07495)
		(width 0.254)
		(layer "F.Cu")
		(net "P3V3_STB_NODE1")
	)
	(segment
		(start 158.190692 -138.878056)
		(end 157.474666 -138.878056)
		(width 0.508)
		(layer "F.Cu")
		(net "P3V3_STB_NODE1")
	)
	(segment
		(start 32.099758 -119.4181)
		(end 32.07004 -119.447818)
		(width 0.508)
		(layer "F.Cu")
		(net "P3V3_STB_NODE1")
	)
	(segment
		(start 42.652696 -113.038636)
		(end 42.652696 -113.355628)
		(width 0.254)
		(layer "F.Cu")
		(net "P3V3_STB_NODE1")
	)
	(segment
		(start 126.22657 -26.169366)
		(end 126.22657 -25.389332)
		(width 0.508)
		(layer "F.Cu")
		(net "P3V3_STB_NODE1")
	)
	(segment
		(start 97.441766 -182.549292)
		(end 102.113842 -182.549292)
		(width 0.508)
		(layer "F.Cu")
		(net "P3V3_STB_NODE1")
	)
	(segment
		(start 174.411894 -131.03987)
		(end 174.411894 -131.876546)
		(width 0.508)
		(layer "F.Cu")
		(net "P3V3_STB_NODE1")
	)
	(segment
		(start 134.35457 -25.344374)
		(end 134.35457 -26.169366)
		(width 0.508)
		(layer "F.Cu")
		(net "P3V3_STB_NODE1")
	)
	(segment
		(start 82.740246 -108.09859)
		(end 83.06054 -108.09859)
		(width 0.508)
		(layer "F.Cu")
		(net "P3V3_STB_NODE1")
	)
	(segment
		(start 188.72708 -122.844814)
		(end 188.7601 -122.811794)
		(width 0.4572)
		(layer "F.Cu")
		(net "P3V3_STB_NODE1")
	)
	(segment
		(start 50.61712 -116.386102)
		(end 53.319172 -113.68405)
		(width 0.254)
		(layer "F.Cu")
		(net "P3V3_STB_NODE1")
	)
	(segment
		(start 42.652696 -112.033558)
		(end 42.652696 -113.038636)
		(width 0.254)
		(layer "F.Cu")
		(net "P3V3_STB_NODE1")
	)
	(segment
		(start 173.45152 -137.05459)
		(end 174.544482 -137.05459)
		(width 0.508)
		(layer "F.Cu")
		(net "P3V3_STB_NODE1")
	)
	(segment
		(start 90.705686 -135.959088)
		(end 90.88628 -135.778494)
		(width 0.4572)
		(layer "F.Cu")
		(net "P3V3_STB_NODE1")
	)
	(segment
		(start 178.010566 -122.36577)
		(end 178.010566 -122.365516)
		(width 0.4572)
		(layer "F.Cu")
		(net "P3V3_STB_NODE1")
	)
	(segment
		(start 175.010318 -121.365772)
		(end 174.510446 -121.865644)
		(width 0.508)
		(layer "F.Cu")
		(net "P3V3_STB_NODE1")
	)
	(segment
		(start 177.10404 -133.022848)
		(end 177.403252 -133.32206)
		(width 0.508)
		(layer "F.Cu")
		(net "P3V3_STB_NODE1")
	)
	(segment
		(start 175.010318 -120.365774)
		(end 175.010318 -120.36552)
		(width 0.508)
		(layer "F.Cu")
		(net "P3V3_STB_NODE1")
	)
	(segment
		(start 48.57242 -117.07495)
		(end 49.261268 -116.386102)
		(width 0.254)
		(layer "F.Cu")
		(net "P3V3_STB_NODE1")
	)
	(segment
		(start 92.85986 -159.426402)
		(end 92.33662 -159.949642)
		(width 0.508)
		(layer "F.Cu")
		(net "P3V3_STB_NODE1")
	)
	(segment
		(start 171.551092 -136.335008)
		(end 172.267118 -136.335008)
		(width 0.508)
		(layer "F.Cu")
		(net "P3V3_STB_NODE1")
	)
	(segment
		(start 102.113842 -182.549292)
		(end 103.30688 -183.74233)
		(width 0.508)
		(layer "F.Cu")
		(net "P3V3_STB_NODE1")
	)
	(segment
		(start 135.37057 -26.169366)
		(end 135.37057 -25.553416)
		(width 0.508)
		(layer "F.Cu")
		(net "P3V3_STB_NODE1")
	)
	(segment
		(start 49.261268 -116.386102)
		(end 50.61712 -116.386102)
		(width 0.254)
		(layer "F.Cu")
		(net "P3V3_STB_NODE1")
	)
	(segment
		(start 59.652408 -113.29289)
		(end 59.652408 -111.762794)
		(width 0.254)
		(layer "F.Cu")
		(net "P3V3_STB_NODE1")
	)
	(segment
		(start 93.339158 -159.426402)
		(end 92.85986 -159.426402)
		(width 0.508)
		(layer "F.Cu")
		(net "P3V3_STB_NODE1")
	)
	(segment
		(start 92.33662 -159.949642)
		(end 92.33662 -159.950658)
		(width 0.508)
		(layer "F.Cu")
		(net "P3V3_STB_NODE1")
	)
	(segment
		(start 85.518752 -136.608312)
		(end 86.616794 -136.608312)
		(width 0.508)
		(layer "F.Cu")
		(net "P3V3_STB_NODE1")
	)
	(segment
		(start 90.899234 -137.981944)
		(end 90.705686 -137.788396)
		(width 0.4572)
		(layer "F.Cu")
		(net "P3V3_STB_NODE1")
	)
	(segment
		(start 111.77016 -153.688034)
		(end 111.77016 -154.568398)
		(width 0.508)
		(layer "F.Cu")
		(net "P3V3_STB_NODE1")
	)
	(segment
		(start 64.718692 -106.915966)
		(end 64.718692 -106.102912)
		(width 0.508)
		(layer "F.Cu")
		(net "P3V3_STB_NODE1")
	)
	(segment
		(start 32.944054 -120.518428)
		(end 32.944054 -119.567452)
		(width 0.508)
		(layer "F.Cu")
		(net "P3V3_STB_NODE1")
	)
	(segment
		(start 183.485282 -131.002278)
		(end 182.710328 -131.002278)
		(width 0.508)
		(layer "F.Cu")
		(net "P3V3_STB_NODE1")
	)
	(segment
		(start 131.30657 -26.169366)
		(end 131.30657 -25.484582)
		(width 0.508)
		(layer "F.Cu")
		(net "P3V3_STB_NODE1")
	)
	(via
		(at 119.83593 -68.057014)
		(size 0.508)
		(drill 0.254)
		(layers "F.Cu" "B.Cu")
		(net "P3V3_STB_NODE1")
	)
	(via
		(at 99.22764 -174.478442)
		(size 0.508)
		(drill 0.254)
		(layers "F.Cu" "B.Cu")
		(net "P3V3_STB_NODE1")
	)
	(via
		(at 134.35457 -25.344374)
		(size 0.508)
		(drill 0.254)
		(layers "F.Cu" "B.Cu")
		(net "P3V3_STB_NODE1")
	)
	(via
		(at 181.05628 -131.990338)
		(size 0.508)
		(drill 0.254)
		(layers "F.Cu" "B.Cu")
		(net "P3V3_STB_NODE1")
	)
	(via
		(at 58.142124 -110.12424)
		(size 0.508)
		(drill 0.254)
		(layers "F.Cu" "B.Cu")
		(net "P3V3_STB_NODE1")
	)
	(via
		(at 178.510438 -119.865648)
		(size 0.49022)
		(drill 0.254)
		(layers "F.Cu" "B.Cu")
		(net "P3V3_STB_NODE1")
	)
	(via
		(at 103.30688 -183.74233)
		(size 0.508)
		(drill 0.254)
		(layers "F.Cu" "B.Cu")
		(net "P3V3_STB_NODE1")
	)
	(via
		(at 175.510444 -122.865642)
		(size 0.49022)
		(drill 0.254)
		(layers "F.Cu" "B.Cu")
		(net "P3V3_STB_NODE1")
	)
	(via
		(at 103.11638 -65.148206)
		(size 0.508)
		(drill 0.254)
		(layers "F.Cu" "B.Cu")
		(net "P3V3_STB_NODE1")
	)
	(via
		(at 162.588448 -72.400668)
		(size 0.508)
		(drill 0.254)
		(layers "F.Cu" "B.Cu")
		(net "P3V3_STB_NODE1")
	)
	(via
		(at 172.267118 -136.335008)
		(size 0.508)
		(drill 0.254)
		(layers "F.Cu" "B.Cu")
		(net "P3V3_STB_NODE1")
	)
	(via
		(at 35.38474 -121.437908)
		(size 0.508)
		(drill 0.254)
		(layers "F.Cu" "B.Cu")
		(net "P3V3_STB_NODE1")
	)
	(via
		(at 188.814456 -121.65965)
		(size 0.508)
		(drill 0.254)
		(layers "F.Cu" "B.Cu")
		(net "P3V3_STB_NODE1")
	)
	(via
		(at 57.156096 -112.386618)
		(size 0.508)
		(drill 0.254)
		(layers "F.Cu" "B.Cu")
		(net "P3V3_STB_NODE1")
	)
	(via
		(at 82.875628 -101.534722)
		(size 0.508)
		(drill 0.254)
		(layers "F.Cu" "B.Cu")
		(net "P3V3_STB_NODE1")
	)
	(via
		(at 158.190692 -138.878056)
		(size 0.508)
		(drill 0.254)
		(layers "F.Cu" "B.Cu")
		(net "P3V3_STB_NODE1")
	)
	(via
		(at 182.710328 -131.002278)
		(size 0.508)
		(drill 0.254)
		(layers "F.Cu" "B.Cu")
		(net "P3V3_STB_NODE1")
	)
	(via
		(at 132.32257 -25.512776)
		(size 0.508)
		(drill 0.254)
		(layers "F.Cu" "B.Cu")
		(net "P3V3_STB_NODE1")
	)
	(via
		(at 34.66338 -122.426476)
		(size 0.508)
		(drill 0.254)
		(layers "F.Cu" "B.Cu")
		(net "P3V3_STB_NODE1")
	)
	(via
		(at 6.092698 -3.296158)
		(size 0.508)
		(drill 0.254)
		(layers "F.Cu" "B.Cu")
		(net "P3V3_STB_NODE1")
	)
	(via
		(at 81.570576 -101.509322)
		(size 0.508)
		(drill 0.254)
		(layers "F.Cu" "B.Cu")
		(net "P3V3_STB_NODE1")
	)
	(via
		(at 128.25857 -25.35682)
		(size 0.508)
		(drill 0.254)
		(layers "F.Cu" "B.Cu")
		(net "P3V3_STB_NODE1")
	)
	(via
		(at 102.932992 -69.273674)
		(size 0.508)
		(drill 0.254)
		(layers "F.Cu" "B.Cu")
		(net "P3V3_STB_NODE1")
	)
	(via
		(at 86.616794 -136.608312)
		(size 0.508)
		(drill 0.254)
		(layers "F.Cu" "B.Cu")
		(net "P3V3_STB_NODE1")
	)
	(via
		(at 92.33662 -159.950658)
		(size 0.508)
		(drill 0.254)
		(layers "F.Cu" "B.Cu")
		(net "P3V3_STB_NODE1")
	)
	(via
		(at 27.932888 -131.955032)
		(size 0.508)
		(drill 0.254)
		(layers "F.Cu" "B.Cu")
		(net "P3V3_STB_NODE1")
	)
	(via
		(at 56.351932 -112.3442)
		(size 0.508)
		(drill 0.254)
		(layers "F.Cu" "B.Cu")
		(net "P3V3_STB_NODE1")
	)
	(via
		(at 173.89348 -136.124442)
		(size 0.508)
		(drill 0.254)
		(layers "F.Cu" "B.Cu")
		(net "P3V3_STB_NODE1")
	)
	(via
		(at 116.483892 -19.803618)
		(size 0.508)
		(drill 0.254)
		(layers "F.Cu" "B.Cu")
		(net "P3V3_STB_NODE1")
	)
	(via
		(at 175.510444 -118.86565)
		(size 0.49022)
		(drill 0.254)
		(layers "F.Cu" "B.Cu")
		(net "P3V3_STB_NODE1")
	)
	(via
		(at 56.237124 -110.88624)
		(size 0.508)
		(drill 0.254)
		(layers "F.Cu" "B.Cu")
		(net "P3V3_STB_NODE1")
	)
	(via
		(at 92.08516 -91.806522)
		(size 0.508)
		(drill 0.254)
		(layers "F.Cu" "B.Cu")
		(net "P3V3_STB_NODE1")
	)
	(via
		(at 57.865264 -112.43945)
		(size 0.508)
		(drill 0.254)
		(layers "F.Cu" "B.Cu")
		(net "P3V3_STB_NODE1")
	)
	(via
		(at 87.88908 -95.01505)
		(size 0.508)
		(drill 0.254)
		(layers "F.Cu" "B.Cu")
		(net "P3V3_STB_NODE1")
	)
	(via
		(at 176.3141 -136.18337)
		(size 0.508)
		(drill 0.254)
		(layers "F.Cu" "B.Cu")
		(net "P3V3_STB_NODE1")
	)
	(via
		(at 61.38418 -165.749732)
		(size 0.508)
		(drill 0.254)
		(layers "F.Cu" "B.Cu")
		(net "P3V3_STB_NODE1")
	)
	(via
		(at 58.142124 -107.83824)
		(size 0.508)
		(drill 0.254)
		(layers "F.Cu" "B.Cu")
		(net "P3V3_STB_NODE1")
	)
	(via
		(at 111.77016 -154.568398)
		(size 0.508)
		(drill 0.254)
		(layers "F.Cu" "B.Cu")
		(net "P3V3_STB_NODE1")
	)
	(via
		(at 179.897532 -139.65301)
		(size 0.508)
		(drill 0.254)
		(layers "F.Cu" "B.Cu")
		(net "P3V3_STB_NODE1")
	)
	(via
		(at 38.250368 -5.327396)
		(size 0.508)
		(drill 0.254)
		(layers "F.Cu" "B.Cu")
		(net "P3V3_STB_NODE1")
	)
	(via
		(at 32.773112 -108.100622)
		(size 0.508)
		(drill 0.254)
		(layers "F.Cu" "B.Cu")
		(net "P3V3_STB_NODE1")
	)
	(via
		(at 131.30657 -25.484582)
		(size 0.508)
		(drill 0.254)
		(layers "F.Cu" "B.Cu")
		(net "P3V3_STB_NODE1")
	)
	(via
		(at 163.027868 -131.24942)
		(size 0.508)
		(drill 0.254)
		(layers "F.Cu" "B.Cu")
		(net "P3V3_STB_NODE1")
	)
	(via
		(at 129.27457 -25.394412)
		(size 0.508)
		(drill 0.254)
		(layers "F.Cu" "B.Cu")
		(net "P3V3_STB_NODE1")
	)
	(via
		(at 178.510438 -121.865644)
		(size 0.49022)
		(drill 0.254)
		(layers "F.Cu" "B.Cu")
		(net "P3V3_STB_NODE1")
	)
	(via
		(at 165.45433 -123.76531)
		(size 0.508)
		(drill 0.254)
		(layers "F.Cu" "B.Cu")
		(net "P3V3_STB_NODE1")
	)
	(via
		(at 178.510438 -118.86565)
		(size 0.49022)
		(drill 0.254)
		(layers "F.Cu" "B.Cu")
		(net "P3V3_STB_NODE1")
	)
	(via
		(at 126.22657 -25.389332)
		(size 0.508)
		(drill 0.254)
		(layers "F.Cu" "B.Cu")
		(net "P3V3_STB_NODE1")
	)
	(via
		(at 32.07004 -119.447818)
		(size 0.508)
		(drill 0.254)
		(layers "F.Cu" "B.Cu")
		(net "P3V3_STB_NODE1")
	)
	(via
		(at 84.94268 -108.87964)
		(size 0.508)
		(drill 0.254)
		(layers "F.Cu" "B.Cu")
		(net "P3V3_STB_NODE1")
	)
	(via
		(at 151.52624 -136.171432)
		(size 0.508)
		(drill 0.254)
		(layers "F.Cu" "B.Cu")
		(net "P3V3_STB_NODE1")
	)
	(via
		(at 188.7601 -122.809508)
		(size 0.508)
		(drill 0.254)
		(layers "F.Cu" "B.Cu")
		(net "P3V3_STB_NODE1")
	)
	(via
		(at 59.330336 -165.739826)
		(size 0.508)
		(drill 0.254)
		(layers "F.Cu" "B.Cu")
		(net "P3V3_STB_NODE1")
	)
	(via
		(at 83.38566 -107.773216)
		(size 0.508)
		(drill 0.254)
		(layers "F.Cu" "B.Cu")
		(net "P3V3_STB_NODE1")
	)
	(via
		(at 80.935576 -101.509322)
		(size 0.508)
		(drill 0.254)
		(layers "F.Cu" "B.Cu")
		(net "P3V3_STB_NODE1")
	)
	(via
		(at 58.89879 -112.332008)
		(size 0.508)
		(drill 0.254)
		(layers "F.Cu" "B.Cu")
		(net "P3V3_STB_NODE1")
	)
	(via
		(at 32.099758 -118.551452)
		(size 0.508)
		(drill 0.254)
		(layers "F.Cu" "B.Cu")
		(net "P3V3_STB_NODE1")
	)
	(via
		(at 88.30818 -163.14039)
		(size 0.508)
		(drill 0.254)
		(layers "F.Cu" "B.Cu")
		(net "P3V3_STB_NODE1")
	)
	(via
		(at 55.494682 -112.4077)
		(size 0.508)
		(drill 0.254)
		(layers "F.Cu" "B.Cu")
		(net "P3V3_STB_NODE1")
	)
	(via
		(at 57.08142 -106.172762)
		(size 0.508)
		(drill 0.254)
		(layers "F.Cu" "B.Cu")
		(net "P3V3_STB_NODE1")
	)
	(via
		(at 177.403252 -133.32206)
		(size 0.508)
		(drill 0.254)
		(layers "F.Cu" "B.Cu")
		(net "P3V3_STB_NODE1")
	)
	(via
		(at 174.510446 -121.865644)
		(size 0.49022)
		(drill 0.254)
		(layers "F.Cu" "B.Cu")
		(net "P3V3_STB_NODE1")
	)
	(via
		(at 179.764944 -129.57556)
		(size 0.508)
		(drill 0.254)
		(layers "F.Cu" "B.Cu")
		(net "P3V3_STB_NODE1")
	)
	(via
		(at 174.544482 -137.05459)
		(size 0.508)
		(drill 0.254)
		(layers "F.Cu" "B.Cu")
		(net "P3V3_STB_NODE1")
	)
	(via
		(at 125.56236 -175.672242)
		(size 0.508)
		(drill 0.254)
		(layers "F.Cu" "B.Cu")
		(net "P3V3_STB_NODE1")
	)
	(via
		(at 37.18052 -5.16763)
		(size 0.508)
		(drill 0.254)
		(layers "F.Cu" "B.Cu")
		(net "P3V3_STB_NODE1")
	)
	(via
		(at 65.734692 -106.068876)
		(size 0.508)
		(drill 0.254)
		(layers "F.Cu" "B.Cu")
		(net "P3V3_STB_NODE1")
	)
	(via
		(at 135.37057 -25.553416)
		(size 0.508)
		(drill 0.254)
		(layers "F.Cu" "B.Cu")
		(net "P3V3_STB_NODE1")
	)
	(via
		(at 58.142124 -110.88624)
		(size 0.508)
		(drill 0.254)
		(layers "F.Cu" "B.Cu")
		(net "P3V3_STB_NODE1")
	)
	(via
		(at 82.205576 -101.509322)
		(size 0.508)
		(drill 0.254)
		(layers "F.Cu" "B.Cu")
		(net "P3V3_STB_NODE1")
	)
	(via
		(at 175.27016 -136.092438)
		(size 0.508)
		(drill 0.254)
		(layers "F.Cu" "B.Cu")
		(net "P3V3_STB_NODE1")
	)
	(via
		(at 71.30542 -100.039424)
		(size 0.508)
		(drill 0.254)
		(layers "F.Cu" "B.Cu")
		(net "P3V3_STB_NODE1")
	)
	(via
		(at 117.225064 -19.88185)
		(size 0.508)
		(drill 0.254)
		(layers "F.Cu" "B.Cu")
		(net "P3V3_STB_NODE1")
	)
	(via
		(at 133.33857 -25.237186)
		(size 0.508)
		(drill 0.254)
		(layers "F.Cu" "B.Cu")
		(net "P3V3_STB_NODE1")
	)
	(via
		(at 58.093102 -106.55935)
		(size 0.508)
		(drill 0.254)
		(layers "F.Cu" "B.Cu")
		(net "P3V3_STB_NODE1")
	)
	(via
		(at 120.216676 -155.754578)
		(size 0.508)
		(drill 0.254)
		(layers "F.Cu" "B.Cu")
		(net "P3V3_STB_NODE1")
	)
	(via
		(at 95.55226 -180.659786)
		(size 0.508)
		(drill 0.254)
		(layers "F.Cu" "B.Cu")
		(net "P3V3_STB_NODE1")
	)
	(via
		(at 58.093102 -105.79735)
		(size 0.508)
		(drill 0.254)
		(layers "F.Cu" "B.Cu")
		(net "P3V3_STB_NODE1")
	)
	(via
		(at 111.5695 -160.267142)
		(size 0.508)
		(drill 0.254)
		(layers "F.Cu" "B.Cu")
		(net "P3V3_STB_NODE1")
	)
	(via
		(at 105.36174 -177.029872)
		(size 0.508)
		(drill 0.254)
		(layers "F.Cu" "B.Cu")
		(net "P3V3_STB_NODE1")
	)
	(via
		(at 90.88628 -135.778494)
		(size 0.508)
		(drill 0.254)
		(layers "F.Cu" "B.Cu")
		(net "P3V3_STB_NODE1")
	)
	(via
		(at 64.718692 -106.102912)
		(size 0.508)
		(drill 0.254)
		(layers "F.Cu" "B.Cu")
		(net "P3V3_STB_NODE1")
	)
	(via
		(at 174.510446 -119.865648)
		(size 0.49022)
		(drill 0.254)
		(layers "F.Cu" "B.Cu")
		(net "P3V3_STB_NODE1")
	)
	(via
		(at 174.411894 -131.876546)
		(size 0.508)
		(drill 0.254)
		(layers "F.Cu" "B.Cu")
		(net "P3V3_STB_NODE1")
	)
	(via
		(at 130.29057 -25.508712)
		(size 0.508)
		(drill 0.254)
		(layers "F.Cu" "B.Cu")
		(net "P3V3_STB_NODE1")
	)
	(via
		(at 58.142124 -108.60024)
		(size 0.508)
		(drill 0.254)
		(layers "F.Cu" "B.Cu")
		(net "P3V3_STB_NODE1")
	)
	(via
		(at 116.83746 -62.46622)
		(size 0.508)
		(drill 0.254)
		(layers "F.Cu" "B.Cu")
		(net "P3V3_STB_NODE1")
	)
	(via
		(at 127.24257 -25.435306)
		(size 0.508)
		(drill 0.254)
		(layers "F.Cu" "B.Cu")
		(net "P3V3_STB_NODE1")
	)
	(via
		(at 58.89498 -111.635794)
		(size 0.508)
		(drill 0.254)
		(layers "F.Cu" "B.Cu")
		(net "P3V3_STB_NODE1")
	)
	(segment
		(start 94.815406 -166.868602)
		(end 96.439228 -168.492424)
		(width 0.508)
		(layer "B.Cu")
		(net "P3V3_STB_NODE1")
	)
	(segment
		(start 89.155778 -159.803084)
		(end 92.189046 -159.803084)
		(width 0.508)
		(layer "B.Cu")
		(net "P3V3_STB_NODE1")
	)
	(segment
		(start 91.4527 -93.426534)
		(end 91.4527 -92.438982)
		(width 0.508)
		(layer "B.Cu")
		(net "P3V3_STB_NODE1")
	)
	(segment
		(start 94.972378 -163.56584)
		(end 94.815406 -163.722812)
		(width 0.508)
		(layer "B.Cu")
		(net "P3V3_STB_NODE1")
	)
	(segment
		(start 92.189046 -159.803084)
		(end 92.33662 -159.950658)
		(width 0.508)
		(layer "B.Cu")
		(net "P3V3_STB_NODE1")
	)
	(segment
		(start 91.4527 -92.438982)
		(end 92.08516 -91.806522)
		(width 0.508)
		(layer "B.Cu")
		(net "P3V3_STB_NODE1")
	)
	(segment
		(start 104.008174 -69.273674)
		(end 102.932992 -69.273674)
		(width 0.508)
		(layer "B.Cu")
		(net "P3V3_STB_NODE1")
	)
	(segment
		(start 43.24858 -18.459196)
		(end 64.744854 -18.459196)
		(width 0.508)
		(layer "B.Cu")
		(net "P3V3_STB_NODE1")
	)
	(segment
		(start 104.008174 -65.148206)
		(end 103.11638 -65.148206)
		(width 0.508)
		(layer "B.Cu")
		(net "P3V3_STB_NODE1")
	)
	(segment
		(start 37.18052 -5.16763)
		(end 38.090602 -5.16763)
		(width 0.508)
		(layer "B.Cu")
		(net "P3V3_STB_NODE1")
	)
	(segment
		(start 35.079432 -2.9083)
		(end 27.37358 -2.9083)
		(width 0.508)
		(layer "B.Cu")
		(net "P3V3_STB_NODE1")
	)
	(segment
		(start 99.685094 -172.785532)
		(end 99.685094 -174.020988)
		(width 0.508)
		(layer "B.Cu")
		(net "P3V3_STB_NODE1")
	)
	(segment
		(start 37.18052 -5.16763)
		(end 37.18052 -5.301996)
		(width 0.508)
		(layer "B.Cu")
		(net "P3V3_STB_NODE1")
	)
	(segment
		(start 103.30688 -183.74233)
		(end 103.30688 -183.63057)
		(width 0.508)
		(layer "B.Cu")
		(net "P3V3_STB_NODE1")
	)
	(segment
		(start 6.092698 -3.042412)
		(end 6.092698 -3.296158)
		(width 0.508)
		(layer "B.Cu")
		(net "P3V3_STB_NODE1")
	)
	(segment
		(start 87.89416 -163.09467)
		(end 87.14232 -162.34283)
		(width 0.508)
		(layer "B.Cu")
		(net "P3V3_STB_NODE1")
	)
	(segment
		(start 31.64078 -15.28572)
		(end 34.318194 -17.963134)
		(width 0.508)
		(layer "B.Cu")
		(net "P3V3_STB_NODE1")
	)
	(segment
		(start 42.752518 -17.963134)
		(end 43.24858 -18.459196)
		(width 0.508)
		(layer "B.Cu")
		(net "P3V3_STB_NODE1")
	)
	(segment
		(start 96.439228 -168.492424)
		(end 96.677988 -168.492424)
		(width 0.508)
		(layer "B.Cu")
		(net "P3V3_STB_NODE1")
	)
	(segment
		(start 102.258622 -182.582312)
		(end 102.258622 -181.928516)
		(width 0.508)
		(layer "B.Cu")
		(net "P3V3_STB_NODE1")
	)
	(segment
		(start 112.55502 -20.766024)
		(end 115.521486 -20.766024)
		(width 0.508)
		(layer "B.Cu")
		(net "P3V3_STB_NODE1")
	)
	(segment
		(start 92.067888 -14.018514)
		(end 103.725726 -14.018514)
		(width 0.508)
		(layer "B.Cu")
		(net "P3V3_STB_NODE1")
	)
	(segment
		(start 115.521486 -20.766024)
		(end 116.483892 -19.803618)
		(width 0.508)
		(layer "B.Cu")
		(net "P3V3_STB_NODE1")
	)
	(segment
		(start 98.8695 -171.24934)
		(end 98.8695 -171.969938)
		(width 0.508)
		(layer "B.Cu")
		(net "P3V3_STB_NODE1")
	)
	(segment
		(start 87.14232 -161.816542)
		(end 89.155778 -159.803084)
		(width 0.508)
		(layer "B.Cu")
		(net "P3V3_STB_NODE1")
	)
	(segment
		(start 36.803584 -5.678932)
		(end 33.989772 -5.678932)
		(width 0.508)
		(layer "B.Cu")
		(net "P3V3_STB_NODE1")
	)
	(segment
		(start 94.972378 -162.586416)
		(end 94.972378 -163.56584)
		(width 0.508)
		(layer "B.Cu")
		(net "P3V3_STB_NODE1")
	)
	(segment
		(start 87.88908 -95.01505)
		(end 88.570816 -94.333314)
		(width 0.508)
		(layer "B.Cu")
		(net "P3V3_STB_NODE1")
	)
	(segment
		(start 27.37358 -2.9083)
		(end 26.02611 -1.56083)
		(width 0.508)
		(layer "B.Cu")
		(net "P3V3_STB_NODE1")
	)
	(segment
		(start 38.090602 -5.16763)
		(end 38.250368 -5.327396)
		(width 0.508)
		(layer "B.Cu")
		(net "P3V3_STB_NODE1")
	)
	(segment
		(start 37.18052 -5.009388)
		(end 35.079432 -2.9083)
		(width 0.508)
		(layer "B.Cu")
		(net "P3V3_STB_NODE1")
	)
	(segment
		(start 103.725726 -14.018514)
		(end 110.20806 -20.500848)
		(width 0.508)
		(layer "B.Cu")
		(net "P3V3_STB_NODE1")
	)
	(segment
		(start 31.64078 -8.027924)
		(end 31.64078 -15.28572)
		(width 0.508)
		(layer "B.Cu")
		(net "P3V3_STB_NODE1")
	)
	(segment
		(start 88.30818 -163.14039)
		(end 88.26246 -163.09467)
		(width 0.508)
		(layer "B.Cu")
		(net "P3V3_STB_NODE1")
	)
	(segment
		(start 37.18052 -5.301996)
		(end 36.803584 -5.678932)
		(width 0.508)
		(layer "B.Cu")
		(net "P3V3_STB_NODE1")
	)
	(segment
		(start 106.753406 -177.16754)
		(end 106.753406 -177.167032)
		(width 0.508)
		(layer "B.Cu")
		(net "P3V3_STB_NODE1")
	)
	(segment
		(start 87.14232 -162.34283)
		(end 87.14232 -161.816542)
		(width 0.508)
		(layer "B.Cu")
		(net "P3V3_STB_NODE1")
	)
	(segment
		(start 26.02611 -1.56083)
		(end 7.57428 -1.56083)
		(width 0.508)
		(layer "B.Cu")
		(net "P3V3_STB_NODE1")
	)
	(segment
		(start 97.37598 -169.190416)
		(end 97.37598 -169.75582)
		(width 0.508)
		(layer "B.Cu")
		(net "P3V3_STB_NODE1")
	)
	(segment
		(start 33.989772 -5.678932)
		(end 31.64078 -8.027924)
		(width 0.508)
		(layer "B.Cu")
		(net "P3V3_STB_NODE1")
	)
	(segment
		(start 90.54592 -94.333314)
		(end 91.4527 -93.426534)
		(width 0.508)
		(layer "B.Cu")
		(net "P3V3_STB_NODE1")
	)
	(segment
		(start 92.33662 -159.950658)
		(end 94.972378 -162.586416)
		(width 0.508)
		(layer "B.Cu")
		(net "P3V3_STB_NODE1")
	)
	(segment
		(start 97.37598 -169.75582)
		(end 98.8695 -171.24934)
		(width 0.508)
		(layer "B.Cu")
		(net "P3V3_STB_NODE1")
	)
	(segment
		(start 7.57428 -1.56083)
		(end 6.092698 -3.042412)
		(width 0.508)
		(layer "B.Cu")
		(net "P3V3_STB_NODE1")
	)
	(segment
		(start 88.26246 -163.09467)
		(end 87.89416 -163.09467)
		(width 0.508)
		(layer "B.Cu")
		(net "P3V3_STB_NODE1")
	)
	(segment
		(start 99.685094 -174.020988)
		(end 99.22764 -174.478442)
		(width 0.508)
		(layer "B.Cu")
		(net "P3V3_STB_NODE1")
	)
	(segment
		(start 91.06662 -15.019782)
		(end 92.067888 -14.018514)
		(width 0.508)
		(layer "B.Cu")
		(net "P3V3_STB_NODE1")
	)
	(segment
		(start 112.289844 -20.500848)
		(end 112.55502 -20.766024)
		(width 0.508)
		(layer "B.Cu")
		(net "P3V3_STB_NODE1")
	)
	(segment
		(start 66.382392 -16.821658)
		(end 90.602308 -16.821658)
		(width 0.508)
		(layer "B.Cu")
		(net "P3V3_STB_NODE1")
	)
	(segment
		(start 105.4989 -177.167032)
		(end 105.36174 -177.029872)
		(width 0.508)
		(layer "B.Cu")
		(net "P3V3_STB_NODE1")
	)
	(segment
		(start 98.8695 -171.969938)
		(end 99.685094 -172.785532)
		(width 0.508)
		(layer "B.Cu")
		(net "P3V3_STB_NODE1")
	)
	(segment
		(start 110.20806 -20.500848)
		(end 112.289844 -20.500848)
		(width 0.508)
		(layer "B.Cu")
		(net "P3V3_STB_NODE1")
	)
	(segment
		(start 90.602308 -16.821658)
		(end 91.06662 -16.357346)
		(width 0.508)
		(layer "B.Cu")
		(net "P3V3_STB_NODE1")
	)
	(segment
		(start 34.318194 -17.963134)
		(end 42.752518 -17.963134)
		(width 0.508)
		(layer "B.Cu")
		(net "P3V3_STB_NODE1")
	)
	(segment
		(start 103.30688 -183.63057)
		(end 102.258622 -182.582312)
		(width 0.508)
		(layer "B.Cu")
		(net "P3V3_STB_NODE1")
	)
	(segment
		(start 96.677988 -168.492424)
		(end 97.37598 -169.190416)
		(width 0.508)
		(layer "B.Cu")
		(net "P3V3_STB_NODE1")
	)
	(segment
		(start 91.06662 -16.357346)
		(end 91.06662 -15.019782)
		(width 0.508)
		(layer "B.Cu")
		(net "P3V3_STB_NODE1")
	)
	(segment
		(start 64.744854 -18.459196)
		(end 66.382392 -16.821658)
		(width 0.508)
		(layer "B.Cu")
		(net "P3V3_STB_NODE1")
	)
	(segment
		(start 106.753406 -177.167032)
		(end 105.4989 -177.167032)
		(width 0.508)
		(layer "B.Cu")
		(net "P3V3_STB_NODE1")
	)
	(segment
		(start 88.570816 -94.333314)
		(end 90.54592 -94.333314)
		(width 0.508)
		(layer "B.Cu")
		(net "P3V3_STB_NODE1")
	)
	(segment
		(start 37.18052 -5.16763)
		(end 37.18052 -5.009388)
		(width 0.508)
		(layer "B.Cu")
		(net "P3V3_STB_NODE1")
	)
	(segment
		(start 94.815406 -163.722812)
		(end 94.815406 -166.868602)
		(width 0.508)
		(layer "B.Cu")
		(net "P3V3_STB_NODE1")
	)
	(segment
		(start 30.796992 -108.100622)
		(end 32.773112 -108.100622)
		(width 0.508)
		(layer "In2.Cu")
		(net "P3V3_STB_NODE1")
	)
	(segment
		(start 30.296612 -113.546382)
		(end 30.296612 -108.601002)
		(width 0.508)
		(layer "In2.Cu")
		(net "P3V3_STB_NODE1")
	)
	(segment
		(start 35.38474 -121.437908)
		(end 35.38474 -118.63451)
		(width 0.508)
		(layer "In2.Cu")
		(net "P3V3_STB_NODE1")
	)
	(segment
		(start 30.296612 -108.601002)
		(end 30.796992 -108.100622)
		(width 0.508)
		(layer "In2.Cu")
		(net "P3V3_STB_NODE1")
	)
	(segment
		(start 35.38474 -118.63451)
		(end 30.296612 -113.546382)
		(width 0.508)
		(layer "In2.Cu")
		(net "P3V3_STB_NODE1")
	)
	(segment
		(start 123.322588 -175.5648)
		(end 122.729752 -174.971964)
		(width 0.508)
		(layer "In7.Cu")
		(net "P3V3_STB_NODE1")
	)
	(segment
		(start 106.25836 -176.352708)
		(end 105.581196 -177.029872)
		(width 0.508)
		(layer "In7.Cu")
		(net "P3V3_STB_NODE1")
	)
	(segment
		(start 65.716912 -165.895782)
		(end 61.52896 -165.895782)
		(width 0.508)
		(layer "In7.Cu")
		(net "P3V3_STB_NODE1")
	)
	(segment
		(start 102.932992 -69.273674)
		(end 103.616252 -68.590414)
		(width 0.508)
		(layer "In7.Cu")
		(net "P3V3_STB_NODE1")
	)
	(segment
		(start 61.52896 -165.895782)
		(end 61.38418 -165.751002)
		(width 0.508)
		(layer "In7.Cu")
		(net "P3V3_STB_NODE1")
	)
	(segment
		(start 107.707176 -174.011844)
		(end 106.25836 -175.46066)
		(width 0.508)
		(layer "In7.Cu")
		(net "P3V3_STB_NODE1")
	)
	(segment
		(start 59.919616 -165.166294)
		(end 59.346084 -165.739826)
		(width 0.508)
		(layer "In7.Cu")
		(net "P3V3_STB_NODE1")
	)
	(segment
		(start 103.616252 -65.648078)
		(end 103.11638 -65.148206)
		(width 0.508)
		(layer "In7.Cu")
		(net "P3V3_STB_NODE1")
	)
	(segment
		(start 61.38418 -165.895782)
		(end 60.654692 -165.166294)
		(width 0.508)
		(layer "In7.Cu")
		(net "P3V3_STB_NODE1")
	)
	(segment
		(start 97.672398 -160.654492)
		(end 102.414832 -160.654492)
		(width 0.508)
		(layer "In7.Cu")
		(net "P3V3_STB_NODE1")
	)
	(segment
		(start 61.38418 -165.749732)
		(end 61.38418 -165.751002)
		(width 0.508)
		(layer "In7.Cu")
		(net "P3V3_STB_NODE1")
	)
	(segment
		(start 108.403898 -174.011844)
		(end 107.707176 -174.011844)
		(width 0.508)
		(layer "In7.Cu")
		(net "P3V3_STB_NODE1")
	)
	(segment
		(start 104.270556 -160.267142)
		(end 111.5695 -160.267142)
		(width 0.508)
		(layer "In7.Cu")
		(net "P3V3_STB_NODE1")
	)
	(segment
		(start 92.33662 -159.952944)
		(end 92.39758 -160.013904)
		(width 0.508)
		(layer "In7.Cu")
		(net "P3V3_STB_NODE1")
	)
	(segment
		(start 80.1751 -160.051496)
		(end 74.878692 -160.051496)
		(width 0.508)
		(layer "In7.Cu")
		(net "P3V3_STB_NODE1")
	)
	(segment
		(start 109.20349 -173.212252)
		(end 108.403898 -174.011844)
		(width 0.508)
		(layer "In7.Cu")
		(net "P3V3_STB_NODE1")
	)
	(segment
		(start 92.33662 -159.950658)
		(end 92.33662 -159.951674)
		(width 0.508)
		(layer "In7.Cu")
		(net "P3V3_STB_NODE1")
	)
	(segment
		(start 70.784974 -164.145214)
		(end 67.46748 -164.145214)
		(width 0.508)
		(layer "In7.Cu")
		(net "P3V3_STB_NODE1")
	)
	(segment
		(start 125.56236 -175.672242)
		(end 125.454918 -175.5648)
		(width 0.508)
		(layer "In7.Cu")
		(net "P3V3_STB_NODE1")
	)
	(segment
		(start 102.414832 -160.654492)
		(end 102.885494 -161.125154)
		(width 0.508)
		(layer "In7.Cu")
		(net "P3V3_STB_NODE1")
	)
	(segment
		(start 125.454918 -175.5648)
		(end 123.322588 -175.5648)
		(width 0.508)
		(layer "In7.Cu")
		(net "P3V3_STB_NODE1")
	)
	(segment
		(start 97.03181 -160.013904)
		(end 97.672398 -160.654492)
		(width 0.508)
		(layer "In7.Cu")
		(net "P3V3_STB_NODE1")
	)
	(segment
		(start 103.616252 -68.590414)
		(end 103.616252 -65.648078)
		(width 0.508)
		(layer "In7.Cu")
		(net "P3V3_STB_NODE1")
	)
	(segment
		(start 90.938858 -160.014412)
		(end 90.754962 -159.830516)
		(width 0.508)
		(layer "In7.Cu")
		(net "P3V3_STB_NODE1")
	)
	(segment
		(start 67.46748 -164.145214)
		(end 65.716912 -165.895782)
		(width 0.508)
		(layer "In7.Cu")
		(net "P3V3_STB_NODE1")
	)
	(segment
		(start 106.25836 -175.46066)
		(end 106.25836 -176.352708)
		(width 0.508)
		(layer "In7.Cu")
		(net "P3V3_STB_NODE1")
	)
	(segment
		(start 92.273882 -160.014412)
		(end 90.938858 -160.014412)
		(width 0.508)
		(layer "In7.Cu")
		(net "P3V3_STB_NODE1")
	)
	(segment
		(start 103.412544 -161.125154)
		(end 104.270556 -160.267142)
		(width 0.508)
		(layer "In7.Cu")
		(net "P3V3_STB_NODE1")
	)
	(segment
		(start 98.11258 -175.239172)
		(end 98.87331 -174.478442)
		(width 0.508)
		(layer "In7.Cu")
		(net "P3V3_STB_NODE1")
	)
	(segment
		(start 122.729752 -174.971964)
		(end 114.214148 -174.971964)
		(width 0.508)
		(layer "In7.Cu")
		(net "P3V3_STB_NODE1")
	)
	(segment
		(start 61.38418 -165.751002)
		(end 61.38418 -165.895782)
		(width 0.508)
		(layer "In7.Cu")
		(net "P3V3_STB_NODE1")
	)
	(segment
		(start 92.39758 -160.013904)
		(end 97.03181 -160.013904)
		(width 0.508)
		(layer "In7.Cu")
		(net "P3V3_STB_NODE1")
	)
	(segment
		(start 96.470978 -181.578504)
		(end 97.78746 -181.578504)
		(width 0.508)
		(layer "In7.Cu")
		(net "P3V3_STB_NODE1")
	)
	(segment
		(start 90.754962 -159.830516)
		(end 80.39608 -159.830516)
		(width 0.508)
		(layer "In7.Cu")
		(net "P3V3_STB_NODE1")
	)
	(segment
		(start 92.33662 -159.951674)
		(end 92.33662 -159.952944)
		(width 0.508)
		(layer "In7.Cu")
		(net "P3V3_STB_NODE1")
	)
	(segment
		(start 98.87331 -174.478442)
		(end 99.22764 -174.478442)
		(width 0.508)
		(layer "In7.Cu")
		(net "P3V3_STB_NODE1")
	)
	(segment
		(start 60.654692 -165.166294)
		(end 59.919616 -165.166294)
		(width 0.508)
		(layer "In7.Cu")
		(net "P3V3_STB_NODE1")
	)
	(segment
		(start 105.581196 -177.029872)
		(end 105.36174 -177.029872)
		(width 0.508)
		(layer "In7.Cu")
		(net "P3V3_STB_NODE1")
	)
	(segment
		(start 97.78746 -181.578504)
		(end 98.11258 -181.253384)
		(width 0.508)
		(layer "In7.Cu")
		(net "P3V3_STB_NODE1")
	)
	(segment
		(start 112.454436 -173.212252)
		(end 109.20349 -173.212252)
		(width 0.508)
		(layer "In7.Cu")
		(net "P3V3_STB_NODE1")
	)
	(segment
		(start 59.346084 -165.739826)
		(end 59.330336 -165.739826)
		(width 0.508)
		(layer "In7.Cu")
		(net "P3V3_STB_NODE1")
	)
	(segment
		(start 95.55226 -180.659786)
		(end 96.470978 -181.578504)
		(width 0.508)
		(layer "In7.Cu")
		(net "P3V3_STB_NODE1")
	)
	(segment
		(start 98.11258 -181.253384)
		(end 98.11258 -175.239172)
		(width 0.508)
		(layer "In7.Cu")
		(net "P3V3_STB_NODE1")
	)
	(segment
		(start 92.33662 -159.951674)
		(end 92.273882 -160.014412)
		(width 0.508)
		(layer "In7.Cu")
		(net "P3V3_STB_NODE1")
	)
	(segment
		(start 114.214148 -174.971964)
		(end 112.454436 -173.212252)
		(width 0.508)
		(layer "In7.Cu")
		(net "P3V3_STB_NODE1")
	)
	(segment
		(start 102.885494 -161.125154)
		(end 103.412544 -161.125154)
		(width 0.508)
		(layer "In7.Cu")
		(net "P3V3_STB_NODE1")
	)
	(segment
		(start 74.878692 -160.051496)
		(end 70.784974 -164.145214)
		(width 0.508)
		(layer "In7.Cu")
		(net "P3V3_STB_NODE1")
	)
	(segment
		(start 80.39608 -159.830516)
		(end 80.1751 -160.051496)
		(width 0.508)
		(layer "In7.Cu")
		(net "P3V3_STB_NODE1")
	)
	(segment
		(start 151.238458 -132.16255)
		(end 153.16454 -134.088632)
		(width 0.1016)
		(layer "F.Cu")
		(net "RST_BTN_L")
	)
	(segment
		(start 151.238458 -131.314444)
		(end 151.238458 -132.16255)
		(width 0.1016)
		(layer "F.Cu")
		(net "RST_BTN_L")
	)
	(segment
		(start 153.155904 -135.155432)
		(end 153.155904 -134.097268)
		(width 0.1016)
		(layer "F.Cu")
		(net "RST_BTN_L")
	)
	(segment
		(start 153.155904 -134.097268)
		(end 153.16454 -134.088632)
		(width 0.1016)
		(layer "F.Cu")
		(net "RST_BTN_L")
	)
	(segment
		(start 153.155904 -136.342628)
		(end 152.355804 -137.142728)
		(width 0.1016)
		(layer "F.Cu")
		(net "RST_BTN_L")
	)
	(segment
		(start 153.155904 -135.155432)
		(end 153.155904 -136.171432)
		(width 0.1016)
		(layer "F.Cu")
		(net "RST_BTN_L")
	)
	(segment
		(start 158.038546 -131.314444)
		(end 151.238458 -131.314444)
		(width 0.1016)
		(layer "F.Cu")
		(net "RST_BTN_L")
	)
	(segment
		(start 153.155904 -136.171432)
		(end 153.155904 -136.342628)
		(width 0.1016)
		(layer "F.Cu")
		(net "RST_BTN_L")
	)
	(segment
		(start 152.355804 -137.142728)
		(end 152.355804 -137.187432)
		(width 0.1016)
		(layer "F.Cu")
		(net "RST_BTN_L")
	)
	(via
		(at 153.16454 -134.088632)
		(size 0.508)
		(drill 0.254)
		(layers "F.Cu" "B.Cu")
		(net "RST_BTN_L")
	)
	(segment
		(start 73.244964 -162.673284)
		(end 71.29653 -164.621718)
		(width 0.1016)
		(layer "F.Cu")
		(net "CPLD2_RSV3")
	)
	(segment
		(start 71.29653 -164.621718)
		(end 70.155054 -164.621718)
		(width 0.1016)
		(layer "F.Cu")
		(net "CPLD2_RSV3")
	)
	(segment
		(start 74.247502 -163.205668)
		(end 74.636122 -163.205668)
		(width 0.1016)
		(layer "F.Cu")
		(net "CPLD2_RSV3")
	)
	(segment
		(start 74.636122 -162.909504)
		(end 74.399902 -162.673284)
		(width 0.1016)
		(layer "F.Cu")
		(net "CPLD2_RSV3")
	)
	(segment
		(start 74.636122 -163.205668)
		(end 74.636122 -163.204144)
		(width 0.1016)
		(layer "F.Cu")
		(net "CPLD2_RSV3")
	)
	(segment
		(start 73.994772 -164.374576)
		(end 73.994772 -163.458398)
		(width 0.1016)
		(layer "F.Cu")
		(net "CPLD2_RSV3")
	)
	(segment
		(start 74.399902 -162.673284)
		(end 73.244964 -162.673284)
		(width 0.1016)
		(layer "F.Cu")
		(net "CPLD2_RSV3")
	)
	(segment
		(start 74.636122 -163.204144)
		(end 74.636122 -162.909504)
		(width 0.1016)
		(layer "F.Cu")
		(net "CPLD2_RSV3")
	)
	(segment
		(start 73.994772 -163.458398)
		(end 74.247502 -163.205668)
		(width 0.1016)
		(layer "F.Cu")
		(net "CPLD2_RSV3")
	)
	(via
		(at 74.636122 -163.204144)
		(size 0.508)
		(drill 0.254)
		(layers "F.Cu" "B.Cu")
		(net "CPLD2_RSV3")
	)
	(segment
		(start 131.160266 -163.358576)
		(end 130.63728 -162.83559)
		(width 0.1016)
		(layer "F.Cu")
		(net "CPLD3_RSV3")
	)
	(segment
		(start 131.302506 -161.150046)
		(end 131.302506 -162.170364)
		(width 0.1016)
		(layer "F.Cu")
		(net "CPLD3_RSV3")
	)
	(segment
		(start 131.302506 -162.170364)
		(end 130.63728 -162.83559)
		(width 0.1016)
		(layer "F.Cu")
		(net "CPLD3_RSV3")
	)
	(segment
		(start 131.525772 -163.358576)
		(end 131.160266 -163.358576)
		(width 0.1016)
		(layer "F.Cu")
		(net "CPLD3_RSV3")
	)
	(via
		(at 130.63728 -162.83559)
		(size 0.508)
		(drill 0.254)
		(layers "F.Cu" "B.Cu")
		(net "CPLD3_RSV3")
	)
	(segment
		(start 127.04699 -165.259004)
		(end 127.833374 -165.259004)
		(width 0.1016)
		(layer "F.Cu")
		(net "CPLD3_RSV1")
	)
	(segment
		(start 129.775712 -165.608508)
		(end 128.787144 -165.608508)
		(width 0.1016)
		(layer "F.Cu")
		(net "CPLD3_RSV1")
	)
	(segment
		(start 128.180084 -165.001448)
		(end 128.09093 -165.001448)
		(width 0.1016)
		(layer "F.Cu")
		(net "CPLD3_RSV1")
	)
	(segment
		(start 128.787144 -165.608508)
		(end 128.180084 -165.001448)
		(width 0.1016)
		(layer "F.Cu")
		(net "CPLD3_RSV1")
	)
	(segment
		(start 127.833374 -165.259004)
		(end 128.09093 -165.001448)
		(width 0.1016)
		(layer "F.Cu")
		(net "CPLD3_RSV1")
	)
	(via
		(at 128.09093 -165.001448)
		(size 0.508)
		(drill 0.254)
		(layers "F.Cu" "B.Cu")
		(net "CPLD3_RSV1")
	)
	(segment
		(start 127.588772 -164.228526)
		(end 127.617474 -164.199824)
		(width 0.1016)
		(layer "F.Cu")
		(net "CPLD3_RSV2")
	)
	(segment
		(start 127.617474 -164.199824)
		(end 128.774444 -164.199824)
		(width 0.1016)
		(layer "F.Cu")
		(net "CPLD3_RSV2")
	)
	(segment
		(start 129.775712 -165.108636)
		(end 129.775712 -164.654992)
		(width 0.1016)
		(layer "F.Cu")
		(net "CPLD3_RSV2")
	)
	(segment
		(start 127.044196 -164.228526)
		(end 127.588772 -164.228526)
		(width 0.1016)
		(layer "F.Cu")
		(net "CPLD3_RSV2")
	)
	(segment
		(start 128.774444 -164.199824)
		(end 129.047494 -163.926774)
		(width 0.1016)
		(layer "F.Cu")
		(net "CPLD3_RSV2")
	)
	(segment
		(start 129.775712 -164.654992)
		(end 129.047494 -163.926774)
		(width 0.1016)
		(layer "F.Cu")
		(net "CPLD3_RSV2")
	)
	(via
		(at 129.047494 -163.926774)
		(size 0.508)
		(drill 0.254)
		(layers "F.Cu" "B.Cu")
		(net "CPLD3_RSV2")
	)
	(segment
		(start 70.789546 -166.748714)
		(end 70.155054 -166.748714)
		(width 0.1016)
		(layer "F.Cu")
		(net "CPLD2_RSV1")
	)
	(segment
		(start 70.913752 -166.624508)
		(end 70.789546 -166.748714)
		(width 0.1016)
		(layer "F.Cu")
		(net "CPLD2_RSV1")
	)
	(segment
		(start 72.244712 -166.624508)
		(end 70.913752 -166.624508)
		(width 0.1016)
		(layer "F.Cu")
		(net "CPLD2_RSV1")
	)
	(via
		(at 70.789546 -166.748714)
		(size 0.508)
		(drill 0.254)
		(layers "F.Cu" "B.Cu")
		(net "CPLD2_RSV1")
	)
	(segment
		(start 72.244712 -165.849554)
		(end 71.570088 -165.17493)
		(width 0.1016)
		(layer "F.Cu")
		(net "CPLD2_RSV2")
	)
	(segment
		(start 70.848982 -165.17493)
		(end 70.361556 -165.662356)
		(width 0.1016)
		(layer "F.Cu")
		(net "CPLD2_RSV2")
	)
	(segment
		(start 71.570088 -165.17493)
		(end 71.34352 -165.17493)
		(width 0.1016)
		(layer "F.Cu")
		(net "CPLD2_RSV2")
	)
	(segment
		(start 72.244712 -166.124636)
		(end 72.244712 -165.849554)
		(width 0.1016)
		(layer "F.Cu")
		(net "CPLD2_RSV2")
	)
	(segment
		(start 71.34352 -165.17493)
		(end 70.848982 -165.17493)
		(width 0.1016)
		(layer "F.Cu")
		(net "CPLD2_RSV2")
	)
	(segment
		(start 70.361556 -165.662356)
		(end 70.155054 -165.662356)
		(width 0.1016)
		(layer "F.Cu")
		(net "CPLD2_RSV2")
	)
	(via
		(at 71.34352 -165.17493)
		(size 0.508)
		(drill 0.254)
		(layers "F.Cu" "B.Cu")
		(net "CPLD2_RSV2")
	)
	(via
		(at 80.310736 -168.30802)
		(size 0.508)
		(drill 0.254)
		(layers "F.Cu" "B.Cu")
		(net "CM_CABLE_DET_N")
	)
	(segment
		(start 79.23149 -168.441624)
		(end 80.177132 -168.441624)
		(width 0.1016)
		(layer "B.Cu")
		(net "CM_CABLE_DET_N")
	)
	(segment
		(start 80.177132 -168.441624)
		(end 80.310736 -168.30802)
		(width 0.1016)
		(layer "B.Cu")
		(net "CM_CABLE_DET_N")
	)
	(segment
		(start 81.906872 -168.254426)
		(end 80.36433 -168.254426)
		(width 0.1016)
		(layer "B.Cu")
		(net "CM_CABLE_DET_N")
	)
	(segment
		(start 80.36433 -168.254426)
		(end 80.310736 -168.30802)
		(width 0.1016)
		(layer "B.Cu")
		(net "CM_CABLE_DET_N")
	)
	(segment
		(start 169.817542 -131.321556)
		(end 169.817542 -130.59537)
		(width 0.1016)
		(layer "F.Cu")
		(net "CPLD1_RSV3")
	)
	(segment
		(start 175.870362 -125.505972)
		(end 175.870362 -127.39624)
		(width 0.1016)
		(layer "F.Cu")
		(net "CPLD1_RSV3")
	)
	(segment
		(start 175.870362 -127.39624)
		(end 176.01057 -127.536448)
		(width 0.1016)
		(layer "F.Cu")
		(net "CPLD1_RSV3")
	)
	(segment
		(start 176.01057 -125.365764)
		(end 175.870362 -125.505972)
		(width 0.1016)
		(layer "F.Cu")
		(net "CPLD1_RSV3")
	)
	(via
		(at 176.01057 -127.536448)
		(size 0.49022)
		(drill 0.254)
		(layers "F.Cu" "B.Cu")
		(net "CPLD1_RSV3")
	)
	(via
		(at 169.817542 -130.59537)
		(size 0.508)
		(drill 0.254)
		(layers "F.Cu" "B.Cu")
		(net "CPLD1_RSV3")
	)
	(segment
		(start 175.731932 -127.536448)
		(end 176.01057 -127.536448)
		(width 0.1016)
		(layer "B.Cu")
		(net "CPLD1_RSV3")
	)
	(segment
		(start 171.832778 -128.580134)
		(end 174.688246 -128.580134)
		(width 0.1016)
		(layer "B.Cu")
		(net "CPLD1_RSV3")
	)
	(segment
		(start 169.817542 -130.59537)
		(end 171.832778 -128.580134)
		(width 0.1016)
		(layer "B.Cu")
		(net "CPLD1_RSV3")
	)
	(segment
		(start 174.688246 -128.580134)
		(end 175.731932 -127.536448)
		(width 0.1016)
		(layer "B.Cu")
		(net "CPLD1_RSV3")
	)
	(segment
		(start 175.010318 -125.365764)
		(end 175.010318 -126.309628)
		(width 0.1016)
		(layer "F.Cu")
		(net "CPLD1_RSV2")
	)
	(segment
		(start 168.66362 -131.315714)
		(end 168.66362 -130.40868)
		(width 0.1016)
		(layer "F.Cu")
		(net "CPLD1_RSV2")
	)
	(segment
		(start 168.66362 -130.40868)
		(end 168.662096 -130.407156)
		(width 0.1016)
		(layer "F.Cu")
		(net "CPLD1_RSV2")
	)
	(segment
		(start 168.662096 -131.315714)
		(end 168.66362 -131.315714)
		(width 0.1016)
		(layer "F.Cu")
		(net "CPLD1_RSV2")
	)
	(via
		(at 175.010318 -126.309628)
		(size 0.508)
		(drill 0.254)
		(layers "F.Cu" "B.Cu")
		(net "CPLD1_RSV2")
	)
	(via
		(at 168.662096 -130.407156)
		(size 0.508)
		(drill 0.254)
		(layers "F.Cu" "B.Cu")
		(net "CPLD1_RSV2")
	)
	(segment
		(start 171.073318 -127.373888)
		(end 173.946058 -127.373888)
		(width 0.1016)
		(layer "B.Cu")
		(net "CPLD1_RSV2")
	)
	(segment
		(start 168.662096 -130.407156)
		(end 168.662096 -129.78511)
		(width 0.1016)
		(layer "B.Cu")
		(net "CPLD1_RSV2")
	)
	(segment
		(start 173.946058 -127.373888)
		(end 175.010318 -126.309628)
		(width 0.1016)
		(layer "B.Cu")
		(net "CPLD1_RSV2")
	)
	(segment
		(start 168.662096 -129.78511)
		(end 171.073318 -127.373888)
		(width 0.1016)
		(layer "B.Cu")
		(net "CPLD1_RSV2")
	)
	(segment
		(start 174.01032 -126.283974)
		(end 173.958504 -126.33579)
		(width 0.1016)
		(layer "F.Cu")
		(net "CPLD1_RSV1")
	)
	(segment
		(start 167.622982 -131.368038)
		(end 167.622982 -130.537458)
		(width 0.1016)
		(layer "F.Cu")
		(net "CPLD1_RSV1")
	)
	(segment
		(start 174.01032 -125.365764)
		(end 174.01032 -126.283974)
		(width 0.1016)
		(layer "F.Cu")
		(net "CPLD1_RSV1")
	)
	(via
		(at 167.622982 -130.537458)
		(size 0.508)
		(drill 0.254)
		(layers "F.Cu" "B.Cu")
		(net "CPLD1_RSV1")
	)
	(via
		(at 173.958504 -126.33579)
		(size 0.508)
		(drill 0.254)
		(layers "F.Cu" "B.Cu")
		(net "CPLD1_RSV1")
	)
	(segment
		(start 173.913038 -126.381256)
		(end 173.958504 -126.33579)
		(width 0.1016)
		(layer "B.Cu")
		(net "CPLD1_RSV1")
	)
	(segment
		(start 167.622982 -130.537458)
		(end 167.622982 -129.533904)
		(width 0.1016)
		(layer "B.Cu")
		(net "CPLD1_RSV1")
	)
	(segment
		(start 167.622982 -129.533904)
		(end 170.77563 -126.381256)
		(width 0.1016)
		(layer "B.Cu")
		(net "CPLD1_RSV1")
	)
	(segment
		(start 170.77563 -126.381256)
		(end 173.913038 -126.381256)
		(width 0.1016)
		(layer "B.Cu")
		(net "CPLD1_RSV1")
	)
	(segment
		(start 69.354954 -166.748714)
		(end 68.797678 -166.748714)
		(width 0.1016)
		(layer "F.Cu")
		(net "CPLD123_RSV1")
	)
	(segment
		(start 164.076888 -132.168138)
		(end 163.827206 -132.41782)
		(width 0.1016)
		(layer "F.Cu")
		(net "CPLD123_RSV1")
	)
	(segment
		(start 68.48856 -166.439596)
		(end 68.48856 -166.44366)
		(width 0.1016)
		(layer "F.Cu")
		(net "CPLD123_RSV1")
	)
	(segment
		(start 126.84506 -162.893502)
		(end 126.84506 -161.617406)
		(width 0.1016)
		(layer "F.Cu")
		(net "CPLD123_RSV1")
	)
	(segment
		(start 161.23031 -132.41782)
		(end 161.17062 -132.47751)
		(width 0.1016)
		(layer "F.Cu")
		(net "CPLD123_RSV1")
	)
	(segment
		(start 167.622982 -132.168138)
		(end 164.076888 -132.168138)
		(width 0.1016)
		(layer "F.Cu")
		(net "CPLD123_RSV1")
	)
	(segment
		(start 163.827206 -132.41782)
		(end 161.23031 -132.41782)
		(width 0.1016)
		(layer "F.Cu")
		(net "CPLD123_RSV1")
	)
	(segment
		(start 125.837696 -164.698426)
		(end 125.837696 -163.900866)
		(width 0.1016)
		(layer "F.Cu")
		(net "CPLD123_RSV1")
	)
	(segment
		(start 126.84506 -161.617406)
		(end 126.15926 -160.931606)
		(width 0.1016)
		(layer "F.Cu")
		(net "CPLD123_RSV1")
	)
	(segment
		(start 126.24689 -165.259004)
		(end 126.24689 -165.10762)
		(width 0.1016)
		(layer "F.Cu")
		(net "CPLD123_RSV1")
	)
	(segment
		(start 125.837696 -163.900866)
		(end 126.84506 -162.893502)
		(width 0.1016)
		(layer "F.Cu")
		(net "CPLD123_RSV1")
	)
	(segment
		(start 126.24689 -165.10762)
		(end 125.837696 -164.698426)
		(width 0.1016)
		(layer "F.Cu")
		(net "CPLD123_RSV1")
	)
	(segment
		(start 68.797678 -166.748714)
		(end 68.48856 -166.439596)
		(width 0.1016)
		(layer "F.Cu")
		(net "CPLD123_RSV1")
	)
	(via
		(at 68.48856 -166.44366)
		(size 0.508)
		(drill 0.254)
		(layers "F.Cu" "B.Cu")
		(net "CPLD123_RSV1")
	)
	(via
		(at 126.15926 -160.931606)
		(size 0.508)
		(drill 0.254)
		(layers "F.Cu" "B.Cu")
		(net "CPLD123_RSV1")
	)
	(via
		(at 161.17062 -132.47751)
		(size 0.508)
		(drill 0.254)
		(layers "F.Cu" "B.Cu")
		(net "CPLD123_RSV1")
	)
	(via
		(at 121.97588 -47.184564)
		(size 0.508)
		(drill 0.254)
		(layers "F.Cu" "B.Cu")
		(net "CPLD123_RSV1")
	)
	(segment
		(start 134.481316 -36.359084)
		(end 132.334 -38.5064)
		(width 0.1016)
		(layer "B.Cu")
		(net "CPLD123_RSV1")
	)
	(segment
		(start 134.796784 -36.359084)
		(end 134.481316 -36.359084)
		(width 0.1016)
		(layer "B.Cu")
		(net "CPLD123_RSV1")
	)
	(segment
		(start 131.787646 -38.5064)
		(end 131.782566 -38.51148)
		(width 0.1016)
		(layer "B.Cu")
		(net "CPLD123_RSV1")
	)
	(segment
		(start 132.334 -38.5064)
		(end 131.787646 -38.5064)
		(width 0.1016)
		(layer "B.Cu")
		(net "CPLD123_RSV1")
	)
	(segment
		(start 130.614674 -38.51148)
		(end 129.187194 -39.93896)
		(width 0.1016)
		(layer "B.Cu")
		(net "CPLD123_RSV1")
	)
	(segment
		(start 121.97588 -47.185072)
		(end 121.97588 -47.184564)
		(width 0.1016)
		(layer "B.Cu")
		(net "CPLD123_RSV1")
	)
	(segment
		(start 122.0597 -47.268892)
		(end 121.97588 -47.185072)
		(width 0.1016)
		(layer "B.Cu")
		(net "CPLD123_RSV1")
	)
	(segment
		(start 131.782566 -38.51148)
		(end 130.614674 -38.51148)
		(width 0.1016)
		(layer "B.Cu")
		(net "CPLD123_RSV1")
	)
	(segment
		(start 129.187194 -39.93896)
		(end 129.187194 -42.346118)
		(width 0.1016)
		(layer "B.Cu")
		(net "CPLD123_RSV1")
	)
	(segment
		(start 129.187194 -42.346118)
		(end 124.26442 -47.268892)
		(width 0.1016)
		(layer "B.Cu")
		(net "CPLD123_RSV1")
	)
	(segment
		(start 124.26442 -47.268892)
		(end 122.0597 -47.268892)
		(width 0.1016)
		(layer "B.Cu")
		(net "CPLD123_RSV1")
	)
	(segment
		(start 123.61418 -63.241682)
		(end 123.61418 -63.502032)
		(width 0.1143)
		(layer "In2.Cu")
		(net "CPLD123_RSV1")
	)
	(segment
		(start 162.57905 -130.701288)
		(end 162.323018 -130.95732)
		(width 0.1143)
		(layer "In2.Cu")
		(net "CPLD123_RSV1")
	)
	(segment
		(start 130.593846 -157.756098)
		(end 129.258568 -159.091376)
		(width 0.1143)
		(layer "In2.Cu")
		(net "CPLD123_RSV1")
	)
	(segment
		(start 126.57836 -160.931606)
		(end 126.15926 -160.931606)
		(width 0.1143)
		(layer "In2.Cu")
		(net "CPLD123_RSV1")
	)
	(segment
		(start 122.39752 -47.606204)
		(end 122.39752 -62.025022)
		(width 0.1143)
		(layer "In2.Cu")
		(net "CPLD123_RSV1")
	)
	(segment
		(start 159.068262 -111.217202)
		(end 162.57905 -114.72799)
		(width 0.1143)
		(layer "In2.Cu")
		(net "CPLD123_RSV1")
	)
	(segment
		(start 131.62788 -71.515732)
		(end 131.62788 -73.259696)
		(width 0.1143)
		(layer "In2.Cu")
		(net "CPLD123_RSV1")
	)
	(segment
		(start 121.97588 -47.184564)
		(end 122.39752 -47.606204)
		(width 0.1143)
		(layer "In2.Cu")
		(net "CPLD123_RSV1")
	)
	(segment
		(start 129.258568 -159.091376)
		(end 128.41859 -159.091376)
		(width 0.1143)
		(layer "In2.Cu")
		(net "CPLD123_RSV1")
	)
	(segment
		(start 136.853676 -156.793692)
		(end 135.89127 -157.756098)
		(width 0.1143)
		(layer "In2.Cu")
		(net "CPLD123_RSV1")
	)
	(segment
		(start 146.5199 -153.88971)
		(end 143.615918 -156.793692)
		(width 0.1143)
		(layer "In2.Cu")
		(net "CPLD123_RSV1")
	)
	(segment
		(start 161.17062 -132.47751)
		(end 155.946602 -132.47751)
		(width 0.1143)
		(layer "In2.Cu")
		(net "CPLD123_RSV1")
	)
	(segment
		(start 146.5199 -152.069292)
		(end 146.5199 -153.88971)
		(width 0.1143)
		(layer "In2.Cu")
		(net "CPLD123_RSV1")
	)
	(segment
		(start 162.323018 -130.95732)
		(end 162.323018 -131.325112)
		(width 0.1143)
		(layer "In2.Cu")
		(net "CPLD123_RSV1")
	)
	(segment
		(start 149.05101 -142.664942)
		(end 149.375876 -142.989808)
		(width 0.1143)
		(layer "In2.Cu")
		(net "CPLD123_RSV1")
	)
	(segment
		(start 123.61418 -63.502032)
		(end 131.62788 -71.515732)
		(width 0.1143)
		(layer "In2.Cu")
		(net "CPLD123_RSV1")
	)
	(segment
		(start 122.39752 -62.025022)
		(end 123.61418 -63.241682)
		(width 0.1143)
		(layer "In2.Cu")
		(net "CPLD123_RSV1")
	)
	(segment
		(start 143.615918 -156.793692)
		(end 136.853676 -156.793692)
		(width 0.1143)
		(layer "In2.Cu")
		(net "CPLD123_RSV1")
	)
	(segment
		(start 150.053294 -139.807696)
		(end 149.05101 -140.80998)
		(width 0.1143)
		(layer "In2.Cu")
		(net "CPLD123_RSV1")
	)
	(segment
		(start 128.41859 -159.091376)
		(end 126.57836 -160.931606)
		(width 0.1143)
		(layer "In2.Cu")
		(net "CPLD123_RSV1")
	)
	(segment
		(start 153.27757 -104.433624)
		(end 153.27757 -108.299758)
		(width 0.1143)
		(layer "In2.Cu")
		(net "CPLD123_RSV1")
	)
	(segment
		(start 152.475692 -94.107508)
		(end 152.475692 -103.631746)
		(width 0.1143)
		(layer "In2.Cu")
		(net "CPLD123_RSV1")
	)
	(segment
		(start 150.053294 -138.370818)
		(end 150.053294 -139.807696)
		(width 0.1143)
		(layer "In2.Cu")
		(net "CPLD123_RSV1")
	)
	(segment
		(start 153.27757 -108.299758)
		(end 156.195014 -111.217202)
		(width 0.1143)
		(layer "In2.Cu")
		(net "CPLD123_RSV1")
	)
	(segment
		(start 152.475692 -103.631746)
		(end 153.27757 -104.433624)
		(width 0.1143)
		(layer "In2.Cu")
		(net "CPLD123_RSV1")
	)
	(segment
		(start 149.375876 -142.989808)
		(end 149.375876 -149.213316)
		(width 0.1143)
		(layer "In2.Cu")
		(net "CPLD123_RSV1")
	)
	(segment
		(start 162.323018 -131.325112)
		(end 161.17062 -132.47751)
		(width 0.1143)
		(layer "In2.Cu")
		(net "CPLD123_RSV1")
	)
	(segment
		(start 162.57905 -114.72799)
		(end 162.57905 -130.701288)
		(width 0.1143)
		(layer "In2.Cu")
		(net "CPLD123_RSV1")
	)
	(segment
		(start 149.05101 -140.80998)
		(end 149.05101 -142.664942)
		(width 0.1143)
		(layer "In2.Cu")
		(net "CPLD123_RSV1")
	)
	(segment
		(start 156.195014 -111.217202)
		(end 159.068262 -111.217202)
		(width 0.1143)
		(layer "In2.Cu")
		(net "CPLD123_RSV1")
	)
	(segment
		(start 135.89127 -157.756098)
		(end 130.593846 -157.756098)
		(width 0.1143)
		(layer "In2.Cu")
		(net "CPLD123_RSV1")
	)
	(segment
		(start 131.62788 -73.259696)
		(end 152.475692 -94.107508)
		(width 0.1143)
		(layer "In2.Cu")
		(net "CPLD123_RSV1")
	)
	(segment
		(start 155.946602 -132.47751)
		(end 150.053294 -138.370818)
		(width 0.1143)
		(layer "In2.Cu")
		(net "CPLD123_RSV1")
	)
	(segment
		(start 149.375876 -149.213316)
		(end 146.5199 -152.069292)
		(width 0.1143)
		(layer "In2.Cu")
		(net "CPLD123_RSV1")
	)
	(segment
		(start 97.360232 -164.44722)
		(end 95.0214 -162.108388)
		(width 0.1143)
		(layer "In7.Cu")
		(net "CPLD123_RSV1")
	)
	(segment
		(start 110.911894 -162.792156)
		(end 108.116878 -162.792156)
		(width 0.1143)
		(layer "In7.Cu")
		(net "CPLD123_RSV1")
	)
	(segment
		(start 121.943368 -163.9062)
		(end 117.287294 -163.9062)
		(width 0.1143)
		(layer "In7.Cu")
		(net "CPLD123_RSV1")
	)
	(segment
		(start 124.580142 -163.227004)
		(end 123.06554 -163.227004)
		(width 0.1143)
		(layer "In7.Cu")
		(net "CPLD123_RSV1")
	)
	(segment
		(start 122.2248 -163.624768)
		(end 121.943368 -163.9062)
		(width 0.1143)
		(layer "In7.Cu")
		(net "CPLD123_RSV1")
	)
	(segment
		(start 79.55534 -162.904678)
		(end 79.55534 -163.102036)
		(width 0.1143)
		(layer "In7.Cu")
		(net "CPLD123_RSV1")
	)
	(segment
		(start 72.71258 -164.681154)
		(end 72.71258 -165.18001)
		(width 0.1143)
		(layer "In7.Cu")
		(net "CPLD123_RSV1")
	)
	(segment
		(start 104.55402 -164.44722)
		(end 97.360232 -164.44722)
		(width 0.1143)
		(layer "In7.Cu")
		(net "CPLD123_RSV1")
	)
	(segment
		(start 79.55534 -163.102036)
		(end 78.923134 -163.734242)
		(width 0.1143)
		(layer "In7.Cu")
		(net "CPLD123_RSV1")
	)
	(segment
		(start 80.635094 -162.371278)
		(end 80.08874 -162.371278)
		(width 0.1143)
		(layer "In7.Cu")
		(net "CPLD123_RSV1")
	)
	(segment
		(start 117.287294 -163.9062)
		(end 116.74348 -163.362386)
		(width 0.1143)
		(layer "In7.Cu")
		(net "CPLD123_RSV1")
	)
	(segment
		(start 73.659492 -163.734242)
		(end 72.71258 -164.681154)
		(width 0.1143)
		(layer "In7.Cu")
		(net "CPLD123_RSV1")
	)
	(segment
		(start 112.406938 -164.2872)
		(end 110.911894 -162.792156)
		(width 0.1143)
		(layer "In7.Cu")
		(net "CPLD123_RSV1")
	)
	(segment
		(start 71.582026 -166.310564)
		(end 68.621656 -166.310564)
		(width 0.1143)
		(layer "In7.Cu")
		(net "CPLD123_RSV1")
	)
	(segment
		(start 108.116878 -162.792156)
		(end 106.139234 -164.7698)
		(width 0.1143)
		(layer "In7.Cu")
		(net "CPLD123_RSV1")
	)
	(segment
		(start 89.27592 -162.108388)
		(end 88.261698 -161.094166)
		(width 0.1143)
		(layer "In7.Cu")
		(net "CPLD123_RSV1")
	)
	(segment
		(start 123.06554 -163.227004)
		(end 122.667776 -163.624768)
		(width 0.1143)
		(layer "In7.Cu")
		(net "CPLD123_RSV1")
	)
	(segment
		(start 78.923134 -163.734242)
		(end 73.659492 -163.734242)
		(width 0.1143)
		(layer "In7.Cu")
		(net "CPLD123_RSV1")
	)
	(segment
		(start 104.8766 -164.7698)
		(end 104.55402 -164.44722)
		(width 0.1143)
		(layer "In7.Cu")
		(net "CPLD123_RSV1")
	)
	(segment
		(start 68.621656 -166.310564)
		(end 68.48856 -166.44366)
		(width 0.1143)
		(layer "In7.Cu")
		(net "CPLD123_RSV1")
	)
	(segment
		(start 126.15926 -161.647886)
		(end 124.580142 -163.227004)
		(width 0.1143)
		(layer "In7.Cu")
		(net "CPLD123_RSV1")
	)
	(segment
		(start 106.139234 -164.7698)
		(end 104.8766 -164.7698)
		(width 0.1143)
		(layer "In7.Cu")
		(net "CPLD123_RSV1")
	)
	(segment
		(start 116.74348 -163.362386)
		(end 115.837208 -163.362386)
		(width 0.1143)
		(layer "In7.Cu")
		(net "CPLD123_RSV1")
	)
	(segment
		(start 126.15926 -160.931606)
		(end 126.15926 -161.647886)
		(width 0.1143)
		(layer "In7.Cu")
		(net "CPLD123_RSV1")
	)
	(segment
		(start 88.261698 -161.094166)
		(end 81.912206 -161.094166)
		(width 0.1143)
		(layer "In7.Cu")
		(net "CPLD123_RSV1")
	)
	(segment
		(start 122.667776 -163.624768)
		(end 122.2248 -163.624768)
		(width 0.1143)
		(layer "In7.Cu")
		(net "CPLD123_RSV1")
	)
	(segment
		(start 95.0214 -162.108388)
		(end 89.27592 -162.108388)
		(width 0.1143)
		(layer "In7.Cu")
		(net "CPLD123_RSV1")
	)
	(segment
		(start 81.912206 -161.094166)
		(end 80.635094 -162.371278)
		(width 0.1143)
		(layer "In7.Cu")
		(net "CPLD123_RSV1")
	)
	(segment
		(start 115.837208 -163.362386)
		(end 114.912394 -164.2872)
		(width 0.1143)
		(layer "In7.Cu")
		(net "CPLD123_RSV1")
	)
	(segment
		(start 72.71258 -165.18001)
		(end 71.582026 -166.310564)
		(width 0.1143)
		(layer "In7.Cu")
		(net "CPLD123_RSV1")
	)
	(segment
		(start 114.912394 -164.2872)
		(end 112.406938 -164.2872)
		(width 0.1143)
		(layer "In7.Cu")
		(net "CPLD123_RSV1")
	)
	(segment
		(start 80.08874 -162.371278)
		(end 79.55534 -162.904678)
		(width 0.1143)
		(layer "In7.Cu")
		(net "CPLD123_RSV1")
	)
	(segment
		(start 169.817542 -132.121656)
		(end 168.730422 -133.208776)
		(width 0.1016)
		(layer "F.Cu")
		(net "CPLD123_RSV3")
	)
	(segment
		(start 68.97751 -164.621718)
		(end 68.59016 -165.009068)
		(width 0.1016)
		(layer "F.Cu")
		(net "CPLD123_RSV3")
	)
	(segment
		(start 168.730422 -133.208776)
		(end 163.84016 -133.208776)
		(width 0.1016)
		(layer "F.Cu")
		(net "CPLD123_RSV3")
	)
	(segment
		(start 130.502406 -161.150046)
		(end 129.755646 -161.150046)
		(width 0.1016)
		(layer "F.Cu")
		(net "CPLD123_RSV3")
	)
	(segment
		(start 69.354954 -164.621718)
		(end 68.97751 -164.621718)
		(width 0.1016)
		(layer "F.Cu")
		(net "CPLD123_RSV3")
	)
	(segment
		(start 129.755646 -161.150046)
		(end 129.7178 -161.1122)
		(width 0.1016)
		(layer "F.Cu")
		(net "CPLD123_RSV3")
	)
	(segment
		(start 68.59016 -165.009068)
		(end 68.59016 -165.415214)
		(width 0.1016)
		(layer "F.Cu")
		(net "CPLD123_RSV3")
	)
	(via
		(at 123.71832 -45.953172)
		(size 0.508)
		(drill 0.254)
		(layers "F.Cu" "B.Cu")
		(net "CPLD123_RSV3")
	)
	(via
		(at 163.84016 -133.208776)
		(size 0.508)
		(drill 0.254)
		(layers "F.Cu" "B.Cu")
		(net "CPLD123_RSV3")
	)
	(via
		(at 68.59016 -165.415214)
		(size 0.508)
		(drill 0.254)
		(layers "F.Cu" "B.Cu")
		(net "CPLD123_RSV3")
	)
	(via
		(at 129.7178 -161.1122)
		(size 0.508)
		(drill 0.254)
		(layers "F.Cu" "B.Cu")
		(net "CPLD123_RSV3")
	)
	(segment
		(start 124.661676 -45.952156)
		(end 128.375664 -42.238168)
		(width 0.1016)
		(layer "B.Cu")
		(net "CPLD123_RSV3")
	)
	(segment
		(start 134.376414 -34.747454)
		(end 134.796784 -34.327084)
		(width 0.1016)
		(layer "B.Cu")
		(net "CPLD123_RSV3")
	)
	(segment
		(start 134.376414 -35.473386)
		(end 134.376414 -34.747454)
		(width 0.1016)
		(layer "B.Cu")
		(net "CPLD123_RSV3")
	)
	(segment
		(start 130.374136 -37.9984)
		(end 131.8514 -37.9984)
		(width 0.1016)
		(layer "B.Cu")
		(net "CPLD123_RSV3")
	)
	(segment
		(start 128.375664 -39.996872)
		(end 130.374136 -37.9984)
		(width 0.1016)
		(layer "B.Cu")
		(net "CPLD123_RSV3")
	)
	(segment
		(start 123.71832 -45.953172)
		(end 123.71832 -45.952156)
		(width 0.1016)
		(layer "B.Cu")
		(net "CPLD123_RSV3")
	)
	(segment
		(start 128.375664 -42.238168)
		(end 128.375664 -39.996872)
		(width 0.1016)
		(layer "B.Cu")
		(net "CPLD123_RSV3")
	)
	(segment
		(start 131.8514 -37.9984)
		(end 134.376414 -35.473386)
		(width 0.1016)
		(layer "B.Cu")
		(net "CPLD123_RSV3")
	)
	(segment
		(start 123.71832 -45.952156)
		(end 124.661676 -45.952156)
		(width 0.1016)
		(layer "B.Cu")
		(net "CPLD123_RSV3")
	)
	(segment
		(start 147.0533 -152.44953)
		(end 149.96414 -149.53869)
		(width 0.1143)
		(layer "In2.Cu")
		(net "CPLD123_RSV3")
	)
	(segment
		(start 133.38556 -159.104584)
		(end 136.717024 -159.104584)
		(width 0.1143)
		(layer "In2.Cu")
		(net "CPLD123_RSV3")
	)
	(segment
		(start 132.16128 -73.038716)
		(end 153.009092 -93.886528)
		(width 0.1143)
		(layer "In2.Cu")
		(net "CPLD123_RSV3")
	)
	(segment
		(start 132.632958 -158.351982)
		(end 133.38556 -159.104584)
		(width 0.1143)
		(layer "In2.Cu")
		(net "CPLD123_RSV3")
	)
	(segment
		(start 153.81097 -108.078778)
		(end 156.26588 -110.533688)
		(width 0.1143)
		(layer "In2.Cu")
		(net "CPLD123_RSV3")
	)
	(segment
		(start 153.81097 -104.055164)
		(end 153.81097 -108.078778)
		(width 0.1143)
		(layer "In2.Cu")
		(net "CPLD123_RSV3")
	)
	(segment
		(start 123.71832 -45.953172)
		(end 123.09983 -46.571662)
		(width 0.1143)
		(layer "In2.Cu")
		(net "CPLD123_RSV3")
	)
	(segment
		(start 149.96414 -143.796512)
		(end 150.58898 -143.171672)
		(width 0.1143)
		(layer "In2.Cu")
		(net "CPLD123_RSV3")
	)
	(segment
		(start 153.009092 -93.886528)
		(end 153.009092 -103.253286)
		(width 0.1143)
		(layer "In2.Cu")
		(net "CPLD123_RSV3")
	)
	(segment
		(start 163.660836 -133.3881)
		(end 163.84016 -133.208776)
		(width 0.1143)
		(layer "In2.Cu")
		(net "CPLD123_RSV3")
	)
	(segment
		(start 155.790392 -133.3881)
		(end 163.660836 -133.3881)
		(width 0.1143)
		(layer "In2.Cu")
		(net "CPLD123_RSV3")
	)
	(segment
		(start 163.2966 -114.69116)
		(end 163.2966 -130.530092)
		(width 0.1143)
		(layer "In2.Cu")
		(net "CPLD123_RSV3")
	)
	(segment
		(start 132.16128 -71.291196)
		(end 132.16128 -73.038716)
		(width 0.1143)
		(layer "In2.Cu")
		(net "CPLD123_RSV3")
	)
	(segment
		(start 129.7178 -160.626552)
		(end 131.99237 -158.351982)
		(width 0.1143)
		(layer "In2.Cu")
		(net "CPLD123_RSV3")
	)
	(segment
		(start 149.96414 -149.53869)
		(end 149.96414 -143.796512)
		(width 0.1143)
		(layer "In2.Cu")
		(net "CPLD123_RSV3")
	)
	(segment
		(start 150.58898 -143.171672)
		(end 150.58898 -138.589512)
		(width 0.1143)
		(layer "In2.Cu")
		(net "CPLD123_RSV3")
	)
	(segment
		(start 131.99237 -158.351982)
		(end 132.632958 -158.351982)
		(width 0.1143)
		(layer "In2.Cu")
		(net "CPLD123_RSV3")
	)
	(segment
		(start 147.0533 -154.11069)
		(end 147.0533 -152.44953)
		(width 0.1143)
		(layer "In2.Cu")
		(net "CPLD123_RSV3")
	)
	(segment
		(start 150.58898 -138.589512)
		(end 155.790392 -133.3881)
		(width 0.1143)
		(layer "In2.Cu")
		(net "CPLD123_RSV3")
	)
	(segment
		(start 129.7178 -161.1122)
		(end 129.7178 -160.626552)
		(width 0.1143)
		(layer "In2.Cu")
		(net "CPLD123_RSV3")
	)
	(segment
		(start 138.494516 -157.327092)
		(end 143.836898 -157.327092)
		(width 0.1143)
		(layer "In2.Cu")
		(net "CPLD123_RSV3")
	)
	(segment
		(start 153.009092 -103.253286)
		(end 153.81097 -104.055164)
		(width 0.1143)
		(layer "In2.Cu")
		(net "CPLD123_RSV3")
	)
	(segment
		(start 163.2966 -130.530092)
		(end 163.669472 -130.902964)
		(width 0.1143)
		(layer "In2.Cu")
		(net "CPLD123_RSV3")
	)
	(segment
		(start 159.139128 -110.533688)
		(end 163.2966 -114.69116)
		(width 0.1143)
		(layer "In2.Cu")
		(net "CPLD123_RSV3")
	)
	(segment
		(start 123.09983 -61.529468)
		(end 124.28474 -62.714378)
		(width 0.1143)
		(layer "In2.Cu")
		(net "CPLD123_RSV3")
	)
	(segment
		(start 123.09983 -46.571662)
		(end 123.09983 -61.529468)
		(width 0.1143)
		(layer "In2.Cu")
		(net "CPLD123_RSV3")
	)
	(segment
		(start 124.28474 -62.714378)
		(end 124.28474 -63.414656)
		(width 0.1143)
		(layer "In2.Cu")
		(net "CPLD123_RSV3")
	)
	(segment
		(start 143.836898 -157.327092)
		(end 147.0533 -154.11069)
		(width 0.1143)
		(layer "In2.Cu")
		(net "CPLD123_RSV3")
	)
	(segment
		(start 163.669472 -130.902964)
		(end 163.669472 -133.038088)
		(width 0.1143)
		(layer "In2.Cu")
		(net "CPLD123_RSV3")
	)
	(segment
		(start 156.26588 -110.533688)
		(end 159.139128 -110.533688)
		(width 0.1143)
		(layer "In2.Cu")
		(net "CPLD123_RSV3")
	)
	(segment
		(start 163.669472 -133.038088)
		(end 163.84016 -133.208776)
		(width 0.1143)
		(layer "In2.Cu")
		(net "CPLD123_RSV3")
	)
	(segment
		(start 124.28474 -63.414656)
		(end 132.16128 -71.291196)
		(width 0.1143)
		(layer "In2.Cu")
		(net "CPLD123_RSV3")
	)
	(segment
		(start 136.717024 -159.104584)
		(end 138.494516 -157.327092)
		(width 0.1143)
		(layer "In2.Cu")
		(net "CPLD123_RSV3")
	)
	(segment
		(start 72.173592 -164.465762)
		(end 74.801476 -161.837878)
		(width 0.1143)
		(layer "In7.Cu")
		(net "CPLD123_RSV3")
	)
	(segment
		(start 74.801476 -161.837878)
		(end 80.33258 -161.837878)
		(width 0.1143)
		(layer "In7.Cu")
		(net "CPLD123_RSV3")
	)
	(segment
		(start 99.709224 -163.065968)
		(end 100.319586 -162.455606)
		(width 0.1143)
		(layer "In7.Cu")
		(net "CPLD123_RSV3")
	)
	(segment
		(start 126.873 -158.9532)
		(end 129.032 -161.1122)
		(width 0.1143)
		(layer "In7.Cu")
		(net "CPLD123_RSV3")
	)
	(segment
		(start 106.207306 -162.94989)
		(end 107.511596 -161.6456)
		(width 0.1143)
		(layer "In7.Cu")
		(net "CPLD123_RSV3")
	)
	(segment
		(start 68.788026 -165.61308)
		(end 71.52513 -165.61308)
		(width 0.1143)
		(layer "In7.Cu")
		(net "CPLD123_RSV3")
	)
	(segment
		(start 107.511596 -161.6456)
		(end 111.7092 -161.6456)
		(width 0.1143)
		(layer "In7.Cu")
		(net "CPLD123_RSV3")
	)
	(segment
		(start 95.535496 -161.529268)
		(end 97.072196 -163.065968)
		(width 0.1143)
		(layer "In7.Cu")
		(net "CPLD123_RSV3")
	)
	(segment
		(start 112.7506 -162.687)
		(end 113.728246 -162.687)
		(width 0.1143)
		(layer "In7.Cu")
		(net "CPLD123_RSV3")
	)
	(segment
		(start 118.7196 -161.4932)
		(end 119.9388 -161.4932)
		(width 0.1143)
		(layer "In7.Cu")
		(net "CPLD123_RSV3")
	)
	(segment
		(start 118.2116 -162.0012)
		(end 118.7196 -161.4932)
		(width 0.1143)
		(layer "In7.Cu")
		(net "CPLD123_RSV3")
	)
	(segment
		(start 89.45372 -161.529268)
		(end 95.535496 -161.529268)
		(width 0.1143)
		(layer "In7.Cu")
		(net "CPLD123_RSV3")
	)
	(segment
		(start 72.173592 -164.964618)
		(end 72.173592 -164.465762)
		(width 0.1143)
		(layer "In7.Cu")
		(net "CPLD123_RSV3")
	)
	(segment
		(start 88.485218 -160.560766)
		(end 89.45372 -161.529268)
		(width 0.1143)
		(layer "In7.Cu")
		(net "CPLD123_RSV3")
	)
	(segment
		(start 114.414046 -162.0012)
		(end 118.2116 -162.0012)
		(width 0.1143)
		(layer "In7.Cu")
		(net "CPLD123_RSV3")
	)
	(segment
		(start 81.609692 -160.560766)
		(end 88.485218 -160.560766)
		(width 0.1143)
		(layer "In7.Cu")
		(net "CPLD123_RSV3")
	)
	(segment
		(start 129.032 -161.1122)
		(end 129.7178 -161.1122)
		(width 0.1143)
		(layer "In7.Cu")
		(net "CPLD123_RSV3")
	)
	(segment
		(start 125.984 -158.9532)
		(end 126.873 -158.9532)
		(width 0.1143)
		(layer "In7.Cu")
		(net "CPLD123_RSV3")
	)
	(segment
		(start 111.7092 -161.6456)
		(end 112.7506 -162.687)
		(width 0.1143)
		(layer "In7.Cu")
		(net "CPLD123_RSV3")
	)
	(segment
		(start 68.59016 -165.415214)
		(end 68.788026 -165.61308)
		(width 0.1143)
		(layer "In7.Cu")
		(net "CPLD123_RSV3")
	)
	(segment
		(start 97.072196 -163.065968)
		(end 99.709224 -163.065968)
		(width 0.1143)
		(layer "In7.Cu")
		(net "CPLD123_RSV3")
	)
	(segment
		(start 71.52513 -165.61308)
		(end 72.173592 -164.964618)
		(width 0.1143)
		(layer "In7.Cu")
		(net "CPLD123_RSV3")
	)
	(segment
		(start 113.728246 -162.687)
		(end 114.414046 -162.0012)
		(width 0.1143)
		(layer "In7.Cu")
		(net "CPLD123_RSV3")
	)
	(segment
		(start 100.319586 -162.455606)
		(end 103.243634 -162.455606)
		(width 0.1143)
		(layer "In7.Cu")
		(net "CPLD123_RSV3")
	)
	(segment
		(start 119.9388 -161.4932)
		(end 120.280938 -161.835338)
		(width 0.1143)
		(layer "In7.Cu")
		(net "CPLD123_RSV3")
	)
	(segment
		(start 123.101862 -161.835338)
		(end 125.984 -158.9532)
		(width 0.1143)
		(layer "In7.Cu")
		(net "CPLD123_RSV3")
	)
	(segment
		(start 103.243634 -162.455606)
		(end 103.737918 -162.94989)
		(width 0.1143)
		(layer "In7.Cu")
		(net "CPLD123_RSV3")
	)
	(segment
		(start 80.33258 -161.837878)
		(end 81.609692 -160.560766)
		(width 0.1143)
		(layer "In7.Cu")
		(net "CPLD123_RSV3")
	)
	(segment
		(start 120.280938 -161.835338)
		(end 123.101862 -161.835338)
		(width 0.1143)
		(layer "In7.Cu")
		(net "CPLD123_RSV3")
	)
	(segment
		(start 103.737918 -162.94989)
		(end 106.207306 -162.94989)
		(width 0.1143)
		(layer "In7.Cu")
		(net "CPLD123_RSV3")
	)
	(segment
		(start 69.354954 -165.662356)
		(end 69.02069 -165.662356)
		(width 0.1016)
		(layer "F.Cu")
		(net "CPLD123_RSV2")
	)
	(segment
		(start 127.13716 -163.09213)
		(end 127.13716 -160.992566)
		(width 0.1016)
		(layer "F.Cu")
		(net "CPLD123_RSV2")
	)
	(segment
		(start 69.02069 -165.662356)
		(end 68.819522 -165.863524)
		(width 0.1016)
		(layer "F.Cu")
		(net "CPLD123_RSV2")
	)
	(segment
		(start 68.819522 -165.863524)
		(end 68.01485 -165.863524)
		(width 0.1016)
		(layer "F.Cu")
		(net "CPLD123_RSV2")
	)
	(segment
		(start 162.88258 -132.704586)
		(end 162.67938 -132.907786)
		(width 0.1016)
		(layer "F.Cu")
		(net "CPLD123_RSV2")
	)
	(segment
		(start 68.01485 -165.863524)
		(end 67.71894 -166.159434)
		(width 0.1016)
		(layer "F.Cu")
		(net "CPLD123_RSV2")
	)
	(segment
		(start 126.244096 -163.985194)
		(end 127.13716 -163.09213)
		(width 0.1016)
		(layer "F.Cu")
		(net "CPLD123_RSV2")
	)
	(segment
		(start 168.662096 -132.115814)
		(end 168.662096 -132.549646)
		(width 0.1016)
		(layer "F.Cu")
		(net "CPLD123_RSV2")
	)
	(segment
		(start 127.13716 -160.992566)
		(end 127.28448 -160.845246)
		(width 0.1016)
		(layer "F.Cu")
		(net "CPLD123_RSV2")
	)
	(segment
		(start 168.662096 -132.549646)
		(end 168.507156 -132.704586)
		(width 0.1016)
		(layer "F.Cu")
		(net "CPLD123_RSV2")
	)
	(segment
		(start 126.244096 -164.228526)
		(end 126.244096 -163.985194)
		(width 0.1016)
		(layer "F.Cu")
		(net "CPLD123_RSV2")
	)
	(segment
		(start 162.67938 -132.907786)
		(end 162.67938 -132.909564)
		(width 0.1016)
		(layer "F.Cu")
		(net "CPLD123_RSV2")
	)
	(segment
		(start 168.507156 -132.704586)
		(end 162.88258 -132.704586)
		(width 0.1016)
		(layer "F.Cu")
		(net "CPLD123_RSV2")
	)
	(via
		(at 122.555 -46.778926)
		(size 0.508)
		(drill 0.254)
		(layers "F.Cu" "B.Cu")
		(net "CPLD123_RSV2")
	)
	(via
		(at 162.67938 -132.909564)
		(size 0.508)
		(drill 0.254)
		(layers "F.Cu" "B.Cu")
		(net "CPLD123_RSV2")
	)
	(via
		(at 67.71894 -166.159434)
		(size 0.508)
		(drill 0.254)
		(layers "F.Cu" "B.Cu")
		(net "CPLD123_RSV2")
	)
	(via
		(at 127.28448 -160.845246)
		(size 0.508)
		(drill 0.254)
		(layers "F.Cu" "B.Cu")
		(net "CPLD123_RSV2")
	)
	(segment
		(start 122.555 -46.778926)
		(end 124.256546 -46.778926)
		(width 0.1016)
		(layer "B.Cu")
		(net "CPLD123_RSV2")
	)
	(segment
		(start 128.85293 -39.879016)
		(end 130.479546 -38.2524)
		(width 0.1016)
		(layer "B.Cu")
		(net "CPLD123_RSV2")
	)
	(segment
		(start 130.479546 -38.2524)
		(end 132.1308 -38.2524)
		(width 0.1016)
		(layer "B.Cu")
		(net "CPLD123_RSV2")
	)
	(segment
		(start 124.256546 -46.778926)
		(end 128.85293 -42.182542)
		(width 0.1016)
		(layer "B.Cu")
		(net "CPLD123_RSV2")
	)
	(segment
		(start 134.796784 -35.586416)
		(end 134.796784 -35.343084)
		(width 0.1016)
		(layer "B.Cu")
		(net "CPLD123_RSV2")
	)
	(segment
		(start 132.1308 -38.2524)
		(end 134.796784 -35.586416)
		(width 0.1016)
		(layer "B.Cu")
		(net "CPLD123_RSV2")
	)
	(segment
		(start 128.85293 -42.182542)
		(end 128.85293 -39.879016)
		(width 0.1016)
		(layer "B.Cu")
		(net "CPLD123_RSV2")
	)
	(segment
		(start 152.742392 -93.997018)
		(end 152.742392 -103.521002)
		(width 0.1143)
		(layer "In2.Cu")
		(net "CPLD123_RSV2")
	)
	(segment
		(start 123.93168 -63.438786)
		(end 131.89458 -71.401686)
		(width 0.1143)
		(layer "In2.Cu")
		(net "CPLD123_RSV2")
	)
	(segment
		(start 149.6441 -149.373336)
		(end 146.7866 -152.230836)
		(width 0.1143)
		(layer "In2.Cu")
		(net "CPLD123_RSV2")
	)
	(segment
		(start 150.319994 -138.481308)
		(end 150.319994 -141.373098)
		(width 0.1143)
		(layer "In2.Cu")
		(net "CPLD123_RSV2")
	)
	(segment
		(start 146.7866 -152.230836)
		(end 146.7866 -154.0002)
		(width 0.1143)
		(layer "In2.Cu")
		(net "CPLD123_RSV2")
	)
	(segment
		(start 122.555 -46.778926)
		(end 122.67946 -46.903386)
		(width 0.1143)
		(layer "In2.Cu")
		(net "CPLD123_RSV2")
	)
	(segment
		(start 143.726408 -157.060392)
		(end 136.966706 -157.060392)
		(width 0.1143)
		(layer "In2.Cu")
		(net "CPLD123_RSV2")
	)
	(segment
		(start 123.93168 -63.066676)
		(end 123.93168 -63.438786)
		(width 0.1143)
		(layer "In2.Cu")
		(net "CPLD123_RSV2")
	)
	(segment
		(start 162.67938 -131.520692)
		(end 162.67938 -132.909564)
		(width 0.1143)
		(layer "In2.Cu")
		(net "CPLD123_RSV2")
	)
	(segment
		(start 149.6441 -142.048992)
		(end 149.6441 -149.373336)
		(width 0.1143)
		(layer "In2.Cu")
		(net "CPLD123_RSV2")
	)
	(segment
		(start 155.885642 -132.91566)
		(end 150.319994 -138.481308)
		(width 0.1143)
		(layer "In2.Cu")
		(net "CPLD123_RSV2")
	)
	(segment
		(start 135.189214 -158.837884)
		(end 133.49859 -158.837884)
		(width 0.1143)
		(layer "In2.Cu")
		(net "CPLD123_RSV2")
	)
	(segment
		(start 159.028638 -110.800388)
		(end 162.84575 -114.6175)
		(width 0.1143)
		(layer "In2.Cu")
		(net "CPLD123_RSV2")
	)
	(segment
		(start 162.84575 -114.6175)
		(end 162.84575 -130.811778)
		(width 0.1143)
		(layer "In2.Cu")
		(net "CPLD123_RSV2")
	)
	(segment
		(start 130.885184 -158.085282)
		(end 128.12522 -160.845246)
		(width 0.1143)
		(layer "In2.Cu")
		(net "CPLD123_RSV2")
	)
	(segment
		(start 131.89458 -73.149206)
		(end 152.742392 -93.997018)
		(width 0.1143)
		(layer "In2.Cu")
		(net "CPLD123_RSV2")
	)
	(segment
		(start 161.359596 -132.909564)
		(end 161.3535 -132.91566)
		(width 0.1143)
		(layer "In2.Cu")
		(net "CPLD123_RSV2")
	)
	(segment
		(start 132.745988 -158.085282)
		(end 130.885184 -158.085282)
		(width 0.1143)
		(layer "In2.Cu")
		(net "CPLD123_RSV2")
	)
	(segment
		(start 146.7866 -154.0002)
		(end 143.726408 -157.060392)
		(width 0.1143)
		(layer "In2.Cu")
		(net "CPLD123_RSV2")
	)
	(segment
		(start 162.589718 -131.43103)
		(end 162.67938 -131.520692)
		(width 0.1143)
		(layer "In2.Cu")
		(net "CPLD123_RSV2")
	)
	(segment
		(start 122.67946 -46.903386)
		(end 122.67946 -61.814456)
		(width 0.1143)
		(layer "In2.Cu")
		(net "CPLD123_RSV2")
	)
	(segment
		(start 162.589718 -131.06781)
		(end 162.589718 -131.43103)
		(width 0.1143)
		(layer "In2.Cu")
		(net "CPLD123_RSV2")
	)
	(segment
		(start 122.67946 -61.814456)
		(end 123.93168 -63.066676)
		(width 0.1143)
		(layer "In2.Cu")
		(net "CPLD123_RSV2")
	)
	(segment
		(start 156.15539 -110.800388)
		(end 159.028638 -110.800388)
		(width 0.1143)
		(layer "In2.Cu")
		(net "CPLD123_RSV2")
	)
	(segment
		(start 153.54427 -104.32288)
		(end 153.54427 -108.189268)
		(width 0.1143)
		(layer "In2.Cu")
		(net "CPLD123_RSV2")
	)
	(segment
		(start 133.49859 -158.837884)
		(end 132.745988 -158.085282)
		(width 0.1143)
		(layer "In2.Cu")
		(net "CPLD123_RSV2")
	)
	(segment
		(start 161.3535 -132.91566)
		(end 155.885642 -132.91566)
		(width 0.1143)
		(layer "In2.Cu")
		(net "CPLD123_RSV2")
	)
	(segment
		(start 153.54427 -108.189268)
		(end 156.15539 -110.800388)
		(width 0.1143)
		(layer "In2.Cu")
		(net "CPLD123_RSV2")
	)
	(segment
		(start 131.89458 -71.401686)
		(end 131.89458 -73.149206)
		(width 0.1143)
		(layer "In2.Cu")
		(net "CPLD123_RSV2")
	)
	(segment
		(start 162.67938 -132.909564)
		(end 161.359596 -132.909564)
		(width 0.1143)
		(layer "In2.Cu")
		(net "CPLD123_RSV2")
	)
	(segment
		(start 152.742392 -103.521002)
		(end 153.54427 -104.32288)
		(width 0.1143)
		(layer "In2.Cu")
		(net "CPLD123_RSV2")
	)
	(segment
		(start 136.966706 -157.060392)
		(end 135.189214 -158.837884)
		(width 0.1143)
		(layer "In2.Cu")
		(net "CPLD123_RSV2")
	)
	(segment
		(start 150.319994 -141.373098)
		(end 149.6441 -142.048992)
		(width 0.1143)
		(layer "In2.Cu")
		(net "CPLD123_RSV2")
	)
	(segment
		(start 128.12522 -160.845246)
		(end 127.28448 -160.845246)
		(width 0.1143)
		(layer "In2.Cu")
		(net "CPLD123_RSV2")
	)
	(segment
		(start 162.84575 -130.811778)
		(end 162.589718 -131.06781)
		(width 0.1143)
		(layer "In2.Cu")
		(net "CPLD123_RSV2")
	)
	(segment
		(start 120.381014 -162.828986)
		(end 118.8212 -162.828986)
		(width 0.1143)
		(layer "In7.Cu")
		(net "CPLD123_RSV2")
	)
	(segment
		(start 102.340664 -162.722306)
		(end 101.6889 -163.37407)
		(width 0.1143)
		(layer "In7.Cu")
		(net "CPLD123_RSV2")
	)
	(segment
		(start 111.633 -162.0012)
		(end 107.5944 -162.0012)
		(width 0.1143)
		(layer "In7.Cu")
		(net "CPLD123_RSV2")
	)
	(segment
		(start 72.44588 -164.570664)
		(end 72.44588 -165.06952)
		(width 0.1143)
		(layer "In7.Cu")
		(net "CPLD123_RSV2")
	)
	(segment
		(start 114.1984 -162.9664)
		(end 112.5982 -162.9664)
		(width 0.1143)
		(layer "In7.Cu")
		(net "CPLD123_RSV2")
	)
	(segment
		(start 80.47228 -162.104578)
		(end 77.909166 -162.104578)
		(width 0.1143)
		(layer "In7.Cu")
		(net "CPLD123_RSV2")
	)
	(segment
		(start 95.394272 -161.795968)
		(end 89.34323 -161.795968)
		(width 0.1143)
		(layer "In7.Cu")
		(net "CPLD123_RSV2")
	)
	(segment
		(start 103.485188 -163.21659)
		(end 102.990904 -162.722306)
		(width 0.1143)
		(layer "In7.Cu")
		(net "CPLD123_RSV2")
	)
	(segment
		(start 102.990904 -162.722306)
		(end 102.340664 -162.722306)
		(width 0.1143)
		(layer "In7.Cu")
		(net "CPLD123_RSV2")
	)
	(segment
		(start 123.32589 -162.14471)
		(end 121.06529 -162.14471)
		(width 0.1143)
		(layer "In7.Cu")
		(net "CPLD123_RSV2")
	)
	(segment
		(start 99.701604 -163.57092)
		(end 97.169224 -163.57092)
		(width 0.1143)
		(layer "In7.Cu")
		(net "CPLD123_RSV2")
	)
	(segment
		(start 101.6889 -163.37407)
		(end 101.219 -163.37407)
		(width 0.1143)
		(layer "In7.Cu")
		(net "CPLD123_RSV2")
	)
	(segment
		(start 121.06529 -162.14471)
		(end 120.381014 -162.828986)
		(width 0.1143)
		(layer "In7.Cu")
		(net "CPLD123_RSV2")
	)
	(segment
		(start 75.856084 -162.840924)
		(end 75.66152 -162.64636)
		(width 0.1143)
		(layer "In7.Cu")
		(net "CPLD123_RSV2")
	)
	(segment
		(start 77.909166 -162.104578)
		(end 77.17282 -162.840924)
		(width 0.1143)
		(layer "In7.Cu")
		(net "CPLD123_RSV2")
	)
	(segment
		(start 106.37901 -163.21659)
		(end 103.485188 -163.21659)
		(width 0.1143)
		(layer "In7.Cu")
		(net "CPLD123_RSV2")
	)
	(segment
		(start 89.34323 -161.795968)
		(end 88.374728 -160.827466)
		(width 0.1143)
		(layer "In7.Cu")
		(net "CPLD123_RSV2")
	)
	(segment
		(start 112.5982 -162.9664)
		(end 111.633 -162.0012)
		(width 0.1143)
		(layer "In7.Cu")
		(net "CPLD123_RSV2")
	)
	(segment
		(start 71.50989 -166.00551)
		(end 67.872864 -166.00551)
		(width 0.1143)
		(layer "In7.Cu")
		(net "CPLD123_RSV2")
	)
	(segment
		(start 125.5268 -159.9438)
		(end 123.32589 -162.14471)
		(width 0.1143)
		(layer "In7.Cu")
		(net "CPLD123_RSV2")
	)
	(segment
		(start 75.66152 -162.64636)
		(end 74.370184 -162.64636)
		(width 0.1143)
		(layer "In7.Cu")
		(net "CPLD123_RSV2")
	)
	(segment
		(start 100.734114 -163.858956)
		(end 99.98964 -163.858956)
		(width 0.1143)
		(layer "In7.Cu")
		(net "CPLD123_RSV2")
	)
	(segment
		(start 72.44588 -165.06952)
		(end 71.50989 -166.00551)
		(width 0.1143)
		(layer "In7.Cu")
		(net "CPLD123_RSV2")
	)
	(segment
		(start 107.5944 -162.0012)
		(end 106.37901 -163.21659)
		(width 0.1143)
		(layer "In7.Cu")
		(net "CPLD123_RSV2")
	)
	(segment
		(start 97.169224 -163.57092)
		(end 95.394272 -161.795968)
		(width 0.1143)
		(layer "In7.Cu")
		(net "CPLD123_RSV2")
	)
	(segment
		(start 99.98964 -163.858956)
		(end 99.701604 -163.57092)
		(width 0.1143)
		(layer "In7.Cu")
		(net "CPLD123_RSV2")
	)
	(segment
		(start 88.374728 -160.827466)
		(end 81.749392 -160.827466)
		(width 0.1143)
		(layer "In7.Cu")
		(net "CPLD123_RSV2")
	)
	(segment
		(start 114.8334 -162.3314)
		(end 114.1984 -162.9664)
		(width 0.1143)
		(layer "In7.Cu")
		(net "CPLD123_RSV2")
	)
	(segment
		(start 118.8212 -162.828986)
		(end 118.323614 -162.3314)
		(width 0.1143)
		(layer "In7.Cu")
		(net "CPLD123_RSV2")
	)
	(segment
		(start 127.28448 -160.73628)
		(end 126.492 -159.9438)
		(width 0.1143)
		(layer "In7.Cu")
		(net "CPLD123_RSV2")
	)
	(segment
		(start 127.28448 -160.845246)
		(end 127.28448 -160.73628)
		(width 0.1143)
		(layer "In7.Cu")
		(net "CPLD123_RSV2")
	)
	(segment
		(start 118.323614 -162.3314)
		(end 114.8334 -162.3314)
		(width 0.1143)
		(layer "In7.Cu")
		(net "CPLD123_RSV2")
	)
	(segment
		(start 101.219 -163.37407)
		(end 100.734114 -163.858956)
		(width 0.1143)
		(layer "In7.Cu")
		(net "CPLD123_RSV2")
	)
	(segment
		(start 126.492 -159.9438)
		(end 125.5268 -159.9438)
		(width 0.1143)
		(layer "In7.Cu")
		(net "CPLD123_RSV2")
	)
	(segment
		(start 77.17282 -162.840924)
		(end 75.856084 -162.840924)
		(width 0.1143)
		(layer "In7.Cu")
		(net "CPLD123_RSV2")
	)
	(segment
		(start 67.872864 -166.00551)
		(end 67.71894 -166.159434)
		(width 0.1143)
		(layer "In7.Cu")
		(net "CPLD123_RSV2")
	)
	(segment
		(start 81.749392 -160.827466)
		(end 80.47228 -162.104578)
		(width 0.1143)
		(layer "In7.Cu")
		(net "CPLD123_RSV2")
	)
	(segment
		(start 74.370184 -162.64636)
		(end 72.44588 -164.570664)
		(width 0.1143)
		(layer "In7.Cu")
		(net "CPLD123_RSV2")
	)
	(segment
		(start 62.941708 -128.058926)
		(end 62.540896 -127.658114)
		(width 0.1016)
		(layer "F.Cu")
		(net "BMC_ROMA0")
	)
	(segment
		(start 62.941708 -128.059434)
		(end 62.941708 -128.058926)
		(width 0.1016)
		(layer "F.Cu")
		(net "BMC_ROMA0")
	)
	(via
		(at 62.540896 -127.658114)
		(size 0.49022)
		(drill 0.254)
		(layers "F.Cu" "B.Cu")
		(net "BMC_ROMA0")
	)
	(via
		(at 61.595508 -126.0602)
		(size 0.6604)
		(drill 0.3302)
		(layers "F.Cu" "B.Cu")
		(net "BMC_ROMA0")
	)
	(segment
		(start 61.595508 -126.576074)
		(end 61.595508 -126.0602)
		(width 0.1016)
		(layer "B.Cu")
		(net "BMC_ROMA0")
	)
	(segment
		(start 61.595508 -125.757432)
		(end 61.595508 -126.0602)
		(width 0.1016)
		(layer "B.Cu")
		(net "BMC_ROMA0")
	)
	(segment
		(start 61.876686 -126.993904)
		(end 61.876686 -126.857252)
		(width 0.1016)
		(layer "B.Cu")
		(net "BMC_ROMA0")
	)
	(segment
		(start 61.523372 -123.319794)
		(end 61.523372 -125.685296)
		(width 0.1016)
		(layer "B.Cu")
		(net "BMC_ROMA0")
	)
	(segment
		(start 61.876686 -126.857252)
		(end 61.595508 -126.576074)
		(width 0.1016)
		(layer "B.Cu")
		(net "BMC_ROMA0")
	)
	(segment
		(start 62.506606 -122.33656)
		(end 61.523372 -123.319794)
		(width 0.1016)
		(layer "B.Cu")
		(net "BMC_ROMA0")
	)
	(segment
		(start 62.540896 -127.658114)
		(end 61.876686 -126.993904)
		(width 0.1016)
		(layer "B.Cu")
		(net "BMC_ROMA0")
	)
	(segment
		(start 62.506606 -121.457466)
		(end 62.506606 -122.33656)
		(width 0.1016)
		(layer "B.Cu")
		(net "BMC_ROMA0")
	)
	(segment
		(start 61.523372 -125.685296)
		(end 61.595508 -125.757432)
		(width 0.1016)
		(layer "B.Cu")
		(net "BMC_ROMA0")
	)
	(segment
		(start 61.341762 -126.459488)
		(end 61.341762 -126.202948)
		(width 0.1016)
		(layer "F.Cu")
		(net "BMC_ROMD3")
	)
	(segment
		(start 61.341762 -126.202948)
		(end 61.182504 -126.04369)
		(width 0.1016)
		(layer "F.Cu")
		(net "BMC_ROMD3")
	)
	(segment
		(start 58.065416 -119.452644)
		(end 58.065416 -121.839228)
		(width 0.1016)
		(layer "F.Cu")
		(net "BMC_ROMD3")
	)
	(segment
		(start 60.682886 -125.290834)
		(end 60.682886 -124.574046)
		(width 0.1016)
		(layer "F.Cu")
		(net "BMC_ROMD3")
	)
	(segment
		(start 60.682886 -124.574046)
		(end 58.065416 -121.956576)
		(width 0.1016)
		(layer "F.Cu")
		(net "BMC_ROMD3")
	)
	(segment
		(start 61.182504 -126.04369)
		(end 61.182504 -125.790452)
		(width 0.1016)
		(layer "F.Cu")
		(net "BMC_ROMD3")
	)
	(segment
		(start 58.065416 -121.956576)
		(end 58.065416 -121.839228)
		(width 0.1016)
		(layer "F.Cu")
		(net "BMC_ROMD3")
	)
	(segment
		(start 61.182504 -125.790452)
		(end 60.682886 -125.290834)
		(width 0.1016)
		(layer "F.Cu")
		(net "BMC_ROMD3")
	)
	(segment
		(start 57.973468 -119.360696)
		(end 58.065416 -119.452644)
		(width 0.1016)
		(layer "F.Cu")
		(net "BMC_ROMD3")
	)
	(via
		(at 58.065416 -121.839228)
		(size 0.508)
		(drill 0.254)
		(layers "F.Cu" "B.Cu")
		(net "BMC_ROMD3")
	)
	(segment
		(start 56.884062 -119.371618)
		(end 56.884062 -119.413782)
		(width 0.1016)
		(layer "F.Cu")
		(net "BMC_ROMD4")
	)
	(segment
		(start 60.928504 -125.895862)
		(end 60.428886 -125.396244)
		(width 0.1016)
		(layer "F.Cu")
		(net "BMC_ROMD4")
	)
	(segment
		(start 60.928504 -126.84633)
		(end 60.928504 -125.895862)
		(width 0.1016)
		(layer "F.Cu")
		(net "BMC_ROMD4")
	)
	(segment
		(start 56.884062 -119.413782)
		(end 57.46877 -119.99849)
		(width 0.1016)
		(layer "F.Cu")
		(net "BMC_ROMD4")
	)
	(segment
		(start 60.428886 -125.396244)
		(end 60.428886 -125.16866)
		(width 0.1016)
		(layer "F.Cu")
		(net "BMC_ROMD4")
	)
	(segment
		(start 57.46877 -122.208544)
		(end 57.46877 -120.035066)
		(width 0.1016)
		(layer "F.Cu")
		(net "BMC_ROMD4")
	)
	(segment
		(start 60.428886 -125.16866)
		(end 57.46877 -122.208544)
		(width 0.1016)
		(layer "F.Cu")
		(net "BMC_ROMD4")
	)
	(segment
		(start 61.341762 -127.259588)
		(end 60.928504 -126.84633)
		(width 0.1016)
		(layer "F.Cu")
		(net "BMC_ROMD4")
	)
	(segment
		(start 57.46877 -119.99849)
		(end 57.46877 -120.035066)
		(width 0.1016)
		(layer "F.Cu")
		(net "BMC_ROMD4")
	)
	(via
		(at 57.46877 -120.035066)
		(size 0.508)
		(drill 0.254)
		(layers "F.Cu" "B.Cu")
		(net "BMC_ROMD4")
	)
	(segment
		(start 181.01056 -126.171198)
		(end 181.350412 -126.51105)
		(width 0.1016)
		(layer "F.Cu")
		(net "SYS_AUTO_POWER_ON_N")
	)
	(segment
		(start 181.01056 -125.365764)
		(end 181.01056 -126.171198)
		(width 0.1016)
		(layer "F.Cu")
		(net "SYS_AUTO_POWER_ON_N")
	)
	(segment
		(start 183.485282 -130.202178)
		(end 181.350412 -128.067308)
		(width 0.1016)
		(layer "F.Cu")
		(net "SYS_AUTO_POWER_ON_N")
	)
	(segment
		(start 184.614566 -130.202178)
		(end 183.485282 -130.202178)
		(width 0.1016)
		(layer "F.Cu")
		(net "SYS_AUTO_POWER_ON_N")
	)
	(segment
		(start 181.350412 -128.067308)
		(end 181.350412 -126.51105)
		(width 0.1016)
		(layer "F.Cu")
		(net "SYS_AUTO_POWER_ON_N")
	)
	(via
		(at 181.350412 -126.51105)
		(size 0.508)
		(drill 0.254)
		(layers "F.Cu" "B.Cu")
		(net "SYS_AUTO_POWER_ON_N")
	)
	(segment
		(start 160.800796 -33.589214)
		(end 160.800796 -33.086802)
		(width 0.1016)
		(layer "F.Cu")
		(net "N37284163")
	)
	(segment
		(start 160.524952 -32.810958)
		(end 160.107884 -32.810958)
		(width 0.1016)
		(layer "F.Cu")
		(net "N37284163")
	)
	(segment
		(start 160.107884 -32.810958)
		(end 159.784034 -33.134808)
		(width 0.1016)
		(layer "F.Cu")
		(net "N37284163")
	)
	(segment
		(start 160.800796 -33.086802)
		(end 160.524952 -32.810958)
		(width 0.1016)
		(layer "F.Cu")
		(net "N37284163")
	)
	(segment
		(start 159.699452 -33.785048)
		(end 160.055306 -33.785048)
		(width 0.1016)
		(layer "F.Cu")
		(net "N37284163")
	)
	(segment
		(start 160.055306 -33.785048)
		(end 160.25114 -33.589214)
		(width 0.1016)
		(layer "F.Cu")
		(net "N37284163")
	)
	(segment
		(start 160.25114 -33.589214)
		(end 160.800796 -33.589214)
		(width 0.1016)
		(layer "F.Cu")
		(net "N37284163")
	)
	(segment
		(start 159.784034 -33.134808)
		(end 158.271972 -33.134808)
		(width 0.1016)
		(layer "F.Cu")
		(net "N37284163")
	)
	(segment
		(start 159.699452 -33.785048)
		(end 158.271972 -33.785048)
		(width 0.1016)
		(layer "F.Cu")
		(net "N37284163")
	)
	(via
		(at 159.699452 -33.785048)
		(size 0.508)
		(drill 0.254)
		(layers "F.Cu" "B.Cu")
		(net "N37284163")
	)
	(segment
		(start 131.16179 -175.108616)
		(end 129.775712 -175.108616)
		(width 0.1016)
		(layer "F.Cu")
		(net "CPLD_EXT_RST_N")
	)
	(segment
		(start 174.01032 -121.365518)
		(end 174.01032 -121.365772)
		(width 0.1016)
		(layer "F.Cu")
		(net "CPLD_EXT_RST_N")
	)
	(segment
		(start 174.01032 -121.365772)
		(end 173.510448 -121.865644)
		(width 0.1016)
		(layer "F.Cu")
		(net "CPLD_EXT_RST_N")
	)
	(segment
		(start 131.543552 -174.726854)
		(end 131.16179 -175.108616)
		(width 0.1016)
		(layer "F.Cu")
		(net "CPLD_EXT_RST_N")
	)
	(via
		(at 173.510448 -121.865644)
		(size 0.508)
		(drill 0.254)
		(layers "F.Cu" "B.Cu")
		(net "CPLD_EXT_RST_N")
	)
	(via
		(at 131.543552 -174.726854)
		(size 0.508)
		(drill 0.254)
		(layers "F.Cu" "B.Cu")
		(net "CPLD_EXT_RST_N")
	)
	(segment
		(start 155.76423 -151.353266)
		(end 155.76423 -151.716486)
		(width 0.1143)
		(layer "In2.Cu")
		(net "CPLD_EXT_RST_N")
	)
	(segment
		(start 173.939708 -122.294904)
		(end 173.939708 -124.438664)
		(width 0.1143)
		(layer "In2.Cu")
		(net "CPLD_EXT_RST_N")
	)
	(segment
		(start 168.061132 -131.637278)
		(end 164.254942 -135.443468)
		(width 0.1143)
		(layer "In2.Cu")
		(net "CPLD_EXT_RST_N")
	)
	(segment
		(start 144.73682 -162.976052)
		(end 144.138396 -163.573714)
		(width 0.1143)
		(layer "In2.Cu")
		(net "CPLD_EXT_RST_N")
	)
	(segment
		(start 136.93013 -164.943536)
		(end 133.27507 -168.598596)
		(width 0.1143)
		(layer "In2.Cu")
		(net "CPLD_EXT_RST_N")
	)
	(segment
		(start 133.27507 -173.025562)
		(end 134.324344 -174.074836)
		(width 0.1143)
		(layer "In2.Cu")
		(net "CPLD_EXT_RST_N")
	)
	(segment
		(start 155.07843 -147.857718)
		(end 155.07843 -150.667466)
		(width 0.1143)
		(layer "In2.Cu")
		(net "CPLD_EXT_RST_N")
	)
	(segment
		(start 155.954984 -139.901168)
		(end 155.954984 -146.981164)
		(width 0.1143)
		(layer "In2.Cu")
		(net "CPLD_EXT_RST_N")
	)
	(segment
		(start 160.412684 -135.443468)
		(end 155.954984 -139.901168)
		(width 0.1143)
		(layer "In2.Cu")
		(net "CPLD_EXT_RST_N")
	)
	(segment
		(start 173.510448 -121.865644)
		(end 173.939708 -122.294904)
		(width 0.1143)
		(layer "In2.Cu")
		(net "CPLD_EXT_RST_N")
	)
	(segment
		(start 134.324344 -174.074836)
		(end 134.324344 -174.438818)
		(width 0.1143)
		(layer "In2.Cu")
		(net "CPLD_EXT_RST_N")
	)
	(segment
		(start 144.138396 -163.573714)
		(end 141.55928 -163.573714)
		(width 0.1143)
		(layer "In2.Cu")
		(net "CPLD_EXT_RST_N")
	)
	(segment
		(start 155.06192 -155.152598)
		(end 147.238466 -162.976052)
		(width 0.1143)
		(layer "In2.Cu")
		(net "CPLD_EXT_RST_N")
	)
	(segment
		(start 168.061132 -130.31724)
		(end 168.061132 -131.637278)
		(width 0.1143)
		(layer "In2.Cu")
		(net "CPLD_EXT_RST_N")
	)
	(segment
		(start 141.55928 -163.573714)
		(end 140.189458 -164.943536)
		(width 0.1143)
		(layer "In2.Cu")
		(net "CPLD_EXT_RST_N")
	)
	(segment
		(start 155.954984 -146.981164)
		(end 155.07843 -147.857718)
		(width 0.1143)
		(layer "In2.Cu")
		(net "CPLD_EXT_RST_N")
	)
	(segment
		(start 155.06192 -152.418796)
		(end 155.06192 -155.152598)
		(width 0.1143)
		(layer "In2.Cu")
		(net "CPLD_EXT_RST_N")
	)
	(segment
		(start 155.07843 -150.667466)
		(end 155.76423 -151.353266)
		(width 0.1143)
		(layer "In2.Cu")
		(net "CPLD_EXT_RST_N")
	)
	(segment
		(start 155.76423 -151.716486)
		(end 155.06192 -152.418796)
		(width 0.1143)
		(layer "In2.Cu")
		(net "CPLD_EXT_RST_N")
	)
	(segment
		(start 173.939708 -124.438664)
		(end 168.061132 -130.31724)
		(width 0.1143)
		(layer "In2.Cu")
		(net "CPLD_EXT_RST_N")
	)
	(segment
		(start 133.27507 -168.598596)
		(end 133.27507 -173.025562)
		(width 0.1143)
		(layer "In2.Cu")
		(net "CPLD_EXT_RST_N")
	)
	(segment
		(start 147.238466 -162.976052)
		(end 144.73682 -162.976052)
		(width 0.1143)
		(layer "In2.Cu")
		(net "CPLD_EXT_RST_N")
	)
	(segment
		(start 134.324344 -174.438818)
		(end 134.036308 -174.726854)
		(width 0.1143)
		(layer "In2.Cu")
		(net "CPLD_EXT_RST_N")
	)
	(segment
		(start 164.254942 -135.443468)
		(end 160.412684 -135.443468)
		(width 0.1143)
		(layer "In2.Cu")
		(net "CPLD_EXT_RST_N")
	)
	(segment
		(start 140.189458 -164.943536)
		(end 136.93013 -164.943536)
		(width 0.1143)
		(layer "In2.Cu")
		(net "CPLD_EXT_RST_N")
	)
	(segment
		(start 134.036308 -174.726854)
		(end 131.543552 -174.726854)
		(width 0.1143)
		(layer "In2.Cu")
		(net "CPLD_EXT_RST_N")
	)
	(segment
		(start 70.884796 -176.713642)
		(end 70.47865 -176.713642)
		(width 0.1016)
		(layer "F.Cu")
		(net "WDT_LED")
	)
	(segment
		(start 71.473822 -176.124616)
		(end 70.884796 -176.713642)
		(width 0.1016)
		(layer "F.Cu")
		(net "WDT_LED")
	)
	(segment
		(start 68.61429 -177.010314)
		(end 68.61429 -177.009806)
		(width 0.1016)
		(layer "F.Cu")
		(net "WDT_LED")
	)
	(segment
		(start 68.61429 -177.009806)
		(end 68.84289 -176.781206)
		(width 0.1016)
		(layer "F.Cu")
		(net "WDT_LED")
	)
	(segment
		(start 68.84289 -176.781206)
		(end 70.411086 -176.781206)
		(width 0.1016)
		(layer "F.Cu")
		(net "WDT_LED")
	)
	(segment
		(start 72.244712 -176.124616)
		(end 71.473822 -176.124616)
		(width 0.1016)
		(layer "F.Cu")
		(net "WDT_LED")
	)
	(segment
		(start 70.411086 -176.781206)
		(end 70.47865 -176.713642)
		(width 0.1016)
		(layer "F.Cu")
		(net "WDT_LED")
	)
	(via
		(at 70.47865 -176.713642)
		(size 0.508)
		(drill 0.254)
		(layers "F.Cu" "B.Cu")
		(net "WDT_LED")
	)
	(segment
		(start 11.887962 -26.04516)
		(end 11.887962 -27.613356)
		(width 0.1016)
		(layer "F.Cu")
		(net "N54251449")
	)
	(segment
		(start 11.889994 -29.378656)
		(end 11.889994 -27.97048)
		(width 0.1016)
		(layer "F.Cu")
		(net "N54251449")
	)
	(segment
		(start 12.538202 -27.322272)
		(end 12.06754 -27.792934)
		(width 0.1016)
		(layer "F.Cu")
		(net "N54251449")
	)
	(segment
		(start 11.887962 -27.613356)
		(end 12.06754 -27.792934)
		(width 0.1016)
		(layer "F.Cu")
		(net "N54251449")
	)
	(segment
		(start 11.889994 -27.97048)
		(end 12.06754 -27.792934)
		(width 0.1016)
		(layer "F.Cu")
		(net "N54251449")
	)
	(segment
		(start 12.538202 -26.04516)
		(end 12.538202 -27.322272)
		(width 0.1016)
		(layer "F.Cu")
		(net "N54251449")
	)
	(via
		(at 12.06754 -27.792934)
		(size 0.508)
		(drill 0.254)
		(layers "F.Cu" "B.Cu")
		(net "N54251449")
	)
	(segment
		(start 20.688808 -52.262532)
		(end 21.406358 -51.544982)
		(width 0.1016)
		(layer "F.Cu")
		(net "VGA_HSYNC")
	)
	(segment
		(start 21.406358 -51.544982)
		(end 23.426928 -51.544982)
		(width 0.1016)
		(layer "F.Cu")
		(net "VGA_HSYNC")
	)
	(segment
		(start 26.405332 -50.988214)
		(end 26.405332 -51.858418)
		(width 0.1016)
		(layer "F.Cu")
		(net "VGA_HSYNC")
	)
	(segment
		(start 18.429478 -51.92903)
		(end 18.76298 -52.262532)
		(width 0.1016)
		(layer "F.Cu")
		(net "VGA_HSYNC")
	)
	(segment
		(start 18.76298 -52.262532)
		(end 20.688808 -52.262532)
		(width 0.1016)
		(layer "F.Cu")
		(net "VGA_HSYNC")
	)
	(segment
		(start 16.486124 -51.92903)
		(end 18.429478 -51.92903)
		(width 0.1016)
		(layer "F.Cu")
		(net "VGA_HSYNC")
	)
	(segment
		(start 26.23185 -50.814732)
		(end 26.405332 -50.988214)
		(width 0.1016)
		(layer "F.Cu")
		(net "VGA_HSYNC")
	)
	(segment
		(start 24.157178 -50.814732)
		(end 26.23185 -50.814732)
		(width 0.1016)
		(layer "F.Cu")
		(net "VGA_HSYNC")
	)
	(segment
		(start 23.426928 -51.544982)
		(end 24.157178 -50.814732)
		(width 0.1016)
		(layer "F.Cu")
		(net "VGA_HSYNC")
	)
	(via
		(at 18.76298 -52.262532)
		(size 0.508)
		(drill 0.254)
		(layers "F.Cu" "B.Cu")
		(net "VGA_HSYNC")
	)
	(segment
		(start 18.1991 -61.14288)
		(end 20.408392 -61.14288)
		(width 0.1016)
		(layer "F.Cu")
		(net "VGA_VSYNC")
	)
	(segment
		(start 25.848564 -58.109612)
		(end 26.4033 -57.031128)
		(width 0.1016)
		(layer "F.Cu")
		(net "VGA_VSYNC")
	)
	(segment
		(start 23.755604 -60.04306)
		(end 24.549608 -59.408568)
		(width 0.1016)
		(layer "F.Cu")
		(net "VGA_VSYNC")
	)
	(segment
		(start 22.731984 -60.652914)
		(end 23.755604 -60.04306)
		(width 0.1016)
		(layer "F.Cu")
		(net "VGA_VSYNC")
	)
	(segment
		(start 21.444966 -60.652914)
		(end 22.731984 -60.652914)
		(width 0.1016)
		(layer "F.Cu")
		(net "VGA_VSYNC")
	)
	(segment
		(start 26.4033 -56.066436)
		(end 26.405332 -56.064404)
		(width 0.1016)
		(layer "F.Cu")
		(net "VGA_VSYNC")
	)
	(segment
		(start 26.405332 -56.064404)
		(end 26.405332 -55.558436)
		(width 0.1016)
		(layer "F.Cu")
		(net "VGA_VSYNC")
	)
	(segment
		(start 15.247366 -60.71362)
		(end 16.184372 -60.71362)
		(width 0.1016)
		(layer "F.Cu")
		(net "VGA_VSYNC")
	)
	(segment
		(start 26.4033 -57.031128)
		(end 26.4033 -56.066436)
		(width 0.1016)
		(layer "F.Cu")
		(net "VGA_VSYNC")
	)
	(segment
		(start 24.549608 -59.408568)
		(end 25.848564 -58.109612)
		(width 0.1016)
		(layer "F.Cu")
		(net "VGA_VSYNC")
	)
	(segment
		(start 20.408392 -61.14288)
		(end 21.444966 -60.652914)
		(width 0.1016)
		(layer "F.Cu")
		(net "VGA_VSYNC")
	)
	(segment
		(start 16.184372 -60.71362)
		(end 18.1991 -61.14288)
		(width 0.1016)
		(layer "F.Cu")
		(net "VGA_VSYNC")
	)
	(via
		(at 16.184372 -60.71362)
		(size 0.508)
		(drill 0.254)
		(layers "F.Cu" "B.Cu")
		(net "VGA_VSYNC")
	)
	(segment
		(start 25.65908 -56.730392)
		(end 25.226772 -57.1627)
		(width 0.1016)
		(layer "F.Cu")
		(net "GFX_BUF_EN_N")
	)
	(segment
		(start 25.226772 -57.1627)
		(end 25.226772 -57.362344)
		(width 0.1016)
		(layer "F.Cu")
		(net "GFX_BUF_EN_N")
	)
	(segment
		(start 25.10536 -54.062376)
		(end 25.755346 -54.712362)
		(width 0.1016)
		(layer "F.Cu")
		(net "GFX_BUF_EN_N")
	)
	(segment
		(start 25.755346 -54.712362)
		(end 25.755346 -55.558436)
		(width 0.1016)
		(layer "F.Cu")
		(net "GFX_BUF_EN_N")
	)
	(segment
		(start 25.10536 -51.858418)
		(end 25.10536 -54.062376)
		(width 0.1016)
		(layer "F.Cu")
		(net "GFX_BUF_EN_N")
	)
	(segment
		(start 25.755346 -56.634126)
		(end 25.65908 -56.730392)
		(width 0.1016)
		(layer "F.Cu")
		(net "GFX_BUF_EN_N")
	)
	(segment
		(start 25.755346 -55.558436)
		(end 25.755346 -56.634126)
		(width 0.1016)
		(layer "F.Cu")
		(net "GFX_BUF_EN_N")
	)
	(via
		(at 25.65908 -56.730392)
		(size 0.508)
		(drill 0.254)
		(layers "F.Cu" "B.Cu")
		(net "GFX_BUF_EN_N")
	)
	(segment
		(start 70.941692 -140.85951)
		(end 70.9422 -140.85951)
		(width 0.1016)
		(layer "F.Cu")
		(net "N20822523")
	)
	(segment
		(start 70.9422 -140.85951)
		(end 71.341996 -141.259306)
		(width 0.1016)
		(layer "F.Cu")
		(net "N20822523")
	)
	(via
		(at 71.341996 -141.259306)
		(size 0.508)
		(drill 0.254)
		(layers "F.Cu" "B.Cu")
		(net "N20822523")
	)
	(via
		(at 74.906886 -146.977862)
		(size 0.6604)
		(drill 0.3302)
		(layers "F.Cu" "B.Cu")
		(net "N20822523")
	)
	(segment
		(start 74.906886 -146.313906)
		(end 73.002902 -144.409922)
		(width 0.1016)
		(layer "B.Cu")
		(net "N20822523")
	)
	(segment
		(start 72.01662 -144.409922)
		(end 71.739506 -144.132808)
		(width 0.1016)
		(layer "B.Cu")
		(net "N20822523")
	)
	(segment
		(start 73.002902 -144.409922)
		(end 72.01662 -144.409922)
		(width 0.1016)
		(layer "B.Cu")
		(net "N20822523")
	)
	(segment
		(start 74.906886 -146.977862)
		(end 74.906886 -146.313906)
		(width 0.1016)
		(layer "B.Cu")
		(net "N20822523")
	)
	(segment
		(start 71.65213 -141.56944)
		(end 71.341996 -141.259306)
		(width 0.1016)
		(layer "B.Cu")
		(net "N20822523")
	)
	(segment
		(start 71.739506 -144.132808)
		(end 71.739506 -141.656816)
		(width 0.1016)
		(layer "B.Cu")
		(net "N20822523")
	)
	(segment
		(start 74.906886 -146.977862)
		(end 74.906886 -148.076412)
		(width 0.1016)
		(layer "B.Cu")
		(net "N20822523")
	)
	(segment
		(start 71.739506 -141.656816)
		(end 71.65213 -141.569694)
		(width 0.1016)
		(layer "B.Cu")
		(net "N20822523")
	)
	(segment
		(start 71.65213 -141.569694)
		(end 71.65213 -141.56944)
		(width 0.1016)
		(layer "B.Cu")
		(net "N20822523")
	)
	(segment
		(start 60.141104 -126.01448)
		(end 59.477656 -125.351032)
		(width 0.1016)
		(layer "F.Cu")
		(net "PECIVDD")
	)
	(segment
		(start 57.111392 -122.704098)
		(end 57.111392 -121.3358)
		(width 0.1016)
		(layer "F.Cu")
		(net "PECIVDD")
	)
	(segment
		(start 57.111392 -121.3358)
		(end 56.841644 -121.066052)
		(width 0.1016)
		(layer "F.Cu")
		(net "PECIVDD")
	)
	(segment
		(start 60.541916 -128.859534)
		(end 60.141104 -128.458722)
		(width 0.1016)
		(layer "F.Cu")
		(net "PECIVDD")
	)
	(segment
		(start 60.141104 -128.458722)
		(end 60.141104 -126.01448)
		(width 0.1016)
		(layer "F.Cu")
		(net "PECIVDD")
	)
	(segment
		(start 59.477656 -125.070362)
		(end 57.111392 -122.704098)
		(width 0.1016)
		(layer "F.Cu")
		(net "PECIVDD")
	)
	(segment
		(start 59.477656 -125.351032)
		(end 59.477656 -125.070362)
		(width 0.1016)
		(layer "F.Cu")
		(net "PECIVDD")
	)
	(via
		(at 58.12028 -118.81612)
		(size 0.6604)
		(drill 0.3302)
		(layers "F.Cu" "B.Cu")
		(net "PECIVDD")
	)
	(via
		(at 56.841644 -121.066052)
		(size 0.508)
		(drill 0.254)
		(layers "F.Cu" "B.Cu")
		(net "PECIVDD")
	)
	(segment
		(start 58.12028 -118.81612)
		(end 58.12028 -120.102122)
		(width 0.1016)
		(layer "B.Cu")
		(net "PECIVDD")
	)
	(segment
		(start 57.482486 -120.739916)
		(end 57.16778 -120.739916)
		(width 0.1016)
		(layer "B.Cu")
		(net "PECIVDD")
	)
	(segment
		(start 57.16778 -120.739916)
		(end 56.841644 -121.066052)
		(width 0.1016)
		(layer "B.Cu")
		(net "PECIVDD")
	)
	(segment
		(start 58.12028 -120.102122)
		(end 57.482486 -120.739916)
		(width 0.1016)
		(layer "B.Cu")
		(net "PECIVDD")
	)
	(segment
		(start 167.791892 -118.346728)
		(end 167.596312 -118.151148)
		(width 0.1016)
		(layer "F.Cu")
		(net "TP_FM_CPLD_NODE1_BMC_EXTRST_L")
	)
	(segment
		(start 172.550328 -118.905528)
		(end 171.838112 -118.905528)
		(width 0.1016)
		(layer "F.Cu")
		(net "TP_FM_CPLD_NODE1_BMC_EXTRST_L")
	)
	(segment
		(start 171.279312 -118.346728)
		(end 167.791892 -118.346728)
		(width 0.1016)
		(layer "F.Cu")
		(net "TP_FM_CPLD_NODE1_BMC_EXTRST_L")
	)
	(segment
		(start 171.838112 -118.905528)
		(end 171.279312 -118.346728)
		(width 0.1016)
		(layer "F.Cu")
		(net "TP_FM_CPLD_NODE1_BMC_EXTRST_L")
	)
	(segment
		(start 173.010322 -119.365522)
		(end 172.550328 -118.905528)
		(width 0.1016)
		(layer "F.Cu")
		(net "TP_FM_CPLD_NODE1_BMC_EXTRST_L")
	)
	(via
		(at 167.596312 -118.151148)
		(size 0.508)
		(drill 0.254)
		(layers "F.Cu" "B.Cu")
		(net "TP_FM_CPLD_NODE1_BMC_EXTRST_L")
	)
	(segment
		(start 73.341738 -128.059434)
		(end 73.742042 -127.65913)
		(width 0.1016)
		(layer "F.Cu")
		(net "LPC_CLK_AST")
	)
	(via
		(at 73.742042 -127.65913)
		(size 0.49022)
		(drill 0.254)
		(layers "F.Cu" "B.Cu")
		(net "LPC_CLK_AST")
	)
	(segment
		(start 76.570078 -128.357884)
		(end 75.871324 -127.65913)
		(width 0.1016)
		(layer "B.Cu")
		(net "LPC_CLK_AST")
	)
	(segment
		(start 75.871324 -127.65913)
		(end 73.742042 -127.65913)
		(width 0.1016)
		(layer "B.Cu")
		(net "LPC_CLK_AST")
	)
	(segment
		(start 76.570078 -128.988566)
		(end 76.570078 -128.357884)
		(width 0.1016)
		(layer "B.Cu")
		(net "LPC_CLK_AST")
	)
	(via
		(at 132.8674 -40.4876)
		(size 0.6604)
		(drill 0.3302)
		(layers "F.Cu" "B.Cu")
		(net "SIO_JTAG_CPLD2_TMS")
	)
	(segment
		(start 133.0706 -40.4876)
		(end 132.8674 -40.4876)
		(width 0.1016)
		(layer "B.Cu")
		(net "SIO_JTAG_CPLD2_TMS")
	)
	(segment
		(start 136.449816 -39.407084)
		(end 136.518142 -39.47541)
		(width 0.1016)
		(layer "B.Cu")
		(net "SIO_JTAG_CPLD2_TMS")
	)
	(segment
		(start 131.70535 -40.62476)
		(end 132.73024 -40.62476)
		(width 0.1016)
		(layer "B.Cu")
		(net "SIO_JTAG_CPLD2_TMS")
	)
	(segment
		(start 135.596884 -39.407084)
		(end 135.059928 -39.94404)
		(width 0.1016)
		(layer "B.Cu")
		(net "SIO_JTAG_CPLD2_TMS")
	)
	(segment
		(start 136.518142 -39.47541)
		(end 137.569956 -39.47541)
		(width 0.1016)
		(layer "B.Cu")
		(net "SIO_JTAG_CPLD2_TMS")
	)
	(segment
		(start 135.596884 -39.407084)
		(end 136.449816 -39.407084)
		(width 0.1016)
		(layer "B.Cu")
		(net "SIO_JTAG_CPLD2_TMS")
	)
	(segment
		(start 133.61416 -39.94404)
		(end 133.0706 -40.4876)
		(width 0.1016)
		(layer "B.Cu")
		(net "SIO_JTAG_CPLD2_TMS")
	)
	(segment
		(start 135.059928 -39.94404)
		(end 133.61416 -39.94404)
		(width 0.1016)
		(layer "B.Cu")
		(net "SIO_JTAG_CPLD2_TMS")
	)
	(segment
		(start 132.73024 -40.62476)
		(end 132.8674 -40.4876)
		(width 0.1016)
		(layer "B.Cu")
		(net "SIO_JTAG_CPLD2_TMS")
	)
	(via
		(at 136.897872 -42.884852)
		(size 0.6604)
		(drill 0.3302)
		(layers "F.Cu" "B.Cu")
		(net "SIO_JTAG_CPLD2_TCK")
	)
	(segment
		(start 135.596884 -41.79443)
		(end 135.562086 -41.829228)
		(width 0.1016)
		(layer "B.Cu")
		(net "SIO_JTAG_CPLD2_TCK")
	)
	(segment
		(start 140.107416 -41.285414)
		(end 139.519406 -41.285414)
		(width 0.1016)
		(layer "B.Cu")
		(net "SIO_JTAG_CPLD2_TCK")
	)
	(segment
		(start 138.29538 -42.50944)
		(end 138.139678 -42.50944)
		(width 0.1016)
		(layer "B.Cu")
		(net "SIO_JTAG_CPLD2_TCK")
	)
	(segment
		(start 137.764266 -42.884852)
		(end 136.897872 -42.884852)
		(width 0.1016)
		(layer "B.Cu")
		(net "SIO_JTAG_CPLD2_TCK")
	)
	(segment
		(start 136.897872 -42.882566)
		(end 136.516872 -42.501566)
		(width 0.1016)
		(layer "B.Cu")
		(net "SIO_JTAG_CPLD2_TCK")
	)
	(segment
		(start 136.516872 -42.501566)
		(end 135.562086 -42.501566)
		(width 0.1016)
		(layer "B.Cu")
		(net "SIO_JTAG_CPLD2_TCK")
	)
	(segment
		(start 135.596884 -41.439084)
		(end 135.596884 -41.79443)
		(width 0.1016)
		(layer "B.Cu")
		(net "SIO_JTAG_CPLD2_TCK")
	)
	(segment
		(start 135.562086 -41.829228)
		(end 135.562086 -42.501566)
		(width 0.1016)
		(layer "B.Cu")
		(net "SIO_JTAG_CPLD2_TCK")
	)
	(segment
		(start 138.139678 -42.50944)
		(end 137.764266 -42.884852)
		(width 0.1016)
		(layer "B.Cu")
		(net "SIO_JTAG_CPLD2_TCK")
	)
	(segment
		(start 136.897872 -42.884852)
		(end 136.897872 -42.882566)
		(width 0.1016)
		(layer "B.Cu")
		(net "SIO_JTAG_CPLD2_TCK")
	)
	(segment
		(start 139.519406 -41.285414)
		(end 138.29538 -42.50944)
		(width 0.1016)
		(layer "B.Cu")
		(net "SIO_JTAG_CPLD2_TCK")
	)
	(via
		(at 132.8674 -38.8874)
		(size 0.6604)
		(drill 0.3302)
		(layers "F.Cu" "B.Cu")
		(net "SIO_JTAG_CPLD2_TDI")
	)
	(segment
		(start 131.711954 -39.064438)
		(end 132.690362 -39.064438)
		(width 0.1016)
		(layer "B.Cu")
		(net "SIO_JTAG_CPLD2_TDI")
	)
	(segment
		(start 136.583674 -37.44341)
		(end 137.569956 -37.44341)
		(width 0.1016)
		(layer "B.Cu")
		(net "SIO_JTAG_CPLD2_TDI")
	)
	(segment
		(start 136.515348 -37.375084)
		(end 136.583674 -37.44341)
		(width 0.1016)
		(layer "B.Cu")
		(net "SIO_JTAG_CPLD2_TDI")
	)
	(segment
		(start 132.690362 -39.064438)
		(end 132.8674 -38.8874)
		(width 0.1016)
		(layer "B.Cu")
		(net "SIO_JTAG_CPLD2_TDI")
	)
	(segment
		(start 132.8674 -38.8874)
		(end 133.859778 -37.895022)
		(width 0.1016)
		(layer "B.Cu")
		(net "SIO_JTAG_CPLD2_TDI")
	)
	(segment
		(start 135.596884 -37.375084)
		(end 136.515348 -37.375084)
		(width 0.1016)
		(layer "B.Cu")
		(net "SIO_JTAG_CPLD2_TDI")
	)
	(segment
		(start 133.859778 -37.895022)
		(end 135.076946 -37.895022)
		(width 0.1016)
		(layer "B.Cu")
		(net "SIO_JTAG_CPLD2_TDI")
	)
	(segment
		(start 135.076946 -37.895022)
		(end 135.596884 -37.375084)
		(width 0.1016)
		(layer "B.Cu")
		(net "SIO_JTAG_CPLD2_TDI")
	)
	(segment
		(start 143.96466 -38.614604)
		(end 141.17447 -38.614604)
		(width 0.1016)
		(layer "F.Cu")
		(net "SIO_JTAG_CPLD2_TDO")
	)
	(segment
		(start 141.17447 -38.614604)
		(end 139.79398 -39.995094)
		(width 0.1016)
		(layer "F.Cu")
		(net "SIO_JTAG_CPLD2_TDO")
	)
	(segment
		(start 144.18945 -38.389814)
		(end 143.96466 -38.614604)
		(width 0.1016)
		(layer "F.Cu")
		(net "SIO_JTAG_CPLD2_TDO")
	)
	(segment
		(start 145.571718 -38.389814)
		(end 144.18945 -38.389814)
		(width 0.1016)
		(layer "F.Cu")
		(net "SIO_JTAG_CPLD2_TDO")
	)
	(via
		(at 139.79398 -39.995094)
		(size 0.508)
		(drill 0.254)
		(layers "F.Cu" "B.Cu")
		(net "SIO_JTAG_CPLD2_TDO")
	)
	(segment
		(start 141.401546 -38.341554)
		(end 139.79398 -39.94912)
		(width 0.1016)
		(layer "B.Cu")
		(net "SIO_JTAG_CPLD2_TDO")
	)
	(segment
		(start 138.370056 -41.373044)
		(end 139.79398 -39.94912)
		(width 0.1016)
		(layer "B.Cu")
		(net "SIO_JTAG_CPLD2_TDO")
	)
	(segment
		(start 141.401546 -37.915596)
		(end 141.401546 -38.341554)
		(width 0.1016)
		(layer "B.Cu")
		(net "SIO_JTAG_CPLD2_TDO")
	)
	(segment
		(start 139.79398 -39.94912)
		(end 139.79398 -39.995094)
		(width 0.1016)
		(layer "B.Cu")
		(net "SIO_JTAG_CPLD2_TDO")
	)
	(segment
		(start 138.370056 -41.50741)
		(end 138.370056 -41.373044)
		(width 0.1016)
		(layer "B.Cu")
		(net "SIO_JTAG_CPLD2_TDO")
	)
	(segment
		(start 178.010566 -118.365524)
		(end 178.510438 -117.865652)
		(width 0.1016)
		(layer "F.Cu")
		(net "TP_FM_CPLD_NODE1_PWR_BTN_BMC")
	)
	(via
		(at 177.94986 -117.417088)
		(size 0.6604)
		(drill 0.3302)
		(layers "F.Cu" "B.Cu")
		(net "TP_FM_CPLD_NODE1_PWR_BTN_BMC")
	)
	(via
		(at 178.510438 -117.865652)
		(size 0.49022)
		(drill 0.254)
		(layers "F.Cu" "B.Cu")
		(net "TP_FM_CPLD_NODE1_PWR_BTN_BMC")
	)
	(segment
		(start 178.061874 -117.417088)
		(end 177.94986 -117.417088)
		(width 0.1016)
		(layer "B.Cu")
		(net "TP_FM_CPLD_NODE1_PWR_BTN_BMC")
	)
	(segment
		(start 178.510438 -117.865652)
		(end 178.061874 -117.417088)
		(width 0.1016)
		(layer "B.Cu")
		(net "TP_FM_CPLD_NODE1_PWR_BTN_BMC")
	)
	(segment
		(start 162.728148 -103.335836)
		(end 161.692844 -104.37114)
		(width 0.1016)
		(layer "F.Cu")
		(net "USB_WAKE_N")
	)
	(segment
		(start 159.216598 -104.521762)
		(end 159.560006 -104.86517)
		(width 0.1016)
		(layer "F.Cu")
		(net "USB_WAKE_N")
	)
	(segment
		(start 156.573474 -104.521762)
		(end 159.216598 -104.521762)
		(width 0.1016)
		(layer "F.Cu")
		(net "USB_WAKE_N")
	)
	(segment
		(start 161.198814 -104.86517)
		(end 161.692844 -104.37114)
		(width 0.1016)
		(layer "F.Cu")
		(net "USB_WAKE_N")
	)
	(segment
		(start 159.560006 -104.86517)
		(end 161.198814 -104.86517)
		(width 0.1016)
		(layer "F.Cu")
		(net "USB_WAKE_N")
	)
	(segment
		(start 156.445712 -104.394)
		(end 156.573474 -104.521762)
		(width 0.1016)
		(layer "F.Cu")
		(net "USB_WAKE_N")
	)
	(segment
		(start 155.444952 -104.394)
		(end 156.445712 -104.394)
		(width 0.1016)
		(layer "F.Cu")
		(net "USB_WAKE_N")
	)
	(segment
		(start 163.340034 -103.335836)
		(end 162.728148 -103.335836)
		(width 0.1016)
		(layer "F.Cu")
		(net "USB_WAKE_N")
	)
	(via
		(at 161.692844 -104.37114)
		(size 0.508)
		(drill 0.254)
		(layers "F.Cu" "B.Cu")
		(net "USB_WAKE_N")
	)
	(segment
		(start 149.57171 -61.15812)
		(end 150.738586 -61.15812)
		(width 0.1778)
		(layer "F.Cu")
		(net "P1V0_SATA")
	)
	(segment
		(start 143.130524 -59.916822)
		(end 143.130524 -58.934858)
		(width 0.1778)
		(layer "F.Cu")
		(net "P1V0_SATA")
	)
	(segment
		(start 143.930624 -69.869558)
		(end 143.960596 -69.89953)
		(width 0.1778)
		(layer "F.Cu")
		(net "P1V0_SATA")
	)
	(segment
		(start 143.930624 -68.799202)
		(end 143.930624 -69.869558)
		(width 0.1778)
		(layer "F.Cu")
		(net "P1V0_SATA")
	)
	(segment
		(start 146.33067 -59.916822)
		(end 146.33067 -58.833004)
		(width 0.1778)
		(layer "F.Cu")
		(net "P1V0_SATA")
	)
	(segment
		(start 140.68933 -62.758066)
		(end 139.72286 -62.758066)
		(width 0.1778)
		(layer "F.Cu")
		(net "P1V0_SATA")
	)
	(segment
		(start 140.68933 -65.557908)
		(end 139.173966 -65.557908)
		(width 0.1778)
		(layer "F.Cu")
		(net "P1V0_SATA")
	)
	(via
		(at 150.738586 -61.15812)
		(size 0.508)
		(drill 0.254)
		(layers "F.Cu" "B.Cu")
		(net "P1V0_SATA")
	)
	(via
		(at 145.46326 -57.548526)
		(size 0.508)
		(drill 0.254)
		(layers "F.Cu" "B.Cu")
		(net "P1V0_SATA")
	)
	(via
		(at 143.960596 -69.89953)
		(size 0.508)
		(drill 0.254)
		(layers "F.Cu" "B.Cu")
		(net "P1V0_SATA")
	)
	(via
		(at 146.33067 -58.833004)
		(size 0.508)
		(drill 0.254)
		(layers "F.Cu" "B.Cu")
		(net "P1V0_SATA")
	)
	(via
		(at 142.559532 -58.458862)
		(size 0.508)
		(drill 0.254)
		(layers "F.Cu" "B.Cu")
		(net "P1V0_SATA")
	)
	(via
		(at 139.173966 -65.557908)
		(size 0.508)
		(drill 0.254)
		(layers "F.Cu" "B.Cu")
		(net "P1V0_SATA")
	)
	(via
		(at 139.72286 -62.758066)
		(size 0.508)
		(drill 0.254)
		(layers "F.Cu" "B.Cu")
		(net "P1V0_SATA")
	)
	(via
		(at 145.29308 -56.487822)
		(size 0.508)
		(drill 0.254)
		(layers "F.Cu" "B.Cu")
		(net "P1V0_SATA")
	)
	(via
		(at 138.459464 -67.779138)
		(size 0.508)
		(drill 0.254)
		(layers "F.Cu" "B.Cu")
		(net "P1V0_SATA")
	)
	(via
		(at 140.884402 -58.618628)
		(size 0.6604)
		(drill 0.3302)
		(layers "F.Cu" "B.Cu")
		(net "P1V0_SATA")
	)
	(via
		(at 143.826992 -58.491882)
		(size 0.508)
		(drill 0.254)
		(layers "F.Cu" "B.Cu")
		(net "P1V0_SATA")
	)
	(via
		(at 144.37614 -57.568338)
		(size 0.508)
		(drill 0.254)
		(layers "F.Cu" "B.Cu")
		(net "P1V0_SATA")
	)
	(via
		(at 143.19885 -57.662572)
		(size 0.6604)
		(drill 0.3302)
		(layers "F.Cu" "B.Cu")
		(net "P1V0_SATA")
	)
	(via
		(at 143.130524 -58.934858)
		(size 0.508)
		(drill 0.254)
		(layers "F.Cu" "B.Cu")
		(net "P1V0_SATA")
	)
	(via
		(at 144.26692 -56.477662)
		(size 0.508)
		(drill 0.254)
		(layers "F.Cu" "B.Cu")
		(net "P1V0_SATA")
	)
	(segment
		(start 166.443152 -105.871772)
		(end 166.465758 -105.894378)
		(width 0.1016)
		(layer "F.Cu")
		(net "TP_U3TXDN4")
	)
	(segment
		(start 166.443152 -104.839008)
		(end 166.443152 -105.871772)
		(width 0.1016)
		(layer "F.Cu")
		(net "TP_U3TXDN4")
	)
	(segment
		(start 166.465758 -106.30408)
		(end 165.308788 -107.46105)
		(width 0.1016)
		(layer "F.Cu")
		(net "TP_U3TXDN4")
	)
	(segment
		(start 166.465758 -105.894378)
		(end 166.465758 -106.30408)
		(width 0.1016)
		(layer "F.Cu")
		(net "TP_U3TXDN4")
	)
	(segment
		(start 165.308788 -107.46105)
		(end 165.308788 -108.02493)
		(width 0.1016)
		(layer "F.Cu")
		(net "TP_U3TXDN4")
	)
	(via
		(at 165.308788 -108.02493)
		(size 0.508)
		(drill 0.254)
		(layers "F.Cu" "B.Cu")
		(net "TP_U3TXDN4")
	)
	(segment
		(start 166.843202 -105.580942)
		(end 166.730172 -105.693972)
		(width 0.1016)
		(layer "F.Cu")
		(net "TP_U3TXDP4")
	)
	(segment
		(start 166.843202 -104.839008)
		(end 166.843202 -105.580942)
		(width 0.1016)
		(layer "F.Cu")
		(net "TP_U3TXDP4")
	)
	(segment
		(start 166.730172 -106.859578)
		(end 166.576248 -107.013502)
		(width 0.1016)
		(layer "F.Cu")
		(net "TP_U3TXDP4")
	)
	(segment
		(start 166.576248 -107.013502)
		(end 166.576248 -107.722924)
		(width 0.1016)
		(layer "F.Cu")
		(net "TP_U3TXDP4")
	)
	(segment
		(start 166.730172 -105.693972)
		(end 166.730172 -106.859578)
		(width 0.1016)
		(layer "F.Cu")
		(net "TP_U3TXDP4")
	)
	(via
		(at 166.576248 -107.722924)
		(size 0.508)
		(drill 0.254)
		(layers "F.Cu" "B.Cu")
		(net "TP_U3TXDP4")
	)
	(segment
		(start 170.443144 -104.927908)
		(end 170.443144 -105.188512)
		(width 0.1016)
		(layer "F.Cu")
		(net "TP_U3TXDP3")
	)
	(segment
		(start 171.035472 -105.78084)
		(end 171.035472 -105.821734)
		(width 0.1016)
		(layer "F.Cu")
		(net "TP_U3TXDP3")
	)
	(segment
		(start 170.443144 -105.188512)
		(end 171.035472 -105.78084)
		(width 0.1016)
		(layer "F.Cu")
		(net "TP_U3TXDP3")
	)
	(via
		(at 171.035472 -105.821734)
		(size 0.508)
		(drill 0.254)
		(layers "F.Cu" "B.Cu")
		(net "TP_U3TXDP3")
	)
	(segment
		(start 170.448224 -105.815638)
		(end 170.448224 -108.2802)
		(width 0.1016)
		(layer "F.Cu")
		(net "TP_U3TXDN3")
	)
	(segment
		(start 170.043348 -104.839008)
		(end 170.043348 -105.410762)
		(width 0.1016)
		(layer "F.Cu")
		(net "TP_U3TXDN3")
	)
	(segment
		(start 170.043348 -105.410762)
		(end 170.448224 -105.815638)
		(width 0.1016)
		(layer "F.Cu")
		(net "TP_U3TXDN3")
	)
	(via
		(at 170.448224 -108.2802)
		(size 0.508)
		(drill 0.254)
		(layers "F.Cu" "B.Cu")
		(net "TP_U3TXDN3")
	)
	(segment
		(start 172.321982 -101.51999)
		(end 173.46803 -101.51999)
		(width 0.1016)
		(layer "F.Cu")
		(net "TP_U3TXDP2")
	)
	(segment
		(start 171.14647 -101.33584)
		(end 172.137832 -101.33584)
		(width 0.1016)
		(layer "F.Cu")
		(net "TP_U3TXDP2")
	)
	(segment
		(start 172.137832 -101.33584)
		(end 172.321982 -101.51999)
		(width 0.1016)
		(layer "F.Cu")
		(net "TP_U3TXDP2")
	)
	(segment
		(start 173.989746 -102.041706)
		(end 175.523398 -102.041706)
		(width 0.1016)
		(layer "F.Cu")
		(net "TP_U3TXDP2")
	)
	(segment
		(start 173.46803 -101.51999)
		(end 173.989746 -102.041706)
		(width 0.1016)
		(layer "F.Cu")
		(net "TP_U3TXDP2")
	)
	(via
		(at 175.523398 -102.041706)
		(size 0.508)
		(drill 0.254)
		(layers "F.Cu" "B.Cu")
		(net "TP_U3TXDP2")
	)
	(segment
		(start 172.808392 -101.77399)
		(end 173.642782 -102.60838)
		(width 0.1016)
		(layer "F.Cu")
		(net "TP_U3TXDN2")
	)
	(segment
		(start 172.216572 -101.77399)
		(end 172.808392 -101.77399)
		(width 0.1016)
		(layer "F.Cu")
		(net "TP_U3TXDN2")
	)
	(segment
		(start 172.178472 -101.73589)
		(end 172.216572 -101.77399)
		(width 0.1016)
		(layer "F.Cu")
		(net "TP_U3TXDN2")
	)
	(segment
		(start 173.642782 -102.60838)
		(end 174.208186 -102.60838)
		(width 0.1016)
		(layer "F.Cu")
		(net "TP_U3TXDN2")
	)
	(segment
		(start 171.14647 -101.73589)
		(end 172.178472 -101.73589)
		(width 0.1016)
		(layer "F.Cu")
		(net "TP_U3TXDN2")
	)
	(via
		(at 174.208186 -102.60838)
		(size 0.508)
		(drill 0.254)
		(layers "F.Cu" "B.Cu")
		(net "TP_U3TXDN2")
	)
	(segment
		(start 166.44112 -96.052894)
		(end 166.443152 -96.054926)
		(width 0.2032)
		(layer "F.Cu")
		(net "USB_OC_PU")
	)
	(segment
		(start 164.843206 -96.2025)
		(end 164.843206 -97.032572)
		(width 0.2032)
		(layer "F.Cu")
		(net "USB_OC_PU")
	)
	(segment
		(start 165.643306 -97.032572)
		(end 165.643306 -95.78975)
		(width 0.2032)
		(layer "F.Cu")
		(net "USB_OC_PU")
	)
	(segment
		(start 167.243252 -96.251522)
		(end 167.016684 -96.024954)
		(width 0.2032)
		(layer "F.Cu")
		(net "USB_OC_PU")
	)
	(segment
		(start 167.243252 -97.032572)
		(end 167.243252 -96.251522)
		(width 0.2032)
		(layer "F.Cu")
		(net "USB_OC_PU")
	)
	(segment
		(start 166.443152 -96.054926)
		(end 166.443152 -97.032572)
		(width 0.2032)
		(layer "F.Cu")
		(net "USB_OC_PU")
	)
	(segment
		(start 165.099492 -95.946214)
		(end 164.843206 -96.2025)
		(width 0.2032)
		(layer "F.Cu")
		(net "USB_OC_PU")
	)
	(via
		(at 165.643306 -95.78975)
		(size 0.508)
		(drill 0.254)
		(layers "F.Cu" "B.Cu")
		(net "USB_OC_PU")
	)
	(segment
		(start 113.785396 -164.066982)
		(end 114.19586 -163.656518)
		(width 0.1016)
		(layer "F.Cu")
		(net "PCA9535_INT_N")
	)
	(segment
		(start 113.785396 -164.442902)
		(end 113.785396 -164.066982)
		(width 0.1016)
		(layer "F.Cu")
		(net "PCA9535_INT_N")
	)
	(segment
		(start 112.9538 -165.5826)
		(end 112.87633 -165.50513)
		(width 0.1016)
		(layer "F.Cu")
		(net "PCA9535_INT_N")
	)
	(segment
		(start 113.371122 -164.857176)
		(end 113.785396 -164.442902)
		(width 0.1016)
		(layer "F.Cu")
		(net "PCA9535_INT_N")
	)
	(segment
		(start 112.9538 -165.5826)
		(end 113.371122 -165.165278)
		(width 0.1016)
		(layer "F.Cu")
		(net "PCA9535_INT_N")
	)
	(segment
		(start 114.19586 -163.656518)
		(end 114.76736 -163.656518)
		(width 0.1016)
		(layer "F.Cu")
		(net "PCA9535_INT_N")
	)
	(segment
		(start 112.87633 -165.50513)
		(end 112.271302 -165.50513)
		(width 0.1016)
		(layer "F.Cu")
		(net "PCA9535_INT_N")
	)
	(segment
		(start 113.371122 -165.165278)
		(end 113.371122 -164.857176)
		(width 0.1016)
		(layer "F.Cu")
		(net "PCA9535_INT_N")
	)
	(via
		(at 59.97448 -178.859942)
		(size 0.508)
		(drill 0.254)
		(layers "F.Cu" "B.Cu")
		(net "PCA9535_INT_N")
	)
	(via
		(at 112.9538 -165.5826)
		(size 0.508)
		(drill 0.254)
		(layers "F.Cu" "B.Cu")
		(net "PCA9535_INT_N")
	)
	(segment
		(start 58.15076 -179.890674)
		(end 59.508644 -179.890674)
		(width 0.1016)
		(layer "B.Cu")
		(net "PCA9535_INT_N")
	)
	(segment
		(start 59.508644 -179.890674)
		(end 59.97448 -179.424838)
		(width 0.1016)
		(layer "B.Cu")
		(net "PCA9535_INT_N")
	)
	(segment
		(start 59.97448 -179.424838)
		(end 59.97448 -178.859942)
		(width 0.1016)
		(layer "B.Cu")
		(net "PCA9535_INT_N")
	)
	(segment
		(start 87.709756 -162.631882)
		(end 87.15248 -162.074606)
		(width 0.1143)
		(layer "In7.Cu")
		(net "PCA9535_INT_N")
	)
	(segment
		(start 105.027476 -165.089078)
		(end 104.740202 -165.376352)
		(width 0.1143)
		(layer "In7.Cu")
		(net "PCA9535_INT_N")
	)
	(segment
		(start 66.08191 -169.032174)
		(end 66.08064 -169.032174)
		(width 0.1143)
		(layer "In7.Cu")
		(net "PCA9535_INT_N")
	)
	(segment
		(start 111.125 -165.5826)
		(end 110.83417 -165.29177)
		(width 0.1143)
		(layer "In7.Cu")
		(net "PCA9535_INT_N")
	)
	(segment
		(start 74.784966 -164.01669)
		(end 70.699376 -168.10228)
		(width 0.1143)
		(layer "In7.Cu")
		(net "PCA9535_INT_N")
	)
	(segment
		(start 103.887778 -165.07333)
		(end 97.53727 -165.07333)
		(width 0.1143)
		(layer "In7.Cu")
		(net "PCA9535_INT_N")
	)
	(segment
		(start 97.53727 -165.07333)
		(end 94.968568 -162.504628)
		(width 0.1143)
		(layer "In7.Cu")
		(net "PCA9535_INT_N")
	)
	(segment
		(start 66.647314 -168.10228)
		(end 66.08191 -168.667684)
		(width 0.1143)
		(layer "In7.Cu")
		(net "PCA9535_INT_N")
	)
	(segment
		(start 86.73846 -161.360866)
		(end 82.151474 -161.360866)
		(width 0.1143)
		(layer "In7.Cu")
		(net "PCA9535_INT_N")
	)
	(segment
		(start 66.08064 -172.753782)
		(end 59.97448 -178.859942)
		(width 0.1143)
		(layer "In7.Cu")
		(net "PCA9535_INT_N")
	)
	(segment
		(start 109.788706 -165.089078)
		(end 105.027476 -165.089078)
		(width 0.1143)
		(layer "In7.Cu")
		(net "PCA9535_INT_N")
	)
	(segment
		(start 104.1908 -165.376352)
		(end 103.887778 -165.07333)
		(width 0.1143)
		(layer "In7.Cu")
		(net "PCA9535_INT_N")
	)
	(segment
		(start 87.15248 -161.774886)
		(end 86.73846 -161.360866)
		(width 0.1143)
		(layer "In7.Cu")
		(net "PCA9535_INT_N")
	)
	(segment
		(start 79.232252 -164.01669)
		(end 74.784966 -164.01669)
		(width 0.1143)
		(layer "In7.Cu")
		(net "PCA9535_INT_N")
	)
	(segment
		(start 82.151474 -161.360866)
		(end 80.43291 -163.07943)
		(width 0.1143)
		(layer "In7.Cu")
		(net "PCA9535_INT_N")
	)
	(segment
		(start 104.740202 -165.376352)
		(end 104.1908 -165.376352)
		(width 0.1143)
		(layer "In7.Cu")
		(net "PCA9535_INT_N")
	)
	(segment
		(start 90.99677 -162.504628)
		(end 90.869516 -162.631882)
		(width 0.1143)
		(layer "In7.Cu")
		(net "PCA9535_INT_N")
	)
	(segment
		(start 109.991398 -165.29177)
		(end 109.788706 -165.089078)
		(width 0.1143)
		(layer "In7.Cu")
		(net "PCA9535_INT_N")
	)
	(segment
		(start 110.83417 -165.29177)
		(end 109.991398 -165.29177)
		(width 0.1143)
		(layer "In7.Cu")
		(net "PCA9535_INT_N")
	)
	(segment
		(start 90.869516 -162.631882)
		(end 87.709756 -162.631882)
		(width 0.1143)
		(layer "In7.Cu")
		(net "PCA9535_INT_N")
	)
	(segment
		(start 66.08064 -169.032174)
		(end 66.08064 -172.753782)
		(width 0.1143)
		(layer "In7.Cu")
		(net "PCA9535_INT_N")
	)
	(segment
		(start 80.43291 -163.266628)
		(end 80.17637 -163.523168)
		(width 0.1143)
		(layer "In7.Cu")
		(net "PCA9535_INT_N")
	)
	(segment
		(start 87.15248 -162.074606)
		(end 87.15248 -161.774886)
		(width 0.1143)
		(layer "In7.Cu")
		(net "PCA9535_INT_N")
	)
	(segment
		(start 94.968568 -162.504628)
		(end 90.99677 -162.504628)
		(width 0.1143)
		(layer "In7.Cu")
		(net "PCA9535_INT_N")
	)
	(segment
		(start 80.43291 -163.07943)
		(end 80.43291 -163.266628)
		(width 0.1143)
		(layer "In7.Cu")
		(net "PCA9535_INT_N")
	)
	(segment
		(start 66.08191 -168.667684)
		(end 66.08191 -169.032174)
		(width 0.1143)
		(layer "In7.Cu")
		(net "PCA9535_INT_N")
	)
	(segment
		(start 112.9538 -165.5826)
		(end 111.125 -165.5826)
		(width 0.1143)
		(layer "In7.Cu")
		(net "PCA9535_INT_N")
	)
	(segment
		(start 70.699376 -168.10228)
		(end 66.647314 -168.10228)
		(width 0.1143)
		(layer "In7.Cu")
		(net "PCA9535_INT_N")
	)
	(segment
		(start 80.17637 -163.523168)
		(end 79.72552 -163.523168)
		(width 0.1143)
		(layer "In7.Cu")
		(net "PCA9535_INT_N")
	)
	(segment
		(start 79.72552 -163.523168)
		(end 79.232252 -164.01669)
		(width 0.1143)
		(layer "In7.Cu")
		(net "PCA9535_INT_N")
	)
	(segment
		(start 143.961358 -36.924488)
		(end 143.275304 -36.924488)
		(width 0.1016)
		(layer "F.Cu")
		(net "CPLD_WDT3_R")
	)
	(segment
		(start 143.996156 -36.88969)
		(end 143.961358 -36.924488)
		(width 0.1016)
		(layer "F.Cu")
		(net "CPLD_WDT3_R")
	)
	(segment
		(start 145.571718 -36.88969)
		(end 143.996156 -36.88969)
		(width 0.1016)
		(layer "F.Cu")
		(net "CPLD_WDT3_R")
	)
	(via
		(at 143.275304 -36.924488)
		(size 0.508)
		(drill 0.254)
		(layers "F.Cu" "B.Cu")
		(net "CPLD_WDT3_R")
	)
	(segment
		(start 139.135612 -38.45941)
		(end 138.370056 -38.45941)
		(width 0.1016)
		(layer "B.Cu")
		(net "CPLD_WDT3_R")
	)
	(segment
		(start 143.275304 -36.924488)
		(end 141.358112 -36.924488)
		(width 0.1016)
		(layer "B.Cu")
		(net "CPLD_WDT3_R")
	)
	(segment
		(start 141.358112 -36.924488)
		(end 140.4874 -37.7952)
		(width 0.1016)
		(layer "B.Cu")
		(net "CPLD_WDT3_R")
	)
	(segment
		(start 143.275304 -37.3507)
		(end 143.275304 -36.924488)
		(width 0.1016)
		(layer "B.Cu")
		(net "CPLD_WDT3_R")
	)
	(segment
		(start 139.799822 -37.7952)
		(end 139.135612 -38.45941)
		(width 0.1016)
		(layer "B.Cu")
		(net "CPLD_WDT3_R")
	)
	(segment
		(start 140.4874 -37.7952)
		(end 139.799822 -37.7952)
		(width 0.1016)
		(layer "B.Cu")
		(net "CPLD_WDT3_R")
	)
	(segment
		(start 144.508982 -38.584378)
		(end 143.275304 -37.3507)
		(width 0.1016)
		(layer "B.Cu")
		(net "CPLD_WDT3_R")
	)
	(segment
		(start 144.508982 -38.710616)
		(end 144.508982 -38.584378)
		(width 0.1016)
		(layer "B.Cu")
		(net "CPLD_WDT3_R")
	)
	(segment
		(start 67.34683 -85.878162)
		(end 66.644266 -85.878162)
		(width 0.1016)
		(layer "F.Cu")
		(net "CPU_RSV_1_R")
	)
	(segment
		(start 67.462146 -85.762846)
		(end 67.34683 -85.878162)
		(width 0.1016)
		(layer "F.Cu")
		(net "CPU_RSV_1_R")
	)
	(via
		(at 66.644266 -85.878162)
		(size 0.508)
		(drill 0.254)
		(layers "F.Cu" "B.Cu")
		(net "CPU_RSV_1_R")
	)
	(via
		(at 68.101972 -95.137732)
		(size 0.6604)
		(drill 0.3302)
		(layers "F.Cu" "B.Cu")
		(net "CPU_RSV_1_R")
	)
	(segment
		(start 66.644266 -86.170262)
		(end 66.644266 -85.878162)
		(width 0.1016)
		(layer "B.Cu")
		(net "CPU_RSV_1_R")
	)
	(segment
		(start 68.101972 -94.509844)
		(end 67.47002 -93.877892)
		(width 0.1016)
		(layer "B.Cu")
		(net "CPU_RSV_1_R")
	)
	(segment
		(start 67.47002 -93.877892)
		(end 67.47002 -90.873326)
		(width 0.1016)
		(layer "B.Cu")
		(net "CPU_RSV_1_R")
	)
	(segment
		(start 66.49847 -86.714838)
		(end 66.49847 -86.316058)
		(width 0.1016)
		(layer "B.Cu")
		(net "CPU_RSV_1_R")
	)
	(segment
		(start 67.429888 -88.4174)
		(end 67.183508 -88.17102)
		(width 0.1016)
		(layer "B.Cu")
		(net "CPU_RSV_1_R")
	)
	(segment
		(start 68.101972 -95.137732)
		(end 68.101972 -94.509844)
		(width 0.1016)
		(layer "B.Cu")
		(net "CPU_RSV_1_R")
	)
	(segment
		(start 68.246498 -96.296734)
		(end 68.101972 -96.152208)
		(width 0.1016)
		(layer "B.Cu")
		(net "CPU_RSV_1_R")
	)
	(segment
		(start 67.429888 -90.645488)
		(end 67.429888 -88.4174)
		(width 0.1016)
		(layer "B.Cu")
		(net "CPU_RSV_1_R")
	)
	(segment
		(start 68.101972 -96.152208)
		(end 68.101972 -95.137732)
		(width 0.1016)
		(layer "B.Cu")
		(net "CPU_RSV_1_R")
	)
	(segment
		(start 66.49847 -86.316058)
		(end 66.644266 -86.170262)
		(width 0.1016)
		(layer "B.Cu")
		(net "CPU_RSV_1_R")
	)
	(segment
		(start 67.47002 -90.873326)
		(end 67.429888 -90.645488)
		(width 0.1016)
		(layer "B.Cu")
		(net "CPU_RSV_1_R")
	)
	(segment
		(start 67.183508 -87.399876)
		(end 66.49847 -86.714838)
		(width 0.1016)
		(layer "B.Cu")
		(net "CPU_RSV_1_R")
	)
	(segment
		(start 67.183508 -88.17102)
		(end 67.183508 -87.399876)
		(width 0.1016)
		(layer "B.Cu")
		(net "CPU_RSV_1_R")
	)
	(segment
		(start 138.025632 -179.58435)
		(end 138.445748 -180.004466)
		(width 0.1016)
		(layer "F.Cu")
		(net "CPLD_WDT3")
	)
	(segment
		(start 80.494632 -179.874672)
		(end 80.494632 -180.637434)
		(width 0.1016)
		(layer "F.Cu")
		(net "CPLD_WDT3")
	)
	(segment
		(start 80.79486 -180.937662)
		(end 80.79486 -181.062884)
		(width 0.1016)
		(layer "F.Cu")
		(net "CPLD_WDT3")
	)
	(segment
		(start 138.025632 -178.858672)
		(end 138.025632 -179.58435)
		(width 0.1016)
		(layer "F.Cu")
		(net "CPLD_WDT3")
	)
	(segment
		(start 80.494632 -180.637434)
		(end 80.79486 -180.937662)
		(width 0.1016)
		(layer "F.Cu")
		(net "CPLD_WDT3")
	)
	(via
		(at 80.79486 -181.062884)
		(size 0.508)
		(drill 0.254)
		(layers "F.Cu" "B.Cu")
		(net "CPLD_WDT3")
	)
	(via
		(at 151.50338 -166.428674)
		(size 0.508)
		(drill 0.254)
		(layers "F.Cu" "B.Cu")
		(net "CPLD_WDT3")
	)
	(via
		(at 138.445748 -180.004466)
		(size 0.508)
		(drill 0.254)
		(layers "F.Cu" "B.Cu")
		(net "CPLD_WDT3")
	)
	(via
		(at 136.81837 -38.45941)
		(size 0.508)
		(drill 0.254)
		(layers "F.Cu" "B.Cu")
		(net "CPLD_WDT3")
	)
	(segment
		(start 138.445748 -180.004466)
		(end 138.445748 -179.444396)
		(width 0.1016)
		(layer "B.Cu")
		(net "CPLD_WDT3")
	)
	(segment
		(start 137.994136 -178.992784)
		(end 137.994136 -177.112422)
		(width 0.1016)
		(layer "B.Cu")
		(net "CPLD_WDT3")
	)
	(segment
		(start 144.177004 -168.039034)
		(end 146.118834 -168.039034)
		(width 0.1016)
		(layer "B.Cu")
		(net "CPLD_WDT3")
	)
	(segment
		(start 151.473916 -166.458138)
		(end 151.50338 -166.428674)
		(width 0.1016)
		(layer "B.Cu")
		(net "CPLD_WDT3")
	)
	(segment
		(start 144.011904 -168.204134)
		(end 144.177004 -168.039034)
		(width 0.1016)
		(layer "B.Cu")
		(net "CPLD_WDT3")
	)
	(segment
		(start 138.445748 -179.444396)
		(end 137.994136 -178.992784)
		(width 0.1016)
		(layer "B.Cu")
		(net "CPLD_WDT3")
	)
	(segment
		(start 138.939524 -176.167034)
		(end 138.939524 -170.351958)
		(width 0.1016)
		(layer "B.Cu")
		(net "CPLD_WDT3")
	)
	(segment
		(start 142.784576 -168.404286)
		(end 142.984728 -168.204134)
		(width 0.1016)
		(layer "B.Cu")
		(net "CPLD_WDT3")
	)
	(segment
		(start 148.966428 -166.084504)
		(end 150.466806 -166.084504)
		(width 0.1016)
		(layer "B.Cu")
		(net "CPLD_WDT3")
	)
	(segment
		(start 146.857212 -168.19372)
		(end 148.966428 -166.084504)
		(width 0.1016)
		(layer "B.Cu")
		(net "CPLD_WDT3")
	)
	(segment
		(start 140.887196 -168.404286)
		(end 142.784576 -168.404286)
		(width 0.1016)
		(layer "B.Cu")
		(net "CPLD_WDT3")
	)
	(segment
		(start 135.596884 -38.391084)
		(end 136.63168 -38.391084)
		(width 0.1016)
		(layer "B.Cu")
		(net "CPLD_WDT3")
	)
	(segment
		(start 150.84044 -166.458138)
		(end 151.473916 -166.458138)
		(width 0.1016)
		(layer "B.Cu")
		(net "CPLD_WDT3")
	)
	(segment
		(start 137.994136 -177.112422)
		(end 138.939524 -176.167034)
		(width 0.1016)
		(layer "B.Cu")
		(net "CPLD_WDT3")
	)
	(segment
		(start 146.27352 -168.19372)
		(end 146.857212 -168.19372)
		(width 0.1016)
		(layer "B.Cu")
		(net "CPLD_WDT3")
	)
	(segment
		(start 150.466806 -166.084504)
		(end 150.84044 -166.458138)
		(width 0.1016)
		(layer "B.Cu")
		(net "CPLD_WDT3")
	)
	(segment
		(start 136.81837 -38.45941)
		(end 137.569956 -38.45941)
		(width 0.1016)
		(layer "B.Cu")
		(net "CPLD_WDT3")
	)
	(segment
		(start 136.63168 -38.391084)
		(end 136.700006 -38.45941)
		(width 0.1016)
		(layer "B.Cu")
		(net "CPLD_WDT3")
	)
	(segment
		(start 142.984728 -168.204134)
		(end 144.011904 -168.204134)
		(width 0.1016)
		(layer "B.Cu")
		(net "CPLD_WDT3")
	)
	(segment
		(start 146.118834 -168.039034)
		(end 146.27352 -168.19372)
		(width 0.1016)
		(layer "B.Cu")
		(net "CPLD_WDT3")
	)
	(segment
		(start 136.700006 -38.45941)
		(end 136.81837 -38.45941)
		(width 0.1016)
		(layer "B.Cu")
		(net "CPLD_WDT3")
	)
	(segment
		(start 138.939524 -170.351958)
		(end 140.887196 -168.404286)
		(width 0.1016)
		(layer "B.Cu")
		(net "CPLD_WDT3")
	)
	(segment
		(start 165.404546 -165.340284)
		(end 169.88282 -165.340284)
		(width 0.1143)
		(layer "In2.Cu")
		(net "CPLD_WDT3")
	)
	(segment
		(start 191.9351 -97.998788)
		(end 178.686714 -84.750402)
		(width 0.1143)
		(layer "In2.Cu")
		(net "CPLD_WDT3")
	)
	(segment
		(start 135.64743 -47.891446)
		(end 136.23798 -47.300896)
		(width 0.1143)
		(layer "In2.Cu")
		(net "CPLD_WDT3")
	)
	(segment
		(start 136.23798 -39.0398)
		(end 136.81837 -38.45941)
		(width 0.1143)
		(layer "In2.Cu")
		(net "CPLD_WDT3")
	)
	(segment
		(start 182.034688 -163.374324)
		(end 192.06464 -153.344372)
		(width 0.1143)
		(layer "In2.Cu")
		(net "CPLD_WDT3")
	)
	(segment
		(start 135.64743 -49.03343)
		(end 135.64743 -47.891446)
		(width 0.1143)
		(layer "In2.Cu")
		(net "CPLD_WDT3")
	)
	(segment
		(start 135.88873 -64.225932)
		(end 135.250682 -63.587884)
		(width 0.1143)
		(layer "In2.Cu")
		(net "CPLD_WDT3")
	)
	(segment
		(start 192.278 -129.032)
		(end 192.278 -121.412)
		(width 0.1143)
		(layer "In2.Cu")
		(net "CPLD_WDT3")
	)
	(segment
		(start 192.06464 -153.344372)
		(end 192.06464 -129.24536)
		(width 0.1143)
		(layer "In2.Cu")
		(net "CPLD_WDT3")
	)
	(segment
		(start 191.9351 -121.0691)
		(end 191.9351 -97.998788)
		(width 0.1143)
		(layer "In2.Cu")
		(net "CPLD_WDT3")
	)
	(segment
		(start 163.984178 -165.938962)
		(end 164.0713 -165.851586)
		(width 0.1143)
		(layer "In2.Cu")
		(net "CPLD_WDT3")
	)
	(segment
		(start 136.144 -49.53)
		(end 135.64743 -49.03343)
		(width 0.1143)
		(layer "In2.Cu")
		(net "CPLD_WDT3")
	)
	(segment
		(start 151.993092 -165.938962)
		(end 163.984178 -165.938962)
		(width 0.1143)
		(layer "In2.Cu")
		(net "CPLD_WDT3")
	)
	(segment
		(start 164.893244 -165.851586)
		(end 165.404546 -165.340284)
		(width 0.1143)
		(layer "In2.Cu")
		(net "CPLD_WDT3")
	)
	(segment
		(start 192.278 -121.412)
		(end 191.9351 -121.0691)
		(width 0.1143)
		(layer "In2.Cu")
		(net "CPLD_WDT3")
	)
	(segment
		(start 164.0713 -165.851586)
		(end 164.893244 -165.851586)
		(width 0.1143)
		(layer "In2.Cu")
		(net "CPLD_WDT3")
	)
	(segment
		(start 181.72684 -163.37407)
		(end 181.72684 -163.374324)
		(width 0.1143)
		(layer "In2.Cu")
		(net "CPLD_WDT3")
	)
	(segment
		(start 151.50338 -166.428674)
		(end 151.993092 -165.938962)
		(width 0.1143)
		(layer "In2.Cu")
		(net "CPLD_WDT3")
	)
	(segment
		(start 135.88873 -69.045328)
		(end 135.88873 -64.225932)
		(width 0.1143)
		(layer "In2.Cu")
		(net "CPLD_WDT3")
	)
	(segment
		(start 135.250682 -57.497218)
		(end 135.8138 -56.9341)
		(width 0.1143)
		(layer "In2.Cu")
		(net "CPLD_WDT3")
	)
	(segment
		(start 171.849034 -163.37407)
		(end 181.72684 -163.37407)
		(width 0.1143)
		(layer "In2.Cu")
		(net "CPLD_WDT3")
	)
	(segment
		(start 176.296574 -84.470494)
		(end 152.40635 -84.470494)
		(width 0.1143)
		(layer "In2.Cu")
		(net "CPLD_WDT3")
	)
	(segment
		(start 176.576482 -84.750402)
		(end 176.296574 -84.470494)
		(width 0.1143)
		(layer "In2.Cu")
		(net "CPLD_WDT3")
	)
	(segment
		(start 135.8138 -56.9341)
		(end 135.8138 -50.3682)
		(width 0.1143)
		(layer "In2.Cu")
		(net "CPLD_WDT3")
	)
	(segment
		(start 169.88282 -165.340284)
		(end 171.849034 -163.37407)
		(width 0.1143)
		(layer "In2.Cu")
		(net "CPLD_WDT3")
	)
	(segment
		(start 140.16228 -75.95616)
		(end 140.16228 -73.318878)
		(width 0.1143)
		(layer "In2.Cu")
		(net "CPLD_WDT3")
	)
	(segment
		(start 136.144 -50.038)
		(end 136.144 -49.53)
		(width 0.1143)
		(layer "In2.Cu")
		(net "CPLD_WDT3")
	)
	(segment
		(start 135.8138 -50.3682)
		(end 136.144 -50.038)
		(width 0.1143)
		(layer "In2.Cu")
		(net "CPLD_WDT3")
	)
	(segment
		(start 152.40635 -84.470494)
		(end 152.36698 -84.509864)
		(width 0.1143)
		(layer "In2.Cu")
		(net "CPLD_WDT3")
	)
	(segment
		(start 135.250682 -63.587884)
		(end 135.250682 -57.497218)
		(width 0.1143)
		(layer "In2.Cu")
		(net "CPLD_WDT3")
	)
	(segment
		(start 136.23798 -47.300896)
		(end 136.23798 -39.0398)
		(width 0.1143)
		(layer "In2.Cu")
		(net "CPLD_WDT3")
	)
	(segment
		(start 192.06464 -129.24536)
		(end 192.278 -129.032)
		(width 0.1143)
		(layer "In2.Cu")
		(net "CPLD_WDT3")
	)
	(segment
		(start 181.72684 -163.374324)
		(end 182.034688 -163.374324)
		(width 0.1143)
		(layer "In2.Cu")
		(net "CPLD_WDT3")
	)
	(segment
		(start 148.715984 -84.509864)
		(end 140.16228 -75.95616)
		(width 0.1143)
		(layer "In2.Cu")
		(net "CPLD_WDT3")
	)
	(segment
		(start 140.16228 -73.318878)
		(end 135.88873 -69.045328)
		(width 0.1143)
		(layer "In2.Cu")
		(net "CPLD_WDT3")
	)
	(segment
		(start 152.36698 -84.509864)
		(end 148.715984 -84.509864)
		(width 0.1143)
		(layer "In2.Cu")
		(net "CPLD_WDT3")
	)
	(segment
		(start 178.686714 -84.750402)
		(end 176.576482 -84.750402)
		(width 0.1143)
		(layer "In2.Cu")
		(net "CPLD_WDT3")
	)
	(segment
		(start 103.853742 -178.874928)
		(end 98.052128 -178.874928)
		(width 0.1143)
		(layer "In6.Cu")
		(net "CPLD_WDT3")
	)
	(segment
		(start 109.85373 -181.338474)
		(end 109.09554 -181.338474)
		(width 0.1143)
		(layer "In6.Cu")
		(net "CPLD_WDT3")
	)
	(segment
		(start 89.82075 -179.96535)
		(end 87.327994 -179.96535)
		(width 0.1143)
		(layer "In6.Cu")
		(net "CPLD_WDT3")
	)
	(segment
		(start 109.09554 -181.338474)
		(end 108.850684 -181.093618)
		(width 0.1143)
		(layer "In6.Cu")
		(net "CPLD_WDT3")
	)
	(segment
		(start 105.482898 -180.129688)
		(end 105.47858 -180.134006)
		(width 0.1143)
		(layer "In6.Cu")
		(net "CPLD_WDT3")
	)
	(segment
		(start 87.10803 -179.745386)
		(end 86.74481 -179.745386)
		(width 0.1143)
		(layer "In6.Cu")
		(net "CPLD_WDT3")
	)
	(segment
		(start 111.98606 -180.144928)
		(end 111.047276 -180.144928)
		(width 0.1143)
		(layer "In6.Cu")
		(net "CPLD_WDT3")
	)
	(segment
		(start 136.363964 -178.598322)
		(end 113.532666 -178.598322)
		(width 0.1143)
		(layer "In6.Cu")
		(net "CPLD_WDT3")
	)
	(segment
		(start 89.98458 -179.80152)
		(end 89.82075 -179.96535)
		(width 0.1143)
		(layer "In6.Cu")
		(net "CPLD_WDT3")
	)
	(segment
		(start 95.724472 -179.80152)
		(end 89.98458 -179.80152)
		(width 0.1143)
		(layer "In6.Cu")
		(net "CPLD_WDT3")
	)
	(segment
		(start 105.47858 -180.134006)
		(end 105.11282 -180.134006)
		(width 0.1143)
		(layer "In6.Cu")
		(net "CPLD_WDT3")
	)
	(segment
		(start 86.74481 -179.745386)
		(end 85.98408 -180.506116)
		(width 0.1143)
		(layer "In6.Cu")
		(net "CPLD_WDT3")
	)
	(segment
		(start 105.11282 -180.134006)
		(end 103.853742 -178.874928)
		(width 0.1143)
		(layer "In6.Cu")
		(net "CPLD_WDT3")
	)
	(segment
		(start 85.98408 -180.506116)
		(end 81.351628 -180.506116)
		(width 0.1143)
		(layer "In6.Cu")
		(net "CPLD_WDT3")
	)
	(segment
		(start 111.047276 -180.144928)
		(end 109.85373 -181.338474)
		(width 0.1143)
		(layer "In6.Cu")
		(net "CPLD_WDT3")
	)
	(segment
		(start 137.770108 -180.004466)
		(end 136.363964 -178.598322)
		(width 0.1143)
		(layer "In6.Cu")
		(net "CPLD_WDT3")
	)
	(segment
		(start 95.7453 -179.822348)
		(end 95.724472 -179.80152)
		(width 0.1143)
		(layer "In6.Cu")
		(net "CPLD_WDT3")
	)
	(segment
		(start 87.327994 -179.96535)
		(end 87.10803 -179.745386)
		(width 0.1143)
		(layer "In6.Cu")
		(net "CPLD_WDT3")
	)
	(segment
		(start 113.532666 -178.598322)
		(end 111.98606 -180.144928)
		(width 0.1143)
		(layer "In6.Cu")
		(net "CPLD_WDT3")
	)
	(segment
		(start 81.351628 -180.506116)
		(end 80.79486 -181.062884)
		(width 0.1143)
		(layer "In6.Cu")
		(net "CPLD_WDT3")
	)
	(segment
		(start 105.77703 -180.129688)
		(end 105.482898 -180.129688)
		(width 0.1143)
		(layer "In6.Cu")
		(net "CPLD_WDT3")
	)
	(segment
		(start 108.850684 -181.093618)
		(end 106.74096 -181.093618)
		(width 0.1143)
		(layer "In6.Cu")
		(net "CPLD_WDT3")
	)
	(segment
		(start 98.052128 -178.874928)
		(end 97.104708 -179.822348)
		(width 0.1143)
		(layer "In6.Cu")
		(net "CPLD_WDT3")
	)
	(segment
		(start 138.445748 -180.004466)
		(end 137.770108 -180.004466)
		(width 0.1143)
		(layer "In6.Cu")
		(net "CPLD_WDT3")
	)
	(segment
		(start 97.104708 -179.822348)
		(end 95.7453 -179.822348)
		(width 0.1143)
		(layer "In6.Cu")
		(net "CPLD_WDT3")
	)
	(segment
		(start 106.74096 -181.093618)
		(end 105.77703 -180.129688)
		(width 0.1143)
		(layer "In6.Cu")
		(net "CPLD_WDT3")
	)
	(segment
		(start 73.63968 -102.44455)
		(end 73.63968 -98.78695)
		(width 0.1016)
		(layer "F.Cu")
		(net "CPU_RSV_1")
	)
	(segment
		(start 43.88104 -103.26116)
		(end 44.672758 -104.052878)
		(width 0.1016)
		(layer "F.Cu")
		(net "CPU_RSV_1")
	)
	(segment
		(start 137.025888 -179.880006)
		(end 137.175748 -180.029866)
		(width 0.1016)
		(layer "F.Cu")
		(net "CPU_RSV_1")
	)
	(segment
		(start 73.38695 -98.53422)
		(end 72.626474 -98.53422)
		(width 0.1016)
		(layer "F.Cu")
		(net "CPU_RSV_1")
	)
	(segment
		(start 70.289928 -99.252532)
		(end 69.976238 -99.252532)
		(width 0.1016)
		(layer "F.Cu")
		(net "CPU_RSV_1")
	)
	(segment
		(start 137.025888 -178.858672)
		(end 137.025888 -179.880006)
		(width 0.1016)
		(layer "F.Cu")
		(net "CPU_RSV_1")
	)
	(segment
		(start 73.63968 -98.78695)
		(end 73.38695 -98.53422)
		(width 0.1016)
		(layer "F.Cu")
		(net "CPU_RSV_1")
	)
	(segment
		(start 72.489568 -98.671126)
		(end 70.871334 -98.671126)
		(width 0.1016)
		(layer "F.Cu")
		(net "CPU_RSV_1")
	)
	(segment
		(start 44.672758 -104.052878)
		(end 72.031352 -104.052878)
		(width 0.1016)
		(layer "F.Cu")
		(net "CPU_RSV_1")
	)
	(segment
		(start 70.871334 -98.671126)
		(end 70.289928 -99.252532)
		(width 0.1016)
		(layer "F.Cu")
		(net "CPU_RSV_1")
	)
	(segment
		(start 79.494888 -179.874672)
		(end 79.494888 -181.024022)
		(width 0.1016)
		(layer "F.Cu")
		(net "CPU_RSV_1")
	)
	(segment
		(start 72.031352 -104.052878)
		(end 73.63968 -102.44455)
		(width 0.1016)
		(layer "F.Cu")
		(net "CPU_RSV_1")
	)
	(segment
		(start 72.626474 -98.53422)
		(end 72.489568 -98.671126)
		(width 0.1016)
		(layer "F.Cu")
		(net "CPU_RSV_1")
	)
	(via
		(at 69.976238 -99.252532)
		(size 0.508)
		(drill 0.254)
		(layers "F.Cu" "B.Cu")
		(net "CPU_RSV_1")
	)
	(via
		(at 33.57626 -168.304464)
		(size 0.508)
		(drill 0.254)
		(layers "F.Cu" "B.Cu")
		(net "CPU_RSV_1")
	)
	(via
		(at 137.175748 -180.029866)
		(size 0.508)
		(drill 0.254)
		(layers "F.Cu" "B.Cu")
		(net "CPU_RSV_1")
	)
	(via
		(at 79.494888 -181.024022)
		(size 0.508)
		(drill 0.254)
		(layers "F.Cu" "B.Cu")
		(net "CPU_RSV_1")
	)
	(via
		(at 43.88104 -103.26116)
		(size 0.508)
		(drill 0.254)
		(layers "F.Cu" "B.Cu")
		(net "CPU_RSV_1")
	)
	(segment
		(start 68.246498 -98.450908)
		(end 69.048122 -99.252532)
		(width 0.1016)
		(layer "B.Cu")
		(net "CPU_RSV_1")
	)
	(segment
		(start 68.246498 -97.096834)
		(end 68.246498 -98.450908)
		(width 0.1016)
		(layer "B.Cu")
		(net "CPU_RSV_1")
	)
	(segment
		(start 69.048122 -99.252532)
		(end 69.976238 -99.252532)
		(width 0.1016)
		(layer "B.Cu")
		(net "CPU_RSV_1")
	)
	(segment
		(start 33.49371 -143.858234)
		(end 33.49371 -150.79853)
		(width 0.1143)
		(layer "In2.Cu")
		(net "CPU_RSV_1")
	)
	(segment
		(start 33.57626 -152.23236)
		(end 33.57626 -168.304464)
		(width 0.1143)
		(layer "In2.Cu")
		(net "CPU_RSV_1")
	)
	(segment
		(start 37.57676 -124.81814)
		(end 37.57676 -134.588758)
		(width 0.1143)
		(layer "In2.Cu")
		(net "CPU_RSV_1")
	)
	(segment
		(start 43.88104 -103.26116)
		(end 43.88104 -106.433874)
		(width 0.1143)
		(layer "In2.Cu")
		(net "CPU_RSV_1")
	)
	(segment
		(start 33.49371 -150.79853)
		(end 33.65881 -150.96363)
		(width 0.1143)
		(layer "In2.Cu")
		(net "CPU_RSV_1")
	)
	(segment
		(start 33.65881 -150.96363)
		(end 33.65881 -152.14981)
		(width 0.1143)
		(layer "In2.Cu")
		(net "CPU_RSV_1")
	)
	(segment
		(start 33.65881 -152.14981)
		(end 33.57626 -152.23236)
		(width 0.1143)
		(layer "In2.Cu")
		(net "CPU_RSV_1")
	)
	(segment
		(start 37.57676 -134.588758)
		(end 34.87674 -137.288778)
		(width 0.1143)
		(layer "In2.Cu")
		(net "CPU_RSV_1")
	)
	(segment
		(start 42.70502 -107.609894)
		(end 42.70502 -119.68988)
		(width 0.1143)
		(layer "In2.Cu")
		(net "CPU_RSV_1")
	)
	(segment
		(start 34.87674 -137.288778)
		(end 34.87674 -142.475204)
		(width 0.1143)
		(layer "In2.Cu")
		(net "CPU_RSV_1")
	)
	(segment
		(start 43.88104 -106.433874)
		(end 42.70502 -107.609894)
		(width 0.1143)
		(layer "In2.Cu")
		(net "CPU_RSV_1")
	)
	(segment
		(start 34.87674 -142.475204)
		(end 33.49371 -143.858234)
		(width 0.1143)
		(layer "In2.Cu")
		(net "CPU_RSV_1")
	)
	(segment
		(start 42.70502 -119.68988)
		(end 37.57676 -124.81814)
		(width 0.1143)
		(layer "In2.Cu")
		(net "CPU_RSV_1")
	)
	(segment
		(start 47.5869 -176.417986)
		(end 40.958262 -169.789348)
		(width 0.1143)
		(layer "In6.Cu")
		(net "CPU_RSV_1")
	)
	(segment
		(start 106.6292 -181.360318)
		(end 106.464354 -181.195472)
		(width 0.1143)
		(layer "In6.Cu")
		(net "CPU_RSV_1")
	)
	(segment
		(start 103.851964 -181.195472)
		(end 102.285546 -179.629054)
		(width 0.1143)
		(layer "In6.Cu")
		(net "CPU_RSV_1")
	)
	(segment
		(start 136.010904 -178.865022)
		(end 113.644426 -178.865022)
		(width 0.1143)
		(layer "In6.Cu")
		(net "CPU_RSV_1")
	)
	(segment
		(start 38.757606 -169.237914)
		(end 34.50971 -169.237914)
		(width 0.1143)
		(layer "In6.Cu")
		(net "CPU_RSV_1")
	)
	(segment
		(start 83.843622 -181.801008)
		(end 81.8896 -181.801008)
		(width 0.1143)
		(layer "In6.Cu")
		(net "CPU_RSV_1")
	)
	(segment
		(start 97.45472 -181.141624)
		(end 94.496382 -181.141624)
		(width 0.1143)
		(layer "In6.Cu")
		(net "CPU_RSV_1")
	)
	(segment
		(start 90.840052 -180.53812)
		(end 89.59215 -181.786022)
		(width 0.1143)
		(layer "In6.Cu")
		(net "CPU_RSV_1")
	)
	(segment
		(start 89.22766 -181.786022)
		(end 89.070688 -181.62905)
		(width 0.1143)
		(layer "In6.Cu")
		(net "CPU_RSV_1")
	)
	(segment
		(start 93.48851 -180.831744)
		(end 92.293694 -180.831744)
		(width 0.1143)
		(layer "In6.Cu")
		(net "CPU_RSV_1")
	)
	(segment
		(start 78.913228 -180.442362)
		(end 49.439576 -180.442362)
		(width 0.1143)
		(layer "In6.Cu")
		(net "CPU_RSV_1")
	)
	(segment
		(start 112.09782 -180.411628)
		(end 111.15802 -180.411628)
		(width 0.1143)
		(layer "In6.Cu")
		(net "CPU_RSV_1")
	)
	(segment
		(start 81.616804 -181.528212)
		(end 79.999078 -181.528212)
		(width 0.1143)
		(layer "In6.Cu")
		(net "CPU_RSV_1")
	)
	(segment
		(start 109.964474 -181.605174)
		(end 108.90123 -181.605174)
		(width 0.1143)
		(layer "In6.Cu")
		(net "CPU_RSV_1")
	)
	(segment
		(start 108.90123 -181.605174)
		(end 108.656374 -181.360318)
		(width 0.1143)
		(layer "In6.Cu")
		(net "CPU_RSV_1")
	)
	(segment
		(start 92.293694 -180.831744)
		(end 92.00007 -180.53812)
		(width 0.1143)
		(layer "In6.Cu")
		(net "CPU_RSV_1")
	)
	(segment
		(start 40.958262 -169.789348)
		(end 39.30904 -169.789348)
		(width 0.1143)
		(layer "In6.Cu")
		(net "CPU_RSV_1")
	)
	(segment
		(start 39.30904 -169.789348)
		(end 38.757606 -169.237914)
		(width 0.1143)
		(layer "In6.Cu")
		(net "CPU_RSV_1")
	)
	(segment
		(start 102.285546 -179.629054)
		(end 100.327968 -179.629054)
		(width 0.1143)
		(layer "In6.Cu")
		(net "CPU_RSV_1")
	)
	(segment
		(start 48.51654 -179.519326)
		(end 48.51654 -177.908712)
		(width 0.1143)
		(layer "In6.Cu")
		(net "CPU_RSV_1")
	)
	(segment
		(start 48.51654 -177.908712)
		(end 47.5869 -176.979072)
		(width 0.1143)
		(layer "In6.Cu")
		(net "CPU_RSV_1")
	)
	(segment
		(start 84.01558 -181.62905)
		(end 83.843622 -181.801008)
		(width 0.1143)
		(layer "In6.Cu")
		(net "CPU_RSV_1")
	)
	(segment
		(start 99.837494 -180.119528)
		(end 98.476816 -180.119528)
		(width 0.1143)
		(layer "In6.Cu")
		(net "CPU_RSV_1")
	)
	(segment
		(start 92.00007 -180.53812)
		(end 90.840052 -180.53812)
		(width 0.1143)
		(layer "In6.Cu")
		(net "CPU_RSV_1")
	)
	(segment
		(start 100.327968 -179.629054)
		(end 99.837494 -180.119528)
		(width 0.1143)
		(layer "In6.Cu")
		(net "CPU_RSV_1")
	)
	(segment
		(start 93.834712 -181.177946)
		(end 93.48851 -180.831744)
		(width 0.1143)
		(layer "In6.Cu")
		(net "CPU_RSV_1")
	)
	(segment
		(start 79.999078 -181.528212)
		(end 79.494888 -181.024022)
		(width 0.1143)
		(layer "In6.Cu")
		(net "CPU_RSV_1")
	)
	(segment
		(start 106.464354 -181.195472)
		(end 103.851964 -181.195472)
		(width 0.1143)
		(layer "In6.Cu")
		(net "CPU_RSV_1")
	)
	(segment
		(start 79.494888 -181.024022)
		(end 78.913228 -180.442362)
		(width 0.1143)
		(layer "In6.Cu")
		(net "CPU_RSV_1")
	)
	(segment
		(start 98.476816 -180.119528)
		(end 97.45472 -181.141624)
		(width 0.1143)
		(layer "In6.Cu")
		(net "CPU_RSV_1")
	)
	(segment
		(start 49.439576 -180.442362)
		(end 48.51654 -179.519326)
		(width 0.1143)
		(layer "In6.Cu")
		(net "CPU_RSV_1")
	)
	(segment
		(start 89.59215 -181.786022)
		(end 89.22766 -181.786022)
		(width 0.1143)
		(layer "In6.Cu")
		(net "CPU_RSV_1")
	)
	(segment
		(start 108.656374 -181.360318)
		(end 106.6292 -181.360318)
		(width 0.1143)
		(layer "In6.Cu")
		(net "CPU_RSV_1")
	)
	(segment
		(start 94.496382 -181.141624)
		(end 94.46006 -181.177946)
		(width 0.1143)
		(layer "In6.Cu")
		(net "CPU_RSV_1")
	)
	(segment
		(start 111.15802 -180.411628)
		(end 109.964474 -181.605174)
		(width 0.1143)
		(layer "In6.Cu")
		(net "CPU_RSV_1")
	)
	(segment
		(start 94.46006 -181.177946)
		(end 93.834712 -181.177946)
		(width 0.1143)
		(layer "In6.Cu")
		(net "CPU_RSV_1")
	)
	(segment
		(start 34.50971 -169.237914)
		(end 33.57626 -168.304464)
		(width 0.1143)
		(layer "In6.Cu")
		(net "CPU_RSV_1")
	)
	(segment
		(start 89.070688 -181.62905)
		(end 84.01558 -181.62905)
		(width 0.1143)
		(layer "In6.Cu")
		(net "CPU_RSV_1")
	)
	(segment
		(start 113.644426 -178.865022)
		(end 112.09782 -180.411628)
		(width 0.1143)
		(layer "In6.Cu")
		(net "CPU_RSV_1")
	)
	(segment
		(start 47.5869 -176.979072)
		(end 47.5869 -176.417986)
		(width 0.1143)
		(layer "In6.Cu")
		(net "CPU_RSV_1")
	)
	(segment
		(start 81.8896 -181.801008)
		(end 81.616804 -181.528212)
		(width 0.1143)
		(layer "In6.Cu")
		(net "CPU_RSV_1")
	)
	(segment
		(start 137.175748 -180.029866)
		(end 136.010904 -178.865022)
		(width 0.1143)
		(layer "In6.Cu")
		(net "CPU_RSV_1")
	)
	(segment
		(start 74.99477 -167.597074)
		(end 74.99477 -164.374576)
		(width 0.1016)
		(layer "F.Cu")
		(net "UART_T3_NODE1_RXD")
	)
	(segment
		(start 75.15606 -167.758364)
		(end 74.99477 -167.597074)
		(width 0.1016)
		(layer "F.Cu")
		(net "UART_T3_NODE1_RXD")
	)
	(segment
		(start 75.15606 -168.316148)
		(end 75.15606 -167.758364)
		(width 0.1016)
		(layer "F.Cu")
		(net "UART_T3_NODE1_RXD")
	)
	(via
		(at 75.15606 -168.316148)
		(size 0.508)
		(drill 0.254)
		(layers "F.Cu" "B.Cu")
		(net "UART_T3_NODE1_RXD")
	)
	(via
		(at 75.1078 -186.215782)
		(size 0.508)
		(drill 0.254)
		(layers "F.Cu" "B.Cu")
		(net "UART_T3_NODE1_RXD")
	)
	(segment
		(start 74.38136 -186.098688)
		(end 74.990706 -186.098688)
		(width 0.1016)
		(layer "B.Cu")
		(net "UART_T3_NODE1_RXD")
	)
	(segment
		(start 74.990706 -186.098688)
		(end 75.1078 -186.215782)
		(width 0.1016)
		(layer "B.Cu")
		(net "UART_T3_NODE1_RXD")
	)
	(segment
		(start 75.04176 -187.726574)
		(end 75.1078 -187.660534)
		(width 0.1016)
		(layer "B.Cu")
		(net "UART_T3_NODE1_RXD")
	)
	(segment
		(start 75.1078 -187.660534)
		(end 75.1078 -186.215782)
		(width 0.1016)
		(layer "B.Cu")
		(net "UART_T3_NODE1_RXD")
	)
	(segment
		(start 74.265536 -187.406788)
		(end 74.95794 -186.714384)
		(width 0.1143)
		(layer "In7.Cu")
		(net "UART_T3_NODE1_RXD")
	)
	(segment
		(start 74.056494 -178.980338)
		(end 71.288656 -181.748176)
		(width 0.1143)
		(layer "In7.Cu")
		(net "UART_T3_NODE1_RXD")
	)
	(segment
		(start 70.517004 -181.748176)
		(end 70.260464 -182.004716)
		(width 0.1143)
		(layer "In7.Cu")
		(net "UART_T3_NODE1_RXD")
	)
	(segment
		(start 69.63537 -184.334658)
		(end 70.71868 -185.417968)
		(width 0.1143)
		(layer "In7.Cu")
		(net "UART_T3_NODE1_RXD")
	)
	(segment
		(start 74.95794 -186.714384)
		(end 74.95794 -186.365642)
		(width 0.1143)
		(layer "In7.Cu")
		(net "UART_T3_NODE1_RXD")
	)
	(segment
		(start 75.15606 -168.316148)
		(end 75.15606 -168.872154)
		(width 0.1143)
		(layer "In7.Cu")
		(net "UART_T3_NODE1_RXD")
	)
	(segment
		(start 75.15606 -168.872154)
		(end 76.3905 -170.106594)
		(width 0.1143)
		(layer "In7.Cu")
		(net "UART_T3_NODE1_RXD")
	)
	(segment
		(start 74.056494 -177.93081)
		(end 74.056494 -178.980338)
		(width 0.1143)
		(layer "In7.Cu")
		(net "UART_T3_NODE1_RXD")
	)
	(segment
		(start 73.106534 -187.305442)
		(end 73.20788 -187.406788)
		(width 0.1143)
		(layer "In7.Cu")
		(net "UART_T3_NODE1_RXD")
	)
	(segment
		(start 76.3905 -170.106594)
		(end 76.3905 -175.596804)
		(width 0.1143)
		(layer "In7.Cu")
		(net "UART_T3_NODE1_RXD")
	)
	(segment
		(start 70.71868 -186.80557)
		(end 71.218552 -187.305442)
		(width 0.1143)
		(layer "In7.Cu")
		(net "UART_T3_NODE1_RXD")
	)
	(segment
		(start 71.288656 -181.748176)
		(end 70.517004 -181.748176)
		(width 0.1143)
		(layer "In7.Cu")
		(net "UART_T3_NODE1_RXD")
	)
	(segment
		(start 76.3905 -175.596804)
		(end 74.056494 -177.93081)
		(width 0.1143)
		(layer "In7.Cu")
		(net "UART_T3_NODE1_RXD")
	)
	(segment
		(start 70.260464 -182.004716)
		(end 70.260464 -182.518558)
		(width 0.1143)
		(layer "In7.Cu")
		(net "UART_T3_NODE1_RXD")
	)
	(segment
		(start 73.20788 -187.406788)
		(end 74.265536 -187.406788)
		(width 0.1143)
		(layer "In7.Cu")
		(net "UART_T3_NODE1_RXD")
	)
	(segment
		(start 74.95794 -186.365642)
		(end 75.1078 -186.215782)
		(width 0.1143)
		(layer "In7.Cu")
		(net "UART_T3_NODE1_RXD")
	)
	(segment
		(start 70.260464 -182.518558)
		(end 69.63537 -183.143652)
		(width 0.1143)
		(layer "In7.Cu")
		(net "UART_T3_NODE1_RXD")
	)
	(segment
		(start 70.71868 -185.417968)
		(end 70.71868 -186.80557)
		(width 0.1143)
		(layer "In7.Cu")
		(net "UART_T3_NODE1_RXD")
	)
	(segment
		(start 71.218552 -187.305442)
		(end 73.106534 -187.305442)
		(width 0.1143)
		(layer "In7.Cu")
		(net "UART_T3_NODE1_RXD")
	)
	(segment
		(start 69.63537 -183.143652)
		(end 69.63537 -184.334658)
		(width 0.1143)
		(layer "In7.Cu")
		(net "UART_T3_NODE1_RXD")
	)
	(segment
		(start 74.494644 -165.056312)
		(end 74.225912 -165.325044)
		(width 0.1016)
		(layer "F.Cu")
		(net "UART_T3_NODE1_TXD")
	)
	(segment
		(start 74.494644 -164.374576)
		(end 74.494644 -165.056312)
		(width 0.1016)
		(layer "F.Cu")
		(net "UART_T3_NODE1_TXD")
	)
	(segment
		(start 73.614026 -165.325044)
		(end 73.151238 -164.862256)
		(width 0.1016)
		(layer "F.Cu")
		(net "UART_T3_NODE1_TXD")
	)
	(segment
		(start 74.225912 -165.325044)
		(end 73.614026 -165.325044)
		(width 0.1016)
		(layer "F.Cu")
		(net "UART_T3_NODE1_TXD")
	)
	(via
		(at 73.151238 -164.862256)
		(size 0.508)
		(drill 0.254)
		(layers "F.Cu" "B.Cu")
		(net "UART_T3_NODE1_TXD")
	)
	(segment
		(start 73.19645 -164.907468)
		(end 73.151238 -164.862256)
		(width 0.1016)
		(layer "B.Cu")
		(net "UART_T3_NODE1_TXD")
	)
	(segment
		(start 74.27468 -164.907468)
		(end 73.19645 -164.907468)
		(width 0.1016)
		(layer "B.Cu")
		(net "UART_T3_NODE1_TXD")
	)
	(segment
		(start 124.49048 -168.326562)
		(end 124.49048 -167.696388)
		(width 0.1016)
		(layer "F.Cu")
		(net "CPLD_WDT1")
	)
	(segment
		(start 124.10821 -167.314118)
		(end 124.10821 -166.523416)
		(width 0.1016)
		(layer "F.Cu")
		(net "CPLD_WDT1")
	)
	(segment
		(start 128.846834 -168.608502)
		(end 129.775712 -168.608502)
		(width 0.1016)
		(layer "F.Cu")
		(net "CPLD_WDT1")
	)
	(segment
		(start 124.49048 -167.696388)
		(end 124.10821 -167.314118)
		(width 0.1016)
		(layer "F.Cu")
		(net "CPLD_WDT1")
	)
	(segment
		(start 124.49048 -168.326562)
		(end 124.54763 -168.269412)
		(width 0.1016)
		(layer "F.Cu")
		(net "CPLD_WDT1")
	)
	(segment
		(start 74.693272 -169.771314)
		(end 74.70648 -169.771314)
		(width 0.1016)
		(layer "F.Cu")
		(net "CPLD_WDT1")
	)
	(segment
		(start 72.244712 -169.624502)
		(end 74.54646 -169.624502)
		(width 0.1016)
		(layer "F.Cu")
		(net "CPLD_WDT1")
	)
	(segment
		(start 124.54763 -168.269412)
		(end 128.507744 -168.269412)
		(width 0.1016)
		(layer "F.Cu")
		(net "CPLD_WDT1")
	)
	(segment
		(start 128.507744 -168.269412)
		(end 128.846834 -168.608502)
		(width 0.1016)
		(layer "F.Cu")
		(net "CPLD_WDT1")
	)
	(segment
		(start 74.54646 -169.624502)
		(end 74.693272 -169.771314)
		(width 0.1016)
		(layer "F.Cu")
		(net "CPLD_WDT1")
	)
	(via
		(at 74.70648 -169.771314)
		(size 0.508)
		(drill 0.254)
		(layers "F.Cu" "B.Cu")
		(net "CPLD_WDT1")
	)
	(via
		(at 124.49048 -168.326562)
		(size 0.508)
		(drill 0.254)
		(layers "F.Cu" "B.Cu")
		(net "CPLD_WDT1")
	)
	(segment
		(start 89.662 -169.888662)
		(end 89.51976 -169.746422)
		(width 0.1143)
		(layer "In2.Cu")
		(net "CPLD_WDT1")
	)
	(segment
		(start 91.223084 -169.380662)
		(end 90.715084 -169.888662)
		(width 0.1143)
		(layer "In2.Cu")
		(net "CPLD_WDT1")
	)
	(segment
		(start 76.52639 -169.771314)
		(end 74.70648 -169.771314)
		(width 0.1143)
		(layer "In2.Cu")
		(net "CPLD_WDT1")
	)
	(segment
		(start 85.1408 -165.692582)
		(end 83.537044 -165.692582)
		(width 0.1143)
		(layer "In2.Cu")
		(net "CPLD_WDT1")
	)
	(segment
		(start 124.49048 -168.326562)
		(end 120.739916 -168.326562)
		(width 0.1143)
		(layer "In2.Cu")
		(net "CPLD_WDT1")
	)
	(segment
		(start 89.51976 -169.746422)
		(end 89.19464 -169.746422)
		(width 0.1143)
		(layer "In2.Cu")
		(net "CPLD_WDT1")
	)
	(segment
		(start 93.20149 -169.380662)
		(end 91.223084 -169.380662)
		(width 0.1143)
		(layer "In2.Cu")
		(net "CPLD_WDT1")
	)
	(segment
		(start 116.999004 -172.067474)
		(end 110.29696 -172.067474)
		(width 0.1143)
		(layer "In2.Cu")
		(net "CPLD_WDT1")
	)
	(segment
		(start 104.84358 -171.292266)
		(end 97.272348 -171.292266)
		(width 0.1143)
		(layer "In2.Cu")
		(net "CPLD_WDT1")
	)
	(segment
		(start 107.425998 -171.069254)
		(end 105.066592 -171.069254)
		(width 0.1143)
		(layer "In2.Cu")
		(net "CPLD_WDT1")
	)
	(segment
		(start 97.272348 -171.292266)
		(end 95.247714 -169.267632)
		(width 0.1143)
		(layer "In2.Cu")
		(net "CPLD_WDT1")
	)
	(segment
		(start 83.01228 -165.533578)
		(end 80.701134 -167.844724)
		(width 0.1143)
		(layer "In2.Cu")
		(net "CPLD_WDT1")
	)
	(segment
		(start 105.066592 -171.069254)
		(end 104.84358 -171.292266)
		(width 0.1143)
		(layer "In2.Cu")
		(net "CPLD_WDT1")
	)
	(segment
		(start 80.03667 -167.844724)
		(end 79.00162 -168.879774)
		(width 0.1143)
		(layer "In2.Cu")
		(net "CPLD_WDT1")
	)
	(segment
		(start 107.591098 -171.234354)
		(end 107.425998 -171.069254)
		(width 0.1143)
		(layer "In2.Cu")
		(net "CPLD_WDT1")
	)
	(segment
		(start 80.701134 -167.844724)
		(end 80.03667 -167.844724)
		(width 0.1143)
		(layer "In2.Cu")
		(net "CPLD_WDT1")
	)
	(segment
		(start 110.29696 -172.067474)
		(end 109.46384 -171.234354)
		(width 0.1143)
		(layer "In2.Cu")
		(net "CPLD_WDT1")
	)
	(segment
		(start 95.247714 -169.267632)
		(end 93.31452 -169.267632)
		(width 0.1143)
		(layer "In2.Cu")
		(net "CPLD_WDT1")
	)
	(segment
		(start 89.19464 -169.746422)
		(end 85.1408 -165.692582)
		(width 0.1143)
		(layer "In2.Cu")
		(net "CPLD_WDT1")
	)
	(segment
		(start 83.37804 -165.533578)
		(end 83.01228 -165.533578)
		(width 0.1143)
		(layer "In2.Cu")
		(net "CPLD_WDT1")
	)
	(segment
		(start 83.537044 -165.692582)
		(end 83.37804 -165.533578)
		(width 0.1143)
		(layer "In2.Cu")
		(net "CPLD_WDT1")
	)
	(segment
		(start 109.46384 -171.234354)
		(end 107.591098 -171.234354)
		(width 0.1143)
		(layer "In2.Cu")
		(net "CPLD_WDT1")
	)
	(segment
		(start 120.739916 -168.326562)
		(end 116.999004 -172.067474)
		(width 0.1143)
		(layer "In2.Cu")
		(net "CPLD_WDT1")
	)
	(segment
		(start 79.00162 -168.879774)
		(end 77.41793 -168.879774)
		(width 0.1143)
		(layer "In2.Cu")
		(net "CPLD_WDT1")
	)
	(segment
		(start 77.41793 -168.879774)
		(end 76.52639 -169.771314)
		(width 0.1143)
		(layer "In2.Cu")
		(net "CPLD_WDT1")
	)
	(segment
		(start 90.715084 -169.888662)
		(end 89.662 -169.888662)
		(width 0.1143)
		(layer "In2.Cu")
		(net "CPLD_WDT1")
	)
	(segment
		(start 93.31452 -169.267632)
		(end 93.20149 -169.380662)
		(width 0.1143)
		(layer "In2.Cu")
		(net "CPLD_WDT1")
	)
	(segment
		(start 69.68744 -171.153074)
		(end 70.337934 -171.153074)
		(width 0.1016)
		(layer "F.Cu")
		(net "UART_T2_NODE3_RXD")
	)
	(segment
		(start 59.67476 -185.605674)
		(end 59.24296 -186.037474)
		(width 0.1016)
		(layer "F.Cu")
		(net "UART_T2_NODE3_RXD")
	)
	(segment
		(start 59.67476 -187.726574)
		(end 59.67476 -187.043568)
		(width 0.1016)
		(layer "F.Cu")
		(net "UART_T2_NODE3_RXD")
	)
	(segment
		(start 59.24296 -186.611768)
		(end 59.67476 -187.043568)
		(width 0.1016)
		(layer "F.Cu")
		(net "UART_T2_NODE3_RXD")
	)
	(segment
		(start 59.24296 -186.037474)
		(end 59.24296 -186.611768)
		(width 0.1016)
		(layer "F.Cu")
		(net "UART_T2_NODE3_RXD")
	)
	(segment
		(start 71.36638 -170.124628)
		(end 72.244712 -170.124628)
		(width 0.1016)
		(layer "F.Cu")
		(net "UART_T2_NODE3_RXD")
	)
	(segment
		(start 70.337934 -171.153074)
		(end 71.36638 -170.124628)
		(width 0.1016)
		(layer "F.Cu")
		(net "UART_T2_NODE3_RXD")
	)
	(via
		(at 59.67476 -187.043568)
		(size 0.508)
		(drill 0.254)
		(layers "F.Cu" "B.Cu")
		(net "UART_T2_NODE3_RXD")
	)
	(via
		(at 69.68744 -171.153074)
		(size 0.508)
		(drill 0.254)
		(layers "F.Cu" "B.Cu")
		(net "UART_T2_NODE3_RXD")
	)
	(segment
		(start 61.51626 -182.579772)
		(end 61.51626 -183.878728)
		(width 0.1143)
		(layer "In7.Cu")
		(net "UART_T2_NODE3_RXD")
	)
	(segment
		(start 70.592696 -174.013622)
		(end 69.05498 -175.551338)
		(width 0.1143)
		(layer "In7.Cu")
		(net "UART_T2_NODE3_RXD")
	)
	(segment
		(start 61.51626 -183.878728)
		(end 60.11418 -185.280808)
		(width 0.1143)
		(layer "In7.Cu")
		(net "UART_T2_NODE3_RXD")
	)
	(segment
		(start 67.02044 -177.075592)
		(end 61.51626 -182.579772)
		(width 0.1143)
		(layer "In7.Cu")
		(net "UART_T2_NODE3_RXD")
	)
	(segment
		(start 69.68744 -171.153074)
		(end 70.592696 -172.05833)
		(width 0.1143)
		(layer "In7.Cu")
		(net "UART_T2_NODE3_RXD")
	)
	(segment
		(start 60.11418 -186.45251)
		(end 59.67476 -186.89193)
		(width 0.1143)
		(layer "In7.Cu")
		(net "UART_T2_NODE3_RXD")
	)
	(segment
		(start 59.67476 -186.89193)
		(end 59.67476 -187.043568)
		(width 0.1143)
		(layer "In7.Cu")
		(net "UART_T2_NODE3_RXD")
	)
	(segment
		(start 69.05498 -175.551338)
		(end 69.05498 -175.703992)
		(width 0.1143)
		(layer "In7.Cu")
		(net "UART_T2_NODE3_RXD")
	)
	(segment
		(start 67.68338 -177.075592)
		(end 67.02044 -177.075592)
		(width 0.1143)
		(layer "In7.Cu")
		(net "UART_T2_NODE3_RXD")
	)
	(segment
		(start 70.592696 -172.05833)
		(end 70.592696 -174.013622)
		(width 0.1143)
		(layer "In7.Cu")
		(net "UART_T2_NODE3_RXD")
	)
	(segment
		(start 60.11418 -185.280808)
		(end 60.11418 -186.45251)
		(width 0.1143)
		(layer "In7.Cu")
		(net "UART_T2_NODE3_RXD")
	)
	(segment
		(start 69.05498 -175.703992)
		(end 67.68338 -177.075592)
		(width 0.1143)
		(layer "In7.Cu")
		(net "UART_T2_NODE3_RXD")
	)
	(segment
		(start 68.43268 -171.973748)
		(end 69.950584 -171.973748)
		(width 0.1016)
		(layer "F.Cu")
		(net "UART_T2_NODE3_TXD")
	)
	(segment
		(start 58.53176 -184.805574)
		(end 58.53176 -183.957468)
		(width 0.1016)
		(layer "F.Cu")
		(net "UART_T2_NODE3_TXD")
	)
	(segment
		(start 69.950584 -171.973748)
		(end 71.299832 -170.6245)
		(width 0.1016)
		(layer "F.Cu")
		(net "UART_T2_NODE3_TXD")
	)
	(segment
		(start 71.299832 -170.6245)
		(end 72.244712 -170.6245)
		(width 0.1016)
		(layer "F.Cu")
		(net "UART_T2_NODE3_TXD")
	)
	(via
		(at 58.53176 -183.957468)
		(size 0.508)
		(drill 0.254)
		(layers "F.Cu" "B.Cu")
		(net "UART_T2_NODE3_TXD")
	)
	(via
		(at 68.43268 -171.973748)
		(size 0.508)
		(drill 0.254)
		(layers "F.Cu" "B.Cu")
		(net "UART_T2_NODE3_TXD")
	)
	(segment
		(start 59.940952 -180.934106)
		(end 59.49823 -180.934106)
		(width 0.1143)
		(layer "In7.Cu")
		(net "UART_T2_NODE3_TXD")
	)
	(segment
		(start 68.43268 -171.973748)
		(end 68.43268 -173.425866)
		(width 0.1143)
		(layer "In7.Cu")
		(net "UART_T2_NODE3_TXD")
	)
	(segment
		(start 58.53176 -181.900576)
		(end 58.53176 -183.957468)
		(width 0.1143)
		(layer "In7.Cu")
		(net "UART_T2_NODE3_TXD")
	)
	(segment
		(start 63.430404 -177.444908)
		(end 59.940952 -180.934106)
		(width 0.1143)
		(layer "In7.Cu")
		(net "UART_T2_NODE3_TXD")
	)
	(segment
		(start 67.5386 -173.925484)
		(end 64.746124 -176.71796)
		(width 0.1143)
		(layer "In7.Cu")
		(net "UART_T2_NODE3_TXD")
	)
	(segment
		(start 63.68542 -176.71796)
		(end 63.430404 -176.972976)
		(width 0.1143)
		(layer "In7.Cu")
		(net "UART_T2_NODE3_TXD")
	)
	(segment
		(start 64.746124 -176.71796)
		(end 63.68542 -176.71796)
		(width 0.1143)
		(layer "In7.Cu")
		(net "UART_T2_NODE3_TXD")
	)
	(segment
		(start 63.430404 -176.972976)
		(end 63.430404 -177.444908)
		(width 0.1143)
		(layer "In7.Cu")
		(net "UART_T2_NODE3_TXD")
	)
	(segment
		(start 59.49823 -180.934106)
		(end 58.53176 -181.900576)
		(width 0.1143)
		(layer "In7.Cu")
		(net "UART_T2_NODE3_TXD")
	)
	(segment
		(start 68.43268 -173.425866)
		(end 67.933062 -173.925484)
		(width 0.1143)
		(layer "In7.Cu")
		(net "UART_T2_NODE3_TXD")
	)
	(segment
		(start 67.933062 -173.925484)
		(end 67.5386 -173.925484)
		(width 0.1143)
		(layer "In7.Cu")
		(net "UART_T2_NODE3_TXD")
	)
	(segment
		(start 63.77178 -187.251594)
		(end 63.77178 -186.800998)
		(width 0.1016)
		(layer "F.Cu")
		(net "UART_T2_NODE1_RXD")
	)
	(segment
		(start 73.563988 -171.985432)
		(end 74.439272 -171.985432)
		(width 0.1016)
		(layer "F.Cu")
		(net "UART_T2_NODE1_RXD")
	)
	(segment
		(start 73.424796 -172.124624)
		(end 73.563988 -171.985432)
		(width 0.1016)
		(layer "F.Cu")
		(net "UART_T2_NODE1_RXD")
	)
	(segment
		(start 64.24676 -186.326018)
		(end 64.24676 -185.605674)
		(width 0.1016)
		(layer "F.Cu")
		(net "UART_T2_NODE1_RXD")
	)
	(segment
		(start 72.244712 -172.124624)
		(end 73.424796 -172.124624)
		(width 0.1016)
		(layer "F.Cu")
		(net "UART_T2_NODE1_RXD")
	)
	(segment
		(start 63.77178 -186.800998)
		(end 64.24676 -186.326018)
		(width 0.1016)
		(layer "F.Cu")
		(net "UART_T2_NODE1_RXD")
	)
	(segment
		(start 64.24676 -187.726574)
		(end 63.77178 -187.251594)
		(width 0.1016)
		(layer "F.Cu")
		(net "UART_T2_NODE1_RXD")
	)
	(via
		(at 74.439272 -171.985432)
		(size 0.508)
		(drill 0.254)
		(layers "F.Cu" "B.Cu")
		(net "UART_T2_NODE1_RXD")
	)
	(via
		(at 64.24676 -186.326018)
		(size 0.508)
		(drill 0.254)
		(layers "F.Cu" "B.Cu")
		(net "UART_T2_NODE1_RXD")
	)
	(segment
		(start 66.41592 -184.156858)
		(end 64.24676 -186.326018)
		(width 0.1143)
		(layer "In7.Cu")
		(net "UART_T2_NODE1_RXD")
	)
	(segment
		(start 67.192906 -183.059578)
		(end 66.41592 -183.836564)
		(width 0.1143)
		(layer "In7.Cu")
		(net "UART_T2_NODE1_RXD")
	)
	(segment
		(start 67.359784 -183.059578)
		(end 67.192906 -183.059578)
		(width 0.1143)
		(layer "In7.Cu")
		(net "UART_T2_NODE1_RXD")
	)
	(segment
		(start 71.1454 -177.974498)
		(end 71.1454 -179.273962)
		(width 0.1143)
		(layer "In7.Cu")
		(net "UART_T2_NODE1_RXD")
	)
	(segment
		(start 73.97496 -175.144938)
		(end 71.1454 -177.974498)
		(width 0.1143)
		(layer "In7.Cu")
		(net "UART_T2_NODE1_RXD")
	)
	(segment
		(start 74.439272 -171.985432)
		(end 73.97496 -172.449744)
		(width 0.1143)
		(layer "In7.Cu")
		(net "UART_T2_NODE1_RXD")
	)
	(segment
		(start 66.41592 -183.836564)
		(end 66.41592 -184.156858)
		(width 0.1143)
		(layer "In7.Cu")
		(net "UART_T2_NODE1_RXD")
	)
	(segment
		(start 73.97496 -172.449744)
		(end 73.97496 -175.144938)
		(width 0.1143)
		(layer "In7.Cu")
		(net "UART_T2_NODE1_RXD")
	)
	(segment
		(start 71.1454 -179.273962)
		(end 67.359784 -183.059578)
		(width 0.1143)
		(layer "In7.Cu")
		(net "UART_T2_NODE1_RXD")
	)
	(segment
		(start 61.13653 -184.805574)
		(end 61.33338 -185.002424)
		(width 0.1016)
		(layer "F.Cu")
		(net "UART_T2_NODE2_TXD")
	)
	(segment
		(start 61.33338 -186.060842)
		(end 61.07938 -186.314842)
		(width 0.1016)
		(layer "F.Cu")
		(net "UART_T2_NODE2_TXD")
	)
	(segment
		(start 61.07938 -186.314842)
		(end 60.833 -186.314842)
		(width 0.1016)
		(layer "F.Cu")
		(net "UART_T2_NODE2_TXD")
	)
	(segment
		(start 61.33338 -185.002424)
		(end 61.33338 -186.060842)
		(width 0.1016)
		(layer "F.Cu")
		(net "UART_T2_NODE2_TXD")
	)
	(segment
		(start 72.244712 -171.624752)
		(end 71.080122 -171.624752)
		(width 0.1016)
		(layer "F.Cu")
		(net "UART_T2_NODE2_TXD")
	)
	(segment
		(start 60.81776 -184.805574)
		(end 61.13653 -184.805574)
		(width 0.1016)
		(layer "F.Cu")
		(net "UART_T2_NODE2_TXD")
	)
	(via
		(at 60.833 -186.314842)
		(size 0.508)
		(drill 0.254)
		(layers "F.Cu" "B.Cu")
		(net "UART_T2_NODE2_TXD")
	)
	(via
		(at 71.080122 -171.624752)
		(size 0.508)
		(drill 0.254)
		(layers "F.Cu" "B.Cu")
		(net "UART_T2_NODE2_TXD")
	)
	(segment
		(start 71.13905 -174.76978)
		(end 69.810122 -176.098708)
		(width 0.1143)
		(layer "In7.Cu")
		(net "UART_T2_NODE2_TXD")
	)
	(segment
		(start 66.41846 -178.689254)
		(end 66.41846 -179.135532)
		(width 0.1143)
		(layer "In7.Cu")
		(net "UART_T2_NODE2_TXD")
	)
	(segment
		(start 64.3763 -180.506624)
		(end 62.37097 -182.511954)
		(width 0.1143)
		(layer "In7.Cu")
		(net "UART_T2_NODE2_TXD")
	)
	(segment
		(start 62.37097 -182.511954)
		(end 62.37097 -183.862472)
		(width 0.1143)
		(layer "In7.Cu")
		(net "UART_T2_NODE2_TXD")
	)
	(segment
		(start 68.473066 -177.612294)
		(end 67.49542 -177.612294)
		(width 0.1143)
		(layer "In7.Cu")
		(net "UART_T2_NODE2_TXD")
	)
	(segment
		(start 65.047368 -180.506624)
		(end 64.3763 -180.506624)
		(width 0.1143)
		(layer "In7.Cu")
		(net "UART_T2_NODE2_TXD")
	)
	(segment
		(start 61.497718 -185.367422)
		(end 61.497718 -185.650124)
		(width 0.1143)
		(layer "In7.Cu")
		(net "UART_T2_NODE2_TXD")
	)
	(segment
		(start 62.37097 -183.862472)
		(end 62.38875 -183.880252)
		(width 0.1143)
		(layer "In7.Cu")
		(net "UART_T2_NODE2_TXD")
	)
	(segment
		(start 69.810122 -176.098708)
		(end 69.810122 -176.275238)
		(width 0.1143)
		(layer "In7.Cu")
		(net "UART_T2_NODE2_TXD")
	)
	(segment
		(start 67.49542 -177.612294)
		(end 66.41846 -178.689254)
		(width 0.1143)
		(layer "In7.Cu")
		(net "UART_T2_NODE2_TXD")
	)
	(segment
		(start 69.810122 -176.275238)
		(end 68.473066 -177.612294)
		(width 0.1143)
		(layer "In7.Cu")
		(net "UART_T2_NODE2_TXD")
	)
	(segment
		(start 62.38875 -184.47639)
		(end 61.497718 -185.367422)
		(width 0.1143)
		(layer "In7.Cu")
		(net "UART_T2_NODE2_TXD")
	)
	(segment
		(start 71.080122 -171.624752)
		(end 71.080122 -174.334678)
		(width 0.1143)
		(layer "In7.Cu")
		(net "UART_T2_NODE2_TXD")
	)
	(segment
		(start 71.080122 -174.334678)
		(end 71.13905 -174.393606)
		(width 0.1143)
		(layer "In7.Cu")
		(net "UART_T2_NODE2_TXD")
	)
	(segment
		(start 66.41846 -179.135532)
		(end 65.047368 -180.506624)
		(width 0.1143)
		(layer "In7.Cu")
		(net "UART_T2_NODE2_TXD")
	)
	(segment
		(start 61.497718 -185.650124)
		(end 60.833 -186.314842)
		(width 0.1143)
		(layer "In7.Cu")
		(net "UART_T2_NODE2_TXD")
	)
	(segment
		(start 62.38875 -183.880252)
		(end 62.38875 -184.47639)
		(width 0.1143)
		(layer "In7.Cu")
		(net "UART_T2_NODE2_TXD")
	)
	(segment
		(start 71.13905 -174.393606)
		(end 71.13905 -174.76978)
		(width 0.1143)
		(layer "In7.Cu")
		(net "UART_T2_NODE2_TXD")
	)
	(segment
		(start 71.473314 -167.624506)
		(end 71.12254 -167.97528)
		(width 0.1016)
		(layer "F.Cu")
		(net "UART_T2_NODE4_TXD")
	)
	(segment
		(start 56.24576 -184.805574)
		(end 57.00014 -182.87238)
		(width 0.1016)
		(layer "F.Cu")
		(net "UART_T2_NODE4_TXD")
	)
	(segment
		(start 71.12254 -167.97528)
		(end 69.141594 -167.97528)
		(width 0.1016)
		(layer "F.Cu")
		(net "UART_T2_NODE4_TXD")
	)
	(segment
		(start 68.12788 -168.82491)
		(end 68.12788 -168.988994)
		(width 0.1016)
		(layer "F.Cu")
		(net "UART_T2_NODE4_TXD")
	)
	(segment
		(start 68.128134 -168.82491)
		(end 68.12788 -168.82491)
		(width 0.1016)
		(layer "F.Cu")
		(net "UART_T2_NODE4_TXD")
	)
	(segment
		(start 69.141594 -167.97528)
		(end 68.98005 -168.136824)
		(width 0.1016)
		(layer "F.Cu")
		(net "UART_T2_NODE4_TXD")
	)
	(segment
		(start 68.81622 -168.136824)
		(end 68.128134 -168.82491)
		(width 0.1016)
		(layer "F.Cu")
		(net "UART_T2_NODE4_TXD")
	)
	(segment
		(start 68.98005 -168.136824)
		(end 68.81622 -168.136824)
		(width 0.1016)
		(layer "F.Cu")
		(net "UART_T2_NODE4_TXD")
	)
	(segment
		(start 67.4497 -169.667174)
		(end 67.4497 -169.77741)
		(width 0.1016)
		(layer "F.Cu")
		(net "UART_T2_NODE4_TXD")
	)
	(segment
		(start 72.244712 -167.624506)
		(end 71.473314 -167.624506)
		(width 0.1016)
		(layer "F.Cu")
		(net "UART_T2_NODE4_TXD")
	)
	(segment
		(start 68.12788 -168.988994)
		(end 67.4497 -169.667174)
		(width 0.1016)
		(layer "F.Cu")
		(net "UART_T2_NODE4_TXD")
	)
	(via
		(at 67.4497 -169.77741)
		(size 0.508)
		(drill 0.254)
		(layers "F.Cu" "B.Cu")
		(net "UART_T2_NODE4_TXD")
	)
	(via
		(at 57.00014 -182.87238)
		(size 0.508)
		(drill 0.254)
		(layers "F.Cu" "B.Cu")
		(net "UART_T2_NODE4_TXD")
	)
	(segment
		(start 67.4497 -169.77741)
		(end 66.90614 -170.32097)
		(width 0.1143)
		(layer "In7.Cu")
		(net "UART_T2_NODE4_TXD")
	)
	(segment
		(start 66.90614 -170.32097)
		(end 66.90614 -172.548042)
		(width 0.1143)
		(layer "In7.Cu")
		(net "UART_T2_NODE4_TXD")
	)
	(segment
		(start 57.4675 -181.985666)
		(end 57.43194 -182.021226)
		(width 0.1143)
		(layer "In7.Cu")
		(net "UART_T2_NODE4_TXD")
	)
	(segment
		(start 57.43194 -182.44058)
		(end 57.00014 -182.87238)
		(width 0.1143)
		(layer "In7.Cu")
		(net "UART_T2_NODE4_TXD")
	)
	(segment
		(start 66.90614 -172.548042)
		(end 57.468516 -181.985666)
		(width 0.1143)
		(layer "In7.Cu")
		(net "UART_T2_NODE4_TXD")
	)
	(segment
		(start 57.43194 -182.021226)
		(end 57.43194 -182.44058)
		(width 0.1143)
		(layer "In7.Cu")
		(net "UART_T2_NODE4_TXD")
	)
	(segment
		(start 57.468516 -181.985666)
		(end 57.4675 -181.985666)
		(width 0.1143)
		(layer "In7.Cu")
		(net "UART_T2_NODE4_TXD")
	)
	(segment
		(start 61.96076 -187.726574)
		(end 61.96076 -187.048648)
		(width 0.1016)
		(layer "F.Cu")
		(net "UART_T2_NODE2_RXD")
	)
	(segment
		(start 72.244712 -171.124626)
		(end 73.49871 -171.124626)
		(width 0.1016)
		(layer "F.Cu")
		(net "UART_T2_NODE2_RXD")
	)
	(segment
		(start 61.96076 -187.048648)
		(end 61.96076 -185.605674)
		(width 0.1016)
		(layer "F.Cu")
		(net "UART_T2_NODE2_RXD")
	)
	(via
		(at 73.49871 -171.124626)
		(size 0.508)
		(drill 0.254)
		(layers "F.Cu" "B.Cu")
		(net "UART_T2_NODE2_RXD")
	)
	(via
		(at 61.96076 -187.048648)
		(size 0.508)
		(drill 0.254)
		(layers "F.Cu" "B.Cu")
		(net "UART_T2_NODE2_RXD")
	)
	(segment
		(start 64.85636 -181.382924)
		(end 64.835024 -181.40426)
		(width 0.1143)
		(layer "In7.Cu")
		(net "UART_T2_NODE2_RXD")
	)
	(segment
		(start 62.70625 -184.644284)
		(end 61.96076 -185.389774)
		(width 0.1143)
		(layer "In7.Cu")
		(net "UART_T2_NODE2_RXD")
	)
	(segment
		(start 65.19418 -181.126384)
		(end 64.93764 -181.382924)
		(width 0.1143)
		(layer "In7.Cu")
		(net "UART_T2_NODE2_RXD")
	)
	(segment
		(start 71.45782 -174.90186)
		(end 70.1294 -176.23028)
		(width 0.1143)
		(layer "In7.Cu")
		(net "UART_T2_NODE2_RXD")
	)
	(segment
		(start 65.19418 -181.045104)
		(end 65.19418 -181.126384)
		(width 0.1143)
		(layer "In7.Cu")
		(net "UART_T2_NODE2_RXD")
	)
	(segment
		(start 64.93764 -181.382924)
		(end 64.85636 -181.382924)
		(width 0.1143)
		(layer "In7.Cu")
		(net "UART_T2_NODE2_RXD")
	)
	(segment
		(start 62.68847 -183.7309)
		(end 62.70625 -183.74868)
		(width 0.1143)
		(layer "In7.Cu")
		(net "UART_T2_NODE2_RXD")
	)
	(segment
		(start 70.128384 -176.40681)
		(end 67.75577 -178.779424)
		(width 0.1143)
		(layer "In7.Cu")
		(net "UART_T2_NODE2_RXD")
	)
	(segment
		(start 62.68847 -182.643526)
		(end 62.68847 -183.7309)
		(width 0.1143)
		(layer "In7.Cu")
		(net "UART_T2_NODE2_RXD")
	)
	(segment
		(start 73.49871 -171.124626)
		(end 71.45782 -173.165516)
		(width 0.1143)
		(layer "In7.Cu")
		(net "UART_T2_NODE2_RXD")
	)
	(segment
		(start 63.927736 -181.40426)
		(end 62.68847 -182.643526)
		(width 0.1143)
		(layer "In7.Cu")
		(net "UART_T2_NODE2_RXD")
	)
	(segment
		(start 70.1294 -176.23028)
		(end 70.1294 -176.40681)
		(width 0.1143)
		(layer "In7.Cu")
		(net "UART_T2_NODE2_RXD")
	)
	(segment
		(start 64.835024 -181.40426)
		(end 63.927736 -181.40426)
		(width 0.1143)
		(layer "In7.Cu")
		(net "UART_T2_NODE2_RXD")
	)
	(segment
		(start 70.1294 -176.40681)
		(end 70.128384 -176.40681)
		(width 0.1143)
		(layer "In7.Cu")
		(net "UART_T2_NODE2_RXD")
	)
	(segment
		(start 62.70625 -183.74868)
		(end 62.70625 -184.644284)
		(width 0.1143)
		(layer "In7.Cu")
		(net "UART_T2_NODE2_RXD")
	)
	(segment
		(start 67.45986 -178.779424)
		(end 65.19418 -181.045104)
		(width 0.1143)
		(layer "In7.Cu")
		(net "UART_T2_NODE2_RXD")
	)
	(segment
		(start 71.45782 -173.165516)
		(end 71.45782 -174.90186)
		(width 0.1143)
		(layer "In7.Cu")
		(net "UART_T2_NODE2_RXD")
	)
	(segment
		(start 61.96076 -185.389774)
		(end 61.96076 -187.048648)
		(width 0.1143)
		(layer "In7.Cu")
		(net "UART_T2_NODE2_RXD")
	)
	(segment
		(start 67.75577 -178.779424)
		(end 67.45986 -178.779424)
		(width 0.1143)
		(layer "In7.Cu")
		(net "UART_T2_NODE2_RXD")
	)
	(segment
		(start 63.68796 -184.289192)
		(end 63.171578 -184.805574)
		(width 0.1016)
		(layer "F.Cu")
		(net "UART_T2_NODE1_TXD")
	)
	(segment
		(start 66.95567 -183.18861)
		(end 64.2874 -183.18861)
		(width 0.1016)
		(layer "F.Cu")
		(net "UART_T2_NODE1_TXD")
	)
	(segment
		(start 74.6506 -177.915316)
		(end 73.67524 -178.890676)
		(width 0.1016)
		(layer "F.Cu")
		(net "UART_T2_NODE1_TXD")
	)
	(segment
		(start 73.468992 -172.852334)
		(end 73.468992 -173.524418)
		(width 0.1016)
		(layer "F.Cu")
		(net "UART_T2_NODE1_TXD")
	)
	(segment
		(start 73.241408 -172.624496)
		(end 73.468992 -172.85208)
		(width 0.1016)
		(layer "F.Cu")
		(net "UART_T2_NODE1_TXD")
	)
	(segment
		(start 74.6506 -174.706026)
		(end 74.6506 -177.915316)
		(width 0.1016)
		(layer "F.Cu")
		(net "UART_T2_NODE1_TXD")
	)
	(segment
		(start 73.67524 -179.41925)
		(end 71.532242 -181.562248)
		(width 0.1016)
		(layer "F.Cu")
		(net "UART_T2_NODE1_TXD")
	)
	(segment
		(start 73.468992 -173.524418)
		(end 74.6506 -174.706026)
		(width 0.1016)
		(layer "F.Cu")
		(net "UART_T2_NODE1_TXD")
	)
	(segment
		(start 63.171578 -184.805574)
		(end 63.10376 -184.805574)
		(width 0.1016)
		(layer "F.Cu")
		(net "UART_T2_NODE1_TXD")
	)
	(segment
		(start 73.67524 -178.890676)
		(end 73.67524 -179.41925)
		(width 0.1016)
		(layer "F.Cu")
		(net "UART_T2_NODE1_TXD")
	)
	(segment
		(start 71.532242 -181.562248)
		(end 68.582032 -181.562248)
		(width 0.1016)
		(layer "F.Cu")
		(net "UART_T2_NODE1_TXD")
	)
	(segment
		(start 64.2874 -183.18861)
		(end 63.68796 -183.78805)
		(width 0.1016)
		(layer "F.Cu")
		(net "UART_T2_NODE1_TXD")
	)
	(segment
		(start 73.468992 -172.85208)
		(end 73.468992 -172.852334)
		(width 0.1016)
		(layer "F.Cu")
		(net "UART_T2_NODE1_TXD")
	)
	(segment
		(start 63.68796 -183.78805)
		(end 63.68796 -184.289192)
		(width 0.1016)
		(layer "F.Cu")
		(net "UART_T2_NODE1_TXD")
	)
	(segment
		(start 72.244712 -172.624496)
		(end 73.241408 -172.624496)
		(width 0.1016)
		(layer "F.Cu")
		(net "UART_T2_NODE1_TXD")
	)
	(segment
		(start 68.582032 -181.562248)
		(end 66.95567 -183.18861)
		(width 0.1016)
		(layer "F.Cu")
		(net "UART_T2_NODE1_TXD")
	)
	(via
		(at 73.468992 -172.852334)
		(size 0.508)
		(drill 0.254)
		(layers "F.Cu" "B.Cu")
		(net "UART_T2_NODE1_TXD")
	)
	(segment
		(start 57.38876 -185.605674)
		(end 57.82056 -186.037474)
		(width 0.1016)
		(layer "F.Cu")
		(net "UART_T2_NODE4_RXD")
	)
	(segment
		(start 57.66816 -186.687968)
		(end 57.66816 -186.775598)
		(width 0.1016)
		(layer "F.Cu")
		(net "UART_T2_NODE4_RXD")
	)
	(segment
		(start 57.66816 -186.775598)
		(end 57.38876 -187.054998)
		(width 0.1016)
		(layer "F.Cu")
		(net "UART_T2_NODE4_RXD")
	)
	(segment
		(start 57.82056 -186.037474)
		(end 57.82056 -186.535568)
		(width 0.1016)
		(layer "F.Cu")
		(net "UART_T2_NODE4_RXD")
	)
	(segment
		(start 67.479164 -168.849294)
		(end 66.52006 -168.849294)
		(width 0.1016)
		(layer "F.Cu")
		(net "UART_T2_NODE4_RXD")
	)
	(segment
		(start 57.82056 -186.535568)
		(end 57.66816 -186.687968)
		(width 0.1016)
		(layer "F.Cu")
		(net "UART_T2_NODE4_RXD")
	)
	(segment
		(start 72.244712 -167.124634)
		(end 71.02475 -167.124634)
		(width 0.1016)
		(layer "F.Cu")
		(net "UART_T2_NODE4_RXD")
	)
	(segment
		(start 70.96887 -167.180514)
		(end 69.147944 -167.180514)
		(width 0.1016)
		(layer "F.Cu")
		(net "UART_T2_NODE4_RXD")
	)
	(segment
		(start 69.147944 -167.180514)
		(end 67.479164 -168.849294)
		(width 0.1016)
		(layer "F.Cu")
		(net "UART_T2_NODE4_RXD")
	)
	(segment
		(start 71.02475 -167.124634)
		(end 70.96887 -167.180514)
		(width 0.1016)
		(layer "F.Cu")
		(net "UART_T2_NODE4_RXD")
	)
	(segment
		(start 57.38876 -187.054998)
		(end 57.38876 -187.726574)
		(width 0.1016)
		(layer "F.Cu")
		(net "UART_T2_NODE4_RXD")
	)
	(via
		(at 66.52006 -168.849294)
		(size 0.508)
		(drill 0.254)
		(layers "F.Cu" "B.Cu")
		(net "UART_T2_NODE4_RXD")
	)
	(via
		(at 57.38876 -187.054998)
		(size 0.508)
		(drill 0.254)
		(layers "F.Cu" "B.Cu")
		(net "UART_T2_NODE4_RXD")
	)
	(segment
		(start 63.7286 -177.95367)
		(end 64.353948 -177.95367)
		(width 0.1143)
		(layer "In7.Cu")
		(net "UART_T2_NODE4_RXD")
	)
	(segment
		(start 56.95061 -186.616848)
		(end 56.95061 -186.159648)
		(width 0.1143)
		(layer "In7.Cu")
		(net "UART_T2_NODE4_RXD")
	)
	(segment
		(start 60.978542 -181.150514)
		(end 60.978542 -180.703728)
		(width 0.1143)
		(layer "In7.Cu")
		(net "UART_T2_NODE4_RXD")
	)
	(segment
		(start 58.97118 -183.157876)
		(end 60.978542 -181.150514)
		(width 0.1143)
		(layer "In7.Cu")
		(net "UART_T2_NODE4_RXD")
	)
	(segment
		(start 58.97118 -184.139078)
		(end 58.97118 -183.157876)
		(width 0.1143)
		(layer "In7.Cu")
		(net "UART_T2_NODE4_RXD")
	)
	(segment
		(start 57.38876 -187.054998)
		(end 56.95061 -186.616848)
		(width 0.1143)
		(layer "In7.Cu")
		(net "UART_T2_NODE4_RXD")
	)
	(segment
		(start 60.978542 -180.703728)
		(end 63.7286 -177.95367)
		(width 0.1143)
		(layer "In7.Cu")
		(net "UART_T2_NODE4_RXD")
	)
	(segment
		(start 69.09562 -170.467782)
		(end 67.477132 -168.849294)
		(width 0.1143)
		(layer "In7.Cu")
		(net "UART_T2_NODE4_RXD")
	)
	(segment
		(start 67.477132 -168.849294)
		(end 66.52006 -168.849294)
		(width 0.1143)
		(layer "In7.Cu")
		(net "UART_T2_NODE4_RXD")
	)
	(segment
		(start 56.95061 -186.159648)
		(end 58.97118 -184.139078)
		(width 0.1143)
		(layer "In7.Cu")
		(net "UART_T2_NODE4_RXD")
	)
	(segment
		(start 64.353948 -177.95367)
		(end 69.09562 -173.211998)
		(width 0.1143)
		(layer "In7.Cu")
		(net "UART_T2_NODE4_RXD")
	)
	(segment
		(start 69.09562 -173.211998)
		(end 69.09562 -170.467782)
		(width 0.1143)
		(layer "In7.Cu")
		(net "UART_T2_NODE4_RXD")
	)
	(segment
		(start 72.244712 -173.124622)
		(end 70.03034 -173.124622)
		(width 0.1016)
		(layer "F.Cu")
		(net "UART_T1_NODE4_RXD")
	)
	(via
		(at 70.03034 -173.124622)
		(size 0.508)
		(drill 0.254)
		(layers "F.Cu" "B.Cu")
		(net "UART_T1_NODE4_RXD")
	)
	(via
		(at 57.38876 -186.352434)
		(size 0.508)
		(drill 0.254)
		(layers "F.Cu" "B.Cu")
		(net "UART_T1_NODE4_RXD")
	)
	(segment
		(start 57.38876 -187.726574)
		(end 56.8833 -187.221114)
		(width 0.1016)
		(layer "B.Cu")
		(net "UART_T1_NODE4_RXD")
	)
	(segment
		(start 57.38876 -186.352434)
		(end 57.38876 -185.605674)
		(width 0.1016)
		(layer "B.Cu")
		(net "UART_T1_NODE4_RXD")
	)
	(segment
		(start 56.8833 -187.221114)
		(end 56.8833 -186.857894)
		(width 0.1016)
		(layer "B.Cu")
		(net "UART_T1_NODE4_RXD")
	)
	(segment
		(start 56.8833 -186.857894)
		(end 57.38876 -186.352434)
		(width 0.1016)
		(layer "B.Cu")
		(net "UART_T1_NODE4_RXD")
	)
	(segment
		(start 60.57773 -182.45201)
		(end 60.32119 -182.70855)
		(width 0.1143)
		(layer "In7.Cu")
		(net "UART_T1_NODE4_RXD")
	)
	(segment
		(start 70.03034 -173.124622)
		(end 70.03034 -173.164754)
		(width 0.1143)
		(layer "In7.Cu")
		(net "UART_T1_NODE4_RXD")
	)
	(segment
		(start 59.85637 -184.4167)
		(end 59.324494 -184.4167)
		(width 0.1143)
		(layer "In7.Cu")
		(net "UART_T1_NODE4_RXD")
	)
	(segment
		(start 60.32119 -183.95188)
		(end 59.85637 -184.4167)
		(width 0.1143)
		(layer "In7.Cu")
		(net "UART_T1_NODE4_RXD")
	)
	(segment
		(start 59.324494 -184.4167)
		(end 57.38876 -186.352434)
		(width 0.1143)
		(layer "In7.Cu")
		(net "UART_T1_NODE4_RXD")
	)
	(segment
		(start 60.743084 -182.45201)
		(end 60.57773 -182.45201)
		(width 0.1143)
		(layer "In7.Cu")
		(net "UART_T1_NODE4_RXD")
	)
	(segment
		(start 60.32119 -182.70855)
		(end 60.32119 -183.95188)
		(width 0.1143)
		(layer "In7.Cu")
		(net "UART_T1_NODE4_RXD")
	)
	(segment
		(start 70.03034 -173.164754)
		(end 60.743084 -182.45201)
		(width 0.1143)
		(layer "In7.Cu")
		(net "UART_T1_NODE4_RXD")
	)
	(segment
		(start 72.244712 -173.624748)
		(end 68.14312 -173.624748)
		(width 0.1016)
		(layer "F.Cu")
		(net "UART_T1_NODE4_TXD")
	)
	(segment
		(start 68.14312 -173.624748)
		(end 67.87896 -173.360588)
		(width 0.1016)
		(layer "F.Cu")
		(net "UART_T1_NODE4_TXD")
	)
	(segment
		(start 67.87896 -173.360588)
		(end 67.87896 -173.359826)
		(width 0.1016)
		(layer "F.Cu")
		(net "UART_T1_NODE4_TXD")
	)
	(via
		(at 57.8231 -183.080914)
		(size 0.508)
		(drill 0.254)
		(layers "F.Cu" "B.Cu")
		(net "UART_T1_NODE4_TXD")
	)
	(via
		(at 67.87896 -173.359826)
		(size 0.508)
		(drill 0.254)
		(layers "F.Cu" "B.Cu")
		(net "UART_T1_NODE4_TXD")
	)
	(segment
		(start 56.24576 -184.096406)
		(end 56.881776 -183.46039)
		(width 0.1016)
		(layer "B.Cu")
		(net "UART_T1_NODE4_TXD")
	)
	(segment
		(start 56.881776 -183.46039)
		(end 57.047384 -183.46039)
		(width 0.1016)
		(layer "B.Cu")
		(net "UART_T1_NODE4_TXD")
	)
	(segment
		(start 57.15508 -183.352694)
		(end 57.552336 -183.352694)
		(width 0.1016)
		(layer "B.Cu")
		(net "UART_T1_NODE4_TXD")
	)
	(segment
		(start 56.24576 -184.805574)
		(end 56.24576 -184.096406)
		(width 0.1016)
		(layer "B.Cu")
		(net "UART_T1_NODE4_TXD")
	)
	(segment
		(start 57.8231 -183.08193)
		(end 57.8231 -183.080914)
		(width 0.1016)
		(layer "B.Cu")
		(net "UART_T1_NODE4_TXD")
	)
	(segment
		(start 57.047384 -183.46039)
		(end 57.15508 -183.352694)
		(width 0.1016)
		(layer "B.Cu")
		(net "UART_T1_NODE4_TXD")
	)
	(segment
		(start 57.552336 -183.352694)
		(end 57.8231 -183.08193)
		(width 0.1016)
		(layer "B.Cu")
		(net "UART_T1_NODE4_TXD")
	)
	(segment
		(start 57.8231 -183.080914)
		(end 57.8231 -182.130954)
		(width 0.1143)
		(layer "In7.Cu")
		(net "UART_T1_NODE4_TXD")
	)
	(segment
		(start 67.483482 -173.359826)
		(end 67.87896 -173.359826)
		(width 0.1143)
		(layer "In7.Cu")
		(net "UART_T1_NODE4_TXD")
	)
	(segment
		(start 63.65748 -176.296828)
		(end 64.54648 -176.296828)
		(width 0.1143)
		(layer "In7.Cu")
		(net "UART_T1_NODE4_TXD")
	)
	(segment
		(start 64.54648 -176.296828)
		(end 67.483482 -173.359826)
		(width 0.1143)
		(layer "In7.Cu")
		(net "UART_T1_NODE4_TXD")
	)
	(segment
		(start 57.8231 -182.130954)
		(end 63.65748 -176.296828)
		(width 0.1143)
		(layer "In7.Cu")
		(net "UART_T1_NODE4_TXD")
	)
	(segment
		(start 165.217602 -179.402486)
		(end 166.52494 -179.402486)
		(width 0.1016)
		(layer "F.Cu")
		(net "CPLD_UART_TX_P3")
	)
	(segment
		(start 146.046952 -177.108612)
		(end 146.618706 -177.680366)
		(width 0.1016)
		(layer "F.Cu")
		(net "CPLD_UART_TX_P3")
	)
	(segment
		(start 149.656292 -177.680366)
		(end 150.61184 -178.635914)
		(width 0.1016)
		(layer "F.Cu")
		(net "CPLD_UART_TX_P3")
	)
	(segment
		(start 146.618706 -177.680366)
		(end 149.656292 -177.680366)
		(width 0.1016)
		(layer "F.Cu")
		(net "CPLD_UART_TX_P3")
	)
	(segment
		(start 145.275808 -177.108612)
		(end 146.046952 -177.108612)
		(width 0.1016)
		(layer "F.Cu")
		(net "CPLD_UART_TX_P3")
	)
	(via
		(at 150.61184 -178.635914)
		(size 0.508)
		(drill 0.254)
		(layers "F.Cu" "B.Cu")
		(net "CPLD_UART_TX_P3")
	)
	(via
		(at 166.52494 -179.402486)
		(size 0.508)
		(drill 0.254)
		(layers "F.Cu" "B.Cu")
		(net "CPLD_UART_TX_P3")
	)
	(segment
		(start 165.535864 -179.402486)
		(end 164.389308 -178.25593)
		(width 0.1143)
		(layer "In2.Cu")
		(net "CPLD_UART_TX_P3")
	)
	(segment
		(start 166.52494 -179.402486)
		(end 165.535864 -179.402486)
		(width 0.1143)
		(layer "In2.Cu")
		(net "CPLD_UART_TX_P3")
	)
	(segment
		(start 150.977092 -178.635914)
		(end 150.61184 -178.635914)
		(width 0.1143)
		(layer "In2.Cu")
		(net "CPLD_UART_TX_P3")
	)
	(segment
		(start 164.389308 -178.25593)
		(end 151.357076 -178.25593)
		(width 0.1143)
		(layer "In2.Cu")
		(net "CPLD_UART_TX_P3")
	)
	(segment
		(start 151.357076 -178.25593)
		(end 150.977092 -178.635914)
		(width 0.1143)
		(layer "In2.Cu")
		(net "CPLD_UART_TX_P3")
	)
	(segment
		(start 155.50642 -178.753008)
		(end 155.50642 -178.365658)
		(width 0.1016)
		(layer "F.Cu")
		(net "CPLD_UART_RX_P3")
	)
	(segment
		(start 155.429966 -178.289204)
		(end 154.983688 -178.289204)
		(width 0.1016)
		(layer "F.Cu")
		(net "CPLD_UART_RX_P3")
	)
	(segment
		(start 146.53768 -176.85512)
		(end 148.435314 -176.85512)
		(width 0.1016)
		(layer "F.Cu")
		(net "CPLD_UART_RX_P3")
	)
	(segment
		(start 148.435314 -176.85512)
		(end 148.6916 -177.111406)
		(width 0.1016)
		(layer "F.Cu")
		(net "CPLD_UART_RX_P3")
	)
	(segment
		(start 146.2913 -176.60874)
		(end 146.53768 -176.85512)
		(width 0.1016)
		(layer "F.Cu")
		(net "CPLD_UART_RX_P3")
	)
	(segment
		(start 145.275808 -176.60874)
		(end 146.2913 -176.60874)
		(width 0.1016)
		(layer "F.Cu")
		(net "CPLD_UART_RX_P3")
	)
	(segment
		(start 155.50642 -178.365658)
		(end 155.429966 -178.289204)
		(width 0.1016)
		(layer "F.Cu")
		(net "CPLD_UART_RX_P3")
	)
	(segment
		(start 154.983688 -178.289204)
		(end 154.386026 -178.289204)
		(width 0.1016)
		(layer "F.Cu")
		(net "CPLD_UART_RX_P3")
	)
	(segment
		(start 155.842716 -179.089304)
		(end 155.50642 -178.753008)
		(width 0.1016)
		(layer "F.Cu")
		(net "CPLD_UART_RX_P3")
	)
	(segment
		(start 155.999688 -179.089304)
		(end 155.842716 -179.089304)
		(width 0.1016)
		(layer "F.Cu")
		(net "CPLD_UART_RX_P3")
	)
	(segment
		(start 154.27452 -178.177698)
		(end 154.27452 -177.716434)
		(width 0.1016)
		(layer "F.Cu")
		(net "CPLD_UART_RX_P3")
	)
	(segment
		(start 154.386026 -178.289204)
		(end 154.27452 -178.177698)
		(width 0.1016)
		(layer "F.Cu")
		(net "CPLD_UART_RX_P3")
	)
	(via
		(at 148.6916 -177.111406)
		(size 0.508)
		(drill 0.254)
		(layers "F.Cu" "B.Cu")
		(net "CPLD_UART_RX_P3")
	)
	(via
		(at 154.27452 -177.716434)
		(size 0.508)
		(drill 0.254)
		(layers "F.Cu" "B.Cu")
		(net "CPLD_UART_RX_P3")
	)
	(segment
		(start 153.218388 -177.111406)
		(end 153.770076 -177.663094)
		(width 0.1143)
		(layer "In2.Cu")
		(net "CPLD_UART_RX_P3")
	)
	(segment
		(start 148.6916 -177.111406)
		(end 153.218388 -177.111406)
		(width 0.1143)
		(layer "In2.Cu")
		(net "CPLD_UART_RX_P3")
	)
	(segment
		(start 154.22118 -177.663094)
		(end 154.27452 -177.716434)
		(width 0.1143)
		(layer "In2.Cu")
		(net "CPLD_UART_RX_P3")
	)
	(segment
		(start 153.770076 -177.663094)
		(end 154.22118 -177.663094)
		(width 0.1143)
		(layer "In2.Cu")
		(net "CPLD_UART_RX_P3")
	)
	(segment
		(start 64.66967 -182.27421)
		(end 66.452242 -182.27421)
		(width 0.1016)
		(layer "F.Cu")
		(net "UART_T1_NODE1_RXD")
	)
	(segment
		(start 56.270398 -182.287418)
		(end 60.984892 -182.287418)
		(width 0.1016)
		(layer "F.Cu")
		(net "UART_T1_NODE1_RXD")
	)
	(segment
		(start 66.452242 -182.27421)
		(end 71.101712 -177.62474)
		(width 0.1016)
		(layer "F.Cu")
		(net "UART_T1_NODE1_RXD")
	)
	(segment
		(start 61.711332 -181.560978)
		(end 63.956438 -181.560978)
		(width 0.1016)
		(layer "F.Cu")
		(net "UART_T1_NODE1_RXD")
	)
	(segment
		(start 55.07228 -183.485536)
		(end 56.270398 -182.287418)
		(width 0.1016)
		(layer "F.Cu")
		(net "UART_T1_NODE1_RXD")
	)
	(segment
		(start 63.956438 -181.560978)
		(end 64.66967 -182.27421)
		(width 0.1016)
		(layer "F.Cu")
		(net "UART_T1_NODE1_RXD")
	)
	(segment
		(start 71.101712 -177.62474)
		(end 72.244712 -177.62474)
		(width 0.1016)
		(layer "F.Cu")
		(net "UART_T1_NODE1_RXD")
	)
	(segment
		(start 55.07228 -183.718454)
		(end 55.07228 -183.485536)
		(width 0.1016)
		(layer "F.Cu")
		(net "UART_T1_NODE1_RXD")
	)
	(segment
		(start 60.984892 -182.287418)
		(end 61.711332 -181.560978)
		(width 0.1016)
		(layer "F.Cu")
		(net "UART_T1_NODE1_RXD")
	)
	(via
		(at 55.07228 -183.718454)
		(size 0.508)
		(drill 0.254)
		(layers "F.Cu" "B.Cu")
		(net "UART_T1_NODE1_RXD")
	)
	(segment
		(start 55.07228 -183.718454)
		(end 55.10276 -183.748934)
		(width 0.1016)
		(layer "B.Cu")
		(net "UART_T1_NODE1_RXD")
	)
	(segment
		(start 54.53126 -187.155074)
		(end 54.53126 -185.377074)
		(width 0.1016)
		(layer "B.Cu")
		(net "UART_T1_NODE1_RXD")
	)
	(segment
		(start 55.10276 -183.748934)
		(end 55.10276 -184.805574)
		(width 0.1016)
		(layer "B.Cu")
		(net "UART_T1_NODE1_RXD")
	)
	(segment
		(start 54.53126 -185.377074)
		(end 55.10276 -184.805574)
		(width 0.1016)
		(layer "B.Cu")
		(net "UART_T1_NODE1_RXD")
	)
	(segment
		(start 55.10276 -187.726574)
		(end 54.53126 -187.155074)
		(width 0.1016)
		(layer "B.Cu")
		(net "UART_T1_NODE1_RXD")
	)
	(segment
		(start 165.411404 -184.335674)
		(end 165.411404 -184.067196)
		(width 0.1016)
		(layer "F.Cu")
		(net "CPLD_UART_DTR_P3_N")
	)
	(segment
		(start 164.611304 -184.855358)
		(end 164.865304 -184.601358)
		(width 0.1016)
		(layer "F.Cu")
		(net "CPLD_UART_DTR_P3_N")
	)
	(segment
		(start 164.05606 -183.343804)
		(end 164.05606 -182.8927)
		(width 0.1016)
		(layer "F.Cu")
		(net "CPLD_UART_DTR_P3_N")
	)
	(segment
		(start 165.411404 -184.067196)
		(end 165.411404 -183.782462)
		(width 0.1016)
		(layer "F.Cu")
		(net "CPLD_UART_DTR_P3_N")
	)
	(segment
		(start 143.525748 -180.004466)
		(end 143.525748 -178.858672)
		(width 0.1016)
		(layer "F.Cu")
		(net "CPLD_UART_DTR_P3_N")
	)
	(segment
		(start 165.14572 -184.601358)
		(end 165.411404 -184.335674)
		(width 0.1016)
		(layer "F.Cu")
		(net "CPLD_UART_DTR_P3_N")
	)
	(segment
		(start 164.05606 -182.8927)
		(end 163.8173 -182.65394)
		(width 0.1016)
		(layer "F.Cu")
		(net "CPLD_UART_DTR_P3_N")
	)
	(segment
		(start 165.411404 -183.782462)
		(end 165.198806 -183.569864)
		(width 0.1016)
		(layer "F.Cu")
		(net "CPLD_UART_DTR_P3_N")
	)
	(segment
		(start 143.528796 -180.007514)
		(end 143.525748 -180.004466)
		(width 0.1016)
		(layer "F.Cu")
		(net "CPLD_UART_DTR_P3_N")
	)
	(segment
		(start 143.528796 -181.106572)
		(end 143.528796 -180.007514)
		(width 0.1016)
		(layer "F.Cu")
		(net "CPLD_UART_DTR_P3_N")
	)
	(segment
		(start 164.865304 -184.601358)
		(end 165.14572 -184.601358)
		(width 0.1016)
		(layer "F.Cu")
		(net "CPLD_UART_DTR_P3_N")
	)
	(segment
		(start 164.611304 -185.083196)
		(end 164.611304 -184.855358)
		(width 0.1016)
		(layer "F.Cu")
		(net "CPLD_UART_DTR_P3_N")
	)
	(segment
		(start 164.28212 -183.569864)
		(end 164.05606 -183.343804)
		(width 0.1016)
		(layer "F.Cu")
		(net "CPLD_UART_DTR_P3_N")
	)
	(segment
		(start 165.198806 -183.569864)
		(end 164.28212 -183.569864)
		(width 0.1016)
		(layer "F.Cu")
		(net "CPLD_UART_DTR_P3_N")
	)
	(via
		(at 163.8173 -182.65394)
		(size 0.508)
		(drill 0.254)
		(layers "F.Cu" "B.Cu")
		(net "CPLD_UART_DTR_P3_N")
	)
	(via
		(at 143.525748 -180.004466)
		(size 0.508)
		(drill 0.254)
		(layers "F.Cu" "B.Cu")
		(net "CPLD_UART_DTR_P3_N")
	)
	(segment
		(start 155.584398 -181.969664)
		(end 153.844752 -181.969664)
		(width 0.1143)
		(layer "In6.Cu")
		(net "CPLD_UART_DTR_P3_N")
	)
	(segment
		(start 155.70581 -181.848252)
		(end 155.584398 -181.969664)
		(width 0.1143)
		(layer "In6.Cu")
		(net "CPLD_UART_DTR_P3_N")
	)
	(segment
		(start 147.49526 -181.328314)
		(end 146.171412 -180.004466)
		(width 0.1143)
		(layer "In6.Cu")
		(net "CPLD_UART_DTR_P3_N")
	)
	(segment
		(start 149.717506 -181.188868)
		(end 149.57806 -181.328314)
		(width 0.1143)
		(layer "In6.Cu")
		(net "CPLD_UART_DTR_P3_N")
	)
	(segment
		(start 157.50921 -182.687214)
		(end 156.670248 -181.848252)
		(width 0.1143)
		(layer "In6.Cu")
		(net "CPLD_UART_DTR_P3_N")
	)
	(segment
		(start 163.784026 -182.687214)
		(end 157.50921 -182.687214)
		(width 0.1143)
		(layer "In6.Cu")
		(net "CPLD_UART_DTR_P3_N")
	)
	(segment
		(start 156.670248 -181.848252)
		(end 155.70581 -181.848252)
		(width 0.1143)
		(layer "In6.Cu")
		(net "CPLD_UART_DTR_P3_N")
	)
	(segment
		(start 149.57806 -181.328314)
		(end 147.49526 -181.328314)
		(width 0.1143)
		(layer "In6.Cu")
		(net "CPLD_UART_DTR_P3_N")
	)
	(segment
		(start 163.8173 -182.65394)
		(end 163.784026 -182.687214)
		(width 0.1143)
		(layer "In6.Cu")
		(net "CPLD_UART_DTR_P3_N")
	)
	(segment
		(start 153.844752 -181.969664)
		(end 153.063956 -181.188868)
		(width 0.1143)
		(layer "In6.Cu")
		(net "CPLD_UART_DTR_P3_N")
	)
	(segment
		(start 153.063956 -181.188868)
		(end 149.717506 -181.188868)
		(width 0.1143)
		(layer "In6.Cu")
		(net "CPLD_UART_DTR_P3_N")
	)
	(segment
		(start 146.171412 -180.004466)
		(end 143.525748 -180.004466)
		(width 0.1143)
		(layer "In6.Cu")
		(net "CPLD_UART_DTR_P3_N")
	)
	(segment
		(start 71.5899 -179.093622)
		(end 70.70598 -179.093622)
		(width 0.1016)
		(layer "F.Cu")
		(net "UART_T1_NODE1_TXD")
	)
	(segment
		(start 72.244712 -178.124612)
		(end 72.244712 -178.43881)
		(width 0.1016)
		(layer "F.Cu")
		(net "UART_T1_NODE1_TXD")
	)
	(segment
		(start 72.244712 -178.43881)
		(end 71.5899 -179.093622)
		(width 0.1016)
		(layer "F.Cu")
		(net "UART_T1_NODE1_TXD")
	)
	(via
		(at 70.70598 -179.093622)
		(size 0.508)
		(drill 0.254)
		(layers "F.Cu" "B.Cu")
		(net "UART_T1_NODE1_TXD")
	)
	(via
		(at 63.66002 -182.742078)
		(size 0.508)
		(drill 0.254)
		(layers "F.Cu" "B.Cu")
		(net "UART_T1_NODE1_TXD")
	)
	(segment
		(start 63.68796 -182.742078)
		(end 63.66002 -182.742078)
		(width 0.1016)
		(layer "B.Cu")
		(net "UART_T1_NODE1_TXD")
	)
	(segment
		(start 57.218834 -182.348124)
		(end 57.218834 -182.346346)
		(width 0.1016)
		(layer "B.Cu")
		(net "UART_T1_NODE1_TXD")
	)
	(segment
		(start 57.218834 -182.346346)
		(end 57.300114 -182.265066)
		(width 0.1016)
		(layer "B.Cu")
		(net "UART_T1_NODE1_TXD")
	)
	(segment
		(start 57.300114 -182.265066)
		(end 63.237364 -182.265066)
		(width 0.1016)
		(layer "B.Cu")
		(net "UART_T1_NODE1_TXD")
	)
	(segment
		(start 63.68796 -182.715662)
		(end 63.68796 -182.742078)
		(width 0.1016)
		(layer "B.Cu")
		(net "UART_T1_NODE1_TXD")
	)
	(segment
		(start 63.237364 -182.265066)
		(end 63.68796 -182.715662)
		(width 0.1016)
		(layer "B.Cu")
		(net "UART_T1_NODE1_TXD")
	)
	(segment
		(start 54.36616 -183.66105)
		(end 55.679086 -182.348124)
		(width 0.1016)
		(layer "B.Cu")
		(net "UART_T1_NODE1_TXD")
	)
	(segment
		(start 54.36616 -184.38876)
		(end 54.36616 -183.66105)
		(width 0.1016)
		(layer "B.Cu")
		(net "UART_T1_NODE1_TXD")
	)
	(segment
		(start 55.679086 -182.348124)
		(end 57.218834 -182.348124)
		(width 0.1016)
		(layer "B.Cu")
		(net "UART_T1_NODE1_TXD")
	)
	(segment
		(start 53.95976 -184.79516)
		(end 54.36616 -184.38876)
		(width 0.1016)
		(layer "B.Cu")
		(net "UART_T1_NODE1_TXD")
	)
	(segment
		(start 53.95976 -184.805574)
		(end 53.95976 -184.79516)
		(width 0.1016)
		(layer "B.Cu")
		(net "UART_T1_NODE1_TXD")
	)
	(segment
		(start 66.526918 -182.742078)
		(end 70.175374 -179.093622)
		(width 0.1143)
		(layer "In7.Cu")
		(net "UART_T1_NODE1_TXD")
	)
	(segment
		(start 70.175374 -179.093622)
		(end 70.70598 -179.093622)
		(width 0.1143)
		(layer "In7.Cu")
		(net "UART_T1_NODE1_TXD")
	)
	(segment
		(start 63.66002 -182.742078)
		(end 66.526918 -182.742078)
		(width 0.1143)
		(layer "In7.Cu")
		(net "UART_T1_NODE1_TXD")
	)
	(segment
		(start 149.8092 -174.512986)
		(end 149.8092 -175.322484)
		(width 0.1016)
		(layer "F.Cu")
		(net "CPLD_UART_RI_P3_N")
	)
	(segment
		(start 145.275808 -176.108614)
		(end 146.23415 -176.108614)
		(width 0.1016)
		(layer "F.Cu")
		(net "CPLD_UART_RI_P3_N")
	)
	(segment
		(start 148.167598 -175.798734)
		(end 147.67179 -176.294542)
		(width 0.1016)
		(layer "F.Cu")
		(net "CPLD_UART_RI_P3_N")
	)
	(segment
		(start 146.23415 -176.108614)
		(end 146.42084 -176.295304)
		(width 0.1016)
		(layer "F.Cu")
		(net "CPLD_UART_RI_P3_N")
	)
	(segment
		(start 149.356064 -175.77562)
		(end 148.190458 -175.77562)
		(width 0.1016)
		(layer "F.Cu")
		(net "CPLD_UART_RI_P3_N")
	)
	(segment
		(start 123.62307 -54.617874)
		(end 123.740672 -54.500272)
		(width 0.1016)
		(layer "F.Cu")
		(net "CPLD_UART_RI_P3_N")
	)
	(segment
		(start 122.583702 -55.482236)
		(end 122.583702 -54.971442)
		(width 0.1016)
		(layer "F.Cu")
		(net "CPLD_UART_RI_P3_N")
	)
	(segment
		(start 122.583702 -56.227218)
		(end 122.583702 -55.482236)
		(width 0.1016)
		(layer "F.Cu")
		(net "CPLD_UART_RI_P3_N")
	)
	(segment
		(start 149.733 -175.398684)
		(end 149.356064 -175.77562)
		(width 0.1016)
		(layer "F.Cu")
		(net "CPLD_UART_RI_P3_N")
	)
	(segment
		(start 147.67179 -176.29632)
		(end 147.67179 -176.295304)
		(width 0.1016)
		(layer "F.Cu")
		(net "CPLD_UART_RI_P3_N")
	)
	(segment
		(start 122.583702 -54.971442)
		(end 122.93727 -54.617874)
		(width 0.1016)
		(layer "F.Cu")
		(net "CPLD_UART_RI_P3_N")
	)
	(segment
		(start 147.67179 -176.294542)
		(end 147.67179 -176.295304)
		(width 0.1016)
		(layer "F.Cu")
		(net "CPLD_UART_RI_P3_N")
	)
	(segment
		(start 146.42084 -176.295304)
		(end 147.67179 -176.295304)
		(width 0.1016)
		(layer "F.Cu")
		(net "CPLD_UART_RI_P3_N")
	)
	(segment
		(start 149.8092 -175.322484)
		(end 149.733 -175.398684)
		(width 0.1016)
		(layer "F.Cu")
		(net "CPLD_UART_RI_P3_N")
	)
	(segment
		(start 123.187968 -56.831484)
		(end 122.583702 -56.227218)
		(width 0.1016)
		(layer "F.Cu")
		(net "CPLD_UART_RI_P3_N")
	)
	(segment
		(start 122.93727 -54.617874)
		(end 123.62307 -54.617874)
		(width 0.1016)
		(layer "F.Cu")
		(net "CPLD_UART_RI_P3_N")
	)
	(segment
		(start 148.190458 -175.77562)
		(end 148.167598 -175.798734)
		(width 0.1016)
		(layer "F.Cu")
		(net "CPLD_UART_RI_P3_N")
	)
	(via
		(at 123.740672 -54.500272)
		(size 0.508)
		(drill 0.254)
		(layers "F.Cu" "B.Cu")
		(net "CPLD_UART_RI_P3_N")
	)
	(via
		(at 162.3949 -63.531242)
		(size 0.508)
		(drill 0.254)
		(layers "F.Cu" "B.Cu")
		(net "CPLD_UART_RI_P3_N")
	)
	(via
		(at 178.24958 -84.312252)
		(size 0.508)
		(drill 0.254)
		(layers "F.Cu" "B.Cu")
		(net "CPLD_UART_RI_P3_N")
	)
	(via
		(at 162.54476 -174.711614)
		(size 0.508)
		(drill 0.254)
		(layers "F.Cu" "B.Cu")
		(net "CPLD_UART_RI_P3_N")
	)
	(via
		(at 149.733 -175.398684)
		(size 0.508)
		(drill 0.254)
		(layers "F.Cu" "B.Cu")
		(net "CPLD_UART_RI_P3_N")
	)
	(segment
		(start 162.565334 -166.023798)
		(end 161.782252 -166.023798)
		(width 0.1016)
		(layer "B.Cu")
		(net "CPLD_UART_RI_P3_N")
	)
	(segment
		(start 164.021008 -167.749474)
		(end 164.021008 -167.479472)
		(width 0.1016)
		(layer "B.Cu")
		(net "CPLD_UART_RI_P3_N")
	)
	(segment
		(start 161.782252 -166.023798)
		(end 161.782252 -173.949106)
		(width 0.1016)
		(layer "B.Cu")
		(net "CPLD_UART_RI_P3_N")
	)
	(segment
		(start 164.021008 -167.479472)
		(end 162.565334 -166.023798)
		(width 0.1016)
		(layer "B.Cu")
		(net "CPLD_UART_RI_P3_N")
	)
	(segment
		(start 161.782252 -173.949106)
		(end 162.54476 -174.711614)
		(width 0.1016)
		(layer "B.Cu")
		(net "CPLD_UART_RI_P3_N")
	)
	(segment
		(start 152.871932 -176.065942)
		(end 152.75814 -176.179734)
		(width 0.1143)
		(layer "In2.Cu")
		(net "CPLD_UART_RI_P3_N")
	)
	(segment
		(start 157.148276 -176.065942)
		(end 152.871932 -176.065942)
		(width 0.1143)
		(layer "In2.Cu")
		(net "CPLD_UART_RI_P3_N")
	)
	(segment
		(start 161.462466 -175.793908)
		(end 157.42031 -175.793908)
		(width 0.1143)
		(layer "In2.Cu")
		(net "CPLD_UART_RI_P3_N")
	)
	(segment
		(start 152.75814 -176.179734)
		(end 150.51405 -176.179734)
		(width 0.1143)
		(layer "In2.Cu")
		(net "CPLD_UART_RI_P3_N")
	)
	(segment
		(start 193.421 -138.811)
		(end 193.421 -119.126)
		(width 0.1143)
		(layer "In2.Cu")
		(net "CPLD_UART_RI_P3_N")
	)
	(segment
		(start 172.029882 -164.615622)
		(end 182.194962 -164.615622)
		(width 0.1143)
		(layer "In2.Cu")
		(net "CPLD_UART_RI_P3_N")
	)
	(segment
		(start 193.421 -119.126)
		(end 193.167 -118.872)
		(width 0.1143)
		(layer "In2.Cu")
		(net "CPLD_UART_RI_P3_N")
	)
	(segment
		(start 170.314366 -166.331138)
		(end 172.029882 -164.615622)
		(width 0.1143)
		(layer "In2.Cu")
		(net "CPLD_UART_RI_P3_N")
	)
	(segment
		(start 162.54476 -174.711614)
		(end 163.418266 -174.711614)
		(width 0.1143)
		(layer "In2.Cu")
		(net "CPLD_UART_RI_P3_N")
	)
	(segment
		(start 150.51405 -176.179734)
		(end 149.733 -175.398684)
		(width 0.1143)
		(layer "In2.Cu")
		(net "CPLD_UART_RI_P3_N")
	)
	(segment
		(start 178.769518 -84.312252)
		(end 178.24958 -84.312252)
		(width 0.1143)
		(layer "In2.Cu")
		(net "CPLD_UART_RI_P3_N")
	)
	(segment
		(start 193.167 -153.643584)
		(end 193.167 -139.065)
		(width 0.1143)
		(layer "In2.Cu")
		(net "CPLD_UART_RI_P3_N")
	)
	(segment
		(start 193.167 -118.872)
		(end 193.167 -98.709734)
		(width 0.1143)
		(layer "In2.Cu")
		(net "CPLD_UART_RI_P3_N")
	)
	(segment
		(start 157.42031 -175.793908)
		(end 157.148276 -176.065942)
		(width 0.1143)
		(layer "In2.Cu")
		(net "CPLD_UART_RI_P3_N")
	)
	(segment
		(start 193.167 -139.065)
		(end 193.421 -138.811)
		(width 0.1143)
		(layer "In2.Cu")
		(net "CPLD_UART_RI_P3_N")
	)
	(segment
		(start 169.468038 -166.331138)
		(end 170.314366 -166.331138)
		(width 0.1143)
		(layer "In2.Cu")
		(net "CPLD_UART_RI_P3_N")
	)
	(segment
		(start 182.194962 -164.615622)
		(end 193.167 -153.643584)
		(width 0.1143)
		(layer "In2.Cu")
		(net "CPLD_UART_RI_P3_N")
	)
	(segment
		(start 165.7223 -170.076876)
		(end 169.468038 -166.331138)
		(width 0.1143)
		(layer "In2.Cu")
		(net "CPLD_UART_RI_P3_N")
	)
	(segment
		(start 163.418266 -174.711614)
		(end 165.7223 -172.40758)
		(width 0.1143)
		(layer "In2.Cu")
		(net "CPLD_UART_RI_P3_N")
	)
	(segment
		(start 162.54476 -174.711614)
		(end 161.462466 -175.793908)
		(width 0.1143)
		(layer "In2.Cu")
		(net "CPLD_UART_RI_P3_N")
	)
	(segment
		(start 165.7223 -172.40758)
		(end 165.7223 -170.076876)
		(width 0.1143)
		(layer "In2.Cu")
		(net "CPLD_UART_RI_P3_N")
	)
	(segment
		(start 193.167 -98.709734)
		(end 178.769518 -84.312252)
		(width 0.1143)
		(layer "In2.Cu")
		(net "CPLD_UART_RI_P3_N")
	)
	(segment
		(start 178.24958 -82.64398)
		(end 178.24958 -84.312252)
		(width 0.1143)
		(layer "In6.Cu")
		(net "CPLD_UART_RI_P3_N")
	)
	(segment
		(start 162.3949 -63.531242)
		(end 162.3949 -66.7893)
		(width 0.1143)
		(layer "In6.Cu")
		(net "CPLD_UART_RI_P3_N")
	)
	(segment
		(start 162.3949 -66.7893)
		(end 178.24958 -82.64398)
		(width 0.1143)
		(layer "In6.Cu")
		(net "CPLD_UART_RI_P3_N")
	)
	(segment
		(start 162.3949 -63.531242)
		(end 161.727642 -63.531242)
		(width 0.1143)
		(layer "In7.Cu")
		(net "CPLD_UART_RI_P3_N")
	)
	(segment
		(start 139.2428 -57.592468)
		(end 138.69035 -58.144918)
		(width 0.1143)
		(layer "In7.Cu")
		(net "CPLD_UART_RI_P3_N")
	)
	(segment
		(start 140.40358 -57.592468)
		(end 139.2428 -57.592468)
		(width 0.1143)
		(layer "In7.Cu")
		(net "CPLD_UART_RI_P3_N")
	)
	(segment
		(start 135.34009 -56.501792)
		(end 125.742192 -56.501792)
		(width 0.1143)
		(layer "In7.Cu")
		(net "CPLD_UART_RI_P3_N")
	)
	(segment
		(start 161.727642 -63.531242)
		(end 157.569408 -59.373008)
		(width 0.1143)
		(layer "In7.Cu")
		(net "CPLD_UART_RI_P3_N")
	)
	(segment
		(start 125.742192 -56.501792)
		(end 123.740672 -54.500272)
		(width 0.1143)
		(layer "In7.Cu")
		(net "CPLD_UART_RI_P3_N")
	)
	(segment
		(start 138.69035 -58.144918)
		(end 136.983216 -58.144918)
		(width 0.1143)
		(layer "In7.Cu")
		(net "CPLD_UART_RI_P3_N")
	)
	(segment
		(start 142.18412 -59.373008)
		(end 140.40358 -57.592468)
		(width 0.1143)
		(layer "In7.Cu")
		(net "CPLD_UART_RI_P3_N")
	)
	(segment
		(start 157.569408 -59.373008)
		(end 142.18412 -59.373008)
		(width 0.1143)
		(layer "In7.Cu")
		(net "CPLD_UART_RI_P3_N")
	)
	(segment
		(start 136.983216 -58.144918)
		(end 135.34009 -56.501792)
		(width 0.1143)
		(layer "In7.Cu")
		(net "CPLD_UART_RI_P3_N")
	)
	(segment
		(start 67.60718 -176.485804)
		(end 67.60718 -175.400208)
		(width 0.1016)
		(layer "F.Cu")
		(net "UART_T1_NODE3_RXD")
	)
	(segment
		(start 68.909692 -174.097696)
		(end 70.057772 -174.097696)
		(width 0.1016)
		(layer "F.Cu")
		(net "UART_T1_NODE3_RXD")
	)
	(segment
		(start 67.60718 -175.400208)
		(end 68.909692 -174.097696)
		(width 0.1016)
		(layer "F.Cu")
		(net "UART_T1_NODE3_RXD")
	)
	(segment
		(start 70.057772 -174.097696)
		(end 70.164706 -173.990762)
		(width 0.1016)
		(layer "F.Cu")
		(net "UART_T1_NODE3_RXD")
	)
	(segment
		(start 71.223378 -174.12462)
		(end 72.244712 -174.12462)
		(width 0.1016)
		(layer "F.Cu")
		(net "UART_T1_NODE3_RXD")
	)
	(segment
		(start 70.164706 -173.990762)
		(end 71.08952 -173.990762)
		(width 0.1016)
		(layer "F.Cu")
		(net "UART_T1_NODE3_RXD")
	)
	(segment
		(start 71.08952 -173.990762)
		(end 71.223378 -174.12462)
		(width 0.1016)
		(layer "F.Cu")
		(net "UART_T1_NODE3_RXD")
	)
	(via
		(at 59.67476 -186.27217)
		(size 0.508)
		(drill 0.254)
		(layers "F.Cu" "B.Cu")
		(net "UART_T1_NODE3_RXD")
	)
	(via
		(at 67.60718 -176.485804)
		(size 0.508)
		(drill 0.254)
		(layers "F.Cu" "B.Cu")
		(net "UART_T1_NODE3_RXD")
	)
	(segment
		(start 59.67476 -185.605674)
		(end 59.67476 -186.27217)
		(width 0.1016)
		(layer "B.Cu")
		(net "UART_T1_NODE3_RXD")
	)
	(segment
		(start 59.23788 -186.70905)
		(end 59.67476 -186.27217)
		(width 0.1016)
		(layer "B.Cu")
		(net "UART_T1_NODE3_RXD")
	)
	(segment
		(start 59.67476 -187.726574)
		(end 59.23788 -187.289694)
		(width 0.1016)
		(layer "B.Cu")
		(net "UART_T1_NODE3_RXD")
	)
	(segment
		(start 59.23788 -187.289694)
		(end 59.23788 -186.70905)
		(width 0.1016)
		(layer "B.Cu")
		(net "UART_T1_NODE3_RXD")
	)
	(segment
		(start 61.19876 -182.4482)
		(end 61.19876 -183.524652)
		(width 0.1143)
		(layer "In7.Cu")
		(net "UART_T1_NODE3_RXD")
	)
	(segment
		(start 61.19876 -183.524652)
		(end 59.67476 -185.048652)
		(width 0.1143)
		(layer "In7.Cu")
		(net "UART_T1_NODE3_RXD")
	)
	(segment
		(start 67.161156 -176.485804)
		(end 61.19876 -182.4482)
		(width 0.1143)
		(layer "In7.Cu")
		(net "UART_T1_NODE3_RXD")
	)
	(segment
		(start 67.60718 -176.485804)
		(end 67.161156 -176.485804)
		(width 0.1143)
		(layer "In7.Cu")
		(net "UART_T1_NODE3_RXD")
	)
	(segment
		(start 59.67476 -185.048652)
		(end 59.67476 -186.27217)
		(width 0.1143)
		(layer "In7.Cu")
		(net "UART_T1_NODE3_RXD")
	)
	(segment
		(start 147.67179 -175.565816)
		(end 147.382484 -175.855122)
		(width 0.1016)
		(layer "F.Cu")
		(net "CPLD_UART_RTS_P3_N")
	)
	(segment
		(start 146.60626 -175.855122)
		(end 146.35988 -175.608742)
		(width 0.1016)
		(layer "F.Cu")
		(net "CPLD_UART_RTS_P3_N")
	)
	(segment
		(start 144.282414 -177.552858)
		(end 144.282414 -175.862742)
		(width 0.1016)
		(layer "F.Cu")
		(net "CPLD_UART_RTS_P3_N")
	)
	(segment
		(start 166.7891 -181.11851)
		(end 166.7891 -181.116478)
		(width 0.1016)
		(layer "F.Cu")
		(net "CPLD_UART_RTS_P3_N")
	)
	(segment
		(start 164.87902 -182.47233)
		(end 165.19017 -182.47233)
		(width 0.1016)
		(layer "F.Cu")
		(net "CPLD_UART_RTS_P3_N")
	)
	(segment
		(start 165.19017 -182.47233)
		(end 165.411404 -182.251096)
		(width 0.1016)
		(layer "F.Cu")
		(net "CPLD_UART_RTS_P3_N")
	)
	(segment
		(start 144.935956 -181.162198)
		(end 144.806416 -181.032658)
		(width 0.1016)
		(layer "F.Cu")
		(net "CPLD_UART_RTS_P3_N")
	)
	(segment
		(start 144.806416 -178.07686)
		(end 144.282414 -177.552858)
		(width 0.1016)
		(layer "F.Cu")
		(net "CPLD_UART_RTS_P3_N")
	)
	(segment
		(start 144.536414 -175.608742)
		(end 145.275808 -175.608742)
		(width 0.1016)
		(layer "F.Cu")
		(net "CPLD_UART_RTS_P3_N")
	)
	(segment
		(start 166.32809 -181.11851)
		(end 166.7891 -181.11851)
		(width 0.1016)
		(layer "F.Cu")
		(net "CPLD_UART_RTS_P3_N")
	)
	(segment
		(start 165.411404 -182.251096)
		(end 165.411404 -182.035196)
		(width 0.1016)
		(layer "F.Cu")
		(net "CPLD_UART_RTS_P3_N")
	)
	(segment
		(start 147.382484 -175.855122)
		(end 146.60626 -175.855122)
		(width 0.1016)
		(layer "F.Cu")
		(net "CPLD_UART_RTS_P3_N")
	)
	(segment
		(start 144.806416 -181.032658)
		(end 144.806416 -178.07686)
		(width 0.1016)
		(layer "F.Cu")
		(net "CPLD_UART_RTS_P3_N")
	)
	(segment
		(start 164.611304 -183.051196)
		(end 164.611304 -182.740046)
		(width 0.1016)
		(layer "F.Cu")
		(net "CPLD_UART_RTS_P3_N")
	)
	(segment
		(start 146.35988 -175.608742)
		(end 145.275808 -175.608742)
		(width 0.1016)
		(layer "F.Cu")
		(net "CPLD_UART_RTS_P3_N")
	)
	(segment
		(start 147.67179 -175.28032)
		(end 147.67179 -175.565816)
		(width 0.1016)
		(layer "F.Cu")
		(net "CPLD_UART_RTS_P3_N")
	)
	(segment
		(start 144.282414 -175.862742)
		(end 144.536414 -175.608742)
		(width 0.1016)
		(layer "F.Cu")
		(net "CPLD_UART_RTS_P3_N")
	)
	(segment
		(start 165.411404 -182.035196)
		(end 166.32809 -181.11851)
		(width 0.1016)
		(layer "F.Cu")
		(net "CPLD_UART_RTS_P3_N")
	)
	(segment
		(start 164.611304 -182.740046)
		(end 164.87902 -182.47233)
		(width 0.1016)
		(layer "F.Cu")
		(net "CPLD_UART_RTS_P3_N")
	)
	(via
		(at 166.7891 -181.116478)
		(size 0.508)
		(drill 0.254)
		(layers "F.Cu" "B.Cu")
		(net "CPLD_UART_RTS_P3_N")
	)
	(via
		(at 144.935956 -181.162198)
		(size 0.508)
		(drill 0.254)
		(layers "F.Cu" "B.Cu")
		(net "CPLD_UART_RTS_P3_N")
	)
	(segment
		(start 153.712418 -182.287164)
		(end 155.267152 -182.287164)
		(width 0.1143)
		(layer "In6.Cu")
		(net "CPLD_UART_RTS_P3_N")
	)
	(segment
		(start 156.0703 -182.724552)
		(end 156.14015 -182.654702)
		(width 0.1143)
		(layer "In6.Cu")
		(net "CPLD_UART_RTS_P3_N")
	)
	(segment
		(start 166.787068 -181.11851)
		(end 166.7891 -181.116478)
		(width 0.1143)
		(layer "In6.Cu")
		(net "CPLD_UART_RTS_P3_N")
	)
	(segment
		(start 147.310602 -181.802532)
		(end 150.278846 -181.802532)
		(width 0.1143)
		(layer "In6.Cu")
		(net "CPLD_UART_RTS_P3_N")
	)
	(segment
		(start 166.485824 -181.11851)
		(end 166.787068 -181.11851)
		(width 0.1143)
		(layer "In6.Cu")
		(net "CPLD_UART_RTS_P3_N")
	)
	(segment
		(start 155.267152 -182.287164)
		(end 155.70454 -182.724552)
		(width 0.1143)
		(layer "In6.Cu")
		(net "CPLD_UART_RTS_P3_N")
	)
	(segment
		(start 144.935956 -181.162198)
		(end 146.670268 -181.162198)
		(width 0.1143)
		(layer "In6.Cu")
		(net "CPLD_UART_RTS_P3_N")
	)
	(segment
		(start 162.523678 -183.004714)
		(end 163.092638 -183.573674)
		(width 0.1143)
		(layer "In6.Cu")
		(net "CPLD_UART_RTS_P3_N")
	)
	(segment
		(start 153.629106 -182.203852)
		(end 153.712418 -182.287164)
		(width 0.1143)
		(layer "In6.Cu")
		(net "CPLD_UART_RTS_P3_N")
	)
	(segment
		(start 156.14015 -182.654702)
		(end 157.025848 -182.654702)
		(width 0.1143)
		(layer "In6.Cu")
		(net "CPLD_UART_RTS_P3_N")
	)
	(segment
		(start 150.278846 -181.802532)
		(end 150.680166 -182.203852)
		(width 0.1143)
		(layer "In6.Cu")
		(net "CPLD_UART_RTS_P3_N")
	)
	(segment
		(start 157.025848 -182.654702)
		(end 157.37586 -183.004714)
		(width 0.1143)
		(layer "In6.Cu")
		(net "CPLD_UART_RTS_P3_N")
	)
	(segment
		(start 146.670268 -181.162198)
		(end 147.310602 -181.802532)
		(width 0.1143)
		(layer "In6.Cu")
		(net "CPLD_UART_RTS_P3_N")
	)
	(segment
		(start 155.70454 -182.724552)
		(end 156.0703 -182.724552)
		(width 0.1143)
		(layer "In6.Cu")
		(net "CPLD_UART_RTS_P3_N")
	)
	(segment
		(start 164.03066 -183.573674)
		(end 166.485824 -181.11851)
		(width 0.1143)
		(layer "In6.Cu")
		(net "CPLD_UART_RTS_P3_N")
	)
	(segment
		(start 157.37586 -183.004714)
		(end 162.523678 -183.004714)
		(width 0.1143)
		(layer "In6.Cu")
		(net "CPLD_UART_RTS_P3_N")
	)
	(segment
		(start 150.680166 -182.203852)
		(end 153.629106 -182.203852)
		(width 0.1143)
		(layer "In6.Cu")
		(net "CPLD_UART_RTS_P3_N")
	)
	(segment
		(start 163.092638 -183.573674)
		(end 164.03066 -183.573674)
		(width 0.1143)
		(layer "In6.Cu")
		(net "CPLD_UART_RTS_P3_N")
	)
	(segment
		(start 73.80732 -178.326542)
		(end 73.37044 -178.763422)
		(width 0.1016)
		(layer "F.Cu")
		(net "UART_T1_NODE3_TXD")
	)
	(segment
		(start 72.244712 -174.624746)
		(end 73.490836 -174.624746)
		(width 0.1016)
		(layer "F.Cu")
		(net "UART_T1_NODE3_TXD")
	)
	(segment
		(start 73.37044 -178.763422)
		(end 73.37044 -179.153058)
		(width 0.1016)
		(layer "F.Cu")
		(net "UART_T1_NODE3_TXD")
	)
	(segment
		(start 61.950092 -182.310278)
		(end 60.93841 -183.32196)
		(width 0.1016)
		(layer "F.Cu")
		(net "UART_T1_NODE3_TXD")
	)
	(segment
		(start 73.490836 -174.624746)
		(end 73.80732 -174.94123)
		(width 0.1016)
		(layer "F.Cu")
		(net "UART_T1_NODE3_TXD")
	)
	(segment
		(start 66.706242 -182.88381)
		(end 64.4144 -182.88381)
		(width 0.1016)
		(layer "F.Cu")
		(net "UART_T1_NODE3_TXD")
	)
	(segment
		(start 71.26605 -181.257448)
		(end 68.332604 -181.257448)
		(width 0.1016)
		(layer "F.Cu")
		(net "UART_T1_NODE3_TXD")
	)
	(segment
		(start 73.37044 -179.153058)
		(end 71.26605 -181.257448)
		(width 0.1016)
		(layer "F.Cu")
		(net "UART_T1_NODE3_TXD")
	)
	(segment
		(start 60.93841 -183.32196)
		(end 59.901836 -183.32196)
		(width 0.1016)
		(layer "F.Cu")
		(net "UART_T1_NODE3_TXD")
	)
	(segment
		(start 64.4144 -182.88381)
		(end 63.840868 -182.310278)
		(width 0.1016)
		(layer "F.Cu")
		(net "UART_T1_NODE3_TXD")
	)
	(segment
		(start 73.80732 -174.94123)
		(end 73.80732 -178.326542)
		(width 0.1016)
		(layer "F.Cu")
		(net "UART_T1_NODE3_TXD")
	)
	(segment
		(start 68.332604 -181.257448)
		(end 66.706242 -182.88381)
		(width 0.1016)
		(layer "F.Cu")
		(net "UART_T1_NODE3_TXD")
	)
	(segment
		(start 63.840868 -182.310278)
		(end 61.950092 -182.310278)
		(width 0.1016)
		(layer "F.Cu")
		(net "UART_T1_NODE3_TXD")
	)
	(segment
		(start 59.901836 -183.32196)
		(end 59.66714 -183.087264)
		(width 0.1016)
		(layer "F.Cu")
		(net "UART_T1_NODE3_TXD")
	)
	(via
		(at 59.66714 -183.087264)
		(size 0.508)
		(drill 0.254)
		(layers "F.Cu" "B.Cu")
		(net "UART_T1_NODE3_TXD")
	)
	(segment
		(start 59.05246 -184.284874)
		(end 59.05246 -183.740806)
		(width 0.1016)
		(layer "B.Cu")
		(net "UART_T1_NODE3_TXD")
	)
	(segment
		(start 59.66714 -183.126126)
		(end 59.66714 -183.087264)
		(width 0.1016)
		(layer "B.Cu")
		(net "UART_T1_NODE3_TXD")
	)
	(segment
		(start 58.53176 -184.805574)
		(end 59.05246 -184.284874)
		(width 0.1016)
		(layer "B.Cu")
		(net "UART_T1_NODE3_TXD")
	)
	(segment
		(start 59.05246 -183.740806)
		(end 59.66714 -183.126126)
		(width 0.1016)
		(layer "B.Cu")
		(net "UART_T1_NODE3_TXD")
	)
	(segment
		(start 70.4342 -177.736246)
		(end 71.545704 -176.624742)
		(width 0.1016)
		(layer "F.Cu")
		(net "UART_T1_NODE2_RXD")
	)
	(segment
		(start 71.545704 -176.624742)
		(end 72.244712 -176.624742)
		(width 0.1016)
		(layer "F.Cu")
		(net "UART_T1_NODE2_RXD")
	)
	(segment
		(start 69.47154 -177.736246)
		(end 70.4342 -177.736246)
		(width 0.1016)
		(layer "F.Cu")
		(net "UART_T1_NODE2_RXD")
	)
	(via
		(at 63.12662 -183.344566)
		(size 0.508)
		(drill 0.254)
		(layers "F.Cu" "B.Cu")
		(net "UART_T1_NODE2_RXD")
	)
	(via
		(at 69.47154 -177.736246)
		(size 0.508)
		(drill 0.254)
		(layers "F.Cu" "B.Cu")
		(net "UART_T1_NODE2_RXD")
	)
	(segment
		(start 61.724032 -183.344566)
		(end 63.12662 -183.344566)
		(width 0.1016)
		(layer "B.Cu")
		(net "UART_T1_NODE2_RXD")
	)
	(segment
		(start 61.3791 -185.486294)
		(end 61.3791 -183.689498)
		(width 0.1016)
		(layer "B.Cu")
		(net "UART_T1_NODE2_RXD")
	)
	(segment
		(start 61.49848 -185.605674)
		(end 61.3791 -185.486294)
		(width 0.1016)
		(layer "B.Cu")
		(net "UART_T1_NODE2_RXD")
	)
	(segment
		(start 61.96076 -186.176412)
		(end 61.96076 -185.605674)
		(width 0.1016)
		(layer "B.Cu")
		(net "UART_T1_NODE2_RXD")
	)
	(segment
		(start 61.96076 -185.605674)
		(end 61.49848 -185.605674)
		(width 0.1016)
		(layer "B.Cu")
		(net "UART_T1_NODE2_RXD")
	)
	(segment
		(start 61.4807 -187.246514)
		(end 61.4807 -186.656472)
		(width 0.1016)
		(layer "B.Cu")
		(net "UART_T1_NODE2_RXD")
	)
	(segment
		(start 61.96076 -187.726574)
		(end 61.4807 -187.246514)
		(width 0.1016)
		(layer "B.Cu")
		(net "UART_T1_NODE2_RXD")
	)
	(segment
		(start 61.4807 -186.656472)
		(end 61.96076 -186.176412)
		(width 0.1016)
		(layer "B.Cu")
		(net "UART_T1_NODE2_RXD")
	)
	(segment
		(start 61.3791 -183.689498)
		(end 61.724032 -183.344566)
		(width 0.1016)
		(layer "B.Cu")
		(net "UART_T1_NODE2_RXD")
	)
	(segment
		(start 63.12662 -182.654448)
		(end 63.12662 -183.344566)
		(width 0.1143)
		(layer "In7.Cu")
		(net "UART_T1_NODE2_RXD")
	)
	(segment
		(start 66.070734 -182.303928)
		(end 63.47714 -182.303928)
		(width 0.1143)
		(layer "In7.Cu")
		(net "UART_T1_NODE2_RXD")
	)
	(segment
		(start 63.47714 -182.303928)
		(end 63.12662 -182.654448)
		(width 0.1143)
		(layer "In7.Cu")
		(net "UART_T1_NODE2_RXD")
	)
	(segment
		(start 69.47154 -178.903122)
		(end 66.070734 -182.303928)
		(width 0.1143)
		(layer "In7.Cu")
		(net "UART_T1_NODE2_RXD")
	)
	(segment
		(start 69.47154 -177.736246)
		(end 69.47154 -178.903122)
		(width 0.1143)
		(layer "In7.Cu")
		(net "UART_T1_NODE2_RXD")
	)
	(segment
		(start 63.829946 -181.865778)
		(end 64.543178 -182.57901)
		(width 0.1016)
		(layer "F.Cu")
		(net "UART_T1_NODE2_TXD")
	)
	(segment
		(start 64.543178 -182.57901)
		(end 66.579242 -182.57901)
		(width 0.1016)
		(layer "F.Cu")
		(net "UART_T1_NODE2_TXD")
	)
	(segment
		(start 61.84011 -181.865778)
		(end 63.829946 -181.865778)
		(width 0.1016)
		(layer "F.Cu")
		(net "UART_T1_NODE2_TXD")
	)
	(segment
		(start 73.3933 -178.305714)
		(end 72.846692 -178.852322)
		(width 0.1016)
		(layer "F.Cu")
		(net "UART_T1_NODE2_TXD")
	)
	(segment
		(start 68.205604 -180.952648)
		(end 70.199504 -180.952648)
		(width 0.1016)
		(layer "F.Cu")
		(net "UART_T1_NODE2_TXD")
	)
	(segment
		(start 73.3933 -177.491898)
		(end 73.3933 -178.305714)
		(width 0.1016)
		(layer "F.Cu")
		(net "UART_T1_NODE2_TXD")
	)
	(segment
		(start 73.026016 -177.124614)
		(end 73.3933 -177.491898)
		(width 0.1016)
		(layer "F.Cu")
		(net "UART_T1_NODE2_TXD")
	)
	(segment
		(start 70.199504 -180.952648)
		(end 72.29983 -178.852322)
		(width 0.1016)
		(layer "F.Cu")
		(net "UART_T1_NODE2_TXD")
	)
	(segment
		(start 72.244712 -177.124614)
		(end 73.026016 -177.124614)
		(width 0.1016)
		(layer "F.Cu")
		(net "UART_T1_NODE2_TXD")
	)
	(segment
		(start 60.815728 -182.89016)
		(end 61.84011 -181.865778)
		(width 0.1016)
		(layer "F.Cu")
		(net "UART_T1_NODE2_TXD")
	)
	(segment
		(start 60.75934 -182.89016)
		(end 60.815728 -182.89016)
		(width 0.1016)
		(layer "F.Cu")
		(net "UART_T1_NODE2_TXD")
	)
	(segment
		(start 66.579242 -182.57901)
		(end 68.205604 -180.952648)
		(width 0.1016)
		(layer "F.Cu")
		(net "UART_T1_NODE2_TXD")
	)
	(segment
		(start 72.29983 -178.852322)
		(end 72.846692 -178.852322)
		(width 0.1016)
		(layer "F.Cu")
		(net "UART_T1_NODE2_TXD")
	)
	(via
		(at 72.846692 -178.852322)
		(size 0.508)
		(drill 0.254)
		(layers "F.Cu" "B.Cu")
		(net "UART_T1_NODE2_TXD")
	)
	(via
		(at 60.75934 -182.89016)
		(size 0.508)
		(drill 0.254)
		(layers "F.Cu" "B.Cu")
		(net "UART_T1_NODE2_TXD")
	)
	(segment
		(start 60.56122 -183.368188)
		(end 60.75934 -183.170068)
		(width 0.1016)
		(layer "B.Cu")
		(net "UART_T1_NODE2_TXD")
	)
	(segment
		(start 60.81776 -184.805574)
		(end 60.56122 -184.805574)
		(width 0.1016)
		(layer "B.Cu")
		(net "UART_T1_NODE2_TXD")
	)
	(segment
		(start 60.75934 -183.170068)
		(end 60.75934 -182.89016)
		(width 0.1016)
		(layer "B.Cu")
		(net "UART_T1_NODE2_TXD")
	)
	(segment
		(start 60.56122 -184.805574)
		(end 60.56122 -183.368188)
		(width 0.1016)
		(layer "B.Cu")
		(net "UART_T1_NODE2_TXD")
	)
	(segment
		(start 141.593316 -160.802828)
		(end 141.957044 -161.166556)
		(width 0.1016)
		(layer "F.Cu")
		(net "N31521709")
	)
	(segment
		(start 141.957044 -161.166556)
		(end 143.202406 -161.166556)
		(width 0.1016)
		(layer "F.Cu")
		(net "N31521709")
	)
	(segment
		(start 143.201136 -160.187386)
		(end 143.651224 -160.637474)
		(width 0.1016)
		(layer "F.Cu")
		(net "N31521709")
	)
	(segment
		(start 143.651224 -160.717738)
		(end 143.651224 -160.637474)
		(width 0.1016)
		(layer "F.Cu")
		(net "N31521709")
	)
	(segment
		(start 141.593316 -160.439608)
		(end 141.593316 -160.802828)
		(width 0.1016)
		(layer "F.Cu")
		(net "N31521709")
	)
	(segment
		(start 143.202406 -161.166556)
		(end 143.651224 -160.717738)
		(width 0.1016)
		(layer "F.Cu")
		(net "N31521709")
	)
	(segment
		(start 142.954248 -160.187386)
		(end 143.201136 -160.187386)
		(width 0.1016)
		(layer "F.Cu")
		(net "N31521709")
	)
	(via
		(at 143.651224 -160.637474)
		(size 0.508)
		(drill 0.254)
		(layers "F.Cu" "B.Cu")
		(net "N31521709")
	)
	(segment
		(start 139.393422 -158.689548)
		(end 138.328654 -158.689548)
		(width 0.1016)
		(layer "F.Cu")
		(net "N31521711")
	)
	(segment
		(start 138.0236 -159.843724)
		(end 138.0236 -158.994602)
		(width 0.1016)
		(layer "F.Cu")
		(net "N31521711")
	)
	(segment
		(start 138.328654 -158.689548)
		(end 138.0236 -158.994602)
		(width 0.1016)
		(layer "F.Cu")
		(net "N31521711")
	)
	(via
		(at 138.0236 -158.994602)
		(size 0.508)
		(drill 0.254)
		(layers "F.Cu" "B.Cu")
		(net "N31521711")
	)
	(segment
		(start 87.744808 -178.6128)
		(end 87.744808 -178.124612)
		(width 0.1016)
		(layer "F.Cu")
		(net "CPLD_UART_TX_P4")
	)
	(segment
		(start 91.516962 -180.067458)
		(end 90.657934 -180.067458)
		(width 0.1016)
		(layer "F.Cu")
		(net "CPLD_UART_TX_P4")
	)
	(segment
		(start 90.61958 -180.105812)
		(end 89.23782 -180.105812)
		(width 0.1016)
		(layer "F.Cu")
		(net "CPLD_UART_TX_P4")
	)
	(segment
		(start 90.657934 -180.067458)
		(end 90.61958 -180.105812)
		(width 0.1016)
		(layer "F.Cu")
		(net "CPLD_UART_TX_P4")
	)
	(segment
		(start 89.23782 -180.105812)
		(end 87.744808 -178.6128)
		(width 0.1016)
		(layer "F.Cu")
		(net "CPLD_UART_TX_P4")
	)
	(segment
		(start 93.35008 -178.23434)
		(end 91.516962 -180.067458)
		(width 0.1016)
		(layer "F.Cu")
		(net "CPLD_UART_TX_P4")
	)
	(via
		(at 154.89936 -181.258718)
		(size 0.508)
		(drill 0.254)
		(layers "F.Cu" "B.Cu")
		(net "CPLD_UART_TX_P4")
	)
	(via
		(at 150.32736 -167.530272)
		(size 0.508)
		(drill 0.254)
		(layers "F.Cu" "B.Cu")
		(net "CPLD_UART_TX_P4")
	)
	(via
		(at 93.35008 -178.23434)
		(size 0.508)
		(drill 0.254)
		(layers "F.Cu" "B.Cu")
		(net "CPLD_UART_TX_P4")
	)
	(segment
		(start 155.91282 -180.693314)
		(end 155.91282 -180.231542)
		(width 0.1016)
		(layer "B.Cu")
		(net "CPLD_UART_TX_P4")
	)
	(segment
		(start 154.89936 -181.258718)
		(end 155.137104 -181.020974)
		(width 0.1016)
		(layer "B.Cu")
		(net "CPLD_UART_TX_P4")
	)
	(segment
		(start 155.137104 -181.020974)
		(end 155.58516 -181.020974)
		(width 0.1016)
		(layer "B.Cu")
		(net "CPLD_UART_TX_P4")
	)
	(segment
		(start 155.58516 -181.020974)
		(end 155.91282 -180.693314)
		(width 0.1016)
		(layer "B.Cu")
		(net "CPLD_UART_TX_P4")
	)
	(segment
		(start 155.91282 -180.231542)
		(end 156.741876 -179.402486)
		(width 0.1016)
		(layer "B.Cu")
		(net "CPLD_UART_TX_P4")
	)
	(segment
		(start 156.741876 -179.402486)
		(end 159.375602 -179.402486)
		(width 0.1016)
		(layer "B.Cu")
		(net "CPLD_UART_TX_P4")
	)
	(segment
		(start 143.226282 -168.373806)
		(end 144.837404 -168.373806)
		(width 0.1143)
		(layer "In2.Cu")
		(net "CPLD_UART_TX_P4")
	)
	(segment
		(start 94.925896 -178.23434)
		(end 95.501714 -177.658522)
		(width 0.1143)
		(layer "In2.Cu")
		(net "CPLD_UART_TX_P4")
	)
	(segment
		(start 108.48594 -178.536092)
		(end 108.858558 -178.163474)
		(width 0.1143)
		(layer "In2.Cu")
		(net "CPLD_UART_TX_P4")
	)
	(segment
		(start 122.24385 -178.864768)
		(end 135.1661 -178.864768)
		(width 0.1143)
		(layer "In2.Cu")
		(net "CPLD_UART_TX_P4")
	)
	(segment
		(start 105.50525 -178.401726)
		(end 107.985814 -178.401726)
		(width 0.1143)
		(layer "In2.Cu")
		(net "CPLD_UART_TX_P4")
	)
	(segment
		(start 107.985814 -178.401726)
		(end 108.12018 -178.536092)
		(width 0.1143)
		(layer "In2.Cu")
		(net "CPLD_UART_TX_P4")
	)
	(segment
		(start 111.270796 -179.161694)
		(end 121.946924 -179.161694)
		(width 0.1143)
		(layer "In2.Cu")
		(net "CPLD_UART_TX_P4")
	)
	(segment
		(start 150.08733 -167.770302)
		(end 150.32736 -167.530272)
		(width 0.1143)
		(layer "In2.Cu")
		(net "CPLD_UART_TX_P4")
	)
	(segment
		(start 144.904968 -168.44137)
		(end 146.958304 -168.44137)
		(width 0.1143)
		(layer "In2.Cu")
		(net "CPLD_UART_TX_P4")
	)
	(segment
		(start 138.83132 -170.958002)
		(end 140.300456 -169.488866)
		(width 0.1143)
		(layer "In2.Cu")
		(net "CPLD_UART_TX_P4")
	)
	(segment
		(start 93.35008 -178.23434)
		(end 94.925896 -178.23434)
		(width 0.1143)
		(layer "In2.Cu")
		(net "CPLD_UART_TX_P4")
	)
	(segment
		(start 105.42016 -178.486816)
		(end 105.50525 -178.401726)
		(width 0.1143)
		(layer "In2.Cu")
		(net "CPLD_UART_TX_P4")
	)
	(segment
		(start 138.83132 -175.199548)
		(end 138.83132 -170.958002)
		(width 0.1143)
		(layer "In2.Cu")
		(net "CPLD_UART_TX_P4")
	)
	(segment
		(start 108.858558 -178.163474)
		(end 110.272576 -178.163474)
		(width 0.1143)
		(layer "In2.Cu")
		(net "CPLD_UART_TX_P4")
	)
	(segment
		(start 97.333562 -177.728118)
		(end 100.24491 -177.728118)
		(width 0.1143)
		(layer "In2.Cu")
		(net "CPLD_UART_TX_P4")
	)
	(segment
		(start 140.300456 -169.488866)
		(end 142.111222 -169.488866)
		(width 0.1143)
		(layer "In2.Cu")
		(net "CPLD_UART_TX_P4")
	)
	(segment
		(start 135.1661 -178.864768)
		(end 138.83132 -175.199548)
		(width 0.1143)
		(layer "In2.Cu")
		(net "CPLD_UART_TX_P4")
	)
	(segment
		(start 147.629372 -167.770302)
		(end 150.08733 -167.770302)
		(width 0.1143)
		(layer "In2.Cu")
		(net "CPLD_UART_TX_P4")
	)
	(segment
		(start 108.12018 -178.536092)
		(end 108.48594 -178.536092)
		(width 0.1143)
		(layer "In2.Cu")
		(net "CPLD_UART_TX_P4")
	)
	(segment
		(start 100.252784 -177.720244)
		(end 104.287828 -177.720244)
		(width 0.1143)
		(layer "In2.Cu")
		(net "CPLD_UART_TX_P4")
	)
	(segment
		(start 97.263966 -177.658522)
		(end 97.333562 -177.728118)
		(width 0.1143)
		(layer "In2.Cu")
		(net "CPLD_UART_TX_P4")
	)
	(segment
		(start 95.501714 -177.658522)
		(end 97.263966 -177.658522)
		(width 0.1143)
		(layer "In2.Cu")
		(net "CPLD_UART_TX_P4")
	)
	(segment
		(start 110.272576 -178.163474)
		(end 111.270796 -179.161694)
		(width 0.1143)
		(layer "In2.Cu")
		(net "CPLD_UART_TX_P4")
	)
	(segment
		(start 105.0544 -178.486816)
		(end 105.42016 -178.486816)
		(width 0.1143)
		(layer "In2.Cu")
		(net "CPLD_UART_TX_P4")
	)
	(segment
		(start 100.24491 -177.728118)
		(end 100.252784 -177.720244)
		(width 0.1143)
		(layer "In2.Cu")
		(net "CPLD_UART_TX_P4")
	)
	(segment
		(start 121.946924 -179.161694)
		(end 122.24385 -178.864768)
		(width 0.1143)
		(layer "In2.Cu")
		(net "CPLD_UART_TX_P4")
	)
	(segment
		(start 146.958304 -168.44137)
		(end 147.629372 -167.770302)
		(width 0.1143)
		(layer "In2.Cu")
		(net "CPLD_UART_TX_P4")
	)
	(segment
		(start 144.837404 -168.373806)
		(end 144.904968 -168.44137)
		(width 0.1143)
		(layer "In2.Cu")
		(net "CPLD_UART_TX_P4")
	)
	(segment
		(start 142.111222 -169.488866)
		(end 143.226282 -168.373806)
		(width 0.1143)
		(layer "In2.Cu")
		(net "CPLD_UART_TX_P4")
	)
	(segment
		(start 104.287828 -177.720244)
		(end 105.0544 -178.486816)
		(width 0.1143)
		(layer "In2.Cu")
		(net "CPLD_UART_TX_P4")
	)
	(segment
		(start 154.693874 -181.053232)
		(end 154.89936 -181.258718)
		(width 0.1143)
		(layer "In7.Cu")
		(net "CPLD_UART_TX_P4")
	)
	(segment
		(start 150.32736 -167.530272)
		(end 151.16556 -168.368472)
		(width 0.1143)
		(layer "In7.Cu")
		(net "CPLD_UART_TX_P4")
	)
	(segment
		(start 151.16556 -168.368472)
		(end 151.16556 -169.902632)
		(width 0.1143)
		(layer "In7.Cu")
		(net "CPLD_UART_TX_P4")
	)
	(segment
		(start 152.06218 -176.429162)
		(end 152.46858 -176.835562)
		(width 0.1143)
		(layer "In7.Cu")
		(net "CPLD_UART_TX_P4")
	)
	(segment
		(start 151.16556 -169.902632)
		(end 152.06218 -170.799252)
		(width 0.1143)
		(layer "In7.Cu")
		(net "CPLD_UART_TX_P4")
	)
	(segment
		(start 152.06218 -170.799252)
		(end 152.06218 -176.429162)
		(width 0.1143)
		(layer "In7.Cu")
		(net "CPLD_UART_TX_P4")
	)
	(segment
		(start 152.46858 -176.835562)
		(end 152.46858 -178.89601)
		(width 0.1143)
		(layer "In7.Cu")
		(net "CPLD_UART_TX_P4")
	)
	(segment
		(start 152.46858 -178.89601)
		(end 154.625802 -181.053232)
		(width 0.1143)
		(layer "In7.Cu")
		(net "CPLD_UART_TX_P4")
	)
	(segment
		(start 154.625802 -181.053232)
		(end 154.693874 -181.053232)
		(width 0.1143)
		(layer "In7.Cu")
		(net "CPLD_UART_TX_P4")
	)
	(segment
		(start 85.994748 -179.874672)
		(end 85.994748 -179.958238)
		(width 0.1016)
		(layer "F.Cu")
		(net "CPLD_UART_DTR_P4_N")
	)
	(segment
		(start 88.291924 -180.390546)
		(end 88.38692 -180.390546)
		(width 0.1016)
		(layer "F.Cu")
		(net "CPLD_UART_DTR_P4_N")
	)
	(segment
		(start 86.220046 -180.183536)
		(end 86.92642 -180.183536)
		(width 0.1016)
		(layer "F.Cu")
		(net "CPLD_UART_DTR_P4_N")
	)
	(segment
		(start 89.342976 -181.346602)
		(end 89.41054 -181.346602)
		(width 0.1016)
		(layer "F.Cu")
		(net "CPLD_UART_DTR_P4_N")
	)
	(segment
		(start 90.41892 -180.626512)
		(end 89.69883 -181.346602)
		(width 0.1016)
		(layer "F.Cu")
		(net "CPLD_UART_DTR_P4_N")
	)
	(segment
		(start 90.41257 -180.626512)
		(end 90.41892 -180.626512)
		(width 0.1016)
		(layer "F.Cu")
		(net "CPLD_UART_DTR_P4_N")
	)
	(segment
		(start 85.994748 -179.958238)
		(end 86.220046 -180.183536)
		(width 0.1016)
		(layer "F.Cu")
		(net "CPLD_UART_DTR_P4_N")
	)
	(segment
		(start 89.41054 -181.346602)
		(end 89.41054 -181.347872)
		(width 0.1016)
		(layer "F.Cu")
		(net "CPLD_UART_DTR_P4_N")
	)
	(segment
		(start 88.38692 -180.390546)
		(end 89.342976 -181.346602)
		(width 0.1016)
		(layer "F.Cu")
		(net "CPLD_UART_DTR_P4_N")
	)
	(segment
		(start 89.69883 -181.346602)
		(end 89.41054 -181.346602)
		(width 0.1016)
		(layer "F.Cu")
		(net "CPLD_UART_DTR_P4_N")
	)
	(via
		(at 86.92642 -180.183536)
		(size 0.508)
		(drill 0.254)
		(layers "F.Cu" "B.Cu")
		(net "CPLD_UART_DTR_P4_N")
	)
	(via
		(at 89.41054 -181.347872)
		(size 0.508)
		(drill 0.254)
		(layers "F.Cu" "B.Cu")
		(net "CPLD_UART_DTR_P4_N")
	)
	(via
		(at 161.58718 -185.25109)
		(size 0.508)
		(drill 0.254)
		(layers "F.Cu" "B.Cu")
		(net "CPLD_UART_DTR_P4_N")
	)
	(segment
		(start 159.501078 -182.395368)
		(end 160.1089 -183.00319)
		(width 0.1016)
		(layer "B.Cu")
		(net "CPLD_UART_DTR_P4_N")
	)
	(segment
		(start 160.843468 -184.507378)
		(end 161.58718 -185.25109)
		(width 0.1016)
		(layer "B.Cu")
		(net "CPLD_UART_DTR_P4_N")
	)
	(segment
		(start 88.246204 -180.183536)
		(end 89.41054 -181.347872)
		(width 0.1016)
		(layer "B.Cu")
		(net "CPLD_UART_DTR_P4_N")
	)
	(segment
		(start 160.1089 -184.066688)
		(end 160.54959 -184.507378)
		(width 0.1016)
		(layer "B.Cu")
		(net "CPLD_UART_DTR_P4_N")
	)
	(segment
		(start 160.54959 -184.507378)
		(end 160.843468 -184.507378)
		(width 0.1016)
		(layer "B.Cu")
		(net "CPLD_UART_DTR_P4_N")
	)
	(segment
		(start 86.92642 -180.183536)
		(end 88.246204 -180.183536)
		(width 0.1016)
		(layer "B.Cu")
		(net "CPLD_UART_DTR_P4_N")
	)
	(segment
		(start 160.1089 -183.00319)
		(end 160.1089 -184.066688)
		(width 0.1016)
		(layer "B.Cu")
		(net "CPLD_UART_DTR_P4_N")
	)
	(segment
		(start 109.33684 -181.437788)
		(end 112.808766 -181.437788)
		(width 0.1143)
		(layer "In2.Cu")
		(net "CPLD_UART_DTR_P4_N")
	)
	(segment
		(start 106.741214 -180.732684)
		(end 108.631736 -180.732684)
		(width 0.1143)
		(layer "In2.Cu")
		(net "CPLD_UART_DTR_P4_N")
	)
	(segment
		(start 149.871176 -187.669932)
		(end 150.24481 -187.296298)
		(width 0.1143)
		(layer "In2.Cu")
		(net "CPLD_UART_DTR_P4_N")
	)
	(segment
		(start 113.32972 -181.958742)
		(end 117.040152 -181.958742)
		(width 0.1143)
		(layer "In2.Cu")
		(net "CPLD_UART_DTR_P4_N")
	)
	(segment
		(start 94.85884 -181.369462)
		(end 98.81235 -181.369462)
		(width 0.1143)
		(layer "In2.Cu")
		(net "CPLD_UART_DTR_P4_N")
	)
	(segment
		(start 124.959618 -187.669932)
		(end 149.871176 -187.669932)
		(width 0.1143)
		(layer "In2.Cu")
		(net "CPLD_UART_DTR_P4_N")
	)
	(segment
		(start 124.42698 -187.137294)
		(end 124.959618 -187.669932)
		(width 0.1143)
		(layer "In2.Cu")
		(net "CPLD_UART_DTR_P4_N")
	)
	(segment
		(start 120.477534 -185.48223)
		(end 123.56846 -185.48223)
		(width 0.1143)
		(layer "In2.Cu")
		(net "CPLD_UART_DTR_P4_N")
	)
	(segment
		(start 112.808766 -181.437788)
		(end 113.32972 -181.958742)
		(width 0.1143)
		(layer "In2.Cu")
		(net "CPLD_UART_DTR_P4_N")
	)
	(segment
		(start 104.609138 -179.629054)
		(end 105.11409 -180.134006)
		(width 0.1143)
		(layer "In2.Cu")
		(net "CPLD_UART_DTR_P4_N")
	)
	(segment
		(start 117.040152 -181.958742)
		(end 118.91518 -183.83377)
		(width 0.1143)
		(layer "In2.Cu")
		(net "CPLD_UART_DTR_P4_N")
	)
	(segment
		(start 118.91518 -183.919876)
		(end 120.477534 -185.48223)
		(width 0.1143)
		(layer "In2.Cu")
		(net "CPLD_UART_DTR_P4_N")
	)
	(segment
		(start 89.41054 -181.347872)
		(end 89.897712 -181.835044)
		(width 0.1143)
		(layer "In2.Cu")
		(net "CPLD_UART_DTR_P4_N")
	)
	(segment
		(start 105.47731 -180.134006)
		(end 105.481628 -180.129688)
		(width 0.1143)
		(layer "In2.Cu")
		(net "CPLD_UART_DTR_P4_N")
	)
	(segment
		(start 93.98254 -181.835044)
		(end 94.10954 -181.708044)
		(width 0.1143)
		(layer "In2.Cu")
		(net "CPLD_UART_DTR_P4_N")
	)
	(segment
		(start 106.138218 -180.129688)
		(end 106.741214 -180.732684)
		(width 0.1143)
		(layer "In2.Cu")
		(net "CPLD_UART_DTR_P4_N")
	)
	(segment
		(start 123.56846 -185.48223)
		(end 124.42698 -186.34075)
		(width 0.1143)
		(layer "In2.Cu")
		(net "CPLD_UART_DTR_P4_N")
	)
	(segment
		(start 150.24481 -187.296298)
		(end 150.804626 -187.296298)
		(width 0.1143)
		(layer "In2.Cu")
		(net "CPLD_UART_DTR_P4_N")
	)
	(segment
		(start 118.91518 -183.83377)
		(end 118.91518 -183.919876)
		(width 0.1143)
		(layer "In2.Cu")
		(net "CPLD_UART_DTR_P4_N")
	)
	(segment
		(start 100.44049 -179.629054)
		(end 104.609138 -179.629054)
		(width 0.1143)
		(layer "In2.Cu")
		(net "CPLD_UART_DTR_P4_N")
	)
	(segment
		(start 99.96932 -180.100224)
		(end 100.44049 -179.629054)
		(width 0.1143)
		(layer "In2.Cu")
		(net "CPLD_UART_DTR_P4_N")
	)
	(segment
		(start 161.276792 -184.940702)
		(end 161.58718 -185.25109)
		(width 0.1143)
		(layer "In2.Cu")
		(net "CPLD_UART_DTR_P4_N")
	)
	(segment
		(start 108.631736 -180.732684)
		(end 109.33684 -181.437788)
		(width 0.1143)
		(layer "In2.Cu")
		(net "CPLD_UART_DTR_P4_N")
	)
	(segment
		(start 105.481628 -180.129688)
		(end 106.138218 -180.129688)
		(width 0.1143)
		(layer "In2.Cu")
		(net "CPLD_UART_DTR_P4_N")
	)
	(segment
		(start 105.11409 -180.134006)
		(end 105.47731 -180.134006)
		(width 0.1143)
		(layer "In2.Cu")
		(net "CPLD_UART_DTR_P4_N")
	)
	(segment
		(start 99.96932 -180.212492)
		(end 99.96932 -180.100224)
		(width 0.1143)
		(layer "In2.Cu")
		(net "CPLD_UART_DTR_P4_N")
	)
	(segment
		(start 151.061166 -187.039758)
		(end 151.061166 -186.676538)
		(width 0.1143)
		(layer "In2.Cu")
		(net "CPLD_UART_DTR_P4_N")
	)
	(segment
		(start 94.10954 -181.708044)
		(end 94.520258 -181.708044)
		(width 0.1143)
		(layer "In2.Cu")
		(net "CPLD_UART_DTR_P4_N")
	)
	(segment
		(start 89.897712 -181.835044)
		(end 93.98254 -181.835044)
		(width 0.1143)
		(layer "In2.Cu")
		(net "CPLD_UART_DTR_P4_N")
	)
	(segment
		(start 152.797002 -184.940702)
		(end 161.276792 -184.940702)
		(width 0.1143)
		(layer "In2.Cu")
		(net "CPLD_UART_DTR_P4_N")
	)
	(segment
		(start 98.81235 -181.369462)
		(end 99.96932 -180.212492)
		(width 0.1143)
		(layer "In2.Cu")
		(net "CPLD_UART_DTR_P4_N")
	)
	(segment
		(start 150.804626 -187.296298)
		(end 151.061166 -187.039758)
		(width 0.1143)
		(layer "In2.Cu")
		(net "CPLD_UART_DTR_P4_N")
	)
	(segment
		(start 94.520258 -181.708044)
		(end 94.85884 -181.369462)
		(width 0.1143)
		(layer "In2.Cu")
		(net "CPLD_UART_DTR_P4_N")
	)
	(segment
		(start 151.061166 -186.676538)
		(end 152.797002 -184.940702)
		(width 0.1143)
		(layer "In2.Cu")
		(net "CPLD_UART_DTR_P4_N")
	)
	(segment
		(start 124.42698 -186.34075)
		(end 124.42698 -187.137294)
		(width 0.1143)
		(layer "In2.Cu")
		(net "CPLD_UART_DTR_P4_N")
	)
	(segment
		(start 87.081868 -177.62474)
		(end 87.744808 -177.62474)
		(width 0.1016)
		(layer "F.Cu")
		(net "CPLD_UART_RX_P4")
	)
	(segment
		(start 86.686136 -177.229008)
		(end 87.081868 -177.62474)
		(width 0.1016)
		(layer "F.Cu")
		(net "CPLD_UART_RX_P4")
	)
	(segment
		(start 86.087204 -177.229008)
		(end 86.686136 -177.229008)
		(width 0.1016)
		(layer "F.Cu")
		(net "CPLD_UART_RX_P4")
	)
	(via
		(at 166.1287 -182.393844)
		(size 0.508)
		(drill 0.254)
		(layers "F.Cu" "B.Cu")
		(net "CPLD_UART_RX_P4")
	)
	(via
		(at 151.637492 -167.134032)
		(size 0.508)
		(drill 0.254)
		(layers "F.Cu" "B.Cu")
		(net "CPLD_UART_RX_P4")
	)
	(via
		(at 86.087204 -177.229008)
		(size 0.508)
		(drill 0.254)
		(layers "F.Cu" "B.Cu")
		(net "CPLD_UART_RX_P4")
	)
	(segment
		(start 165.411658 -183.027574)
		(end 165.411658 -182.035196)
		(width 0.1016)
		(layer "B.Cu")
		(net "CPLD_UART_RX_P4")
	)
	(segment
		(start 165.411658 -183.027574)
		(end 166.045388 -182.393844)
		(width 0.1016)
		(layer "B.Cu")
		(net "CPLD_UART_RX_P4")
	)
	(segment
		(start 165.411658 -183.051196)
		(end 165.411658 -183.027574)
		(width 0.1016)
		(layer "B.Cu")
		(net "CPLD_UART_RX_P4")
	)
	(segment
		(start 166.045388 -182.393844)
		(end 166.1287 -182.393844)
		(width 0.1016)
		(layer "B.Cu")
		(net "CPLD_UART_RX_P4")
	)
	(segment
		(start 90.9193 -178.642518)
		(end 90.529664 -178.642518)
		(width 0.1143)
		(layer "In2.Cu")
		(net "CPLD_UART_RX_P4")
	)
	(segment
		(start 110.511844 -179.041552)
		(end 108.026454 -179.041552)
		(width 0.1143)
		(layer "In2.Cu")
		(net "CPLD_UART_RX_P4")
	)
	(segment
		(start 144.756124 -168.85285)
		(end 144.337532 -169.271442)
		(width 0.1143)
		(layer "In2.Cu")
		(net "CPLD_UART_RX_P4")
	)
	(segment
		(start 92.70492 -179.21859)
		(end 91.495372 -179.21859)
		(width 0.1143)
		(layer "In2.Cu")
		(net "CPLD_UART_RX_P4")
	)
	(segment
		(start 144.337532 -169.271442)
		(end 143.062452 -169.271442)
		(width 0.1143)
		(layer "In2.Cu")
		(net "CPLD_UART_RX_P4")
	)
	(segment
		(start 151.637492 -167.134032)
		(end 151.458168 -167.134032)
		(width 0.1143)
		(layer "In2.Cu")
		(net "CPLD_UART_RX_P4")
	)
	(segment
		(start 133.606032 -180.427122)
		(end 133.228588 -180.049678)
		(width 0.1143)
		(layer "In2.Cu")
		(net "CPLD_UART_RX_P4")
	)
	(segment
		(start 97.274888 -178.58232)
		(end 94.758256 -178.58232)
		(width 0.1143)
		(layer "In2.Cu")
		(net "CPLD_UART_RX_P4")
	)
	(segment
		(start 97.496884 -178.804316)
		(end 97.274888 -178.58232)
		(width 0.1143)
		(layer "In2.Cu")
		(net "CPLD_UART_RX_P4")
	)
	(segment
		(start 147.076414 -168.85285)
		(end 144.756124 -168.85285)
		(width 0.1143)
		(layer "In2.Cu")
		(net "CPLD_UART_RX_P4")
	)
	(segment
		(start 107.704128 -178.719226)
		(end 105.63733 -178.719226)
		(width 0.1143)
		(layer "In2.Cu")
		(net "CPLD_UART_RX_P4")
	)
	(segment
		(start 90.529664 -178.642518)
		(end 90.221308 -178.334162)
		(width 0.1143)
		(layer "In2.Cu")
		(net "CPLD_UART_RX_P4")
	)
	(segment
		(start 123.834398 -179.49545)
		(end 110.965742 -179.49545)
		(width 0.1143)
		(layer "In2.Cu")
		(net "CPLD_UART_RX_P4")
	)
	(segment
		(start 110.965742 -179.49545)
		(end 110.511844 -179.041552)
		(width 0.1143)
		(layer "In2.Cu")
		(net "CPLD_UART_RX_P4")
	)
	(segment
		(start 140.987526 -170.42257)
		(end 139.45108 -171.959016)
		(width 0.1143)
		(layer "In2.Cu")
		(net "CPLD_UART_RX_P4")
	)
	(segment
		(start 139.45108 -175.7807)
		(end 134.804658 -180.427122)
		(width 0.1143)
		(layer "In2.Cu")
		(net "CPLD_UART_RX_P4")
	)
	(segment
		(start 149.541738 -169.050462)
		(end 147.274026 -169.050462)
		(width 0.1143)
		(layer "In2.Cu")
		(net "CPLD_UART_RX_P4")
	)
	(segment
		(start 151.458168 -167.134032)
		(end 149.541738 -169.050462)
		(width 0.1143)
		(layer "In2.Cu")
		(net "CPLD_UART_RX_P4")
	)
	(segment
		(start 93.75394 -179.586636)
		(end 93.072966 -179.586636)
		(width 0.1143)
		(layer "In2.Cu")
		(net "CPLD_UART_RX_P4")
	)
	(segment
		(start 105.55224 -178.804316)
		(end 97.496884 -178.804316)
		(width 0.1143)
		(layer "In2.Cu")
		(net "CPLD_UART_RX_P4")
	)
	(segment
		(start 108.026454 -179.041552)
		(end 107.704128 -178.719226)
		(width 0.1143)
		(layer "In2.Cu")
		(net "CPLD_UART_RX_P4")
	)
	(segment
		(start 124.388626 -180.049678)
		(end 123.834398 -179.49545)
		(width 0.1143)
		(layer "In2.Cu")
		(net "CPLD_UART_RX_P4")
	)
	(segment
		(start 94.758256 -178.58232)
		(end 93.75394 -179.586636)
		(width 0.1143)
		(layer "In2.Cu")
		(net "CPLD_UART_RX_P4")
	)
	(segment
		(start 139.45108 -171.959016)
		(end 139.45108 -175.7807)
		(width 0.1143)
		(layer "In2.Cu")
		(net "CPLD_UART_RX_P4")
	)
	(segment
		(start 141.911324 -170.42257)
		(end 140.987526 -170.42257)
		(width 0.1143)
		(layer "In2.Cu")
		(net "CPLD_UART_RX_P4")
	)
	(segment
		(start 87.192358 -178.334162)
		(end 86.087204 -177.229008)
		(width 0.1143)
		(layer "In2.Cu")
		(net "CPLD_UART_RX_P4")
	)
	(segment
		(start 143.062452 -169.271442)
		(end 141.911324 -170.42257)
		(width 0.1143)
		(layer "In2.Cu")
		(net "CPLD_UART_RX_P4")
	)
	(segment
		(start 105.63733 -178.719226)
		(end 105.55224 -178.804316)
		(width 0.1143)
		(layer "In2.Cu")
		(net "CPLD_UART_RX_P4")
	)
	(segment
		(start 90.221308 -178.334162)
		(end 87.192358 -178.334162)
		(width 0.1143)
		(layer "In2.Cu")
		(net "CPLD_UART_RX_P4")
	)
	(segment
		(start 133.228588 -180.049678)
		(end 124.388626 -180.049678)
		(width 0.1143)
		(layer "In2.Cu")
		(net "CPLD_UART_RX_P4")
	)
	(segment
		(start 134.804658 -180.427122)
		(end 133.606032 -180.427122)
		(width 0.1143)
		(layer "In2.Cu")
		(net "CPLD_UART_RX_P4")
	)
	(segment
		(start 93.072966 -179.586636)
		(end 92.70492 -179.21859)
		(width 0.1143)
		(layer "In2.Cu")
		(net "CPLD_UART_RX_P4")
	)
	(segment
		(start 91.495372 -179.21859)
		(end 90.9193 -178.642518)
		(width 0.1143)
		(layer "In2.Cu")
		(net "CPLD_UART_RX_P4")
	)
	(segment
		(start 147.274026 -169.050462)
		(end 147.076414 -168.85285)
		(width 0.1143)
		(layer "In2.Cu")
		(net "CPLD_UART_RX_P4")
	)
	(segment
		(start 154.36088 -169.47769)
		(end 154.63774 -169.75455)
		(width 0.1143)
		(layer "In7.Cu")
		(net "CPLD_UART_RX_P4")
	)
	(segment
		(start 154.89555 -177.721006)
		(end 154.95397 -177.721006)
		(width 0.1143)
		(layer "In7.Cu")
		(net "CPLD_UART_RX_P4")
	)
	(segment
		(start 151.637492 -167.134032)
		(end 151.72309 -167.21963)
		(width 0.1143)
		(layer "In7.Cu")
		(net "CPLD_UART_RX_P4")
	)
	(segment
		(start 151.72309 -167.21963)
		(end 152.233122 -167.21963)
		(width 0.1143)
		(layer "In7.Cu")
		(net "CPLD_UART_RX_P4")
	)
	(segment
		(start 154.36088 -169.347388)
		(end 154.36088 -169.47769)
		(width 0.1143)
		(layer "In7.Cu")
		(net "CPLD_UART_RX_P4")
	)
	(segment
		(start 154.63774 -169.75455)
		(end 154.63774 -177.463196)
		(width 0.1143)
		(layer "In7.Cu")
		(net "CPLD_UART_RX_P4")
	)
	(segment
		(start 158.04134 -180.808376)
		(end 164.793168 -180.808376)
		(width 0.1143)
		(layer "In7.Cu")
		(net "CPLD_UART_RX_P4")
	)
	(segment
		(start 152.233122 -167.21963)
		(end 154.36088 -169.347388)
		(width 0.1143)
		(layer "In7.Cu")
		(net "CPLD_UART_RX_P4")
	)
	(segment
		(start 164.793168 -180.808376)
		(end 166.1287 -182.143908)
		(width 0.1143)
		(layer "In7.Cu")
		(net "CPLD_UART_RX_P4")
	)
	(segment
		(start 154.95397 -177.721006)
		(end 158.04134 -180.808376)
		(width 0.1143)
		(layer "In7.Cu")
		(net "CPLD_UART_RX_P4")
	)
	(segment
		(start 166.1287 -182.143908)
		(end 166.1287 -182.393844)
		(width 0.1143)
		(layer "In7.Cu")
		(net "CPLD_UART_RX_P4")
	)
	(segment
		(start 154.63774 -177.463196)
		(end 154.89555 -177.721006)
		(width 0.1143)
		(layer "In7.Cu")
		(net "CPLD_UART_RX_P4")
	)
	(segment
		(start 90.414348 -176.562512)
		(end 90.414348 -177.576734)
		(width 0.1016)
		(layer "F.Cu")
		(net "CPLD_UART_RTS_P4_N")
	)
	(segment
		(start 87.023702 -176.624742)
		(end 87.744808 -176.624742)
		(width 0.1016)
		(layer "F.Cu")
		(net "CPLD_UART_RTS_P4_N")
	)
	(segment
		(start 86.565994 -176.167034)
		(end 87.023702 -176.624742)
		(width 0.1016)
		(layer "F.Cu")
		(net "CPLD_UART_RTS_P4_N")
	)
	(segment
		(start 85.655404 -177.449988)
		(end 85.655404 -176.62906)
		(width 0.1016)
		(layer "F.Cu")
		(net "CPLD_UART_RTS_P4_N")
	)
	(segment
		(start 85.655404 -176.62906)
		(end 86.11743 -176.167034)
		(width 0.1016)
		(layer "F.Cu")
		(net "CPLD_UART_RTS_P4_N")
	)
	(segment
		(start 89.355676 -177.578512)
		(end 90.41257 -177.578512)
		(width 0.1016)
		(layer "F.Cu")
		(net "CPLD_UART_RTS_P4_N")
	)
	(segment
		(start 88.401906 -176.624742)
		(end 89.355676 -177.578512)
		(width 0.1016)
		(layer "F.Cu")
		(net "CPLD_UART_RTS_P4_N")
	)
	(segment
		(start 90.414348 -177.576734)
		(end 90.41257 -177.578512)
		(width 0.1016)
		(layer "F.Cu")
		(net "CPLD_UART_RTS_P4_N")
	)
	(segment
		(start 86.10854 -177.903124)
		(end 85.655404 -177.449988)
		(width 0.1016)
		(layer "F.Cu")
		(net "CPLD_UART_RTS_P4_N")
	)
	(segment
		(start 86.11743 -176.167034)
		(end 86.565994 -176.167034)
		(width 0.1016)
		(layer "F.Cu")
		(net "CPLD_UART_RTS_P4_N")
	)
	(segment
		(start 87.744808 -176.624742)
		(end 88.401906 -176.624742)
		(width 0.1016)
		(layer "F.Cu")
		(net "CPLD_UART_RTS_P4_N")
	)
	(via
		(at 151.7142 -168.434512)
		(size 0.508)
		(drill 0.254)
		(layers "F.Cu" "B.Cu")
		(net "CPLD_UART_RTS_P4_N")
	)
	(via
		(at 157.69082 -182.249064)
		(size 0.508)
		(drill 0.254)
		(layers "F.Cu" "B.Cu")
		(net "CPLD_UART_RTS_P4_N")
	)
	(via
		(at 86.10854 -177.903124)
		(size 0.508)
		(drill 0.254)
		(layers "F.Cu" "B.Cu")
		(net "CPLD_UART_RTS_P4_N")
	)
	(segment
		(start 158.09976 -182.395368)
		(end 157.953456 -182.249064)
		(width 0.1016)
		(layer "B.Cu")
		(net "CPLD_UART_RTS_P4_N")
	)
	(segment
		(start 158.485078 -182.395368)
		(end 158.09976 -182.395368)
		(width 0.1016)
		(layer "B.Cu")
		(net "CPLD_UART_RTS_P4_N")
	)
	(segment
		(start 157.953456 -182.249064)
		(end 157.69082 -182.249064)
		(width 0.1016)
		(layer "B.Cu")
		(net "CPLD_UART_RTS_P4_N")
	)
	(segment
		(start 97.953068 -179.751228)
		(end 99.68484 -179.751228)
		(width 0.1143)
		(layer "In2.Cu")
		(net "CPLD_UART_RTS_P4_N")
	)
	(segment
		(start 150.78075 -169.367962)
		(end 151.7142 -168.434512)
		(width 0.1143)
		(layer "In2.Cu")
		(net "CPLD_UART_RTS_P4_N")
	)
	(segment
		(start 91.36253 -179.53609)
		(end 92.571062 -179.53609)
		(width 0.1143)
		(layer "In2.Cu")
		(net "CPLD_UART_RTS_P4_N")
	)
	(segment
		(start 120.539256 -179.84724)
		(end 122.53087 -181.838854)
		(width 0.1143)
		(layer "In2.Cu")
		(net "CPLD_UART_RTS_P4_N")
	)
	(segment
		(start 133.982206 -182.655972)
		(end 135.480552 -181.157626)
		(width 0.1143)
		(layer "In2.Cu")
		(net "CPLD_UART_RTS_P4_N")
	)
	(segment
		(start 86.773258 -178.960018)
		(end 90.786458 -178.960018)
		(width 0.1143)
		(layer "In2.Cu")
		(net "CPLD_UART_RTS_P4_N")
	)
	(segment
		(start 113.06683 -180.195474)
		(end 113.415064 -179.84724)
		(width 0.1143)
		(layer "In2.Cu")
		(net "CPLD_UART_RTS_P4_N")
	)
	(segment
		(start 106.068876 -179.812188)
		(end 106.271822 -179.812188)
		(width 0.1143)
		(layer "In2.Cu")
		(net "CPLD_UART_RTS_P4_N")
	)
	(segment
		(start 125.108208 -182.669942)
		(end 129.856992 -182.669942)
		(width 0.1143)
		(layer "In2.Cu")
		(net "CPLD_UART_RTS_P4_N")
	)
	(segment
		(start 144.637252 -169.610786)
		(end 145.077688 -169.17035)
		(width 0.1143)
		(layer "In2.Cu")
		(net "CPLD_UART_RTS_P4_N")
	)
	(segment
		(start 140.56487 -171.861226)
		(end 140.889482 -171.536614)
		(width 0.1143)
		(layer "In2.Cu")
		(net "CPLD_UART_RTS_P4_N")
	)
	(segment
		(start 143.357346 -169.610786)
		(end 144.637252 -169.610786)
		(width 0.1143)
		(layer "In2.Cu")
		(net "CPLD_UART_RTS_P4_N")
	)
	(segment
		(start 129.856992 -182.669942)
		(end 129.870962 -182.655972)
		(width 0.1143)
		(layer "In2.Cu")
		(net "CPLD_UART_RTS_P4_N")
	)
	(segment
		(start 90.786458 -178.960018)
		(end 91.36253 -179.53609)
		(width 0.1143)
		(layer "In2.Cu")
		(net "CPLD_UART_RTS_P4_N")
	)
	(segment
		(start 141.431518 -171.536614)
		(end 143.357346 -169.610786)
		(width 0.1143)
		(layer "In2.Cu")
		(net "CPLD_UART_RTS_P4_N")
	)
	(segment
		(start 105.514394 -179.257706)
		(end 106.068876 -179.812188)
		(width 0.1143)
		(layer "In2.Cu")
		(net "CPLD_UART_RTS_P4_N")
	)
	(segment
		(start 109.22508 -180.195474)
		(end 113.06683 -180.195474)
		(width 0.1143)
		(layer "In2.Cu")
		(net "CPLD_UART_RTS_P4_N")
	)
	(segment
		(start 99.68484 -179.751228)
		(end 100.178362 -179.257706)
		(width 0.1143)
		(layer "In2.Cu")
		(net "CPLD_UART_RTS_P4_N")
	)
	(segment
		(start 109.163358 -180.257196)
		(end 109.22508 -180.195474)
		(width 0.1143)
		(layer "In2.Cu")
		(net "CPLD_UART_RTS_P4_N")
	)
	(segment
		(start 94.890336 -178.89982)
		(end 97.10166 -178.89982)
		(width 0.1143)
		(layer "In2.Cu")
		(net "CPLD_UART_RTS_P4_N")
	)
	(segment
		(start 86.10854 -178.2953)
		(end 86.773258 -178.960018)
		(width 0.1143)
		(layer "In2.Cu")
		(net "CPLD_UART_RTS_P4_N")
	)
	(segment
		(start 113.415064 -179.84724)
		(end 120.539256 -179.84724)
		(width 0.1143)
		(layer "In2.Cu")
		(net "CPLD_UART_RTS_P4_N")
	)
	(segment
		(start 124.27712 -181.838854)
		(end 125.108208 -182.669942)
		(width 0.1143)
		(layer "In2.Cu")
		(net "CPLD_UART_RTS_P4_N")
	)
	(segment
		(start 129.870962 -182.655972)
		(end 133.982206 -182.655972)
		(width 0.1143)
		(layer "In2.Cu")
		(net "CPLD_UART_RTS_P4_N")
	)
	(segment
		(start 147.059396 -169.367962)
		(end 150.78075 -169.367962)
		(width 0.1143)
		(layer "In2.Cu")
		(net "CPLD_UART_RTS_P4_N")
	)
	(segment
		(start 145.077688 -169.17035)
		(end 146.861784 -169.17035)
		(width 0.1143)
		(layer "In2.Cu")
		(net "CPLD_UART_RTS_P4_N")
	)
	(segment
		(start 122.53087 -181.838854)
		(end 124.27712 -181.838854)
		(width 0.1143)
		(layer "In2.Cu")
		(net "CPLD_UART_RTS_P4_N")
	)
	(segment
		(start 139.398248 -178.427126)
		(end 139.826238 -178.427126)
		(width 0.1143)
		(layer "In2.Cu")
		(net "CPLD_UART_RTS_P4_N")
	)
	(segment
		(start 106.71683 -180.257196)
		(end 109.163358 -180.257196)
		(width 0.1143)
		(layer "In2.Cu")
		(net "CPLD_UART_RTS_P4_N")
	)
	(segment
		(start 139.826238 -178.427126)
		(end 140.56487 -177.688494)
		(width 0.1143)
		(layer "In2.Cu")
		(net "CPLD_UART_RTS_P4_N")
	)
	(segment
		(start 86.10854 -177.903124)
		(end 86.10854 -178.2953)
		(width 0.1143)
		(layer "In2.Cu")
		(net "CPLD_UART_RTS_P4_N")
	)
	(segment
		(start 92.939108 -179.904136)
		(end 93.88602 -179.904136)
		(width 0.1143)
		(layer "In2.Cu")
		(net "CPLD_UART_RTS_P4_N")
	)
	(segment
		(start 135.480552 -181.157626)
		(end 136.667748 -181.157626)
		(width 0.1143)
		(layer "In2.Cu")
		(net "CPLD_UART_RTS_P4_N")
	)
	(segment
		(start 146.861784 -169.17035)
		(end 147.059396 -169.367962)
		(width 0.1143)
		(layer "In2.Cu")
		(net "CPLD_UART_RTS_P4_N")
	)
	(segment
		(start 100.178362 -179.257706)
		(end 105.514394 -179.257706)
		(width 0.1143)
		(layer "In2.Cu")
		(net "CPLD_UART_RTS_P4_N")
	)
	(segment
		(start 97.10166 -178.89982)
		(end 97.953068 -179.751228)
		(width 0.1143)
		(layer "In2.Cu")
		(net "CPLD_UART_RTS_P4_N")
	)
	(segment
		(start 140.889482 -171.536614)
		(end 141.431518 -171.536614)
		(width 0.1143)
		(layer "In2.Cu")
		(net "CPLD_UART_RTS_P4_N")
	)
	(segment
		(start 140.56487 -177.688494)
		(end 140.56487 -171.861226)
		(width 0.1143)
		(layer "In2.Cu")
		(net "CPLD_UART_RTS_P4_N")
	)
	(segment
		(start 92.571062 -179.53609)
		(end 92.939108 -179.904136)
		(width 0.1143)
		(layer "In2.Cu")
		(net "CPLD_UART_RTS_P4_N")
	)
	(segment
		(start 136.667748 -181.157626)
		(end 139.398248 -178.427126)
		(width 0.1143)
		(layer "In2.Cu")
		(net "CPLD_UART_RTS_P4_N")
	)
	(segment
		(start 93.88602 -179.904136)
		(end 94.890336 -178.89982)
		(width 0.1143)
		(layer "In2.Cu")
		(net "CPLD_UART_RTS_P4_N")
	)
	(segment
		(start 106.271822 -179.812188)
		(end 106.71683 -180.257196)
		(width 0.1143)
		(layer "In2.Cu")
		(net "CPLD_UART_RTS_P4_N")
	)
	(segment
		(start 154.04338 -169.609262)
		(end 154.04338 -169.47896)
		(width 0.1143)
		(layer "In7.Cu")
		(net "CPLD_UART_RTS_P4_N")
	)
	(segment
		(start 154.08783 -169.653712)
		(end 154.04338 -169.609262)
		(width 0.1143)
		(layer "In7.Cu")
		(net "CPLD_UART_RTS_P4_N")
	)
	(segment
		(start 154.09291 -178.154584)
		(end 153.83637 -177.898044)
		(width 0.1143)
		(layer "In7.Cu")
		(net "CPLD_UART_RTS_P4_N")
	)
	(segment
		(start 153.83637 -177.898044)
		(end 153.83637 -177.533554)
		(width 0.1143)
		(layer "In7.Cu")
		(net "CPLD_UART_RTS_P4_N")
	)
	(segment
		(start 154.71648 -178.154584)
		(end 154.09291 -178.154584)
		(width 0.1143)
		(layer "In7.Cu")
		(net "CPLD_UART_RTS_P4_N")
	)
	(segment
		(start 157.69082 -182.249064)
		(end 156.11856 -180.676804)
		(width 0.1143)
		(layer "In7.Cu")
		(net "CPLD_UART_RTS_P4_N")
	)
	(segment
		(start 153.83637 -177.533554)
		(end 154.08783 -177.282094)
		(width 0.1143)
		(layer "In7.Cu")
		(net "CPLD_UART_RTS_P4_N")
	)
	(segment
		(start 154.04338 -169.47896)
		(end 152.901142 -168.336722)
		(width 0.1143)
		(layer "In7.Cu")
		(net "CPLD_UART_RTS_P4_N")
	)
	(segment
		(start 156.11856 -180.676804)
		(end 156.11856 -179.556664)
		(width 0.1143)
		(layer "In7.Cu")
		(net "CPLD_UART_RTS_P4_N")
	)
	(segment
		(start 152.901142 -168.336722)
		(end 151.81199 -168.336722)
		(width 0.1143)
		(layer "In7.Cu")
		(net "CPLD_UART_RTS_P4_N")
	)
	(segment
		(start 151.81199 -168.336722)
		(end 151.7142 -168.434512)
		(width 0.1143)
		(layer "In7.Cu")
		(net "CPLD_UART_RTS_P4_N")
	)
	(segment
		(start 154.08783 -177.282094)
		(end 154.08783 -169.653712)
		(width 0.1143)
		(layer "In7.Cu")
		(net "CPLD_UART_RTS_P4_N")
	)
	(segment
		(start 156.11856 -179.556664)
		(end 154.71648 -178.154584)
		(width 0.1143)
		(layer "In7.Cu")
		(net "CPLD_UART_RTS_P4_N")
	)
	(segment
		(start 34.990786 -176.244504)
		(end 35.236404 -176.490122)
		(width 0.1016)
		(layer "F.Cu")
		(net "SMB_BMC_NODE1_HSC_ALERT_R_L")
	)
	(segment
		(start 34.990786 -175.85055)
		(end 34.990786 -176.244504)
		(width 0.1016)
		(layer "F.Cu")
		(net "SMB_BMC_NODE1_HSC_ALERT_R_L")
	)
	(segment
		(start 34.63925 -177.765202)
		(end 34.63925 -177.119534)
		(width 0.1016)
		(layer "F.Cu")
		(net "SMB_BMC_NODE1_HSC_ALERT_R_L")
	)
	(segment
		(start 35.236404 -176.490122)
		(end 35.236404 -176.963578)
		(width 0.1016)
		(layer "F.Cu")
		(net "SMB_BMC_NODE1_HSC_ALERT_R_L")
	)
	(segment
		(start 34.795206 -176.963578)
		(end 35.236404 -176.963578)
		(width 0.1016)
		(layer "F.Cu")
		(net "SMB_BMC_NODE1_HSC_ALERT_R_L")
	)
	(segment
		(start 34.63925 -177.119534)
		(end 34.795206 -176.963578)
		(width 0.1016)
		(layer "F.Cu")
		(net "SMB_BMC_NODE1_HSC_ALERT_R_L")
	)
	(via
		(at 35.236404 -176.963578)
		(size 0.508)
		(drill 0.254)
		(layers "F.Cu" "B.Cu")
		(net "SMB_BMC_NODE1_HSC_ALERT_R_L")
	)
	(segment
		(start 32.259778 -174.157132)
		(end 32.64662 -173.77029)
		(width 0.1016)
		(layer "F.Cu")
		(net "SMB_CPU_NODE1_BMC_DAT")
	)
	(segment
		(start 33.13938 -177.765202)
		(end 33.13938 -176.812702)
		(width 0.1016)
		(layer "F.Cu")
		(net "SMB_CPU_NODE1_BMC_DAT")
	)
	(segment
		(start 32.259778 -175.933608)
		(end 32.259778 -174.157132)
		(width 0.1016)
		(layer "F.Cu")
		(net "SMB_CPU_NODE1_BMC_DAT")
	)
	(segment
		(start 145.342102 -142.19555)
		(end 146.085052 -142.19555)
		(width 0.1016)
		(layer "F.Cu")
		(net "SMB_CPU_NODE1_BMC_DAT")
	)
	(segment
		(start 33.110678 -173.77029)
		(end 34.36112 -172.519848)
		(width 0.1016)
		(layer "F.Cu")
		(net "SMB_CPU_NODE1_BMC_DAT")
	)
	(segment
		(start 33.138872 -176.812702)
		(end 32.259778 -175.933608)
		(width 0.1016)
		(layer "F.Cu")
		(net "SMB_CPU_NODE1_BMC_DAT")
	)
	(segment
		(start 32.64662 -173.77029)
		(end 33.110678 -173.77029)
		(width 0.1016)
		(layer "F.Cu")
		(net "SMB_CPU_NODE1_BMC_DAT")
	)
	(segment
		(start 33.13938 -176.812702)
		(end 33.138872 -176.812702)
		(width 0.1016)
		(layer "F.Cu")
		(net "SMB_CPU_NODE1_BMC_DAT")
	)
	(via
		(at 34.36112 -172.519848)
		(size 0.508)
		(drill 0.254)
		(layers "F.Cu" "B.Cu")
		(net "SMB_CPU_NODE1_BMC_DAT")
	)
	(via
		(at 146.085052 -142.19555)
		(size 0.508)
		(drill 0.254)
		(layers "F.Cu" "B.Cu")
		(net "SMB_CPU_NODE1_BMC_DAT")
	)
	(via
		(at 44.618402 -98.151696)
		(size 0.508)
		(drill 0.254)
		(layers "F.Cu" "B.Cu")
		(net "SMB_CPU_NODE1_BMC_DAT")
	)
	(segment
		(start 44.618402 -98.151696)
		(end 44.618402 -97.782888)
		(width 0.1016)
		(layer "B.Cu")
		(net "SMB_CPU_NODE1_BMC_DAT")
	)
	(segment
		(start 45.734732 -94.80042)
		(end 45.734732 -96.61271)
		(width 0.1016)
		(layer "B.Cu")
		(net "SMB_CPU_NODE1_BMC_DAT")
	)
	(segment
		(start 45.669454 -96.731836)
		(end 45.669454 -96.677988)
		(width 0.1016)
		(layer "B.Cu")
		(net "SMB_CPU_NODE1_BMC_DAT")
	)
	(segment
		(start 45.734732 -96.61271)
		(end 45.669454 -96.677988)
		(width 0.1016)
		(layer "B.Cu")
		(net "SMB_CPU_NODE1_BMC_DAT")
	)
	(segment
		(start 44.618402 -97.782888)
		(end 45.669454 -96.731836)
		(width 0.1016)
		(layer "B.Cu")
		(net "SMB_CPU_NODE1_BMC_DAT")
	)
	(segment
		(start 42.113708 -119.484902)
		(end 37.08146 -124.51715)
		(width 0.1143)
		(layer "In2.Cu")
		(net "SMB_CPU_NODE1_BMC_DAT")
	)
	(segment
		(start 84.14004 -160.064704)
		(end 81.395824 -160.064704)
		(width 0.1143)
		(layer "In2.Cu")
		(net "SMB_CPU_NODE1_BMC_DAT")
	)
	(segment
		(start 144.43964 -144.280636)
		(end 144.43964 -149.505162)
		(width 0.1143)
		(layer "In2.Cu")
		(net "SMB_CPU_NODE1_BMC_DAT")
	)
	(segment
		(start 67.417442 -165.721284)
		(end 67.124326 -166.0144)
		(width 0.1143)
		(layer "In2.Cu")
		(net "SMB_CPU_NODE1_BMC_DAT")
	)
	(segment
		(start 72.44588 -164.02177)
		(end 72.44588 -164.69233)
		(width 0.1143)
		(layer "In2.Cu")
		(net "SMB_CPU_NODE1_BMC_DAT")
	)
	(segment
		(start 131.90728 -153.80208)
		(end 131.58724 -154.12212)
		(width 0.1143)
		(layer "In2.Cu")
		(net "SMB_CPU_NODE1_BMC_DAT")
	)
	(segment
		(start 122.29592 -155.09494)
		(end 114.763804 -147.562824)
		(width 0.1143)
		(layer "In2.Cu")
		(net "SMB_CPU_NODE1_BMC_DAT")
	)
	(segment
		(start 85.0646 -159.140144)
		(end 84.14004 -160.064704)
		(width 0.1143)
		(layer "In2.Cu")
		(net "SMB_CPU_NODE1_BMC_DAT")
	)
	(segment
		(start 36.28136 -171.928028)
		(end 35.68954 -172.519848)
		(width 0.1143)
		(layer "In2.Cu")
		(net "SMB_CPU_NODE1_BMC_DAT")
	)
	(segment
		(start 128.524 -154.770582)
		(end 128.199642 -155.09494)
		(width 0.1143)
		(layer "In2.Cu")
		(net "SMB_CPU_NODE1_BMC_DAT")
	)
	(segment
		(start 146.085052 -142.19555)
		(end 146.085052 -142.635224)
		(width 0.1143)
		(layer "In2.Cu")
		(net "SMB_CPU_NODE1_BMC_DAT")
	)
	(segment
		(start 140.800836 -153.143966)
		(end 139.92479 -153.143966)
		(width 0.1143)
		(layer "In2.Cu")
		(net "SMB_CPU_NODE1_BMC_DAT")
	)
	(segment
		(start 62.58814 -166.0144)
		(end 61.875416 -165.301676)
		(width 0.1143)
		(layer "In2.Cu")
		(net "SMB_CPU_NODE1_BMC_DAT")
	)
	(segment
		(start 139.556236 -153.140156)
		(end 138.894312 -153.80208)
		(width 0.1143)
		(layer "In2.Cu")
		(net "SMB_CPU_NODE1_BMC_DAT")
	)
	(segment
		(start 33.29686 -138.167618)
		(end 33.29686 -143.353282)
		(width 0.1143)
		(layer "In2.Cu")
		(net "SMB_CPU_NODE1_BMC_DAT")
	)
	(segment
		(start 89.252552 -147.562824)
		(end 85.0646 -151.750776)
		(width 0.1143)
		(layer "In2.Cu")
		(net "SMB_CPU_NODE1_BMC_DAT")
	)
	(segment
		(start 144.43964 -149.505162)
		(end 140.800836 -153.143966)
		(width 0.1143)
		(layer "In2.Cu")
		(net "SMB_CPU_NODE1_BMC_DAT")
	)
	(segment
		(start 138.894312 -153.80208)
		(end 131.90728 -153.80208)
		(width 0.1143)
		(layer "In2.Cu")
		(net "SMB_CPU_NODE1_BMC_DAT")
	)
	(segment
		(start 44.207684 -168.171114)
		(end 43.612308 -168.76649)
		(width 0.1143)
		(layer "In2.Cu")
		(net "SMB_CPU_NODE1_BMC_DAT")
	)
	(segment
		(start 36.28136 -169.660062)
		(end 36.28136 -171.928028)
		(width 0.1143)
		(layer "In2.Cu")
		(net "SMB_CPU_NODE1_BMC_DAT")
	)
	(segment
		(start 56.36006 -165.301676)
		(end 56.039766 -165.62197)
		(width 0.1143)
		(layer "In2.Cu")
		(net "SMB_CPU_NODE1_BMC_DAT")
	)
	(segment
		(start 43.612308 -168.76649)
		(end 37.174932 -168.76649)
		(width 0.1143)
		(layer "In2.Cu")
		(net "SMB_CPU_NODE1_BMC_DAT")
	)
	(segment
		(start 37.08146 -134.383018)
		(end 33.29686 -138.167618)
		(width 0.1143)
		(layer "In2.Cu")
		(net "SMB_CPU_NODE1_BMC_DAT")
	)
	(segment
		(start 47.704756 -168.171114)
		(end 44.207684 -168.171114)
		(width 0.1143)
		(layer "In2.Cu")
		(net "SMB_CPU_NODE1_BMC_DAT")
	)
	(segment
		(start 68.088764 -165.721284)
		(end 67.417442 -165.721284)
		(width 0.1143)
		(layer "In2.Cu")
		(net "SMB_CPU_NODE1_BMC_DAT")
	)
	(segment
		(start 32.78251 -143.867632)
		(end 32.78251 -168.2115)
		(width 0.1143)
		(layer "In2.Cu")
		(net "SMB_CPU_NODE1_BMC_DAT")
	)
	(segment
		(start 81.395824 -160.064704)
		(end 80.683608 -160.77692)
		(width 0.1143)
		(layer "In2.Cu")
		(net "SMB_CPU_NODE1_BMC_DAT")
	)
	(segment
		(start 139.92098 -153.140156)
		(end 139.556236 -153.140156)
		(width 0.1143)
		(layer "In2.Cu")
		(net "SMB_CPU_NODE1_BMC_DAT")
	)
	(segment
		(start 35.68954 -172.519848)
		(end 34.36112 -172.519848)
		(width 0.1143)
		(layer "In2.Cu")
		(net "SMB_CPU_NODE1_BMC_DAT")
	)
	(segment
		(start 78.397608 -160.350708)
		(end 76.116942 -160.350708)
		(width 0.1143)
		(layer "In2.Cu")
		(net "SMB_CPU_NODE1_BMC_DAT")
	)
	(segment
		(start 128.524 -154.765502)
		(end 128.524 -154.770582)
		(width 0.1143)
		(layer "In2.Cu")
		(net "SMB_CPU_NODE1_BMC_DAT")
	)
	(segment
		(start 129.167382 -154.12212)
		(end 128.524 -154.765502)
		(width 0.1143)
		(layer "In2.Cu")
		(net "SMB_CPU_NODE1_BMC_DAT")
	)
	(segment
		(start 71.49846 -165.63975)
		(end 70.176644 -165.63975)
		(width 0.1143)
		(layer "In2.Cu")
		(net "SMB_CPU_NODE1_BMC_DAT")
	)
	(segment
		(start 85.0646 -151.750776)
		(end 85.0646 -159.140144)
		(width 0.1143)
		(layer "In2.Cu")
		(net "SMB_CPU_NODE1_BMC_DAT")
	)
	(segment
		(start 56.039766 -165.62197)
		(end 50.2539 -165.62197)
		(width 0.1143)
		(layer "In2.Cu")
		(net "SMB_CPU_NODE1_BMC_DAT")
	)
	(segment
		(start 37.08146 -124.51715)
		(end 37.08146 -134.383018)
		(width 0.1143)
		(layer "In2.Cu")
		(net "SMB_CPU_NODE1_BMC_DAT")
	)
	(segment
		(start 42.113708 -103.872284)
		(end 42.113708 -119.484902)
		(width 0.1143)
		(layer "In2.Cu")
		(net "SMB_CPU_NODE1_BMC_DAT")
	)
	(segment
		(start 69.96303 -165.853364)
		(end 68.220844 -165.853364)
		(width 0.1143)
		(layer "In2.Cu")
		(net "SMB_CPU_NODE1_BMC_DAT")
	)
	(segment
		(start 42.3799 -100.390198)
		(end 42.3799 -103.606092)
		(width 0.1143)
		(layer "In2.Cu")
		(net "SMB_CPU_NODE1_BMC_DAT")
	)
	(segment
		(start 50.2539 -165.62197)
		(end 47.704756 -168.171114)
		(width 0.1143)
		(layer "In2.Cu")
		(net "SMB_CPU_NODE1_BMC_DAT")
	)
	(segment
		(start 61.875416 -165.301676)
		(end 56.36006 -165.301676)
		(width 0.1143)
		(layer "In2.Cu")
		(net "SMB_CPU_NODE1_BMC_DAT")
	)
	(segment
		(start 139.92479 -153.143966)
		(end 139.92098 -153.140156)
		(width 0.1143)
		(layer "In2.Cu")
		(net "SMB_CPU_NODE1_BMC_DAT")
	)
	(segment
		(start 44.618402 -98.151696)
		(end 42.3799 -100.390198)
		(width 0.1143)
		(layer "In2.Cu")
		(net "SMB_CPU_NODE1_BMC_DAT")
	)
	(segment
		(start 33.29686 -143.353282)
		(end 32.78251 -143.867632)
		(width 0.1143)
		(layer "In2.Cu")
		(net "SMB_CPU_NODE1_BMC_DAT")
	)
	(segment
		(start 34.36112 -169.79011)
		(end 34.36112 -172.519848)
		(width 0.1143)
		(layer "In2.Cu")
		(net "SMB_CPU_NODE1_BMC_DAT")
	)
	(segment
		(start 128.199642 -155.09494)
		(end 122.29592 -155.09494)
		(width 0.1143)
		(layer "In2.Cu")
		(net "SMB_CPU_NODE1_BMC_DAT")
	)
	(segment
		(start 72.44588 -164.69233)
		(end 71.49846 -165.63975)
		(width 0.1143)
		(layer "In2.Cu")
		(net "SMB_CPU_NODE1_BMC_DAT")
	)
	(segment
		(start 80.683608 -160.77692)
		(end 78.82382 -160.77692)
		(width 0.1143)
		(layer "In2.Cu")
		(net "SMB_CPU_NODE1_BMC_DAT")
	)
	(segment
		(start 131.58724 -154.12212)
		(end 129.167382 -154.12212)
		(width 0.1143)
		(layer "In2.Cu")
		(net "SMB_CPU_NODE1_BMC_DAT")
	)
	(segment
		(start 42.3799 -103.606092)
		(end 42.113708 -103.872284)
		(width 0.1143)
		(layer "In2.Cu")
		(net "SMB_CPU_NODE1_BMC_DAT")
	)
	(segment
		(start 70.176644 -165.63975)
		(end 69.96303 -165.853364)
		(width 0.1143)
		(layer "In2.Cu")
		(net "SMB_CPU_NODE1_BMC_DAT")
	)
	(segment
		(start 76.116942 -160.350708)
		(end 72.44588 -164.02177)
		(width 0.1143)
		(layer "In2.Cu")
		(net "SMB_CPU_NODE1_BMC_DAT")
	)
	(segment
		(start 146.085052 -142.635224)
		(end 144.43964 -144.280636)
		(width 0.1143)
		(layer "In2.Cu")
		(net "SMB_CPU_NODE1_BMC_DAT")
	)
	(segment
		(start 114.763804 -147.562824)
		(end 89.252552 -147.562824)
		(width 0.1143)
		(layer "In2.Cu")
		(net "SMB_CPU_NODE1_BMC_DAT")
	)
	(segment
		(start 37.174932 -168.76649)
		(end 36.28136 -169.660062)
		(width 0.1143)
		(layer "In2.Cu")
		(net "SMB_CPU_NODE1_BMC_DAT")
	)
	(segment
		(start 78.82382 -160.77692)
		(end 78.397608 -160.350708)
		(width 0.1143)
		(layer "In2.Cu")
		(net "SMB_CPU_NODE1_BMC_DAT")
	)
	(segment
		(start 68.220844 -165.853364)
		(end 68.088764 -165.721284)
		(width 0.1143)
		(layer "In2.Cu")
		(net "SMB_CPU_NODE1_BMC_DAT")
	)
	(segment
		(start 67.124326 -166.0144)
		(end 62.58814 -166.0144)
		(width 0.1143)
		(layer "In2.Cu")
		(net "SMB_CPU_NODE1_BMC_DAT")
	)
	(segment
		(start 32.78251 -168.2115)
		(end 34.36112 -169.79011)
		(width 0.1143)
		(layer "In2.Cu")
		(net "SMB_CPU_NODE1_BMC_DAT")
	)
	(segment
		(start 80.72628 -163.324286)
		(end 80.494632 -163.555934)
		(width 0.1016)
		(layer "F.Cu")
		(net "CLK_33K_CPLD23")
	)
	(segment
		(start 80.494632 -163.555934)
		(end 80.494632 -164.374576)
		(width 0.1016)
		(layer "F.Cu")
		(net "CLK_33K_CPLD23")
	)
	(segment
		(start 138.025632 -163.358576)
		(end 138.0236 -163.356544)
		(width 0.1016)
		(layer "F.Cu")
		(net "CLK_33K_CPLD23")
	)
	(segment
		(start 81.626456 -161.249106)
		(end 80.72628 -162.149282)
		(width 0.1016)
		(layer "F.Cu")
		(net "CLK_33K_CPLD23")
	)
	(segment
		(start 138.0236 -163.356544)
		(end 138.0236 -161.44621)
		(width 0.1016)
		(layer "F.Cu")
		(net "CLK_33K_CPLD23")
	)
	(segment
		(start 138.0236 -161.44621)
		(end 138.0236 -160.643824)
		(width 0.1016)
		(layer "F.Cu")
		(net "CLK_33K_CPLD23")
	)
	(segment
		(start 80.72628 -162.149282)
		(end 80.72628 -163.324286)
		(width 0.1016)
		(layer "F.Cu")
		(net "CLK_33K_CPLD23")
	)
	(segment
		(start 87.77732 -162.079686)
		(end 86.94674 -161.249106)
		(width 0.1016)
		(layer "F.Cu")
		(net "CLK_33K_CPLD23")
	)
	(segment
		(start 86.94674 -161.249106)
		(end 81.626456 -161.249106)
		(width 0.1016)
		(layer "F.Cu")
		(net "CLK_33K_CPLD23")
	)
	(via
		(at 87.77732 -162.079686)
		(size 0.508)
		(drill 0.254)
		(layers "F.Cu" "B.Cu")
		(net "CLK_33K_CPLD23")
	)
	(via
		(at 138.0236 -161.44621)
		(size 0.508)
		(drill 0.254)
		(layers "F.Cu" "B.Cu")
		(net "CLK_33K_CPLD23")
	)
	(segment
		(start 95.166434 -163.152074)
		(end 96.671638 -163.152074)
		(width 0.1143)
		(layer "In2.Cu")
		(net "CLK_33K_CPLD23")
	)
	(segment
		(start 115.66652 -163.067746)
		(end 116.845588 -161.888678)
		(width 0.1143)
		(layer "In2.Cu")
		(net "CLK_33K_CPLD23")
	)
	(segment
		(start 87.77732 -162.079686)
		(end 88.101424 -161.755582)
		(width 0.1143)
		(layer "In2.Cu")
		(net "CLK_33K_CPLD23")
	)
	(segment
		(start 129.61112 -161.727642)
		(end 132.13461 -161.727642)
		(width 0.1143)
		(layer "In2.Cu")
		(net "CLK_33K_CPLD23")
	)
	(segment
		(start 88.101424 -161.755582)
		(end 88.90254 -161.755582)
		(width 0.1143)
		(layer "In2.Cu")
		(net "CLK_33K_CPLD23")
	)
	(segment
		(start 93.98889 -161.97453)
		(end 95.166434 -163.152074)
		(width 0.1143)
		(layer "In2.Cu")
		(net "CLK_33K_CPLD23")
	)
	(segment
		(start 110.227364 -162.792156)
		(end 111.66348 -162.792156)
		(width 0.1143)
		(layer "In2.Cu")
		(net "CLK_33K_CPLD23")
	)
	(segment
		(start 98.707448 -164.61867)
		(end 102.664514 -164.61867)
		(width 0.1143)
		(layer "In2.Cu")
		(net "CLK_33K_CPLD23")
	)
	(segment
		(start 132.416042 -161.44621)
		(end 138.0236 -161.44621)
		(width 0.1143)
		(layer "In2.Cu")
		(net "CLK_33K_CPLD23")
	)
	(segment
		(start 126.275592 -161.667698)
		(end 129.551176 -161.667698)
		(width 0.1143)
		(layer "In2.Cu")
		(net "CLK_33K_CPLD23")
	)
	(segment
		(start 88.90254 -161.755582)
		(end 89.121488 -161.97453)
		(width 0.1143)
		(layer "In2.Cu")
		(net "CLK_33K_CPLD23")
	)
	(segment
		(start 118.555262 -161.888678)
		(end 120.018302 -160.425638)
		(width 0.1143)
		(layer "In2.Cu")
		(net "CLK_33K_CPLD23")
	)
	(segment
		(start 109.527086 -163.492434)
		(end 110.227364 -162.792156)
		(width 0.1143)
		(layer "In2.Cu")
		(net "CLK_33K_CPLD23")
	)
	(segment
		(start 103.563674 -163.71951)
		(end 107.191556 -163.71951)
		(width 0.1143)
		(layer "In2.Cu")
		(net "CLK_33K_CPLD23")
	)
	(segment
		(start 96.671638 -163.152074)
		(end 96.953832 -163.434268)
		(width 0.1143)
		(layer "In2.Cu")
		(net "CLK_33K_CPLD23")
	)
	(segment
		(start 125.033532 -160.425638)
		(end 126.275592 -161.667698)
		(width 0.1143)
		(layer "In2.Cu")
		(net "CLK_33K_CPLD23")
	)
	(segment
		(start 132.13461 -161.727642)
		(end 132.416042 -161.44621)
		(width 0.1143)
		(layer "In2.Cu")
		(net "CLK_33K_CPLD23")
	)
	(segment
		(start 89.121488 -161.97453)
		(end 93.98889 -161.97453)
		(width 0.1143)
		(layer "In2.Cu")
		(net "CLK_33K_CPLD23")
	)
	(segment
		(start 129.551176 -161.667698)
		(end 129.61112 -161.727642)
		(width 0.1143)
		(layer "In2.Cu")
		(net "CLK_33K_CPLD23")
	)
	(segment
		(start 102.664514 -164.61867)
		(end 103.563674 -163.71951)
		(width 0.1143)
		(layer "In2.Cu")
		(net "CLK_33K_CPLD23")
	)
	(segment
		(start 96.953832 -163.434268)
		(end 97.523046 -163.434268)
		(width 0.1143)
		(layer "In2.Cu")
		(net "CLK_33K_CPLD23")
	)
	(segment
		(start 107.191556 -163.71951)
		(end 107.418632 -163.492434)
		(width 0.1143)
		(layer "In2.Cu")
		(net "CLK_33K_CPLD23")
	)
	(segment
		(start 97.523046 -163.434268)
		(end 98.707448 -164.61867)
		(width 0.1143)
		(layer "In2.Cu")
		(net "CLK_33K_CPLD23")
	)
	(segment
		(start 116.845588 -161.888678)
		(end 118.555262 -161.888678)
		(width 0.1143)
		(layer "In2.Cu")
		(net "CLK_33K_CPLD23")
	)
	(segment
		(start 120.018302 -160.425638)
		(end 125.033532 -160.425638)
		(width 0.1143)
		(layer "In2.Cu")
		(net "CLK_33K_CPLD23")
	)
	(segment
		(start 111.66348 -162.792156)
		(end 111.93907 -163.067746)
		(width 0.1143)
		(layer "In2.Cu")
		(net "CLK_33K_CPLD23")
	)
	(segment
		(start 111.93907 -163.067746)
		(end 115.66652 -163.067746)
		(width 0.1143)
		(layer "In2.Cu")
		(net "CLK_33K_CPLD23")
	)
	(segment
		(start 107.418632 -163.492434)
		(end 109.527086 -163.492434)
		(width 0.1143)
		(layer "In2.Cu")
		(net "CLK_33K_CPLD23")
	)
	(segment
		(start 32.476694 -173.28769)
		(end 33.08604 -172.678344)
		(width 0.1016)
		(layer "F.Cu")
		(net "SMB_CPU_NODE1_BMC_CLK")
	)
	(segment
		(start 31.7754 -176.267618)
		(end 31.7754 -173.95698)
		(width 0.1016)
		(layer "F.Cu")
		(net "SMB_CPU_NODE1_BMC_CLK")
	)
	(segment
		(start 32.639254 -177.131472)
		(end 31.7754 -176.267618)
		(width 0.1016)
		(layer "F.Cu")
		(net "SMB_CPU_NODE1_BMC_CLK")
	)
	(segment
		(start 31.7754 -173.95698)
		(end 31.77667 -173.95698)
		(width 0.1016)
		(layer "F.Cu")
		(net "SMB_CPU_NODE1_BMC_CLK")
	)
	(segment
		(start 32.44596 -173.28769)
		(end 32.476694 -173.28769)
		(width 0.1016)
		(layer "F.Cu")
		(net "SMB_CPU_NODE1_BMC_CLK")
	)
	(segment
		(start 32.639254 -177.765202)
		(end 32.639254 -177.131472)
		(width 0.1016)
		(layer "F.Cu")
		(net "SMB_CPU_NODE1_BMC_CLK")
	)
	(segment
		(start 145.316702 -141.20495)
		(end 145.754852 -141.20495)
		(width 0.1016)
		(layer "F.Cu")
		(net "SMB_CPU_NODE1_BMC_CLK")
	)
	(segment
		(start 145.754852 -141.20495)
		(end 146.059652 -140.90015)
		(width 0.1016)
		(layer "F.Cu")
		(net "SMB_CPU_NODE1_BMC_CLK")
	)
	(segment
		(start 31.77667 -173.95698)
		(end 32.44596 -173.28769)
		(width 0.1016)
		(layer "F.Cu")
		(net "SMB_CPU_NODE1_BMC_CLK")
	)
	(via
		(at 33.08604 -172.678344)
		(size 0.508)
		(drill 0.254)
		(layers "F.Cu" "B.Cu")
		(net "SMB_CPU_NODE1_BMC_CLK")
	)
	(via
		(at 146.059652 -140.90015)
		(size 0.508)
		(drill 0.254)
		(layers "F.Cu" "B.Cu")
		(net "SMB_CPU_NODE1_BMC_CLK")
	)
	(via
		(at 40.82034 -97.547176)
		(size 0.508)
		(drill 0.254)
		(layers "F.Cu" "B.Cu")
		(net "SMB_CPU_NODE1_BMC_CLK")
	)
	(segment
		(start 39.941246 -96.668082)
		(end 40.82034 -97.547176)
		(width 0.1016)
		(layer "B.Cu")
		(net "SMB_CPU_NODE1_BMC_CLK")
	)
	(segment
		(start 39.650416 -94.812104)
		(end 39.650416 -96.668082)
		(width 0.1016)
		(layer "B.Cu")
		(net "SMB_CPU_NODE1_BMC_CLK")
	)
	(segment
		(start 39.650416 -96.668082)
		(end 39.941246 -96.668082)
		(width 0.1016)
		(layer "B.Cu")
		(net "SMB_CPU_NODE1_BMC_CLK")
	)
	(segment
		(start 39.638732 -94.80042)
		(end 39.650416 -94.812104)
		(width 0.1016)
		(layer "B.Cu")
		(net "SMB_CPU_NODE1_BMC_CLK")
	)
	(segment
		(start 32.77108 -142.888462)
		(end 32.77108 -137.992104)
		(width 0.1143)
		(layer "In2.Cu")
		(net "SMB_CPU_NODE1_BMC_CLK")
	)
	(segment
		(start 85.56244 -159.345122)
		(end 85.56244 -158.935166)
		(width 0.1143)
		(layer "In2.Cu")
		(net "SMB_CPU_NODE1_BMC_CLK")
	)
	(segment
		(start 112.437672 -148.412962)
		(end 112.778794 -148.754084)
		(width 0.1143)
		(layer "In2.Cu")
		(net "SMB_CPU_NODE1_BMC_CLK")
	)
	(segment
		(start 32.13481 -143.524732)
		(end 32.77108 -142.888462)
		(width 0.1143)
		(layer "In2.Cu")
		(net "SMB_CPU_NODE1_BMC_CLK")
	)
	(segment
		(start 37.37991 -169.262044)
		(end 47.31639 -169.262044)
		(width 0.1143)
		(layer "In2.Cu")
		(net "SMB_CPU_NODE1_BMC_CLK")
	)
	(segment
		(start 33.08604 -172.678344)
		(end 33.08604 -170.444922)
		(width 0.1143)
		(layer "In2.Cu")
		(net "SMB_CPU_NODE1_BMC_CLK")
	)
	(segment
		(start 35.894772 -173.015148)
		(end 36.81222 -172.0977)
		(width 0.1143)
		(layer "In2.Cu")
		(net "SMB_CPU_NODE1_BMC_CLK")
	)
	(segment
		(start 80.561434 -161.60115)
		(end 81.60258 -160.560004)
		(width 0.1143)
		(layer "In2.Cu")
		(net "SMB_CPU_NODE1_BMC_CLK")
	)
	(segment
		(start 90.223086 -148.412962)
		(end 112.437672 -148.412962)
		(width 0.1143)
		(layer "In2.Cu")
		(net "SMB_CPU_NODE1_BMC_CLK")
	)
	(segment
		(start 75.660758 -163.52266)
		(end 75.917298 -163.26612)
		(width 0.1143)
		(layer "In2.Cu")
		(net "SMB_CPU_NODE1_BMC_CLK")
	)
	(segment
		(start 33.675574 -172.678344)
		(end 34.012378 -173.015148)
		(width 0.1143)
		(layer "In2.Cu")
		(net "SMB_CPU_NODE1_BMC_CLK")
	)
	(segment
		(start 36.58616 -134.177024)
		(end 36.58616 -124.096526)
		(width 0.1143)
		(layer "In2.Cu")
		(net "SMB_CPU_NODE1_BMC_CLK")
	)
	(segment
		(start 76.601828 -161.469324)
		(end 78.539086 -161.469324)
		(width 0.1143)
		(layer "In2.Cu")
		(net "SMB_CPU_NODE1_BMC_CLK")
	)
	(segment
		(start 69.778372 -166.88181)
		(end 70.525132 -166.13505)
		(width 0.1143)
		(layer "In2.Cu")
		(net "SMB_CPU_NODE1_BMC_CLK")
	)
	(segment
		(start 78.90764 -161.837878)
		(end 79.2734 -161.837878)
		(width 0.1143)
		(layer "In2.Cu")
		(net "SMB_CPU_NODE1_BMC_CLK")
	)
	(segment
		(start 47.31639 -169.262044)
		(end 50.334926 -166.243508)
		(width 0.1143)
		(layer "In2.Cu")
		(net "SMB_CPU_NODE1_BMC_CLK")
	)
	(segment
		(start 78.539086 -161.469324)
		(end 78.90764 -161.837878)
		(width 0.1143)
		(layer "In2.Cu")
		(net "SMB_CPU_NODE1_BMC_CLK")
	)
	(segment
		(start 146.580352 -141.990318)
		(end 146.059652 -141.469618)
		(width 0.1143)
		(layer "In2.Cu")
		(net "SMB_CPU_NODE1_BMC_CLK")
	)
	(segment
		(start 41.88206 -103.377746)
		(end 41.88206 -98.608896)
		(width 0.1143)
		(layer "In2.Cu")
		(net "SMB_CPU_NODE1_BMC_CLK")
	)
	(segment
		(start 131.04876 -155.36164)
		(end 132.11302 -154.29738)
		(width 0.1143)
		(layer "In2.Cu")
		(net "SMB_CPU_NODE1_BMC_CLK")
	)
	(segment
		(start 61.650372 -166.243508)
		(end 62.098428 -166.691564)
		(width 0.1143)
		(layer "In2.Cu")
		(net "SMB_CPU_NODE1_BMC_CLK")
	)
	(segment
		(start 115.254532 -148.754084)
		(end 122.090688 -155.59024)
		(width 0.1143)
		(layer "In2.Cu")
		(net "SMB_CPU_NODE1_BMC_CLK")
	)
	(segment
		(start 81.60258 -160.560004)
		(end 84.34578 -160.560004)
		(width 0.1143)
		(layer "In2.Cu")
		(net "SMB_CPU_NODE1_BMC_CLK")
	)
	(segment
		(start 41.618408 -103.641398)
		(end 41.88206 -103.377746)
		(width 0.1143)
		(layer "In2.Cu")
		(net "SMB_CPU_NODE1_BMC_CLK")
	)
	(segment
		(start 41.88206 -98.608896)
		(end 40.82034 -97.547176)
		(width 0.1143)
		(layer "In2.Cu")
		(net "SMB_CPU_NODE1_BMC_CLK")
	)
	(segment
		(start 85.56244 -158.935166)
		(end 85.5599 -158.932626)
		(width 0.1143)
		(layer "In2.Cu")
		(net "SMB_CPU_NODE1_BMC_CLK")
	)
	(segment
		(start 67.85356 -166.88181)
		(end 69.778372 -166.88181)
		(width 0.1143)
		(layer "In2.Cu")
		(net "SMB_CPU_NODE1_BMC_CLK")
	)
	(segment
		(start 84.34578 -160.560004)
		(end 85.560662 -159.345122)
		(width 0.1143)
		(layer "In2.Cu")
		(net "SMB_CPU_NODE1_BMC_CLK")
	)
	(segment
		(start 36.81222 -172.0977)
		(end 36.81222 -169.829734)
		(width 0.1143)
		(layer "In2.Cu")
		(net "SMB_CPU_NODE1_BMC_CLK")
	)
	(segment
		(start 85.560662 -159.345122)
		(end 85.56244 -159.345122)
		(width 0.1143)
		(layer "In2.Cu")
		(net "SMB_CPU_NODE1_BMC_CLK")
	)
	(segment
		(start 75.11034 -163.52266)
		(end 75.660758 -163.52266)
		(width 0.1143)
		(layer "In2.Cu")
		(net "SMB_CPU_NODE1_BMC_CLK")
	)
	(segment
		(start 144.93494 -144.486376)
		(end 146.580352 -142.840964)
		(width 0.1143)
		(layer "In2.Cu")
		(net "SMB_CPU_NODE1_BMC_CLK")
	)
	(segment
		(start 112.778794 -148.754084)
		(end 115.254532 -148.754084)
		(width 0.1143)
		(layer "In2.Cu")
		(net "SMB_CPU_NODE1_BMC_CLK")
	)
	(segment
		(start 34.012378 -173.015148)
		(end 35.894772 -173.015148)
		(width 0.1143)
		(layer "In2.Cu")
		(net "SMB_CPU_NODE1_BMC_CLK")
	)
	(segment
		(start 144.93494 -149.710394)
		(end 144.93494 -144.486376)
		(width 0.1143)
		(layer "In2.Cu")
		(net "SMB_CPU_NODE1_BMC_CLK")
	)
	(segment
		(start 36.58616 -124.096526)
		(end 41.618408 -119.064278)
		(width 0.1143)
		(layer "In2.Cu")
		(net "SMB_CPU_NODE1_BMC_CLK")
	)
	(segment
		(start 50.334926 -166.243508)
		(end 61.650372 -166.243508)
		(width 0.1143)
		(layer "In2.Cu")
		(net "SMB_CPU_NODE1_BMC_CLK")
	)
	(segment
		(start 79.510128 -161.60115)
		(end 80.561434 -161.60115)
		(width 0.1143)
		(layer "In2.Cu")
		(net "SMB_CPU_NODE1_BMC_CLK")
	)
	(segment
		(start 67.663314 -166.691564)
		(end 67.85356 -166.88181)
		(width 0.1143)
		(layer "In2.Cu")
		(net "SMB_CPU_NODE1_BMC_CLK")
	)
	(segment
		(start 79.2734 -161.837878)
		(end 79.510128 -161.60115)
		(width 0.1143)
		(layer "In2.Cu")
		(net "SMB_CPU_NODE1_BMC_CLK")
	)
	(segment
		(start 146.580352 -142.840964)
		(end 146.580352 -141.990318)
		(width 0.1143)
		(layer "In2.Cu")
		(net "SMB_CPU_NODE1_BMC_CLK")
	)
	(segment
		(start 32.77108 -137.992104)
		(end 36.58616 -134.177024)
		(width 0.1143)
		(layer "In2.Cu")
		(net "SMB_CPU_NODE1_BMC_CLK")
	)
	(segment
		(start 41.618408 -119.064278)
		(end 41.618408 -103.641398)
		(width 0.1143)
		(layer "In2.Cu")
		(net "SMB_CPU_NODE1_BMC_CLK")
	)
	(segment
		(start 132.11302 -154.29738)
		(end 140.347954 -154.29738)
		(width 0.1143)
		(layer "In2.Cu")
		(net "SMB_CPU_NODE1_BMC_CLK")
	)
	(segment
		(start 36.81222 -169.829734)
		(end 37.37991 -169.262044)
		(width 0.1143)
		(layer "In2.Cu")
		(net "SMB_CPU_NODE1_BMC_CLK")
	)
	(segment
		(start 33.08604 -172.678344)
		(end 33.675574 -172.678344)
		(width 0.1143)
		(layer "In2.Cu")
		(net "SMB_CPU_NODE1_BMC_CLK")
	)
	(segment
		(start 140.347954 -154.29738)
		(end 144.93494 -149.710394)
		(width 0.1143)
		(layer "In2.Cu")
		(net "SMB_CPU_NODE1_BMC_CLK")
	)
	(segment
		(start 85.5599 -158.932626)
		(end 85.5599 -153.076148)
		(width 0.1143)
		(layer "In2.Cu")
		(net "SMB_CPU_NODE1_BMC_CLK")
	)
	(segment
		(start 128.40716 -155.59024)
		(end 128.63576 -155.36164)
		(width 0.1143)
		(layer "In2.Cu")
		(net "SMB_CPU_NODE1_BMC_CLK")
	)
	(segment
		(start 72.498204 -166.13505)
		(end 75.11034 -163.52266)
		(width 0.1143)
		(layer "In2.Cu")
		(net "SMB_CPU_NODE1_BMC_CLK")
	)
	(segment
		(start 122.090688 -155.59024)
		(end 128.40716 -155.59024)
		(width 0.1143)
		(layer "In2.Cu")
		(net "SMB_CPU_NODE1_BMC_CLK")
	)
	(segment
		(start 62.098428 -166.691564)
		(end 67.663314 -166.691564)
		(width 0.1143)
		(layer "In2.Cu")
		(net "SMB_CPU_NODE1_BMC_CLK")
	)
	(segment
		(start 75.917298 -163.26612)
		(end 75.917298 -162.153854)
		(width 0.1143)
		(layer "In2.Cu")
		(net "SMB_CPU_NODE1_BMC_CLK")
	)
	(segment
		(start 128.63576 -155.36164)
		(end 131.04876 -155.36164)
		(width 0.1143)
		(layer "In2.Cu")
		(net "SMB_CPU_NODE1_BMC_CLK")
	)
	(segment
		(start 146.059652 -141.469618)
		(end 146.059652 -140.90015)
		(width 0.1143)
		(layer "In2.Cu")
		(net "SMB_CPU_NODE1_BMC_CLK")
	)
	(segment
		(start 85.5599 -153.076148)
		(end 90.223086 -148.412962)
		(width 0.1143)
		(layer "In2.Cu")
		(net "SMB_CPU_NODE1_BMC_CLK")
	)
	(segment
		(start 70.525132 -166.13505)
		(end 72.498204 -166.13505)
		(width 0.1143)
		(layer "In2.Cu")
		(net "SMB_CPU_NODE1_BMC_CLK")
	)
	(segment
		(start 33.08604 -170.444922)
		(end 32.13481 -169.493692)
		(width 0.1143)
		(layer "In2.Cu")
		(net "SMB_CPU_NODE1_BMC_CLK")
	)
	(segment
		(start 32.13481 -169.493692)
		(end 32.13481 -143.524732)
		(width 0.1143)
		(layer "In2.Cu")
		(net "SMB_CPU_NODE1_BMC_CLK")
	)
	(segment
		(start 75.917298 -162.153854)
		(end 76.601828 -161.469324)
		(width 0.1143)
		(layer "In2.Cu")
		(net "SMB_CPU_NODE1_BMC_CLK")
	)
	(segment
		(start 115.33378 -180.146706)
		(end 115.30076 -180.113686)
		(width 0.1016)
		(layer "F.Cu")
		(net "UART_SW_S4_N")
	)
	(segment
		(start 109.121702 -177.065686)
		(end 108.332778 -176.276762)
		(width 0.1016)
		(layer "F.Cu")
		(net "UART_SW_S4_N")
	)
	(segment
		(start 83.258406 -168.942512)
		(end 83.7946 -169.478706)
		(width 0.1016)
		(layer "F.Cu")
		(net "UART_SW_S4_N")
	)
	(segment
		(start 108.332778 -176.276762)
		(end 107.0229 -176.276762)
		(width 0.1016)
		(layer "F.Cu")
		(net "UART_SW_S4_N")
	)
	(segment
		(start 115.33378 -181.413404)
		(end 115.33378 -180.146706)
		(width 0.1016)
		(layer "F.Cu")
		(net "UART_SW_S4_N")
	)
	(segment
		(start 83.49488 -179.075842)
		(end 83.49488 -179.874672)
		(width 0.1016)
		(layer "F.Cu")
		(net "UART_SW_S4_N")
	)
	(segment
		(start 113.76279 -180.697886)
		(end 113.100104 -180.697886)
		(width 0.1016)
		(layer "F.Cu")
		(net "UART_SW_S4_N")
	)
	(segment
		(start 83.7946 -169.478706)
		(end 83.7946 -173.323504)
		(width 0.1016)
		(layer "F.Cu")
		(net "UART_SW_S4_N")
	)
	(segment
		(start 113.100104 -180.697886)
		(end 109.467904 -177.065686)
		(width 0.1016)
		(layer "F.Cu")
		(net "UART_SW_S4_N")
	)
	(segment
		(start 83.16468 -173.953424)
		(end 83.16468 -178.745642)
		(width 0.1016)
		(layer "F.Cu")
		(net "UART_SW_S4_N")
	)
	(segment
		(start 114.478308 -181.413404)
		(end 113.76279 -180.697886)
		(width 0.1016)
		(layer "F.Cu")
		(net "UART_SW_S4_N")
	)
	(segment
		(start 83.7946 -173.323504)
		(end 83.16468 -173.953424)
		(width 0.1016)
		(layer "F.Cu")
		(net "UART_SW_S4_N")
	)
	(segment
		(start 141.02588 -179.964334)
		(end 141.02588 -178.858672)
		(width 0.1016)
		(layer "F.Cu")
		(net "UART_SW_S4_N")
	)
	(segment
		(start 115.33378 -181.413404)
		(end 114.478308 -181.413404)
		(width 0.1016)
		(layer "F.Cu")
		(net "UART_SW_S4_N")
	)
	(segment
		(start 140.985748 -180.004466)
		(end 141.02588 -179.964334)
		(width 0.1016)
		(layer "F.Cu")
		(net "UART_SW_S4_N")
	)
	(segment
		(start 83.16468 -178.745642)
		(end 83.49488 -179.075842)
		(width 0.1016)
		(layer "F.Cu")
		(net "UART_SW_S4_N")
	)
	(segment
		(start 109.467904 -177.065686)
		(end 109.121702 -177.065686)
		(width 0.1016)
		(layer "F.Cu")
		(net "UART_SW_S4_N")
	)
	(segment
		(start 82.54238 -168.942512)
		(end 83.258406 -168.942512)
		(width 0.1016)
		(layer "F.Cu")
		(net "UART_SW_S4_N")
	)
	(via
		(at 140.985748 -180.004466)
		(size 0.508)
		(drill 0.254)
		(layers "F.Cu" "B.Cu")
		(net "UART_SW_S4_N")
	)
	(via
		(at 115.33378 -181.413404)
		(size 0.508)
		(drill 0.254)
		(layers "F.Cu" "B.Cu")
		(net "UART_SW_S4_N")
	)
	(via
		(at 82.54238 -168.942512)
		(size 0.508)
		(drill 0.254)
		(layers "F.Cu" "B.Cu")
		(net "UART_SW_S4_N")
	)
	(via
		(at 107.0229 -176.276762)
		(size 0.508)
		(drill 0.254)
		(layers "F.Cu" "B.Cu")
		(net "UART_SW_S4_N")
	)
	(segment
		(start 82.8802 -168.604692)
		(end 82.8802 -167.886126)
		(width 0.1016)
		(layer "B.Cu")
		(net "UART_SW_S4_N")
	)
	(segment
		(start 79.23149 -167.425624)
		(end 80.00492 -167.425624)
		(width 0.1016)
		(layer "B.Cu")
		(net "UART_SW_S4_N")
	)
	(segment
		(start 80.183736 -167.60444)
		(end 81.906872 -167.60444)
		(width 0.1016)
		(layer "B.Cu")
		(net "UART_SW_S4_N")
	)
	(segment
		(start 80.00492 -167.425624)
		(end 80.183736 -167.60444)
		(width 0.1016)
		(layer "B.Cu")
		(net "UART_SW_S4_N")
	)
	(segment
		(start 82.598514 -167.60444)
		(end 81.906872 -167.60444)
		(width 0.1016)
		(layer "B.Cu")
		(net "UART_SW_S4_N")
	)
	(segment
		(start 82.54238 -168.942512)
		(end 82.8802 -168.604692)
		(width 0.1016)
		(layer "B.Cu")
		(net "UART_SW_S4_N")
	)
	(segment
		(start 82.8802 -167.886126)
		(end 82.598514 -167.60444)
		(width 0.1016)
		(layer "B.Cu")
		(net "UART_SW_S4_N")
	)
	(segment
		(start 140.985748 -180.004466)
		(end 140.328904 -180.66131)
		(width 0.1143)
		(layer "In2.Cu")
		(net "UART_SW_S4_N")
	)
	(segment
		(start 135.418068 -182.970932)
		(end 134.648956 -183.740044)
		(width 0.1143)
		(layer "In2.Cu")
		(net "UART_SW_S4_N")
	)
	(segment
		(start 134.363968 -184.389268)
		(end 128.24206 -184.389268)
		(width 0.1143)
		(layer "In2.Cu")
		(net "UART_SW_S4_N")
	)
	(segment
		(start 127.573278 -183.720486)
		(end 123.389898 -183.720486)
		(width 0.1143)
		(layer "In2.Cu")
		(net "UART_SW_S4_N")
	)
	(segment
		(start 134.648956 -183.740044)
		(end 134.648956 -184.10428)
		(width 0.1143)
		(layer "In2.Cu")
		(net "UART_SW_S4_N")
	)
	(segment
		(start 137.418572 -181.339236)
		(end 135.786876 -182.970932)
		(width 0.1143)
		(layer "In2.Cu")
		(net "UART_SW_S4_N")
	)
	(segment
		(start 135.786876 -182.970932)
		(end 135.418068 -182.970932)
		(width 0.1143)
		(layer "In2.Cu")
		(net "UART_SW_S4_N")
	)
	(segment
		(start 139.54506 -181.255162)
		(end 138.700764 -181.255162)
		(width 0.1143)
		(layer "In2.Cu")
		(net "UART_SW_S4_N")
	)
	(segment
		(start 120.204992 -180.53558)
		(end 116.211604 -180.53558)
		(width 0.1143)
		(layer "In2.Cu")
		(net "UART_SW_S4_N")
	)
	(segment
		(start 138.700764 -181.255162)
		(end 138.61669 -181.339236)
		(width 0.1143)
		(layer "In2.Cu")
		(net "UART_SW_S4_N")
	)
	(segment
		(start 138.61669 -181.339236)
		(end 137.418572 -181.339236)
		(width 0.1143)
		(layer "In2.Cu")
		(net "UART_SW_S4_N")
	)
	(segment
		(start 123.389898 -183.720486)
		(end 120.204992 -180.53558)
		(width 0.1143)
		(layer "In2.Cu")
		(net "UART_SW_S4_N")
	)
	(segment
		(start 116.211604 -180.53558)
		(end 115.33378 -181.413404)
		(width 0.1143)
		(layer "In2.Cu")
		(net "UART_SW_S4_N")
	)
	(segment
		(start 128.24206 -184.389268)
		(end 127.573278 -183.720486)
		(width 0.1143)
		(layer "In2.Cu")
		(net "UART_SW_S4_N")
	)
	(segment
		(start 134.648956 -184.10428)
		(end 134.363968 -184.389268)
		(width 0.1143)
		(layer "In2.Cu")
		(net "UART_SW_S4_N")
	)
	(segment
		(start 140.138912 -180.66131)
		(end 139.54506 -181.255162)
		(width 0.1143)
		(layer "In2.Cu")
		(net "UART_SW_S4_N")
	)
	(segment
		(start 140.328904 -180.66131)
		(end 140.138912 -180.66131)
		(width 0.1143)
		(layer "In2.Cu")
		(net "UART_SW_S4_N")
	)
	(segment
		(start 106.310684 -175.1711)
		(end 106.310684 -171.378626)
		(width 0.1143)
		(layer "In6.Cu")
		(net "UART_SW_S4_N")
	)
	(segment
		(start 83.72094 -168.942512)
		(end 82.54238 -168.942512)
		(width 0.1143)
		(layer "In6.Cu")
		(net "UART_SW_S4_N")
	)
	(segment
		(start 102.65918 -168.368472)
		(end 101.00437 -166.713662)
		(width 0.1143)
		(layer "In6.Cu")
		(net "UART_SW_S4_N")
	)
	(segment
		(start 92.20962 -166.287704)
		(end 91.40063 -166.287704)
		(width 0.1143)
		(layer "In6.Cu")
		(net "UART_SW_S4_N")
	)
	(segment
		(start 86.211156 -166.831772)
		(end 85.42782 -167.615108)
		(width 0.1143)
		(layer "In6.Cu")
		(net "UART_SW_S4_N")
	)
	(segment
		(start 104.9909 -170.058842)
		(end 104.300528 -170.058842)
		(width 0.1143)
		(layer "In6.Cu")
		(net "UART_SW_S4_N")
	)
	(segment
		(start 92.52331 -165.974014)
		(end 92.20962 -166.287704)
		(width 0.1143)
		(layer "In6.Cu")
		(net "UART_SW_S4_N")
	)
	(segment
		(start 85.048344 -167.615108)
		(end 83.72094 -168.942512)
		(width 0.1143)
		(layer "In6.Cu")
		(net "UART_SW_S4_N")
	)
	(segment
		(start 91.40063 -166.287704)
		(end 90.856562 -166.831772)
		(width 0.1143)
		(layer "In6.Cu")
		(net "UART_SW_S4_N")
	)
	(segment
		(start 94.570042 -165.974014)
		(end 92.52331 -165.974014)
		(width 0.1143)
		(layer "In6.Cu")
		(net "UART_SW_S4_N")
	)
	(segment
		(start 101.00437 -166.713662)
		(end 100.062538 -166.713662)
		(width 0.1143)
		(layer "In6.Cu")
		(net "UART_SW_S4_N")
	)
	(segment
		(start 100.062538 -166.713662)
		(end 98.947732 -165.598856)
		(width 0.1143)
		(layer "In6.Cu")
		(net "UART_SW_S4_N")
	)
	(segment
		(start 106.310684 -171.378626)
		(end 104.9909 -170.058842)
		(width 0.1143)
		(layer "In6.Cu")
		(net "UART_SW_S4_N")
	)
	(segment
		(start 90.856562 -166.831772)
		(end 86.211156 -166.831772)
		(width 0.1143)
		(layer "In6.Cu")
		(net "UART_SW_S4_N")
	)
	(segment
		(start 96.209358 -165.598856)
		(end 95.952818 -165.342316)
		(width 0.1143)
		(layer "In6.Cu")
		(net "UART_SW_S4_N")
	)
	(segment
		(start 102.65918 -168.417494)
		(end 102.65918 -168.368472)
		(width 0.1143)
		(layer "In6.Cu")
		(net "UART_SW_S4_N")
	)
	(segment
		(start 107.0229 -176.276254)
		(end 106.54284 -175.796194)
		(width 0.1143)
		(layer "In6.Cu")
		(net "UART_SW_S4_N")
	)
	(segment
		(start 107.0229 -176.276762)
		(end 107.0229 -176.276254)
		(width 0.1143)
		(layer "In6.Cu")
		(net "UART_SW_S4_N")
	)
	(segment
		(start 98.947732 -165.598856)
		(end 96.209358 -165.598856)
		(width 0.1143)
		(layer "In6.Cu")
		(net "UART_SW_S4_N")
	)
	(segment
		(start 85.42782 -167.615108)
		(end 85.048344 -167.615108)
		(width 0.1143)
		(layer "In6.Cu")
		(net "UART_SW_S4_N")
	)
	(segment
		(start 106.54284 -175.403256)
		(end 106.310684 -175.1711)
		(width 0.1143)
		(layer "In6.Cu")
		(net "UART_SW_S4_N")
	)
	(segment
		(start 95.20174 -165.342316)
		(end 94.570042 -165.974014)
		(width 0.1143)
		(layer "In6.Cu")
		(net "UART_SW_S4_N")
	)
	(segment
		(start 106.54284 -175.796194)
		(end 106.54284 -175.403256)
		(width 0.1143)
		(layer "In6.Cu")
		(net "UART_SW_S4_N")
	)
	(segment
		(start 104.300528 -170.058842)
		(end 102.65918 -168.417494)
		(width 0.1143)
		(layer "In6.Cu")
		(net "UART_SW_S4_N")
	)
	(segment
		(start 95.952818 -165.342316)
		(end 95.20174 -165.342316)
		(width 0.1143)
		(layer "In6.Cu")
		(net "UART_SW_S4_N")
	)
	(segment
		(start 110.633764 -177.166016)
		(end 109.453172 -175.985424)
		(width 0.1016)
		(layer "F.Cu")
		(net "UART_SW_S5_N")
	)
	(segment
		(start 113.64976 -180.113686)
		(end 113.974626 -180.113686)
		(width 0.1016)
		(layer "F.Cu")
		(net "UART_SW_S5_N")
	)
	(segment
		(start 83.119976 -171.223432)
		(end 82.944208 -171.223432)
		(width 0.1016)
		(layer "F.Cu")
		(net "UART_SW_S5_N")
	)
	(segment
		(start 82.944208 -171.223432)
		(end 82.69097 -170.970194)
		(width 0.1016)
		(layer "F.Cu")
		(net "UART_SW_S5_N")
	)
	(segment
		(start 113.032032 -180.113686)
		(end 110.633764 -177.715418)
		(width 0.1016)
		(layer "F.Cu")
		(net "UART_SW_S5_N")
	)
	(segment
		(start 113.974626 -180.113686)
		(end 114.76228 -180.90134)
		(width 0.1016)
		(layer "F.Cu")
		(net "UART_SW_S5_N")
	)
	(segment
		(start 83.46186 -172.971206)
		(end 83.46186 -171.565316)
		(width 0.1016)
		(layer "F.Cu")
		(net "UART_SW_S5_N")
	)
	(segment
		(start 140.041376 -180.227986)
		(end 139.701016 -180.227986)
		(width 0.1016)
		(layer "F.Cu")
		(net "UART_SW_S5_N")
	)
	(segment
		(start 110.633764 -177.715418)
		(end 110.633764 -177.166016)
		(width 0.1016)
		(layer "F.Cu")
		(net "UART_SW_S5_N")
	)
	(segment
		(start 109.023912 -175.751236)
		(end 108.51134 -175.751236)
		(width 0.1016)
		(layer "F.Cu")
		(net "UART_SW_S5_N")
	)
	(segment
		(start 82.85988 -173.573186)
		(end 83.46186 -172.971206)
		(width 0.1016)
		(layer "F.Cu")
		(net "UART_SW_S5_N")
	)
	(segment
		(start 82.85988 -178.876452)
		(end 82.85988 -173.573186)
		(width 0.1016)
		(layer "F.Cu")
		(net "UART_SW_S5_N")
	)
	(segment
		(start 83.46186 -171.565316)
		(end 83.119976 -171.223432)
		(width 0.1016)
		(layer "F.Cu")
		(net "UART_SW_S5_N")
	)
	(segment
		(start 109.453172 -175.985424)
		(end 109.2581 -175.985424)
		(width 0.1016)
		(layer "F.Cu")
		(net "UART_SW_S5_N")
	)
	(segment
		(start 140.525754 -178.858672)
		(end 140.525754 -179.743608)
		(width 0.1016)
		(layer "F.Cu")
		(net "UART_SW_S5_N")
	)
	(segment
		(start 113.64976 -180.113686)
		(end 113.032032 -180.113686)
		(width 0.1016)
		(layer "F.Cu")
		(net "UART_SW_S5_N")
	)
	(segment
		(start 82.69097 -170.61307)
		(end 83.185 -170.11904)
		(width 0.1016)
		(layer "F.Cu")
		(net "UART_SW_S5_N")
	)
	(segment
		(start 83.185 -170.11904)
		(end 83.185 -169.479976)
		(width 0.1016)
		(layer "F.Cu")
		(net "UART_SW_S5_N")
	)
	(segment
		(start 140.525754 -179.743608)
		(end 140.041376 -180.227986)
		(width 0.1016)
		(layer "F.Cu")
		(net "UART_SW_S5_N")
	)
	(segment
		(start 82.994754 -179.011326)
		(end 82.85988 -178.876452)
		(width 0.1016)
		(layer "F.Cu")
		(net "UART_SW_S5_N")
	)
	(segment
		(start 109.2581 -175.985424)
		(end 109.023912 -175.751236)
		(width 0.1016)
		(layer "F.Cu")
		(net "UART_SW_S5_N")
	)
	(segment
		(start 82.994754 -179.874672)
		(end 82.994754 -179.011326)
		(width 0.1016)
		(layer "F.Cu")
		(net "UART_SW_S5_N")
	)
	(segment
		(start 82.69097 -170.970194)
		(end 82.69097 -170.61307)
		(width 0.1016)
		(layer "F.Cu")
		(net "UART_SW_S5_N")
	)
	(via
		(at 139.701016 -180.227986)
		(size 0.508)
		(drill 0.254)
		(layers "F.Cu" "B.Cu")
		(net "UART_SW_S5_N")
	)
	(via
		(at 83.185 -169.479976)
		(size 0.508)
		(drill 0.254)
		(layers "F.Cu" "B.Cu")
		(net "UART_SW_S5_N")
	)
	(via
		(at 108.51134 -175.751236)
		(size 0.508)
		(drill 0.254)
		(layers "F.Cu" "B.Cu")
		(net "UART_SW_S5_N")
	)
	(via
		(at 114.76228 -180.90134)
		(size 0.508)
		(drill 0.254)
		(layers "F.Cu" "B.Cu")
		(net "UART_SW_S5_N")
	)
	(segment
		(start 81.906872 -166.954454)
		(end 80.41259 -166.954454)
		(width 0.1016)
		(layer "B.Cu")
		(net "UART_SW_S5_N")
	)
	(segment
		(start 83.185 -169.479976)
		(end 83.185 -167.272716)
		(width 0.1016)
		(layer "B.Cu")
		(net "UART_SW_S5_N")
	)
	(segment
		(start 79.86776 -166.409624)
		(end 79.23149 -166.409624)
		(width 0.1016)
		(layer "B.Cu")
		(net "UART_SW_S5_N")
	)
	(segment
		(start 83.185 -167.272716)
		(end 82.866738 -166.954454)
		(width 0.1016)
		(layer "B.Cu")
		(net "UART_SW_S5_N")
	)
	(segment
		(start 82.866738 -166.954454)
		(end 81.906872 -166.954454)
		(width 0.1016)
		(layer "B.Cu")
		(net "UART_SW_S5_N")
	)
	(segment
		(start 80.41259 -166.954454)
		(end 79.86776 -166.409624)
		(width 0.1016)
		(layer "B.Cu")
		(net "UART_SW_S5_N")
	)
	(segment
		(start 122.278394 -182.15991)
		(end 124.137674 -182.15991)
		(width 0.1143)
		(layer "In2.Cu")
		(net "UART_SW_S5_N")
	)
	(segment
		(start 124.965206 -182.987442)
		(end 129.989072 -182.987442)
		(width 0.1143)
		(layer "In2.Cu")
		(net "UART_SW_S5_N")
	)
	(segment
		(start 129.989072 -182.987442)
		(end 130.003042 -182.973472)
		(width 0.1143)
		(layer "In2.Cu")
		(net "UART_SW_S5_N")
	)
	(segment
		(start 114.76228 -180.90134)
		(end 115.49888 -180.16474)
		(width 0.1143)
		(layer "In2.Cu")
		(net "UART_SW_S5_N")
	)
	(segment
		(start 138.902694 -180.227986)
		(end 139.701016 -180.227986)
		(width 0.1143)
		(layer "In2.Cu")
		(net "UART_SW_S5_N")
	)
	(segment
		(start 130.003042 -182.973472)
		(end 134.718044 -182.973472)
		(width 0.1143)
		(layer "In2.Cu")
		(net "UART_SW_S5_N")
	)
	(segment
		(start 135.940038 -182.368698)
		(end 137.287 -181.021736)
		(width 0.1143)
		(layer "In2.Cu")
		(net "UART_SW_S5_N")
	)
	(segment
		(start 120.283224 -180.16474)
		(end 122.278394 -182.15991)
		(width 0.1143)
		(layer "In2.Cu")
		(net "UART_SW_S5_N")
	)
	(segment
		(start 124.137674 -182.15991)
		(end 124.965206 -182.987442)
		(width 0.1143)
		(layer "In2.Cu")
		(net "UART_SW_S5_N")
	)
	(segment
		(start 115.49888 -180.16474)
		(end 120.283224 -180.16474)
		(width 0.1143)
		(layer "In2.Cu")
		(net "UART_SW_S5_N")
	)
	(segment
		(start 138.108944 -181.021736)
		(end 138.902694 -180.227986)
		(width 0.1143)
		(layer "In2.Cu")
		(net "UART_SW_S5_N")
	)
	(segment
		(start 137.287 -181.021736)
		(end 138.108944 -181.021736)
		(width 0.1143)
		(layer "In2.Cu")
		(net "UART_SW_S5_N")
	)
	(segment
		(start 134.718044 -182.973472)
		(end 135.322818 -182.368698)
		(width 0.1143)
		(layer "In2.Cu")
		(net "UART_SW_S5_N")
	)
	(segment
		(start 135.322818 -182.368698)
		(end 135.940038 -182.368698)
		(width 0.1143)
		(layer "In2.Cu")
		(net "UART_SW_S5_N")
	)
	(segment
		(start 104.31653 -168.96969)
		(end 103.992426 -168.645586)
		(width 0.1143)
		(layer "In6.Cu")
		(net "UART_SW_S5_N")
	)
	(segment
		(start 82.3595 -169.380662)
		(end 83.085686 -169.380662)
		(width 0.1143)
		(layer "In6.Cu")
		(net "UART_SW_S5_N")
	)
	(segment
		(start 99.41814 -165.281356)
		(end 97.762314 -165.281356)
		(width 0.1143)
		(layer "In6.Cu")
		(net "UART_SW_S5_N")
	)
	(segment
		(start 84.777834 -167.024304)
		(end 84.34197 -167.024304)
		(width 0.1143)
		(layer "In6.Cu")
		(net "UART_SW_S5_N")
	)
	(segment
		(start 95.231204 -164.705538)
		(end 91.243404 -164.705538)
		(width 0.1143)
		(layer "In6.Cu")
		(net "UART_SW_S5_N")
	)
	(segment
		(start 108.51134 -175.751236)
		(end 108.78312 -175.479456)
		(width 0.1143)
		(layer "In6.Cu")
		(net "UART_SW_S5_N")
	)
	(segment
		(start 106.6292 -172.6692)
		(end 106.6292 -170.698922)
		(width 0.1143)
		(layer "In6.Cu")
		(net "UART_SW_S5_N")
	)
	(segment
		(start 97.762314 -165.281356)
		(end 97.11182 -164.630862)
		(width 0.1143)
		(layer "In6.Cu")
		(net "UART_SW_S5_N")
	)
	(segment
		(start 91.243404 -164.705538)
		(end 90.503248 -165.445694)
		(width 0.1143)
		(layer "In6.Cu")
		(net "UART_SW_S5_N")
	)
	(segment
		(start 106.6292 -170.698922)
		(end 104.899968 -168.96969)
		(width 0.1143)
		(layer "In6.Cu")
		(net "UART_SW_S5_N")
	)
	(segment
		(start 95.30588 -164.630862)
		(end 95.231204 -164.705538)
		(width 0.1143)
		(layer "In6.Cu")
		(net "UART_SW_S5_N")
	)
	(segment
		(start 82.861912 -168.504362)
		(end 82.36077 -168.504362)
		(width 0.1143)
		(layer "In6.Cu")
		(net "UART_SW_S5_N")
	)
	(segment
		(start 97.11182 -164.630862)
		(end 95.30588 -164.630862)
		(width 0.1143)
		(layer "In6.Cu")
		(net "UART_SW_S5_N")
	)
	(segment
		(start 82.10423 -169.125392)
		(end 82.3595 -169.380662)
		(width 0.1143)
		(layer "In6.Cu")
		(net "UART_SW_S5_N")
	)
	(segment
		(start 101.163374 -166.358316)
		(end 100.4951 -166.358316)
		(width 0.1143)
		(layer "In6.Cu")
		(net "UART_SW_S5_N")
	)
	(segment
		(start 86.356444 -165.445694)
		(end 84.777834 -167.024304)
		(width 0.1143)
		(layer "In6.Cu")
		(net "UART_SW_S5_N")
	)
	(segment
		(start 82.36077 -168.504362)
		(end 82.10423 -168.760902)
		(width 0.1143)
		(layer "In6.Cu")
		(net "UART_SW_S5_N")
	)
	(segment
		(start 90.503248 -165.445694)
		(end 86.356444 -165.445694)
		(width 0.1143)
		(layer "In6.Cu")
		(net "UART_SW_S5_N")
	)
	(segment
		(start 82.10423 -168.760902)
		(end 82.10423 -169.125392)
		(width 0.1143)
		(layer "In6.Cu")
		(net "UART_SW_S5_N")
	)
	(segment
		(start 104.899968 -168.96969)
		(end 104.31653 -168.96969)
		(width 0.1143)
		(layer "In6.Cu")
		(net "UART_SW_S5_N")
	)
	(segment
		(start 100.4951 -166.358316)
		(end 99.41814 -165.281356)
		(width 0.1143)
		(layer "In6.Cu")
		(net "UART_SW_S5_N")
	)
	(segment
		(start 103.992426 -168.645586)
		(end 103.450644 -168.645586)
		(width 0.1143)
		(layer "In6.Cu")
		(net "UART_SW_S5_N")
	)
	(segment
		(start 108.78312 -174.82312)
		(end 106.6292 -172.6692)
		(width 0.1143)
		(layer "In6.Cu")
		(net "UART_SW_S5_N")
	)
	(segment
		(start 103.450644 -168.645586)
		(end 101.163374 -166.358316)
		(width 0.1143)
		(layer "In6.Cu")
		(net "UART_SW_S5_N")
	)
	(segment
		(start 83.085686 -169.380662)
		(end 83.185 -169.479976)
		(width 0.1143)
		(layer "In6.Cu")
		(net "UART_SW_S5_N")
	)
	(segment
		(start 84.34197 -167.024304)
		(end 82.861912 -168.504362)
		(width 0.1143)
		(layer "In6.Cu")
		(net "UART_SW_S5_N")
	)
	(segment
		(start 108.78312 -175.479456)
		(end 108.78312 -174.82312)
		(width 0.1143)
		(layer "In6.Cu")
		(net "UART_SW_S5_N")
	)
	(segment
		(start 84.489544 -168.476676)
		(end 84.869528 -168.476676)
		(width 0.1016)
		(layer "F.Cu")
		(net "UART_SW_S3_N")
	)
	(segment
		(start 114.448082 -181.845204)
		(end 113.69167 -181.088792)
		(width 0.1016)
		(layer "F.Cu")
		(net "UART_SW_S3_N")
	)
	(segment
		(start 109.350302 -178.169824)
		(end 108.09986 -176.919382)
		(width 0.1016)
		(layer "F.Cu")
		(net "UART_SW_S3_N")
	)
	(segment
		(start 109.89564 -178.496976)
		(end 109.568488 -178.169824)
		(width 0.1016)
		(layer "F.Cu")
		(net "UART_SW_S3_N")
	)
	(segment
		(start 116.595906 -181.845204)
		(end 114.448082 -181.845204)
		(width 0.1016)
		(layer "F.Cu")
		(net "UART_SW_S3_N")
	)
	(segment
		(start 141.474444 -179.640484)
		(end 141.474444 -180.3908)
		(width 0.1016)
		(layer "F.Cu")
		(net "UART_SW_S3_N")
	)
	(segment
		(start 84.0994 -168.86682)
		(end 84.489544 -168.476676)
		(width 0.1016)
		(layer "F.Cu")
		(net "UART_SW_S3_N")
	)
	(segment
		(start 84.0994 -173.449996)
		(end 84.0994 -168.86682)
		(width 0.1016)
		(layer "F.Cu")
		(net "UART_SW_S3_N")
	)
	(segment
		(start 83.46948 -174.079916)
		(end 84.0994 -173.449996)
		(width 0.1016)
		(layer "F.Cu")
		(net "UART_SW_S3_N")
	)
	(segment
		(start 141.041882 -180.823362)
		(end 141.041882 -181.786022)
		(width 0.1016)
		(layer "F.Cu")
		(net "UART_SW_S3_N")
	)
	(segment
		(start 83.994752 -179.874672)
		(end 83.994752 -179.144422)
		(width 0.1016)
		(layer "F.Cu")
		(net "UART_SW_S3_N")
	)
	(segment
		(start 141.525752 -179.589176)
		(end 141.474444 -179.640484)
		(width 0.1016)
		(layer "F.Cu")
		(net "UART_SW_S3_N")
	)
	(segment
		(start 113.69167 -181.088792)
		(end 112.82934 -181.088792)
		(width 0.1016)
		(layer "F.Cu")
		(net "UART_SW_S3_N")
	)
	(segment
		(start 117.048788 -181.392322)
		(end 116.595906 -181.845204)
		(width 0.1016)
		(layer "F.Cu")
		(net "UART_SW_S3_N")
	)
	(segment
		(start 117.07876 -180.113686)
		(end 117.07876 -180.975508)
		(width 0.1016)
		(layer "F.Cu")
		(net "UART_SW_S3_N")
	)
	(segment
		(start 141.525752 -178.858672)
		(end 141.525752 -179.589176)
		(width 0.1016)
		(layer "F.Cu")
		(net "UART_SW_S3_N")
	)
	(segment
		(start 141.041882 -181.786022)
		(end 140.64615 -182.181754)
		(width 0.1016)
		(layer "F.Cu")
		(net "UART_SW_S3_N")
	)
	(segment
		(start 83.994752 -179.144422)
		(end 83.46948 -178.61915)
		(width 0.1016)
		(layer "F.Cu")
		(net "UART_SW_S3_N")
	)
	(segment
		(start 117.048788 -181.00548)
		(end 117.048788 -181.392322)
		(width 0.1016)
		(layer "F.Cu")
		(net "UART_SW_S3_N")
	)
	(segment
		(start 109.568488 -178.169824)
		(end 109.350302 -178.169824)
		(width 0.1016)
		(layer "F.Cu")
		(net "UART_SW_S3_N")
	)
	(segment
		(start 110.237524 -178.496976)
		(end 109.89564 -178.496976)
		(width 0.1016)
		(layer "F.Cu")
		(net "UART_SW_S3_N")
	)
	(segment
		(start 108.09986 -176.919382)
		(end 108.09986 -176.75733)
		(width 0.1016)
		(layer "F.Cu")
		(net "UART_SW_S3_N")
	)
	(segment
		(start 117.07876 -180.975508)
		(end 117.048788 -181.00548)
		(width 0.1016)
		(layer "F.Cu")
		(net "UART_SW_S3_N")
	)
	(segment
		(start 112.82934 -181.088792)
		(end 110.237524 -178.496976)
		(width 0.1016)
		(layer "F.Cu")
		(net "UART_SW_S3_N")
	)
	(segment
		(start 141.474444 -180.3908)
		(end 141.041882 -180.823362)
		(width 0.1016)
		(layer "F.Cu")
		(net "UART_SW_S3_N")
	)
	(segment
		(start 83.46948 -178.61915)
		(end 83.46948 -174.079916)
		(width 0.1016)
		(layer "F.Cu")
		(net "UART_SW_S3_N")
	)
	(segment
		(start 84.869528 -168.476676)
		(end 84.915502 -168.430702)
		(width 0.1016)
		(layer "F.Cu")
		(net "UART_SW_S3_N")
	)
	(via
		(at 108.09986 -176.75733)
		(size 0.508)
		(drill 0.254)
		(layers "F.Cu" "B.Cu")
		(net "UART_SW_S3_N")
	)
	(via
		(at 117.048788 -181.00548)
		(size 0.508)
		(drill 0.254)
		(layers "F.Cu" "B.Cu")
		(net "UART_SW_S3_N")
	)
	(via
		(at 140.64615 -182.181754)
		(size 0.508)
		(drill 0.254)
		(layers "F.Cu" "B.Cu")
		(net "UART_SW_S3_N")
	)
	(via
		(at 84.915502 -168.430702)
		(size 0.508)
		(drill 0.254)
		(layers "F.Cu" "B.Cu")
		(net "UART_SW_S3_N")
	)
	(segment
		(start 89.09304 -164.390324)
		(end 88.479122 -165.004242)
		(width 0.1016)
		(layer "B.Cu")
		(net "UART_SW_S3_N")
	)
	(segment
		(start 90.41257 -164.878512)
		(end 89.924382 -164.390324)
		(width 0.1016)
		(layer "B.Cu")
		(net "UART_SW_S3_N")
	)
	(segment
		(start 84.81314 -167.615362)
		(end 84.915502 -167.717724)
		(width 0.1016)
		(layer "B.Cu")
		(net "UART_SW_S3_N")
	)
	(segment
		(start 86.151466 -165.004242)
		(end 85.32114 -165.834568)
		(width 0.1016)
		(layer "B.Cu")
		(net "UART_SW_S3_N")
	)
	(segment
		(start 88.479122 -165.004242)
		(end 87.748872 -165.004242)
		(width 0.1016)
		(layer "B.Cu")
		(net "UART_SW_S3_N")
	)
	(segment
		(start 85.32114 -165.834568)
		(end 85.32114 -166.364412)
		(width 0.1016)
		(layer "B.Cu")
		(net "UART_SW_S3_N")
	)
	(segment
		(start 87.748872 -165.004242)
		(end 86.151466 -165.004242)
		(width 0.1016)
		(layer "B.Cu")
		(net "UART_SW_S3_N")
	)
	(segment
		(start 84.915502 -167.717724)
		(end 84.915502 -168.430702)
		(width 0.1016)
		(layer "B.Cu")
		(net "UART_SW_S3_N")
	)
	(segment
		(start 84.81314 -166.872412)
		(end 84.81314 -167.615362)
		(width 0.1016)
		(layer "B.Cu")
		(net "UART_SW_S3_N")
	)
	(segment
		(start 89.924382 -164.390324)
		(end 89.09304 -164.390324)
		(width 0.1016)
		(layer "B.Cu")
		(net "UART_SW_S3_N")
	)
	(segment
		(start 85.32114 -166.364412)
		(end 84.81314 -166.872412)
		(width 0.1016)
		(layer "B.Cu")
		(net "UART_SW_S3_N")
	)
	(segment
		(start 118.284498 -182.24119)
		(end 117.048788 -181.00548)
		(width 0.1143)
		(layer "In2.Cu")
		(net "UART_SW_S3_N")
	)
	(segment
		(start 138.27252 -182.609236)
		(end 137.95375 -182.928006)
		(width 0.1143)
		(layer "In2.Cu")
		(net "UART_SW_S3_N")
	)
	(segment
		(start 140.64615 -182.181754)
		(end 140.302742 -182.525162)
		(width 0.1143)
		(layer "In2.Cu")
		(net "UART_SW_S3_N")
	)
	(segment
		(start 135.822436 -185.659268)
		(end 126.915672 -185.659268)
		(width 0.1143)
		(layer "In2.Cu")
		(net "UART_SW_S3_N")
	)
	(segment
		(start 139.227052 -182.525162)
		(end 139.142978 -182.609236)
		(width 0.1143)
		(layer "In2.Cu")
		(net "UART_SW_S3_N")
	)
	(segment
		(start 126.915672 -185.659268)
		(end 126.421134 -185.16473)
		(width 0.1143)
		(layer "In2.Cu")
		(net "UART_SW_S3_N")
	)
	(segment
		(start 120.20804 -183.40324)
		(end 120.20804 -182.752746)
		(width 0.1143)
		(layer "In2.Cu")
		(net "UART_SW_S3_N")
	)
	(segment
		(start 126.421134 -185.16473)
		(end 121.96953 -185.16473)
		(width 0.1143)
		(layer "In2.Cu")
		(net "UART_SW_S3_N")
	)
	(segment
		(start 119.696484 -182.24119)
		(end 118.284498 -182.24119)
		(width 0.1143)
		(layer "In2.Cu")
		(net "UART_SW_S3_N")
	)
	(segment
		(start 139.142978 -182.609236)
		(end 138.27252 -182.609236)
		(width 0.1143)
		(layer "In2.Cu")
		(net "UART_SW_S3_N")
	)
	(segment
		(start 137.95375 -182.928006)
		(end 137.95375 -183.527954)
		(width 0.1143)
		(layer "In2.Cu")
		(net "UART_SW_S3_N")
	)
	(segment
		(start 137.95375 -183.527954)
		(end 135.822436 -185.659268)
		(width 0.1143)
		(layer "In2.Cu")
		(net "UART_SW_S3_N")
	)
	(segment
		(start 120.20804 -182.752746)
		(end 119.696484 -182.24119)
		(width 0.1143)
		(layer "In2.Cu")
		(net "UART_SW_S3_N")
	)
	(segment
		(start 140.302742 -182.525162)
		(end 139.227052 -182.525162)
		(width 0.1143)
		(layer "In2.Cu")
		(net "UART_SW_S3_N")
	)
	(segment
		(start 121.96953 -185.16473)
		(end 120.20804 -183.40324)
		(width 0.1143)
		(layer "In2.Cu")
		(net "UART_SW_S3_N")
	)
	(segment
		(start 103.970074 -170.415966)
		(end 104.74706 -170.415966)
		(width 0.1143)
		(layer "In6.Cu")
		(net "UART_SW_S3_N")
	)
	(segment
		(start 105.92689 -175.236378)
		(end 106.22534 -175.534828)
		(width 0.1143)
		(layer "In6.Cu")
		(net "UART_SW_S3_N")
	)
	(segment
		(start 104.74706 -170.415966)
		(end 105.92689 -171.595796)
		(width 0.1143)
		(layer "In6.Cu")
		(net "UART_SW_S3_N")
	)
	(segment
		(start 96.15297 -166.019988)
		(end 98.076512 -166.019988)
		(width 0.1143)
		(layer "In6.Cu")
		(net "UART_SW_S3_N")
	)
	(segment
		(start 102.020624 -168.466516)
		(end 103.970074 -170.415966)
		(width 0.1143)
		(layer "In6.Cu")
		(net "UART_SW_S3_N")
	)
	(segment
		(start 100.52304 -168.466516)
		(end 102.020624 -168.466516)
		(width 0.1143)
		(layer "In6.Cu")
		(net "UART_SW_S3_N")
	)
	(segment
		(start 107.605068 -177.435764)
		(end 108.09986 -176.940972)
		(width 0.1143)
		(layer "In6.Cu")
		(net "UART_SW_S3_N")
	)
	(segment
		(start 92.488258 -167.608758)
		(end 93.59519 -167.608758)
		(width 0.1143)
		(layer "In6.Cu")
		(net "UART_SW_S3_N")
	)
	(segment
		(start 95.48622 -165.717728)
		(end 95.85071 -165.717728)
		(width 0.1143)
		(layer "In6.Cu")
		(net "UART_SW_S3_N")
	)
	(segment
		(start 90.664792 -168.000172)
		(end 90.932762 -167.732202)
		(width 0.1143)
		(layer "In6.Cu")
		(net "UART_SW_S3_N")
	)
	(segment
		(start 95.85071 -165.717728)
		(end 96.15297 -166.019988)
		(width 0.1143)
		(layer "In6.Cu")
		(net "UART_SW_S3_N")
	)
	(segment
		(start 84.915502 -168.430702)
		(end 84.915502 -168.431464)
		(width 0.1143)
		(layer "In6.Cu")
		(net "UART_SW_S3_N")
	)
	(segment
		(start 86.4362 -168.378124)
		(end 87.485728 -168.378124)
		(width 0.1143)
		(layer "In6.Cu")
		(net "UART_SW_S3_N")
	)
	(segment
		(start 105.92689 -171.595796)
		(end 105.92689 -175.236378)
		(width 0.1143)
		(layer "In6.Cu")
		(net "UART_SW_S3_N")
	)
	(segment
		(start 86.2711 -168.543224)
		(end 86.4362 -168.378124)
		(width 0.1143)
		(layer "In6.Cu")
		(net "UART_SW_S3_N")
	)
	(segment
		(start 106.22534 -176.414176)
		(end 107.246928 -177.435764)
		(width 0.1143)
		(layer "In6.Cu")
		(net "UART_SW_S3_N")
	)
	(segment
		(start 92.364814 -167.732202)
		(end 92.488258 -167.608758)
		(width 0.1143)
		(layer "In6.Cu")
		(net "UART_SW_S3_N")
	)
	(segment
		(start 87.86368 -168.000172)
		(end 90.664792 -168.000172)
		(width 0.1143)
		(layer "In6.Cu")
		(net "UART_SW_S3_N")
	)
	(segment
		(start 93.59519 -167.608758)
		(end 95.48622 -165.717728)
		(width 0.1143)
		(layer "In6.Cu")
		(net "UART_SW_S3_N")
	)
	(segment
		(start 107.246928 -177.435764)
		(end 107.605068 -177.435764)
		(width 0.1143)
		(layer "In6.Cu")
		(net "UART_SW_S3_N")
	)
	(segment
		(start 106.22534 -175.534828)
		(end 106.22534 -176.414176)
		(width 0.1143)
		(layer "In6.Cu")
		(net "UART_SW_S3_N")
	)
	(segment
		(start 85.027262 -168.543224)
		(end 86.2711 -168.543224)
		(width 0.1143)
		(layer "In6.Cu")
		(net "UART_SW_S3_N")
	)
	(segment
		(start 98.076512 -166.019988)
		(end 100.52304 -168.466516)
		(width 0.1143)
		(layer "In6.Cu")
		(net "UART_SW_S3_N")
	)
	(segment
		(start 87.485728 -168.378124)
		(end 87.86368 -168.000172)
		(width 0.1143)
		(layer "In6.Cu")
		(net "UART_SW_S3_N")
	)
	(segment
		(start 84.915502 -168.431464)
		(end 85.027262 -168.543224)
		(width 0.1143)
		(layer "In6.Cu")
		(net "UART_SW_S3_N")
	)
	(segment
		(start 90.932762 -167.732202)
		(end 92.364814 -167.732202)
		(width 0.1143)
		(layer "In6.Cu")
		(net "UART_SW_S3_N")
	)
	(segment
		(start 108.09986 -176.940972)
		(end 108.09986 -176.75733)
		(width 0.1143)
		(layer "In6.Cu")
		(net "UART_SW_S3_N")
	)
	(segment
		(start 91.21267 -179.610512)
		(end 91.21267 -179.371244)
		(width 0.1016)
		(layer "F.Cu")
		(net "CPLD_UART_RI_P4_N")
	)
	(segment
		(start 86.2965 -176.598834)
		(end 86.487254 -176.598834)
		(width 0.1016)
		(layer "F.Cu")
		(net "CPLD_UART_RI_P4_N")
	)
	(segment
		(start 90.72626 -179.164488)
		(end 90.41257 -178.850798)
		(width 0.1016)
		(layer "F.Cu")
		(net "CPLD_UART_RI_P4_N")
	)
	(segment
		(start 88.426544 -177.124614)
		(end 89.896442 -178.594512)
		(width 0.1016)
		(layer "F.Cu")
		(net "CPLD_UART_RI_P4_N")
	)
	(segment
		(start 91.005914 -179.164488)
		(end 90.72626 -179.164488)
		(width 0.1016)
		(layer "F.Cu")
		(net "CPLD_UART_RI_P4_N")
	)
	(segment
		(start 90.41257 -178.850798)
		(end 90.41257 -178.594512)
		(width 0.1016)
		(layer "F.Cu")
		(net "CPLD_UART_RI_P4_N")
	)
	(segment
		(start 87.013034 -177.124614)
		(end 87.744808 -177.124614)
		(width 0.1016)
		(layer "F.Cu")
		(net "CPLD_UART_RI_P4_N")
	)
	(segment
		(start 87.744808 -177.124614)
		(end 88.426544 -177.124614)
		(width 0.1016)
		(layer "F.Cu")
		(net "CPLD_UART_RI_P4_N")
	)
	(segment
		(start 89.896442 -178.594512)
		(end 90.41257 -178.594512)
		(width 0.1016)
		(layer "F.Cu")
		(net "CPLD_UART_RI_P4_N")
	)
	(segment
		(start 86.487254 -176.598834)
		(end 87.013034 -177.124614)
		(width 0.1016)
		(layer "F.Cu")
		(net "CPLD_UART_RI_P4_N")
	)
	(segment
		(start 91.21267 -179.371244)
		(end 91.005914 -179.164488)
		(width 0.1016)
		(layer "F.Cu")
		(net "CPLD_UART_RI_P4_N")
	)
	(via
		(at 150.184866 -166.680642)
		(size 0.508)
		(drill 0.254)
		(layers "F.Cu" "B.Cu")
		(net "CPLD_UART_RI_P4_N")
	)
	(via
		(at 86.2965 -176.598834)
		(size 0.508)
		(drill 0.254)
		(layers "F.Cu" "B.Cu")
		(net "CPLD_UART_RI_P4_N")
	)
	(segment
		(start 153.361898 -168.548558)
		(end 156.676598 -168.548558)
		(width 0.1016)
		(layer "B.Cu")
		(net "CPLD_UART_RI_P4_N")
	)
	(segment
		(start 152.73274 -167.9194)
		(end 153.361898 -168.548558)
		(width 0.1016)
		(layer "B.Cu")
		(net "CPLD_UART_RI_P4_N")
	)
	(segment
		(start 151.423624 -167.9194)
		(end 152.73274 -167.9194)
		(width 0.1016)
		(layer "B.Cu")
		(net "CPLD_UART_RI_P4_N")
	)
	(segment
		(start 161.452052 -167.438324)
		(end 161.096452 -167.082724)
		(width 0.1016)
		(layer "B.Cu")
		(net "CPLD_UART_RI_P4_N")
	)
	(segment
		(start 163.17214 -165.469824)
		(end 163.17214 -166.08171)
		(width 0.1016)
		(layer "B.Cu")
		(net "CPLD_UART_RI_P4_N")
	)
	(segment
		(start 150.184866 -166.680642)
		(end 151.423624 -167.9194)
		(width 0.1016)
		(layer "B.Cu")
		(net "CPLD_UART_RI_P4_N")
	)
	(segment
		(start 157.389576 -167.83558)
		(end 158.293308 -167.83558)
		(width 0.1016)
		(layer "B.Cu")
		(net "CPLD_UART_RI_P4_N")
	)
	(segment
		(start 161.452052 -168.967658)
		(end 161.452052 -167.438324)
		(width 0.1016)
		(layer "B.Cu")
		(net "CPLD_UART_RI_P4_N")
	)
	(segment
		(start 161.196782 -169.222928)
		(end 161.452052 -168.967658)
		(width 0.1016)
		(layer "B.Cu")
		(net "CPLD_UART_RI_P4_N")
	)
	(segment
		(start 164.836602 -167.746172)
		(end 165.186106 -167.746172)
		(width 0.1016)
		(layer "B.Cu")
		(net "CPLD_UART_RI_P4_N")
	)
	(segment
		(start 161.096452 -165.315138)
		(end 161.42589 -164.9857)
		(width 0.1016)
		(layer "B.Cu")
		(net "CPLD_UART_RI_P4_N")
	)
	(segment
		(start 158.293308 -167.83558)
		(end 158.293308 -168.679368)
		(width 0.1016)
		(layer "B.Cu")
		(net "CPLD_UART_RI_P4_N")
	)
	(segment
		(start 158.293308 -168.679368)
		(end 158.836868 -169.222928)
		(width 0.1016)
		(layer "B.Cu")
		(net "CPLD_UART_RI_P4_N")
	)
	(segment
		(start 156.676598 -168.548558)
		(end 157.389576 -167.83558)
		(width 0.1016)
		(layer "B.Cu")
		(net "CPLD_UART_RI_P4_N")
	)
	(segment
		(start 162.688016 -164.9857)
		(end 163.17214 -165.469824)
		(width 0.1016)
		(layer "B.Cu")
		(net "CPLD_UART_RI_P4_N")
	)
	(segment
		(start 163.17214 -166.08171)
		(end 164.836602 -167.746172)
		(width 0.1016)
		(layer "B.Cu")
		(net "CPLD_UART_RI_P4_N")
	)
	(segment
		(start 158.836868 -169.222928)
		(end 161.196782 -169.222928)
		(width 0.1016)
		(layer "B.Cu")
		(net "CPLD_UART_RI_P4_N")
	)
	(segment
		(start 161.096452 -167.082724)
		(end 161.096452 -165.315138)
		(width 0.1016)
		(layer "B.Cu")
		(net "CPLD_UART_RI_P4_N")
	)
	(segment
		(start 161.42589 -164.9857)
		(end 162.688016 -164.9857)
		(width 0.1016)
		(layer "B.Cu")
		(net "CPLD_UART_RI_P4_N")
	)
	(segment
		(start 145.238724 -168.12387)
		(end 145.17116 -168.056306)
		(width 0.1143)
		(layer "In2.Cu")
		(net "CPLD_UART_RI_P4_N")
	)
	(segment
		(start 149.933406 -166.429182)
		(end 148.52142 -166.429182)
		(width 0.1143)
		(layer "In2.Cu")
		(net "CPLD_UART_RI_P4_N")
	)
	(segment
		(start 146.826732 -168.12387)
		(end 145.238724 -168.12387)
		(width 0.1143)
		(layer "In2.Cu")
		(net "CPLD_UART_RI_P4_N")
	)
	(segment
		(start 92.85224 -177.814478)
		(end 92.277438 -177.814478)
		(width 0.1143)
		(layer "In2.Cu")
		(net "CPLD_UART_RI_P4_N")
	)
	(segment
		(start 143.057626 -168.056306)
		(end 142.616428 -168.497504)
		(width 0.1143)
		(layer "In2.Cu")
		(net "CPLD_UART_RI_P4_N")
	)
	(segment
		(start 97.409762 -175.899826)
		(end 95.252794 -175.899826)
		(width 0.1143)
		(layer "In2.Cu")
		(net "CPLD_UART_RI_P4_N")
	)
	(segment
		(start 105.113582 -177.402744)
		(end 99.735894 -177.402744)
		(width 0.1143)
		(layer "In2.Cu")
		(net "CPLD_UART_RI_P4_N")
	)
	(segment
		(start 92.075254 -178.016662)
		(end 87.727028 -178.016662)
		(width 0.1143)
		(layer "In2.Cu")
		(net "CPLD_UART_RI_P4_N")
	)
	(segment
		(start 142.616428 -168.497504)
		(end 140.842746 -168.497504)
		(width 0.1143)
		(layer "In2.Cu")
		(net "CPLD_UART_RI_P4_N")
	)
	(segment
		(start 86.3092 -176.598834)
		(end 86.2965 -176.598834)
		(width 0.1143)
		(layer "In2.Cu")
		(net "CPLD_UART_RI_P4_N")
	)
	(segment
		(start 145.17116 -168.056306)
		(end 143.057626 -168.056306)
		(width 0.1143)
		(layer "In2.Cu")
		(net "CPLD_UART_RI_P4_N")
	)
	(segment
		(start 111.75365 -178.844194)
		(end 110.05693 -177.147474)
		(width 0.1143)
		(layer "In2.Cu")
		(net "CPLD_UART_RI_P4_N")
	)
	(segment
		(start 108.364782 -177.468022)
		(end 105.17886 -177.468022)
		(width 0.1143)
		(layer "In2.Cu")
		(net "CPLD_UART_RI_P4_N")
	)
	(segment
		(start 140.842746 -168.497504)
		(end 138.51382 -170.82643)
		(width 0.1143)
		(layer "In2.Cu")
		(net "CPLD_UART_RI_P4_N")
	)
	(segment
		(start 98.920554 -177.410618)
		(end 97.409762 -175.899826)
		(width 0.1143)
		(layer "In2.Cu")
		(net "CPLD_UART_RI_P4_N")
	)
	(segment
		(start 99.72802 -177.410618)
		(end 98.920554 -177.410618)
		(width 0.1143)
		(layer "In2.Cu")
		(net "CPLD_UART_RI_P4_N")
	)
	(segment
		(start 112.413796 -178.547268)
		(end 112.11687 -178.844194)
		(width 0.1143)
		(layer "In2.Cu")
		(net "CPLD_UART_RI_P4_N")
	)
	(segment
		(start 110.05693 -177.147474)
		(end 108.68533 -177.147474)
		(width 0.1143)
		(layer "In2.Cu")
		(net "CPLD_UART_RI_P4_N")
	)
	(segment
		(start 108.68533 -177.147474)
		(end 108.364782 -177.468022)
		(width 0.1143)
		(layer "In2.Cu")
		(net "CPLD_UART_RI_P4_N")
	)
	(segment
		(start 148.52142 -166.429182)
		(end 146.826732 -168.12387)
		(width 0.1143)
		(layer "In2.Cu")
		(net "CPLD_UART_RI_P4_N")
	)
	(segment
		(start 95.252794 -175.899826)
		(end 93.4466 -177.70602)
		(width 0.1143)
		(layer "In2.Cu")
		(net "CPLD_UART_RI_P4_N")
	)
	(segment
		(start 105.17886 -177.468022)
		(end 105.113582 -177.402744)
		(width 0.1143)
		(layer "In2.Cu")
		(net "CPLD_UART_RI_P4_N")
	)
	(segment
		(start 92.960698 -177.70602)
		(end 92.85224 -177.814478)
		(width 0.1143)
		(layer "In2.Cu")
		(net "CPLD_UART_RI_P4_N")
	)
	(segment
		(start 150.184866 -166.680642)
		(end 149.933406 -166.429182)
		(width 0.1143)
		(layer "In2.Cu")
		(net "CPLD_UART_RI_P4_N")
	)
	(segment
		(start 138.51382 -174.819818)
		(end 134.78637 -178.547268)
		(width 0.1143)
		(layer "In2.Cu")
		(net "CPLD_UART_RI_P4_N")
	)
	(segment
		(start 138.51382 -170.82643)
		(end 138.51382 -174.819818)
		(width 0.1143)
		(layer "In2.Cu")
		(net "CPLD_UART_RI_P4_N")
	)
	(segment
		(start 93.4466 -177.70602)
		(end 92.960698 -177.70602)
		(width 0.1143)
		(layer "In2.Cu")
		(net "CPLD_UART_RI_P4_N")
	)
	(segment
		(start 99.735894 -177.402744)
		(end 99.72802 -177.410618)
		(width 0.1143)
		(layer "In2.Cu")
		(net "CPLD_UART_RI_P4_N")
	)
	(segment
		(start 112.11687 -178.844194)
		(end 111.75365 -178.844194)
		(width 0.1143)
		(layer "In2.Cu")
		(net "CPLD_UART_RI_P4_N")
	)
	(segment
		(start 134.78637 -178.547268)
		(end 112.413796 -178.547268)
		(width 0.1143)
		(layer "In2.Cu")
		(net "CPLD_UART_RI_P4_N")
	)
	(segment
		(start 92.277438 -177.814478)
		(end 92.075254 -178.016662)
		(width 0.1143)
		(layer "In2.Cu")
		(net "CPLD_UART_RI_P4_N")
	)
	(segment
		(start 87.727028 -178.016662)
		(end 86.3092 -176.598834)
		(width 0.1143)
		(layer "In2.Cu")
		(net "CPLD_UART_RI_P4_N")
	)
	(segment
		(start 110.977172 -181.456076)
		(end 111.347504 -181.826408)
		(width 0.1016)
		(layer "F.Cu")
		(net "UART_SW_S1_N")
	)
	(segment
		(start 84.350098 -177.785268)
		(end 84.07908 -177.51425)
		(width 0.1016)
		(layer "F.Cu")
		(net "UART_SW_S1_N")
	)
	(segment
		(start 84.63788 -178.726592)
		(end 84.63788 -178.037998)
		(width 0.1016)
		(layer "F.Cu")
		(net "UART_SW_S1_N")
	)
	(segment
		(start 84.99475 -179.874672)
		(end 84.99475 -179.083462)
		(width 0.1016)
		(layer "F.Cu")
		(net "UART_SW_S1_N")
	)
	(segment
		(start 108.236258 -180.075332)
		(end 109.617002 -181.456076)
		(width 0.1016)
		(layer "F.Cu")
		(net "UART_SW_S1_N")
	)
	(segment
		(start 109.617002 -181.456076)
		(end 110.977172 -181.456076)
		(width 0.1016)
		(layer "F.Cu")
		(net "UART_SW_S1_N")
	)
	(segment
		(start 113.40465 -182.454804)
		(end 119.328692 -182.454804)
		(width 0.1016)
		(layer "F.Cu")
		(net "UART_SW_S1_N")
	)
	(segment
		(start 84.99475 -179.083462)
		(end 84.63788 -178.726592)
		(width 0.1016)
		(layer "F.Cu")
		(net "UART_SW_S1_N")
	)
	(segment
		(start 142.52575 -178.858672)
		(end 142.52575 -179.734464)
		(width 0.1016)
		(layer "F.Cu")
		(net "UART_SW_S1_N")
	)
	(segment
		(start 112.776254 -181.826408)
		(end 113.40465 -182.454804)
		(width 0.1016)
		(layer "F.Cu")
		(net "UART_SW_S1_N")
	)
	(segment
		(start 142.52575 -179.734464)
		(end 142.255748 -180.004466)
		(width 0.1016)
		(layer "F.Cu")
		(net "UART_SW_S1_N")
	)
	(segment
		(start 107.759754 -180.075332)
		(end 108.236258 -180.075332)
		(width 0.1016)
		(layer "F.Cu")
		(net "UART_SW_S1_N")
	)
	(segment
		(start 84.07908 -174.3329)
		(end 84.73186 -173.68012)
		(width 0.1016)
		(layer "F.Cu")
		(net "UART_SW_S1_N")
	)
	(segment
		(start 84.38515 -177.785268)
		(end 84.350098 -177.785268)
		(width 0.1016)
		(layer "F.Cu")
		(net "UART_SW_S1_N")
	)
	(segment
		(start 107.503468 -179.819046)
		(end 107.759754 -180.075332)
		(width 0.1016)
		(layer "F.Cu")
		(net "UART_SW_S1_N")
	)
	(segment
		(start 84.63788 -178.037998)
		(end 84.38515 -177.785268)
		(width 0.1016)
		(layer "F.Cu")
		(net "UART_SW_S1_N")
	)
	(segment
		(start 84.73186 -170.760136)
		(end 85.12302 -170.368976)
		(width 0.1016)
		(layer "F.Cu")
		(net "UART_SW_S1_N")
	)
	(segment
		(start 111.347504 -181.826408)
		(end 112.776254 -181.826408)
		(width 0.1016)
		(layer "F.Cu")
		(net "UART_SW_S1_N")
	)
	(segment
		(start 84.07908 -177.51425)
		(end 84.07908 -174.3329)
		(width 0.1016)
		(layer "F.Cu")
		(net "UART_SW_S1_N")
	)
	(segment
		(start 119.328692 -182.454804)
		(end 120.38076 -181.402736)
		(width 0.1016)
		(layer "F.Cu")
		(net "UART_SW_S1_N")
	)
	(segment
		(start 120.38076 -181.402736)
		(end 120.38076 -180.113686)
		(width 0.1016)
		(layer "F.Cu")
		(net "UART_SW_S1_N")
	)
	(segment
		(start 84.73186 -173.68012)
		(end 84.73186 -170.760136)
		(width 0.1016)
		(layer "F.Cu")
		(net "UART_SW_S1_N")
	)
	(via
		(at 107.503468 -179.819046)
		(size 0.508)
		(drill 0.254)
		(layers "F.Cu" "B.Cu")
		(net "UART_SW_S1_N")
	)
	(via
		(at 85.12302 -170.368976)
		(size 0.508)
		(drill 0.254)
		(layers "F.Cu" "B.Cu")
		(net "UART_SW_S1_N")
	)
	(via
		(at 120.38076 -181.402736)
		(size 0.508)
		(drill 0.254)
		(layers "F.Cu" "B.Cu")
		(net "UART_SW_S1_N")
	)
	(via
		(at 142.255748 -180.004466)
		(size 0.508)
		(drill 0.254)
		(layers "F.Cu" "B.Cu")
		(net "UART_SW_S1_N")
	)
	(segment
		(start 89.007696 -166.910512)
		(end 90.41257 -166.910512)
		(width 0.1016)
		(layer "B.Cu")
		(net "UART_SW_S1_N")
	)
	(segment
		(start 86.09076 -169.401236)
		(end 86.09076 -168.800018)
		(width 0.1016)
		(layer "B.Cu")
		(net "UART_SW_S1_N")
	)
	(segment
		(start 87.748872 -167.60444)
		(end 88.313768 -167.60444)
		(width 0.1016)
		(layer "B.Cu")
		(net "UART_SW_S1_N")
	)
	(segment
		(start 87.163656 -167.610028)
		(end 87.163656 -167.60444)
		(width 0.1016)
		(layer "B.Cu")
		(net "UART_SW_S1_N")
	)
	(segment
		(start 87.163656 -167.60444)
		(end 87.748872 -167.60444)
		(width 0.1016)
		(layer "B.Cu")
		(net "UART_SW_S1_N")
	)
	(segment
		(start 86.518242 -168.384474)
		(end 86.77402 -168.128696)
		(width 0.1016)
		(layer "B.Cu")
		(net "UART_SW_S1_N")
	)
	(segment
		(start 86.77402 -167.999664)
		(end 87.163656 -167.610028)
		(width 0.1016)
		(layer "B.Cu")
		(net "UART_SW_S1_N")
	)
	(segment
		(start 85.12302 -170.368976)
		(end 86.09076 -169.401236)
		(width 0.1016)
		(layer "B.Cu")
		(net "UART_SW_S1_N")
	)
	(segment
		(start 88.313768 -167.60444)
		(end 89.007696 -166.910512)
		(width 0.1016)
		(layer "B.Cu")
		(net "UART_SW_S1_N")
	)
	(segment
		(start 86.506304 -168.384474)
		(end 86.518242 -168.384474)
		(width 0.1016)
		(layer "B.Cu")
		(net "UART_SW_S1_N")
	)
	(segment
		(start 86.09076 -168.800018)
		(end 86.506304 -168.384474)
		(width 0.1016)
		(layer "B.Cu")
		(net "UART_SW_S1_N")
	)
	(segment
		(start 86.77402 -168.128696)
		(end 86.77402 -167.999664)
		(width 0.1016)
		(layer "B.Cu")
		(net "UART_SW_S1_N")
	)
	(segment
		(start 136.202166 -183.030876)
		(end 137.576306 -181.656736)
		(width 0.1143)
		(layer "In2.Cu")
		(net "UART_SW_S1_N")
	)
	(segment
		(start 128.108202 -184.706768)
		(end 134.921752 -184.706768)
		(width 0.1143)
		(layer "In2.Cu")
		(net "UART_SW_S1_N")
	)
	(segment
		(start 139.722098 -181.572662)
		(end 140.307314 -180.987446)
		(width 0.1143)
		(layer "In2.Cu")
		(net "UART_SW_S1_N")
	)
	(segment
		(start 141.779498 -180.004466)
		(end 142.255748 -180.004466)
		(width 0.1143)
		(layer "In2.Cu")
		(net "UART_SW_S1_N")
	)
	(segment
		(start 134.921752 -184.706768)
		(end 136.202166 -183.426354)
		(width 0.1143)
		(layer "In2.Cu")
		(net "UART_SW_S1_N")
	)
	(segment
		(start 140.796518 -180.987446)
		(end 141.779498 -180.004466)
		(width 0.1143)
		(layer "In2.Cu")
		(net "UART_SW_S1_N")
	)
	(segment
		(start 120.38076 -181.402736)
		(end 123.01601 -184.037986)
		(width 0.1143)
		(layer "In2.Cu")
		(net "UART_SW_S1_N")
	)
	(segment
		(start 136.202166 -183.426354)
		(end 136.202166 -183.030876)
		(width 0.1143)
		(layer "In2.Cu")
		(net "UART_SW_S1_N")
	)
	(segment
		(start 140.307314 -180.987446)
		(end 140.796518 -180.987446)
		(width 0.1143)
		(layer "In2.Cu")
		(net "UART_SW_S1_N")
	)
	(segment
		(start 137.576306 -181.656736)
		(end 138.748262 -181.656736)
		(width 0.1143)
		(layer "In2.Cu")
		(net "UART_SW_S1_N")
	)
	(segment
		(start 138.748262 -181.656736)
		(end 138.832336 -181.572662)
		(width 0.1143)
		(layer "In2.Cu")
		(net "UART_SW_S1_N")
	)
	(segment
		(start 123.01601 -184.037986)
		(end 127.43942 -184.037986)
		(width 0.1143)
		(layer "In2.Cu")
		(net "UART_SW_S1_N")
	)
	(segment
		(start 138.832336 -181.572662)
		(end 139.722098 -181.572662)
		(width 0.1143)
		(layer "In2.Cu")
		(net "UART_SW_S1_N")
	)
	(segment
		(start 127.43942 -184.037986)
		(end 128.108202 -184.706768)
		(width 0.1143)
		(layer "In2.Cu")
		(net "UART_SW_S1_N")
	)
	(segment
		(start 94.73184 -167.815768)
		(end 93.943678 -168.60393)
		(width 0.1143)
		(layer "In6.Cu")
		(net "UART_SW_S1_N")
	)
	(segment
		(start 89.087198 -169.637456)
		(end 88.809068 -169.915586)
		(width 0.1143)
		(layer "In6.Cu")
		(net "UART_SW_S1_N")
	)
	(segment
		(start 105.03281 -177.507392)
		(end 103.52278 -175.997362)
		(width 0.1143)
		(layer "In6.Cu")
		(net "UART_SW_S1_N")
	)
	(segment
		(start 96.72828 -168.138856)
		(end 96.36252 -168.138856)
		(width 0.1143)
		(layer "In6.Cu")
		(net "UART_SW_S1_N")
	)
	(segment
		(start 105.90022 -178.092354)
		(end 105.315258 -177.507392)
		(width 0.1143)
		(layer "In6.Cu")
		(net "UART_SW_S1_N")
	)
	(segment
		(start 93.57868 -168.60393)
		(end 92.782644 -169.399966)
		(width 0.1143)
		(layer "In6.Cu")
		(net "UART_SW_S1_N")
	)
	(segment
		(start 89.70772 -169.888662)
		(end 89.456514 -169.637456)
		(width 0.1143)
		(layer "In6.Cu")
		(net "UART_SW_S1_N")
	)
	(segment
		(start 96.36252 -168.138856)
		(end 96.039432 -167.815768)
		(width 0.1143)
		(layer "In6.Cu")
		(net "UART_SW_S1_N")
	)
	(segment
		(start 89.456514 -169.637456)
		(end 89.087198 -169.637456)
		(width 0.1143)
		(layer "In6.Cu")
		(net "UART_SW_S1_N")
	)
	(segment
		(start 88.809068 -169.915586)
		(end 85.57641 -169.915586)
		(width 0.1143)
		(layer "In6.Cu")
		(net "UART_SW_S1_N")
	)
	(segment
		(start 103.52278 -172.80509)
		(end 98.83775 -168.12006)
		(width 0.1143)
		(layer "In6.Cu")
		(net "UART_SW_S1_N")
	)
	(segment
		(start 107.503468 -179.819046)
		(end 105.90022 -178.215798)
		(width 0.1143)
		(layer "In6.Cu")
		(net "UART_SW_S1_N")
	)
	(segment
		(start 92.782644 -169.399966)
		(end 90.914728 -169.399966)
		(width 0.1143)
		(layer "In6.Cu")
		(net "UART_SW_S1_N")
	)
	(segment
		(start 90.426032 -169.888662)
		(end 89.70772 -169.888662)
		(width 0.1143)
		(layer "In6.Cu")
		(net "UART_SW_S1_N")
	)
	(segment
		(start 105.315258 -177.507392)
		(end 105.03281 -177.507392)
		(width 0.1143)
		(layer "In6.Cu")
		(net "UART_SW_S1_N")
	)
	(segment
		(start 96.747076 -168.12006)
		(end 96.72828 -168.138856)
		(width 0.1143)
		(layer "In6.Cu")
		(net "UART_SW_S1_N")
	)
	(segment
		(start 96.039432 -167.815768)
		(end 94.73184 -167.815768)
		(width 0.1143)
		(layer "In6.Cu")
		(net "UART_SW_S1_N")
	)
	(segment
		(start 105.90022 -178.215798)
		(end 105.90022 -178.092354)
		(width 0.1143)
		(layer "In6.Cu")
		(net "UART_SW_S1_N")
	)
	(segment
		(start 93.943678 -168.60393)
		(end 93.57868 -168.60393)
		(width 0.1143)
		(layer "In6.Cu")
		(net "UART_SW_S1_N")
	)
	(segment
		(start 85.57641 -169.915586)
		(end 85.12302 -170.368976)
		(width 0.1143)
		(layer "In6.Cu")
		(net "UART_SW_S1_N")
	)
	(segment
		(start 103.52278 -175.997362)
		(end 103.52278 -172.80509)
		(width 0.1143)
		(layer "In6.Cu")
		(net "UART_SW_S1_N")
	)
	(segment
		(start 90.914728 -169.399966)
		(end 90.426032 -169.888662)
		(width 0.1143)
		(layer "In6.Cu")
		(net "UART_SW_S1_N")
	)
	(segment
		(start 98.83775 -168.12006)
		(end 96.747076 -168.12006)
		(width 0.1143)
		(layer "In6.Cu")
		(net "UART_SW_S1_N")
	)
	(segment
		(start 141.797024 -180.93182)
		(end 141.601952 -181.126892)
		(width 0.1016)
		(layer "F.Cu")
		(net "UART_SW_S2_N")
	)
	(segment
		(start 108.303314 -178.097942)
		(end 108.303314 -178.12639)
		(width 0.1016)
		(layer "F.Cu")
		(net "UART_SW_S2_N")
	)
	(segment
		(start 141.797024 -179.740306)
		(end 141.797024 -180.93182)
		(width 0.1016)
		(layer "F.Cu")
		(net "UART_SW_S2_N")
	)
	(segment
		(start 109.99089 -179.068476)
		(end 111.20882 -180.286406)
		(width 0.1016)
		(layer "F.Cu")
		(net "UART_SW_S2_N")
	)
	(segment
		(start 117.762274 -182.150004)
		(end 118.52148 -181.390798)
		(width 0.1016)
		(layer "F.Cu")
		(net "UART_SW_S2_N")
	)
	(segment
		(start 141.601952 -181.126892)
		(end 141.601952 -181.282086)
		(width 0.1016)
		(layer "F.Cu")
		(net "UART_SW_S2_N")
	)
	(segment
		(start 84.42706 -169.995088)
		(end 84.42706 -173.553628)
		(width 0.1016)
		(layer "F.Cu")
		(net "UART_SW_S2_N")
	)
	(segment
		(start 142.025878 -179.511452)
		(end 141.797024 -179.740306)
		(width 0.1016)
		(layer "F.Cu")
		(net "UART_SW_S2_N")
	)
	(segment
		(start 111.581692 -181.521608)
		(end 112.902746 -181.521608)
		(width 0.1016)
		(layer "F.Cu")
		(net "UART_SW_S2_N")
	)
	(segment
		(start 109.2454 -179.068476)
		(end 109.99089 -179.068476)
		(width 0.1016)
		(layer "F.Cu")
		(net "UART_SW_S2_N")
	)
	(segment
		(start 118.72976 -180.113686)
		(end 118.72976 -181.182518)
		(width 0.1016)
		(layer "F.Cu")
		(net "UART_SW_S2_N")
	)
	(segment
		(start 111.20882 -180.286406)
		(end 111.20882 -181.148736)
		(width 0.1016)
		(layer "F.Cu")
		(net "UART_SW_S2_N")
	)
	(segment
		(start 112.902746 -181.521608)
		(end 113.531142 -182.150004)
		(width 0.1016)
		(layer "F.Cu")
		(net "UART_SW_S2_N")
	)
	(segment
		(start 83.77428 -174.206408)
		(end 83.77428 -178.49215)
		(width 0.1016)
		(layer "F.Cu")
		(net "UART_SW_S2_N")
	)
	(segment
		(start 108.303314 -178.12639)
		(end 109.2454 -179.068476)
		(width 0.1016)
		(layer "F.Cu")
		(net "UART_SW_S2_N")
	)
	(segment
		(start 84.62772 -169.065194)
		(end 84.62772 -169.794428)
		(width 0.1016)
		(layer "F.Cu")
		(net "UART_SW_S2_N")
	)
	(segment
		(start 113.531142 -182.150004)
		(end 117.762274 -182.150004)
		(width 0.1016)
		(layer "F.Cu")
		(net "UART_SW_S2_N")
	)
	(segment
		(start 84.62772 -169.794428)
		(end 84.42706 -169.995088)
		(width 0.1016)
		(layer "F.Cu")
		(net "UART_SW_S2_N")
	)
	(segment
		(start 84.4931 -179.874672)
		(end 84.494878 -179.874672)
		(width 0.1016)
		(layer "F.Cu")
		(net "UART_SW_S2_N")
	)
	(segment
		(start 118.72976 -181.182518)
		(end 118.52148 -181.390798)
		(width 0.1016)
		(layer "F.Cu")
		(net "UART_SW_S2_N")
	)
	(segment
		(start 84.4931 -179.21097)
		(end 84.4931 -179.874672)
		(width 0.1016)
		(layer "F.Cu")
		(net "UART_SW_S2_N")
	)
	(segment
		(start 142.025878 -178.858672)
		(end 142.025878 -179.511452)
		(width 0.1016)
		(layer "F.Cu")
		(net "UART_SW_S2_N")
	)
	(segment
		(start 83.77428 -178.49215)
		(end 84.4931 -179.21097)
		(width 0.1016)
		(layer "F.Cu")
		(net "UART_SW_S2_N")
	)
	(segment
		(start 111.20882 -181.148736)
		(end 111.581692 -181.521608)
		(width 0.1016)
		(layer "F.Cu")
		(net "UART_SW_S2_N")
	)
	(segment
		(start 84.42706 -173.553628)
		(end 83.77428 -174.206408)
		(width 0.1016)
		(layer "F.Cu")
		(net "UART_SW_S2_N")
	)
	(via
		(at 141.601952 -181.282086)
		(size 0.508)
		(drill 0.254)
		(layers "F.Cu" "B.Cu")
		(net "UART_SW_S2_N")
	)
	(via
		(at 108.303314 -178.097942)
		(size 0.508)
		(drill 0.254)
		(layers "F.Cu" "B.Cu")
		(net "UART_SW_S2_N")
	)
	(via
		(at 118.52148 -181.390798)
		(size 0.508)
		(drill 0.254)
		(layers "F.Cu" "B.Cu")
		(net "UART_SW_S2_N")
	)
	(via
		(at 84.62772 -169.065194)
		(size 0.508)
		(drill 0.254)
		(layers "F.Cu" "B.Cu")
		(net "UART_SW_S2_N")
	)
	(segment
		(start 86.240366 -165.654228)
		(end 87.748872 -165.654228)
		(width 0.1016)
		(layer "B.Cu")
		(net "UART_SW_S2_N")
	)
	(segment
		(start 88.838786 -165.64864)
		(end 89.963752 -165.64864)
		(width 0.1016)
		(layer "B.Cu")
		(net "UART_SW_S2_N")
	)
	(segment
		(start 84.62772 -169.065194)
		(end 84.89188 -169.065194)
		(width 0.1016)
		(layer "B.Cu")
		(net "UART_SW_S2_N")
	)
	(segment
		(start 88.833198 -165.654228)
		(end 88.838786 -165.64864)
		(width 0.1016)
		(layer "B.Cu")
		(net "UART_SW_S2_N")
	)
	(segment
		(start 87.748872 -165.654228)
		(end 88.833198 -165.654228)
		(width 0.1016)
		(layer "B.Cu")
		(net "UART_SW_S2_N")
	)
	(segment
		(start 85.91042 -167.219122)
		(end 85.91042 -165.984174)
		(width 0.1016)
		(layer "B.Cu")
		(net "UART_SW_S2_N")
	)
	(segment
		(start 85.34908 -167.780462)
		(end 85.91042 -167.219122)
		(width 0.1016)
		(layer "B.Cu")
		(net "UART_SW_S2_N")
	)
	(segment
		(start 84.89188 -169.065194)
		(end 85.34908 -168.607994)
		(width 0.1016)
		(layer "B.Cu")
		(net "UART_SW_S2_N")
	)
	(segment
		(start 90.209624 -165.894512)
		(end 90.41257 -165.894512)
		(width 0.1016)
		(layer "B.Cu")
		(net "UART_SW_S2_N")
	)
	(segment
		(start 85.91042 -165.984174)
		(end 86.240366 -165.654228)
		(width 0.1016)
		(layer "B.Cu")
		(net "UART_SW_S2_N")
	)
	(segment
		(start 85.34908 -168.607994)
		(end 85.34908 -167.780462)
		(width 0.1016)
		(layer "B.Cu")
		(net "UART_SW_S2_N")
	)
	(segment
		(start 89.963752 -165.64864)
		(end 90.209624 -165.894512)
		(width 0.1016)
		(layer "B.Cu")
		(net "UART_SW_S2_N")
	)
	(segment
		(start 139.999974 -182.207662)
		(end 140.545312 -181.662324)
		(width 0.1143)
		(layer "In2.Cu")
		(net "UART_SW_S2_N")
	)
	(segment
		(start 137.599166 -183.433466)
		(end 137.599166 -182.833518)
		(width 0.1143)
		(layer "In2.Cu")
		(net "UART_SW_S2_N")
	)
	(segment
		(start 139.09548 -182.207662)
		(end 139.999974 -182.207662)
		(width 0.1143)
		(layer "In2.Cu")
		(net "UART_SW_S2_N")
	)
	(segment
		(start 120.6246 -183.369966)
		(end 121.959878 -184.705244)
		(width 0.1143)
		(layer "In2.Cu")
		(net "UART_SW_S2_N")
	)
	(segment
		(start 141.221714 -181.662324)
		(end 141.601952 -181.282086)
		(width 0.1143)
		(layer "In2.Cu")
		(net "UART_SW_S2_N")
	)
	(segment
		(start 121.959878 -184.705244)
		(end 127.20574 -184.705244)
		(width 0.1143)
		(layer "In2.Cu")
		(net "UART_SW_S2_N")
	)
	(segment
		(start 135.690864 -185.341768)
		(end 137.599166 -183.433466)
		(width 0.1143)
		(layer "In2.Cu")
		(net "UART_SW_S2_N")
	)
	(segment
		(start 140.545312 -181.662324)
		(end 141.221714 -181.662324)
		(width 0.1143)
		(layer "In2.Cu")
		(net "UART_SW_S2_N")
	)
	(segment
		(start 138.140948 -182.291736)
		(end 139.011406 -182.291736)
		(width 0.1143)
		(layer "In2.Cu")
		(net "UART_SW_S2_N")
	)
	(segment
		(start 127.842264 -185.341768)
		(end 135.690864 -185.341768)
		(width 0.1143)
		(layer "In2.Cu")
		(net "UART_SW_S2_N")
	)
	(segment
		(start 120.6246 -182.720234)
		(end 120.6246 -183.369966)
		(width 0.1143)
		(layer "In2.Cu")
		(net "UART_SW_S2_N")
	)
	(segment
		(start 127.20574 -184.705244)
		(end 127.842264 -185.341768)
		(width 0.1143)
		(layer "In2.Cu")
		(net "UART_SW_S2_N")
	)
	(segment
		(start 118.94312 -181.812438)
		(end 119.716804 -181.812438)
		(width 0.1143)
		(layer "In2.Cu")
		(net "UART_SW_S2_N")
	)
	(segment
		(start 119.716804 -181.812438)
		(end 120.6246 -182.720234)
		(width 0.1143)
		(layer "In2.Cu")
		(net "UART_SW_S2_N")
	)
	(segment
		(start 139.011406 -182.291736)
		(end 139.09548 -182.207662)
		(width 0.1143)
		(layer "In2.Cu")
		(net "UART_SW_S2_N")
	)
	(segment
		(start 137.599166 -182.833518)
		(end 138.140948 -182.291736)
		(width 0.1143)
		(layer "In2.Cu")
		(net "UART_SW_S2_N")
	)
	(segment
		(start 118.52148 -181.390798)
		(end 118.94312 -181.812438)
		(width 0.1143)
		(layer "In2.Cu")
		(net "UART_SW_S2_N")
	)
	(segment
		(start 91.58732 -168.060878)
		(end 92.605098 -168.060878)
		(width 0.1143)
		(layer "In6.Cu")
		(net "UART_SW_S2_N")
	)
	(segment
		(start 94.598998 -167.498268)
		(end 95.018352 -167.498268)
		(width 0.1143)
		(layer "In6.Cu")
		(net "UART_SW_S2_N")
	)
	(segment
		(start 85.928454 -169.065194)
		(end 86.268306 -169.405046)
		(width 0.1143)
		(layer "In6.Cu")
		(net "UART_SW_S2_N")
	)
	(segment
		(start 105.66527 -176.591722)
		(end 107.17149 -178.097942)
		(width 0.1143)
		(layer "In6.Cu")
		(net "UART_SW_S2_N")
	)
	(segment
		(start 92.605098 -168.060878)
		(end 92.6846 -167.981376)
		(width 0.1143)
		(layer "In6.Cu")
		(net "UART_SW_S2_N")
	)
	(segment
		(start 86.268306 -169.405046)
		(end 87.126826 -169.405046)
		(width 0.1143)
		(layer "In6.Cu")
		(net "UART_SW_S2_N")
	)
	(segment
		(start 95.018352 -167.498268)
		(end 95.95612 -166.5605)
		(width 0.1143)
		(layer "In6.Cu")
		(net "UART_SW_S2_N")
	)
	(segment
		(start 87.126826 -169.405046)
		(end 87.549736 -168.982136)
		(width 0.1143)
		(layer "In6.Cu")
		(net "UART_SW_S2_N")
	)
	(segment
		(start 103.84028 -175.86579)
		(end 104.566212 -176.591722)
		(width 0.1143)
		(layer "In6.Cu")
		(net "UART_SW_S2_N")
	)
	(segment
		(start 95.95612 -166.5605)
		(end 97.932494 -166.5605)
		(width 0.1143)
		(layer "In6.Cu")
		(net "UART_SW_S2_N")
	)
	(segment
		(start 94.11589 -167.981376)
		(end 94.598998 -167.498268)
		(width 0.1143)
		(layer "In6.Cu")
		(net "UART_SW_S2_N")
	)
	(segment
		(start 90.666062 -168.982136)
		(end 91.58732 -168.060878)
		(width 0.1143)
		(layer "In6.Cu")
		(net "UART_SW_S2_N")
	)
	(segment
		(start 103.84028 -172.468286)
		(end 103.84028 -175.86579)
		(width 0.1143)
		(layer "In6.Cu")
		(net "UART_SW_S2_N")
	)
	(segment
		(start 84.62772 -169.065194)
		(end 85.928454 -169.065194)
		(width 0.1143)
		(layer "In6.Cu")
		(net "UART_SW_S2_N")
	)
	(segment
		(start 104.566212 -176.591722)
		(end 105.66527 -176.591722)
		(width 0.1143)
		(layer "In6.Cu")
		(net "UART_SW_S2_N")
	)
	(segment
		(start 97.932494 -166.5605)
		(end 103.84028 -172.468286)
		(width 0.1143)
		(layer "In6.Cu")
		(net "UART_SW_S2_N")
	)
	(segment
		(start 92.6846 -167.981376)
		(end 94.11589 -167.981376)
		(width 0.1143)
		(layer "In6.Cu")
		(net "UART_SW_S2_N")
	)
	(segment
		(start 87.549736 -168.982136)
		(end 90.666062 -168.982136)
		(width 0.1143)
		(layer "In6.Cu")
		(net "UART_SW_S2_N")
	)
	(segment
		(start 107.17149 -178.097942)
		(end 108.303314 -178.097942)
		(width 0.1143)
		(layer "In6.Cu")
		(net "UART_SW_S2_N")
	)
	(segment
		(start 110.970822 -182.131208)
		(end 110.60049 -181.760876)
		(width 0.1016)
		(layer "F.Cu")
		(net "UART_SW_S0_N")
	)
	(segment
		(start 120.021604 -183.463946)
		(end 119.317262 -182.759604)
		(width 0.1016)
		(layer "F.Cu")
		(net "UART_SW_S0_N")
	)
	(segment
		(start 85.91931 -180.944266)
		(end 86.66226 -180.944266)
		(width 0.1016)
		(layer "F.Cu")
		(net "UART_SW_S0_N")
	)
	(segment
		(start 113.278158 -182.759604)
		(end 112.649762 -182.131208)
		(width 0.1016)
		(layer "F.Cu")
		(net "UART_SW_S0_N")
	)
	(segment
		(start 85.494876 -179.874672)
		(end 85.494876 -180.519832)
		(width 0.1016)
		(layer "F.Cu")
		(net "UART_SW_S0_N")
	)
	(segment
		(start 122.03176 -182.770526)
		(end 122.03176 -180.113686)
		(width 0.1016)
		(layer "F.Cu")
		(net "UART_SW_S0_N")
	)
	(segment
		(start 110.60049 -181.760876)
		(end 108.820204 -181.760876)
		(width 0.1016)
		(layer "F.Cu")
		(net "UART_SW_S0_N")
	)
	(segment
		(start 142.88516 -181.12105)
		(end 142.88516 -181.217316)
		(width 0.1016)
		(layer "F.Cu")
		(net "UART_SW_S0_N")
	)
	(segment
		(start 112.649762 -182.131208)
		(end 110.970822 -182.131208)
		(width 0.1016)
		(layer "F.Cu")
		(net "UART_SW_S0_N")
	)
	(segment
		(start 143.025876 -178.858672)
		(end 143.025876 -180.980334)
		(width 0.1016)
		(layer "F.Cu")
		(net "UART_SW_S0_N")
	)
	(segment
		(start 121.33834 -183.463946)
		(end 122.03176 -182.770526)
		(width 0.1016)
		(layer "F.Cu")
		(net "UART_SW_S0_N")
	)
	(segment
		(start 121.33834 -183.463946)
		(end 120.021604 -183.463946)
		(width 0.1016)
		(layer "F.Cu")
		(net "UART_SW_S0_N")
	)
	(segment
		(start 108.820204 -181.760876)
		(end 107.627166 -180.567838)
		(width 0.1016)
		(layer "F.Cu")
		(net "UART_SW_S0_N")
	)
	(segment
		(start 143.025876 -180.980334)
		(end 142.88516 -181.12105)
		(width 0.1016)
		(layer "F.Cu")
		(net "UART_SW_S0_N")
	)
	(segment
		(start 107.627166 -180.567838)
		(end 105.59542 -180.567838)
		(width 0.1016)
		(layer "F.Cu")
		(net "UART_SW_S0_N")
	)
	(segment
		(start 85.494876 -180.519832)
		(end 85.91931 -180.944266)
		(width 0.1016)
		(layer "F.Cu")
		(net "UART_SW_S0_N")
	)
	(segment
		(start 119.317262 -182.759604)
		(end 113.278158 -182.759604)
		(width 0.1016)
		(layer "F.Cu")
		(net "UART_SW_S0_N")
	)
	(via
		(at 86.58098 -168.920668)
		(size 0.508)
		(drill 0.254)
		(layers "F.Cu" "B.Cu")
		(net "UART_SW_S0_N")
	)
	(via
		(at 121.33834 -183.463946)
		(size 0.508)
		(drill 0.254)
		(layers "F.Cu" "B.Cu")
		(net "UART_SW_S0_N")
	)
	(via
		(at 142.88516 -181.217316)
		(size 0.508)
		(drill 0.254)
		(layers "F.Cu" "B.Cu")
		(net "UART_SW_S0_N")
	)
	(via
		(at 105.59542 -180.567838)
		(size 0.508)
		(drill 0.254)
		(layers "F.Cu" "B.Cu")
		(net "UART_SW_S0_N")
	)
	(via
		(at 86.66226 -180.944266)
		(size 0.508)
		(drill 0.254)
		(layers "F.Cu" "B.Cu")
		(net "UART_SW_S0_N")
	)
	(segment
		(start 90.41257 -167.926512)
		(end 88.900254 -167.926512)
		(width 0.1016)
		(layer "B.Cu")
		(net "UART_SW_S0_N")
	)
	(segment
		(start 87.748872 -168.254426)
		(end 87.082122 -168.254426)
		(width 0.1016)
		(layer "B.Cu")
		(net "UART_SW_S0_N")
	)
	(segment
		(start 87.082122 -168.254426)
		(end 86.58098 -168.755568)
		(width 0.1016)
		(layer "B.Cu")
		(net "UART_SW_S0_N")
	)
	(segment
		(start 88.900254 -167.926512)
		(end 88.57234 -168.254426)
		(width 0.1016)
		(layer "B.Cu")
		(net "UART_SW_S0_N")
	)
	(segment
		(start 88.57234 -168.254426)
		(end 87.748872 -168.254426)
		(width 0.1016)
		(layer "B.Cu")
		(net "UART_SW_S0_N")
	)
	(segment
		(start 86.58098 -168.755568)
		(end 86.58098 -168.920668)
		(width 0.1016)
		(layer "B.Cu")
		(net "UART_SW_S0_N")
	)
	(segment
		(start 136.557004 -183.236108)
		(end 137.818876 -181.974236)
		(width 0.1143)
		(layer "In2.Cu")
		(net "UART_SW_S0_N")
	)
	(segment
		(start 121.33834 -183.463946)
		(end 122.262138 -184.387744)
		(width 0.1143)
		(layer "In2.Cu")
		(net "UART_SW_S0_N")
	)
	(segment
		(start 127.33782 -184.387744)
		(end 127.974344 -185.024268)
		(width 0.1143)
		(layer "In2.Cu")
		(net "UART_SW_S0_N")
	)
	(segment
		(start 140.936218 -181.318408)
		(end 141.41069 -180.843936)
		(width 0.1143)
		(layer "In2.Cu")
		(net "UART_SW_S0_N")
	)
	(segment
		(start 138.879834 -181.974236)
		(end 138.963908 -181.890162)
		(width 0.1143)
		(layer "In2.Cu")
		(net "UART_SW_S0_N")
	)
	(segment
		(start 140.428218 -181.318408)
		(end 140.936218 -181.318408)
		(width 0.1143)
		(layer "In2.Cu")
		(net "UART_SW_S0_N")
	)
	(segment
		(start 141.41069 -180.843936)
		(end 142.51178 -180.843936)
		(width 0.1143)
		(layer "In2.Cu")
		(net "UART_SW_S0_N")
	)
	(segment
		(start 135.053324 -185.024268)
		(end 136.557004 -183.520588)
		(width 0.1143)
		(layer "In2.Cu")
		(net "UART_SW_S0_N")
	)
	(segment
		(start 139.856464 -181.890162)
		(end 140.428218 -181.318408)
		(width 0.1143)
		(layer "In2.Cu")
		(net "UART_SW_S0_N")
	)
	(segment
		(start 127.974344 -185.024268)
		(end 135.053324 -185.024268)
		(width 0.1143)
		(layer "In2.Cu")
		(net "UART_SW_S0_N")
	)
	(segment
		(start 137.818876 -181.974236)
		(end 138.879834 -181.974236)
		(width 0.1143)
		(layer "In2.Cu")
		(net "UART_SW_S0_N")
	)
	(segment
		(start 122.262138 -184.387744)
		(end 127.33782 -184.387744)
		(width 0.1143)
		(layer "In2.Cu")
		(net "UART_SW_S0_N")
	)
	(segment
		(start 136.557004 -183.520588)
		(end 136.557004 -183.236108)
		(width 0.1143)
		(layer "In2.Cu")
		(net "UART_SW_S0_N")
	)
	(segment
		(start 138.963908 -181.890162)
		(end 139.856464 -181.890162)
		(width 0.1143)
		(layer "In2.Cu")
		(net "UART_SW_S0_N")
	)
	(segment
		(start 142.51178 -180.843936)
		(end 142.88516 -181.217316)
		(width 0.1143)
		(layer "In2.Cu")
		(net "UART_SW_S0_N")
	)
	(segment
		(start 97.698052 -179.751228)
		(end 99.68357 -179.751228)
		(width 0.1143)
		(layer "In6.Cu")
		(net "UART_SW_S0_N")
	)
	(segment
		(start 92.177362 -180.190648)
		(end 97.258632 -180.190648)
		(width 0.1143)
		(layer "In6.Cu")
		(net "UART_SW_S0_N")
	)
	(segment
		(start 87.19947 -180.944266)
		(end 87.39124 -180.752496)
		(width 0.1143)
		(layer "In6.Cu")
		(net "UART_SW_S0_N")
	)
	(segment
		(start 97.258632 -180.190648)
		(end 97.698052 -179.751228)
		(width 0.1143)
		(layer "In6.Cu")
		(net "UART_SW_S0_N")
	)
	(segment
		(start 86.66226 -180.944266)
		(end 87.19947 -180.944266)
		(width 0.1143)
		(layer "In6.Cu")
		(net "UART_SW_S0_N")
	)
	(segment
		(start 104.962452 -180.567838)
		(end 105.59542 -180.567838)
		(width 0.1143)
		(layer "In6.Cu")
		(net "UART_SW_S0_N")
	)
	(segment
		(start 103.655368 -179.260754)
		(end 104.962452 -180.567838)
		(width 0.1143)
		(layer "In6.Cu")
		(net "UART_SW_S0_N")
	)
	(segment
		(start 87.39124 -180.752496)
		(end 89.55659 -180.752496)
		(width 0.1143)
		(layer "In6.Cu")
		(net "UART_SW_S0_N")
	)
	(segment
		(start 99.68357 -179.751228)
		(end 100.174044 -179.260754)
		(width 0.1143)
		(layer "In6.Cu")
		(net "UART_SW_S0_N")
	)
	(segment
		(start 100.174044 -179.260754)
		(end 103.655368 -179.260754)
		(width 0.1143)
		(layer "In6.Cu")
		(net "UART_SW_S0_N")
	)
	(segment
		(start 90.139266 -180.16982)
		(end 92.156534 -180.16982)
		(width 0.1143)
		(layer "In6.Cu")
		(net "UART_SW_S0_N")
	)
	(segment
		(start 89.55659 -180.752496)
		(end 90.139266 -180.16982)
		(width 0.1143)
		(layer "In6.Cu")
		(net "UART_SW_S0_N")
	)
	(segment
		(start 92.156534 -180.16982)
		(end 92.177362 -180.190648)
		(width 0.1143)
		(layer "In6.Cu")
		(net "UART_SW_S0_N")
	)
	(segment
		(start 86.73465 -178.130454)
		(end 86.48827 -178.376834)
		(width 0.1143)
		(layer "In7.Cu")
		(net "UART_SW_S0_N")
	)
	(segment
		(start 86.48827 -180.770276)
		(end 86.66226 -180.944266)
		(width 0.1143)
		(layer "In7.Cu")
		(net "UART_SW_S0_N")
	)
	(segment
		(start 87.086186 -169.425874)
		(end 87.086186 -172.52188)
		(width 0.1143)
		(layer "In7.Cu")
		(net "UART_SW_S0_N")
	)
	(segment
		(start 86.48827 -178.376834)
		(end 86.48827 -180.770276)
		(width 0.1143)
		(layer "In7.Cu")
		(net "UART_SW_S0_N")
	)
	(segment
		(start 85.362542 -175.045116)
		(end 86.73465 -176.417224)
		(width 0.1143)
		(layer "In7.Cu")
		(net "UART_SW_S0_N")
	)
	(segment
		(start 86.73465 -176.417224)
		(end 86.73465 -178.130454)
		(width 0.1143)
		(layer "In7.Cu")
		(net "UART_SW_S0_N")
	)
	(segment
		(start 86.58098 -168.920668)
		(end 87.086186 -169.425874)
		(width 0.1143)
		(layer "In7.Cu")
		(net "UART_SW_S0_N")
	)
	(segment
		(start 85.362542 -174.245524)
		(end 85.362542 -175.045116)
		(width 0.1143)
		(layer "In7.Cu")
		(net "UART_SW_S0_N")
	)
	(segment
		(start 87.086186 -172.52188)
		(end 85.362542 -174.245524)
		(width 0.1143)
		(layer "In7.Cu")
		(net "UART_SW_S0_N")
	)
	(segment
		(start 73.994772 -181.32425)
		(end 73.994772 -179.874672)
		(width 0.1016)
		(layer "F.Cu")
		(net "JTAG_CPLD2_TDO")
	)
	(via
		(at 73.994772 -181.32425)
		(size 0.508)
		(drill 0.254)
		(layers "F.Cu" "B.Cu")
		(net "JTAG_CPLD2_TDO")
	)
	(via
		(at 170.815 -190.291466)
		(size 0.508)
		(drill 0.254)
		(layers "F.Cu" "B.Cu")
		(net "JTAG_CPLD2_TDO")
	)
	(via
		(at 191.897 -85.798914)
		(size 0.508)
		(drill 0.254)
		(layers "F.Cu" "B.Cu")
		(net "JTAG_CPLD2_TDO")
	)
	(segment
		(start 137.88009 -43.723052)
		(end 135.100822 -43.723052)
		(width 0.1016)
		(layer "B.Cu")
		(net "JTAG_CPLD2_TDO")
	)
	(segment
		(start 146.080734 -43.071288)
		(end 140.190982 -43.071288)
		(width 0.1016)
		(layer "B.Cu")
		(net "JTAG_CPLD2_TDO")
	)
	(segment
		(start 153.268172 -25.261824)
		(end 153.268172 -29.927042)
		(width 0.1016)
		(layer "B.Cu")
		(net "JTAG_CPLD2_TDO")
	)
	(segment
		(start 152.798272 -8.382)
		(end 146.1516 -8.382)
		(width 0.1016)
		(layer "B.Cu")
		(net "JTAG_CPLD2_TDO")
	)
	(segment
		(start 152.69464 -39.57447)
		(end 148.852382 -43.416728)
		(width 0.1016)
		(layer "B.Cu")
		(net "JTAG_CPLD2_TDO")
	)
	(segment
		(start 133.31825 -41.94048)
		(end 133.31825 -40.896286)
		(width 0.1016)
		(layer "B.Cu")
		(net "JTAG_CPLD2_TDO")
	)
	(segment
		(start 140.190982 -43.071288)
		(end 140.169138 -43.093132)
		(width 0.1016)
		(layer "B.Cu")
		(net "JTAG_CPLD2_TDO")
	)
	(segment
		(start 138.404854 -43.198288)
		(end 137.88009 -43.723052)
		(width 0.1016)
		(layer "B.Cu")
		(net "JTAG_CPLD2_TDO")
	)
	(segment
		(start 152.317196 -17.265396)
		(end 152.317196 -24.310848)
		(width 0.1016)
		(layer "B.Cu")
		(net "JTAG_CPLD2_TDO")
	)
	(segment
		(start 136.90854 -41.50741)
		(end 137.569956 -41.50741)
		(width 0.1016)
		(layer "B.Cu")
		(net "JTAG_CPLD2_TDO")
	)
	(segment
		(start 140.063728 -43.198288)
		(end 138.404854 -43.198288)
		(width 0.1016)
		(layer "B.Cu")
		(net "JTAG_CPLD2_TDO")
	)
	(segment
		(start 146.1516 -8.382)
		(end 145.288 -9.2456)
		(width 0.1016)
		(layer "B.Cu")
		(net "JTAG_CPLD2_TDO")
	)
	(segment
		(start 148.852382 -43.416728)
		(end 146.426174 -43.416728)
		(width 0.1016)
		(layer "B.Cu")
		(net "JTAG_CPLD2_TDO")
	)
	(segment
		(start 140.169138 -43.093132)
		(end 140.063728 -43.198288)
		(width 0.1016)
		(layer "B.Cu")
		(net "JTAG_CPLD2_TDO")
	)
	(segment
		(start 153.268172 -29.927042)
		(end 152.69464 -30.500574)
		(width 0.1016)
		(layer "B.Cu")
		(net "JTAG_CPLD2_TDO")
	)
	(segment
		(start 149.2758 -14.224)
		(end 152.317196 -17.265396)
		(width 0.1016)
		(layer "B.Cu")
		(net "JTAG_CPLD2_TDO")
	)
	(segment
		(start 135.100822 -43.723052)
		(end 133.31825 -41.94048)
		(width 0.1016)
		(layer "B.Cu")
		(net "JTAG_CPLD2_TDO")
	)
	(segment
		(start 152.317196 -24.310848)
		(end 153.268172 -25.261824)
		(width 0.1016)
		(layer "B.Cu")
		(net "JTAG_CPLD2_TDO")
	)
	(segment
		(start 145.288 -12.1412)
		(end 147.3708 -14.224)
		(width 0.1016)
		(layer "B.Cu")
		(net "JTAG_CPLD2_TDO")
	)
	(segment
		(start 154.272234 -9.855962)
		(end 152.798272 -8.382)
		(width 0.1016)
		(layer "B.Cu")
		(net "JTAG_CPLD2_TDO")
	)
	(segment
		(start 146.426174 -43.416728)
		(end 146.080734 -43.071288)
		(width 0.1016)
		(layer "B.Cu")
		(net "JTAG_CPLD2_TDO")
	)
	(segment
		(start 145.288 -9.2456)
		(end 145.288 -12.1412)
		(width 0.1016)
		(layer "B.Cu")
		(net "JTAG_CPLD2_TDO")
	)
	(segment
		(start 152.69464 -30.500574)
		(end 152.69464 -39.57447)
		(width 0.1016)
		(layer "B.Cu")
		(net "JTAG_CPLD2_TDO")
	)
	(segment
		(start 133.31825 -40.896286)
		(end 133.615684 -40.598852)
		(width 0.1016)
		(layer "B.Cu")
		(net "JTAG_CPLD2_TDO")
	)
	(segment
		(start 147.3708 -14.224)
		(end 149.2758 -14.224)
		(width 0.1016)
		(layer "B.Cu")
		(net "JTAG_CPLD2_TDO")
	)
	(segment
		(start 135.999982 -40.598852)
		(end 136.90854 -41.50741)
		(width 0.1016)
		(layer "B.Cu")
		(net "JTAG_CPLD2_TDO")
	)
	(segment
		(start 133.615684 -40.598852)
		(end 135.999982 -40.598852)
		(width 0.1016)
		(layer "B.Cu")
		(net "JTAG_CPLD2_TDO")
	)
	(segment
		(start 198.0184 -154.658822)
		(end 198.0184 -90.8558)
		(width 0.1143)
		(layer "In2.Cu")
		(net "JTAG_CPLD2_TDO")
	)
	(segment
		(start 186.92368 -166.51732)
		(end 186.92368 -165.753542)
		(width 0.1143)
		(layer "In2.Cu")
		(net "JTAG_CPLD2_TDO")
	)
	(segment
		(start 170.43019 -189.88659)
		(end 170.43019 -189.36081)
		(width 0.1143)
		(layer "In2.Cu")
		(net "JTAG_CPLD2_TDO")
	)
	(segment
		(start 184.1754 -179.2478)
		(end 184.1754 -169.291)
		(width 0.1143)
		(layer "In2.Cu")
		(net "JTAG_CPLD2_TDO")
	)
	(segment
		(start 185.501026 -167.965374)
		(end 185.501026 -167.939974)
		(width 0.1143)
		(layer "In2.Cu")
		(net "JTAG_CPLD2_TDO")
	)
	(segment
		(start 170.815 -190.291466)
		(end 170.815 -190.2714)
		(width 0.1143)
		(layer "In2.Cu")
		(net "JTAG_CPLD2_TDO")
	)
	(segment
		(start 193.2432 -86.0806)
		(end 192.532 -86.0806)
		(width 0.1143)
		(layer "In2.Cu")
		(net "JTAG_CPLD2_TDO")
	)
	(segment
		(start 186.92368 -165.753542)
		(end 198.0184 -154.658822)
		(width 0.1143)
		(layer "In2.Cu")
		(net "JTAG_CPLD2_TDO")
	)
	(segment
		(start 185.501026 -167.939974)
		(end 186.92368 -166.51732)
		(width 0.1143)
		(layer "In2.Cu")
		(net "JTAG_CPLD2_TDO")
	)
	(segment
		(start 174.9171 -188.5061)
		(end 184.1754 -179.2478)
		(width 0.1143)
		(layer "In2.Cu")
		(net "JTAG_CPLD2_TDO")
	)
	(segment
		(start 192.250314 -85.798914)
		(end 191.897 -85.798914)
		(width 0.1143)
		(layer "In2.Cu")
		(net "JTAG_CPLD2_TDO")
	)
	(segment
		(start 170.815 -190.2714)
		(end 170.43019 -189.88659)
		(width 0.1143)
		(layer "In2.Cu")
		(net "JTAG_CPLD2_TDO")
	)
	(segment
		(start 192.532 -86.0806)
		(end 192.250314 -85.798914)
		(width 0.1143)
		(layer "In2.Cu")
		(net "JTAG_CPLD2_TDO")
	)
	(segment
		(start 170.43019 -189.36081)
		(end 171.2849 -188.5061)
		(width 0.1143)
		(layer "In2.Cu")
		(net "JTAG_CPLD2_TDO")
	)
	(segment
		(start 171.2849 -188.5061)
		(end 174.9171 -188.5061)
		(width 0.1143)
		(layer "In2.Cu")
		(net "JTAG_CPLD2_TDO")
	)
	(segment
		(start 184.1754 -169.291)
		(end 185.501026 -167.965374)
		(width 0.1143)
		(layer "In2.Cu")
		(net "JTAG_CPLD2_TDO")
	)
	(segment
		(start 198.0184 -90.8558)
		(end 193.2432 -86.0806)
		(width 0.1143)
		(layer "In2.Cu")
		(net "JTAG_CPLD2_TDO")
	)
	(segment
		(start 164.4396 -190.0936)
		(end 165.735 -188.7982)
		(width 0.1143)
		(layer "In6.Cu")
		(net "JTAG_CPLD2_TDO")
	)
	(segment
		(start 170.9166 -47.683166)
		(end 168.40708 -45.173646)
		(width 0.1143)
		(layer "In6.Cu")
		(net "JTAG_CPLD2_TDO")
	)
	(segment
		(start 161.6456 -190.0936)
		(end 164.4396 -190.0936)
		(width 0.1143)
		(layer "In6.Cu")
		(net "JTAG_CPLD2_TDO")
	)
	(segment
		(start 166.77132 -34.587688)
		(end 166.77132 -19.70532)
		(width 0.1143)
		(layer "In6.Cu")
		(net "JTAG_CPLD2_TDO")
	)
	(segment
		(start 104.419654 -185.662824)
		(end 128.040638 -185.662824)
		(width 0.1143)
		(layer "In6.Cu")
		(net "JTAG_CPLD2_TDO")
	)
	(segment
		(start 160.3756 -188.818266)
		(end 160.3756 -188.8236)
		(width 0.1143)
		(layer "In6.Cu")
		(net "JTAG_CPLD2_TDO")
	)
	(segment
		(start 92.348812 -185.189876)
		(end 92.46362 -185.304684)
		(width 0.1143)
		(layer "In6.Cu")
		(net "JTAG_CPLD2_TDO")
	)
	(segment
		(start 165.735 -188.7982)
		(end 169.3418 -188.7982)
		(width 0.1143)
		(layer "In6.Cu")
		(net "JTAG_CPLD2_TDO")
	)
	(segment
		(start 192.17005 -84.92236)
		(end 191.91351 -84.66582)
		(width 0.1143)
		(layer "In6.Cu")
		(net "JTAG_CPLD2_TDO")
	)
	(segment
		(start 85.70722 -185.85434)
		(end 85.767418 -185.794142)
		(width 0.1143)
		(layer "In6.Cu")
		(net "JTAG_CPLD2_TDO")
	)
	(segment
		(start 85.767418 -185.794142)
		(end 90.464132 -185.794142)
		(width 0.1143)
		(layer "In6.Cu")
		(net "JTAG_CPLD2_TDO")
	)
	(segment
		(start 192.17005 -85.525864)
		(end 192.17005 -84.92236)
		(width 0.1143)
		(layer "In6.Cu")
		(net "JTAG_CPLD2_TDO")
	)
	(segment
		(start 168.40708 -36.223448)
		(end 166.77132 -34.587688)
		(width 0.1143)
		(layer "In6.Cu")
		(net "JTAG_CPLD2_TDO")
	)
	(segment
		(start 191.897 -85.798914)
		(end 192.17005 -85.525864)
		(width 0.1143)
		(layer "In6.Cu")
		(net "JTAG_CPLD2_TDO")
	)
	(segment
		(start 75.60818 -185.85434)
		(end 85.70722 -185.85434)
		(width 0.1143)
		(layer "In6.Cu")
		(net "JTAG_CPLD2_TDO")
	)
	(segment
		(start 168.40708 -45.173646)
		(end 168.40708 -36.223448)
		(width 0.1143)
		(layer "In6.Cu")
		(net "JTAG_CPLD2_TDO")
	)
	(segment
		(start 158.0896 -11.0236)
		(end 155.439872 -11.0236)
		(width 0.1143)
		(layer "In6.Cu")
		(net "JTAG_CPLD2_TDO")
	)
	(segment
		(start 95.876618 -185.304684)
		(end 96.992948 -184.188354)
		(width 0.1143)
		(layer "In6.Cu")
		(net "JTAG_CPLD2_TDO")
	)
	(segment
		(start 74.06005 -181.389528)
		(end 74.06005 -184.30621)
		(width 0.1143)
		(layer "In6.Cu")
		(net "JTAG_CPLD2_TDO")
	)
	(segment
		(start 91.068398 -185.189876)
		(end 92.348812 -185.189876)
		(width 0.1143)
		(layer "In6.Cu")
		(net "JTAG_CPLD2_TDO")
	)
	(segment
		(start 166.77132 -19.70532)
		(end 158.0896 -11.0236)
		(width 0.1143)
		(layer "In6.Cu")
		(net "JTAG_CPLD2_TDO")
	)
	(segment
		(start 170.9166 -67.3862)
		(end 170.9166 -47.683166)
		(width 0.1143)
		(layer "In6.Cu")
		(net "JTAG_CPLD2_TDO")
	)
	(segment
		(start 160.2232 -188.665866)
		(end 160.3756 -188.818266)
		(width 0.1143)
		(layer "In6.Cu")
		(net "JTAG_CPLD2_TDO")
	)
	(segment
		(start 191.91351 -84.66582)
		(end 188.19622 -84.66582)
		(width 0.1143)
		(layer "In6.Cu")
		(net "JTAG_CPLD2_TDO")
	)
	(segment
		(start 101.602286 -182.938166)
		(end 101.96703 -182.938166)
		(width 0.1143)
		(layer "In6.Cu")
		(net "JTAG_CPLD2_TDO")
	)
	(segment
		(start 169.3418 -188.7982)
		(end 170.815 -190.2714)
		(width 0.1143)
		(layer "In6.Cu")
		(net "JTAG_CPLD2_TDO")
	)
	(segment
		(start 73.994772 -181.32425)
		(end 74.06005 -181.389528)
		(width 0.1143)
		(layer "In6.Cu")
		(net "JTAG_CPLD2_TDO")
	)
	(segment
		(start 128.040638 -185.662824)
		(end 131.04368 -188.665866)
		(width 0.1143)
		(layer "In6.Cu")
		(net "JTAG_CPLD2_TDO")
	)
	(segment
		(start 170.815 -190.2714)
		(end 170.815 -190.291466)
		(width 0.1143)
		(layer "In6.Cu")
		(net "JTAG_CPLD2_TDO")
	)
	(segment
		(start 102.22484 -183.46801)
		(end 104.419654 -185.662824)
		(width 0.1143)
		(layer "In6.Cu")
		(net "JTAG_CPLD2_TDO")
	)
	(segment
		(start 96.992948 -184.188354)
		(end 100.352098 -184.188354)
		(width 0.1143)
		(layer "In6.Cu")
		(net "JTAG_CPLD2_TDO")
	)
	(segment
		(start 160.3756 -188.8236)
		(end 161.6456 -190.0936)
		(width 0.1143)
		(layer "In6.Cu")
		(net "JTAG_CPLD2_TDO")
	)
	(segment
		(start 188.19622 -84.66582)
		(end 170.9166 -67.3862)
		(width 0.1143)
		(layer "In6.Cu")
		(net "JTAG_CPLD2_TDO")
	)
	(segment
		(start 101.96703 -182.938166)
		(end 102.22484 -183.195976)
		(width 0.1143)
		(layer "In6.Cu")
		(net "JTAG_CPLD2_TDO")
	)
	(segment
		(start 131.04368 -188.665866)
		(end 160.2232 -188.665866)
		(width 0.1143)
		(layer "In6.Cu")
		(net "JTAG_CPLD2_TDO")
	)
	(segment
		(start 102.22484 -183.195976)
		(end 102.22484 -183.46801)
		(width 0.1143)
		(layer "In6.Cu")
		(net "JTAG_CPLD2_TDO")
	)
	(segment
		(start 74.06005 -184.30621)
		(end 75.60818 -185.85434)
		(width 0.1143)
		(layer "In6.Cu")
		(net "JTAG_CPLD2_TDO")
	)
	(segment
		(start 155.439872 -11.0236)
		(end 154.272234 -9.855962)
		(width 0.1143)
		(layer "In6.Cu")
		(net "JTAG_CPLD2_TDO")
	)
	(segment
		(start 90.464132 -185.794142)
		(end 91.068398 -185.189876)
		(width 0.1143)
		(layer "In6.Cu")
		(net "JTAG_CPLD2_TDO")
	)
	(segment
		(start 92.46362 -185.304684)
		(end 95.876618 -185.304684)
		(width 0.1143)
		(layer "In6.Cu")
		(net "JTAG_CPLD2_TDO")
	)
	(segment
		(start 100.352098 -184.188354)
		(end 101.602286 -182.938166)
		(width 0.1143)
		(layer "In6.Cu")
		(net "JTAG_CPLD2_TDO")
	)
	(segment
		(start 75.876658 -182.171848)
		(end 75.494642 -181.789832)
		(width 0.1016)
		(layer "F.Cu")
		(net "JTAG_CPLD2_TMS")
	)
	(segment
		(start 75.494642 -180.621432)
		(end 75.494642 -179.874672)
		(width 0.1016)
		(layer "F.Cu")
		(net "JTAG_CPLD2_TMS")
	)
	(segment
		(start 75.494642 -181.742842)
		(end 75.49388 -181.742842)
		(width 0.1016)
		(layer "F.Cu")
		(net "JTAG_CPLD2_TMS")
	)
	(segment
		(start 76.402946 -182.171848)
		(end 75.876658 -182.171848)
		(width 0.1016)
		(layer "F.Cu")
		(net "JTAG_CPLD2_TMS")
	)
	(segment
		(start 75.49388 -180.621432)
		(end 75.494642 -180.621432)
		(width 0.1016)
		(layer "F.Cu")
		(net "JTAG_CPLD2_TMS")
	)
	(segment
		(start 75.49388 -181.742842)
		(end 75.49388 -180.621432)
		(width 0.1016)
		(layer "F.Cu")
		(net "JTAG_CPLD2_TMS")
	)
	(segment
		(start 75.494642 -181.789832)
		(end 75.494642 -181.742842)
		(width 0.1016)
		(layer "F.Cu")
		(net "JTAG_CPLD2_TMS")
	)
	(via
		(at 75.494642 -181.742842)
		(size 0.508)
		(drill 0.254)
		(layers "F.Cu" "B.Cu")
		(net "JTAG_CPLD2_TMS")
	)
	(via
		(at 191.7319 -85.10397)
		(size 0.508)
		(drill 0.254)
		(layers "F.Cu" "B.Cu")
		(net "JTAG_CPLD2_TMS")
	)
	(via
		(at 170.86834 -189.54369)
		(size 0.508)
		(drill 0.254)
		(layers "F.Cu" "B.Cu")
		(net "JTAG_CPLD2_TMS")
	)
	(segment
		(start 152.73274 -17.19834)
		(end 152.73274 -22.087078)
		(width 0.1016)
		(layer "B.Cu")
		(net "JTAG_CPLD2_TMS")
	)
	(segment
		(start 147.5486 -13.8938)
		(end 149.4282 -13.8938)
		(width 0.1016)
		(layer "B.Cu")
		(net "JTAG_CPLD2_TMS")
	)
	(segment
		(start 140.039598 -43.689524)
		(end 138.380724 -43.689524)
		(width 0.1016)
		(layer "B.Cu")
		(net "JTAG_CPLD2_TMS")
	)
	(segment
		(start 138.380724 -43.689524)
		(end 138.016996 -44.053252)
		(width 0.1016)
		(layer "B.Cu")
		(net "JTAG_CPLD2_TMS")
	)
	(segment
		(start 145.943828 -43.401488)
		(end 140.327634 -43.401488)
		(width 0.1016)
		(layer "B.Cu")
		(net "JTAG_CPLD2_TMS")
	)
	(segment
		(start 138.016996 -44.053252)
		(end 134.858252 -44.053252)
		(width 0.1016)
		(layer "B.Cu")
		(net "JTAG_CPLD2_TMS")
	)
	(segment
		(start 149.4282 -13.8938)
		(end 152.73274 -17.19834)
		(width 0.1016)
		(layer "B.Cu")
		(net "JTAG_CPLD2_TMS")
	)
	(segment
		(start 132.2832 -41.4782)
		(end 131.3434 -41.4782)
		(width 0.1016)
		(layer "B.Cu")
		(net "JTAG_CPLD2_TMS")
	)
	(segment
		(start 153.04008 -30.833314)
		(end 153.04008 -39.696136)
		(width 0.1016)
		(layer "B.Cu")
		(net "JTAG_CPLD2_TMS")
	)
	(segment
		(start 151.732234 -9.855962)
		(end 150.715472 -8.8392)
		(width 0.1016)
		(layer "B.Cu")
		(net "JTAG_CPLD2_TMS")
	)
	(segment
		(start 131.3434 -41.4782)
		(end 130.90525 -41.04005)
		(width 0.1016)
		(layer "B.Cu")
		(net "JTAG_CPLD2_TMS")
	)
	(segment
		(start 130.90525 -41.04005)
		(end 130.90525 -40.62476)
		(width 0.1016)
		(layer "B.Cu")
		(net "JTAG_CPLD2_TMS")
	)
	(segment
		(start 148.989288 -43.746928)
		(end 146.289268 -43.746928)
		(width 0.1016)
		(layer "B.Cu")
		(net "JTAG_CPLD2_TMS")
	)
	(segment
		(start 153.985722 -29.887672)
		(end 153.04008 -30.833314)
		(width 0.1016)
		(layer "B.Cu")
		(net "JTAG_CPLD2_TMS")
	)
	(segment
		(start 140.327634 -43.401488)
		(end 140.039598 -43.689524)
		(width 0.1016)
		(layer "B.Cu")
		(net "JTAG_CPLD2_TMS")
	)
	(segment
		(start 134.858252 -44.053252)
		(end 132.2832 -41.4782)
		(width 0.1016)
		(layer "B.Cu")
		(net "JTAG_CPLD2_TMS")
	)
	(segment
		(start 145.6182 -11.9634)
		(end 147.5486 -13.8938)
		(width 0.1016)
		(layer "B.Cu")
		(net "JTAG_CPLD2_TMS")
	)
	(segment
		(start 152.73274 -22.087078)
		(end 153.985722 -23.34006)
		(width 0.1016)
		(layer "B.Cu")
		(net "JTAG_CPLD2_TMS")
	)
	(segment
		(start 153.985722 -23.34006)
		(end 153.985722 -29.887672)
		(width 0.1016)
		(layer "B.Cu")
		(net "JTAG_CPLD2_TMS")
	)
	(segment
		(start 150.715472 -8.8392)
		(end 146.2024 -8.8392)
		(width 0.1016)
		(layer "B.Cu")
		(net "JTAG_CPLD2_TMS")
	)
	(segment
		(start 153.04008 -39.696136)
		(end 148.989288 -43.746928)
		(width 0.1016)
		(layer "B.Cu")
		(net "JTAG_CPLD2_TMS")
	)
	(segment
		(start 146.289268 -43.746928)
		(end 145.943828 -43.401488)
		(width 0.1016)
		(layer "B.Cu")
		(net "JTAG_CPLD2_TMS")
	)
	(segment
		(start 146.2024 -8.8392)
		(end 145.6182 -9.4234)
		(width 0.1016)
		(layer "B.Cu")
		(net "JTAG_CPLD2_TMS")
	)
	(segment
		(start 145.6182 -9.4234)
		(end 145.6182 -11.9634)
		(width 0.1016)
		(layer "B.Cu")
		(net "JTAG_CPLD2_TMS")
	)
	(segment
		(start 192.6844 -85.598)
		(end 192.19037 -85.10397)
		(width 0.1143)
		(layer "In2.Cu")
		(net "JTAG_CPLD2_TMS")
	)
	(segment
		(start 184.7088 -169.458386)
		(end 198.4502 -155.716986)
		(width 0.1143)
		(layer "In2.Cu")
		(net "JTAG_CPLD2_TMS")
	)
	(segment
		(start 175.6664 -189.1792)
		(end 184.7088 -180.1368)
		(width 0.1143)
		(layer "In2.Cu")
		(net "JTAG_CPLD2_TMS")
	)
	(segment
		(start 192.19037 -85.10397)
		(end 191.7319 -85.10397)
		(width 0.1143)
		(layer "In2.Cu")
		(net "JTAG_CPLD2_TMS")
	)
	(segment
		(start 198.4502 -155.716986)
		(end 198.4502 -90.551)
		(width 0.1143)
		(layer "In2.Cu")
		(net "JTAG_CPLD2_TMS")
	)
	(segment
		(start 193.4972 -85.598)
		(end 192.6844 -85.598)
		(width 0.1143)
		(layer "In2.Cu")
		(net "JTAG_CPLD2_TMS")
	)
	(segment
		(start 198.4502 -90.551)
		(end 193.4972 -85.598)
		(width 0.1143)
		(layer "In2.Cu")
		(net "JTAG_CPLD2_TMS")
	)
	(segment
		(start 184.7088 -180.1368)
		(end 184.7088 -169.458386)
		(width 0.1143)
		(layer "In2.Cu")
		(net "JTAG_CPLD2_TMS")
	)
	(segment
		(start 171.23283 -189.1792)
		(end 175.6664 -189.1792)
		(width 0.1143)
		(layer "In2.Cu")
		(net "JTAG_CPLD2_TMS")
	)
	(segment
		(start 170.86834 -189.54369)
		(end 171.23283 -189.1792)
		(width 0.1143)
		(layer "In2.Cu")
		(net "JTAG_CPLD2_TMS")
	)
	(segment
		(start 89.090754 -185.375042)
		(end 85.592158 -185.375042)
		(width 0.1143)
		(layer "In6.Cu")
		(net "JTAG_CPLD2_TMS")
	)
	(segment
		(start 103.7463 -183.594248)
		(end 103.7463 -183.56199)
		(width 0.1143)
		(layer "In6.Cu")
		(net "JTAG_CPLD2_TMS")
	)
	(segment
		(start 103.48849 -183.30418)
		(end 103.048308 -183.30418)
		(width 0.1143)
		(layer "In6.Cu")
		(net "JTAG_CPLD2_TMS")
	)
	(segment
		(start 164.2364 -188.8236)
		(end 161.5186 -188.8236)
		(width 0.1143)
		(layer "In6.Cu")
		(net "JTAG_CPLD2_TMS")
	)
	(segment
		(start 164.813234 -188.246766)
		(end 164.2364 -188.8236)
		(width 0.1143)
		(layer "In6.Cu")
		(net "JTAG_CPLD2_TMS")
	)
	(segment
		(start 126.88316 -184.751726)
		(end 126.701296 -184.93359)
		(width 0.1143)
		(layer "In6.Cu")
		(net "JTAG_CPLD2_TMS")
	)
	(segment
		(start 74.97064 -183.905398)
		(end 74.97064 -182.205376)
		(width 0.1143)
		(layer "In6.Cu")
		(net "JTAG_CPLD2_TMS")
	)
	(segment
		(start 170.46956 -49.59604)
		(end 167.93464 -47.06112)
		(width 0.1143)
		(layer "In6.Cu")
		(net "JTAG_CPLD2_TMS")
	)
	(segment
		(start 187.99937 -85.10397)
		(end 170.46956 -67.57416)
		(width 0.1143)
		(layer "In6.Cu")
		(net "JTAG_CPLD2_TMS")
	)
	(segment
		(start 95.692214 -184.336436)
		(end 90.12936 -184.336436)
		(width 0.1143)
		(layer "In6.Cu")
		(net "JTAG_CPLD2_TMS")
	)
	(segment
		(start 74.97064 -182.205376)
		(end 75.433174 -181.742842)
		(width 0.1143)
		(layer "In6.Cu")
		(net "JTAG_CPLD2_TMS")
	)
	(segment
		(start 102.263194 -182.519066)
		(end 101.184202 -182.519066)
		(width 0.1143)
		(layer "In6.Cu")
		(net "JTAG_CPLD2_TMS")
	)
	(segment
		(start 75.433174 -181.742842)
		(end 75.494642 -181.742842)
		(width 0.1143)
		(layer "In6.Cu")
		(net "JTAG_CPLD2_TMS")
	)
	(segment
		(start 105.085642 -184.93359)
		(end 103.7463 -183.594248)
		(width 0.1143)
		(layer "In6.Cu")
		(net "JTAG_CPLD2_TMS")
	)
	(segment
		(start 161.5186 -188.8236)
		(end 161.2138 -188.5188)
		(width 0.1143)
		(layer "In6.Cu")
		(net "JTAG_CPLD2_TMS")
	)
	(segment
		(start 166.243 -19.7866)
		(end 157.9372 -11.4808)
		(width 0.1143)
		(layer "In6.Cu")
		(net "JTAG_CPLD2_TMS")
	)
	(segment
		(start 170.46956 -67.57416)
		(end 170.46956 -49.59604)
		(width 0.1143)
		(layer "In6.Cu")
		(net "JTAG_CPLD2_TMS")
	)
	(segment
		(start 90.12936 -184.336436)
		(end 89.090754 -185.375042)
		(width 0.1143)
		(layer "In6.Cu")
		(net "JTAG_CPLD2_TMS")
	)
	(segment
		(start 191.7319 -85.10397)
		(end 187.99937 -85.10397)
		(width 0.1143)
		(layer "In6.Cu")
		(net "JTAG_CPLD2_TMS")
	)
	(segment
		(start 100.720144 -182.983124)
		(end 97.603818 -182.983124)
		(width 0.1143)
		(layer "In6.Cu")
		(net "JTAG_CPLD2_TMS")
	)
	(segment
		(start 95.78848 -184.432702)
		(end 95.692214 -184.336436)
		(width 0.1143)
		(layer "In6.Cu")
		(net "JTAG_CPLD2_TMS")
	)
	(segment
		(start 85.592158 -185.375042)
		(end 85.53196 -185.43524)
		(width 0.1143)
		(layer "In6.Cu")
		(net "JTAG_CPLD2_TMS")
	)
	(segment
		(start 170.86834 -189.54369)
		(end 170.86834 -189.53734)
		(width 0.1143)
		(layer "In6.Cu")
		(net "JTAG_CPLD2_TMS")
	)
	(segment
		(start 157.9372 -11.4808)
		(end 153.357072 -11.4808)
		(width 0.1143)
		(layer "In6.Cu")
		(net "JTAG_CPLD2_TMS")
	)
	(segment
		(start 153.357072 -11.4808)
		(end 151.732234 -9.855962)
		(width 0.1143)
		(layer "In6.Cu")
		(net "JTAG_CPLD2_TMS")
	)
	(segment
		(start 161.2138 -188.5188)
		(end 161.2138 -188.500766)
		(width 0.1143)
		(layer "In6.Cu")
		(net "JTAG_CPLD2_TMS")
	)
	(segment
		(start 76.500482 -185.43524)
		(end 74.97064 -183.905398)
		(width 0.1143)
		(layer "In6.Cu")
		(net "JTAG_CPLD2_TMS")
	)
	(segment
		(start 126.701296 -184.93359)
		(end 105.085642 -184.93359)
		(width 0.1143)
		(layer "In6.Cu")
		(net "JTAG_CPLD2_TMS")
	)
	(segment
		(start 167.93464 -47.06112)
		(end 167.93464 -36.430712)
		(width 0.1143)
		(layer "In6.Cu")
		(net "JTAG_CPLD2_TMS")
	)
	(segment
		(start 103.7463 -183.56199)
		(end 103.48849 -183.30418)
		(width 0.1143)
		(layer "In6.Cu")
		(net "JTAG_CPLD2_TMS")
	)
	(segment
		(start 160.9598 -188.246766)
		(end 132.06095 -188.246766)
		(width 0.1143)
		(layer "In6.Cu")
		(net "JTAG_CPLD2_TMS")
	)
	(segment
		(start 167.93464 -36.430712)
		(end 166.243 -34.739072)
		(width 0.1143)
		(layer "In6.Cu")
		(net "JTAG_CPLD2_TMS")
	)
	(segment
		(start 97.603818 -182.983124)
		(end 96.15424 -184.432702)
		(width 0.1143)
		(layer "In6.Cu")
		(net "JTAG_CPLD2_TMS")
	)
	(segment
		(start 170.86834 -189.53734)
		(end 169.577766 -188.246766)
		(width 0.1143)
		(layer "In6.Cu")
		(net "JTAG_CPLD2_TMS")
	)
	(segment
		(start 128.56591 -184.751726)
		(end 126.88316 -184.751726)
		(width 0.1143)
		(layer "In6.Cu")
		(net "JTAG_CPLD2_TMS")
	)
	(segment
		(start 161.2138 -188.500766)
		(end 160.9598 -188.246766)
		(width 0.1143)
		(layer "In6.Cu")
		(net "JTAG_CPLD2_TMS")
	)
	(segment
		(start 103.048308 -183.30418)
		(end 102.263194 -182.519066)
		(width 0.1143)
		(layer "In6.Cu")
		(net "JTAG_CPLD2_TMS")
	)
	(segment
		(start 166.243 -34.739072)
		(end 166.243 -19.7866)
		(width 0.1143)
		(layer "In6.Cu")
		(net "JTAG_CPLD2_TMS")
	)
	(segment
		(start 101.184202 -182.519066)
		(end 100.720144 -182.983124)
		(width 0.1143)
		(layer "In6.Cu")
		(net "JTAG_CPLD2_TMS")
	)
	(segment
		(start 85.53196 -185.43524)
		(end 76.500482 -185.43524)
		(width 0.1143)
		(layer "In6.Cu")
		(net "JTAG_CPLD2_TMS")
	)
	(segment
		(start 169.577766 -188.246766)
		(end 164.813234 -188.246766)
		(width 0.1143)
		(layer "In6.Cu")
		(net "JTAG_CPLD2_TMS")
	)
	(segment
		(start 96.15424 -184.432702)
		(end 95.78848 -184.432702)
		(width 0.1143)
		(layer "In6.Cu")
		(net "JTAG_CPLD2_TMS")
	)
	(segment
		(start 132.06095 -188.246766)
		(end 128.56591 -184.751726)
		(width 0.1143)
		(layer "In6.Cu")
		(net "JTAG_CPLD2_TMS")
	)
	(segment
		(start 74.494644 -178.690016)
		(end 74.494644 -179.874672)
		(width 0.1016)
		(layer "F.Cu")
		(net "JTAG_CPLD2_TCK")
	)
	(segment
		(start 72.914256 -181.831234)
		(end 74.294746 -181.831234)
		(width 0.1016)
		(layer "F.Cu")
		(net "JTAG_CPLD2_TCK")
	)
	(segment
		(start 74.294746 -181.831234)
		(end 74.494644 -181.631336)
		(width 0.1016)
		(layer "F.Cu")
		(net "JTAG_CPLD2_TCK")
	)
	(segment
		(start 72.559164 -182.186326)
		(end 72.914256 -181.831234)
		(width 0.1016)
		(layer "F.Cu")
		(net "JTAG_CPLD2_TCK")
	)
	(segment
		(start 74.494644 -181.631336)
		(end 74.494644 -179.874672)
		(width 0.1016)
		(layer "F.Cu")
		(net "JTAG_CPLD2_TCK")
	)
	(via
		(at 163.8681 -136.068816)
		(size 0.508)
		(drill 0.254)
		(layers "F.Cu" "B.Cu")
		(net "JTAG_CPLD2_TCK")
	)
	(via
		(at 74.494644 -178.690016)
		(size 0.508)
		(drill 0.254)
		(layers "F.Cu" "B.Cu")
		(net "JTAG_CPLD2_TCK")
	)
	(segment
		(start 137.742676 -43.392852)
		(end 135.237728 -43.392852)
		(width 0.1016)
		(layer "B.Cu")
		(net "JTAG_CPLD2_TCK")
	)
	(segment
		(start 149.1234 -14.5542)
		(end 151.9682 -17.399)
		(width 0.1016)
		(layer "B.Cu")
		(net "JTAG_CPLD2_TCK")
	)
	(segment
		(start 156.812234 -9.855962)
		(end 155.6004 -8.644128)
		(width 0.1016)
		(layer "B.Cu")
		(net "JTAG_CPLD2_TCK")
	)
	(segment
		(start 144.9578 -7.4422)
		(end 144.9578 -12.2936)
		(width 0.1016)
		(layer "B.Cu")
		(net "JTAG_CPLD2_TCK")
	)
	(segment
		(start 148.239734 -43.086528)
		(end 146.56308 -43.086528)
		(width 0.1016)
		(layer "B.Cu")
		(net "JTAG_CPLD2_TCK")
	)
	(segment
		(start 146.116802 -42.64025)
		(end 140.521944 -42.64025)
		(width 0.1016)
		(layer "B.Cu")
		(net "JTAG_CPLD2_TCK")
	)
	(segment
		(start 144.9578 -12.2936)
		(end 147.2184 -14.5542)
		(width 0.1016)
		(layer "B.Cu")
		(net "JTAG_CPLD2_TCK")
	)
	(segment
		(start 147.2184 -14.5542)
		(end 149.1234 -14.5542)
		(width 0.1016)
		(layer "B.Cu")
		(net "JTAG_CPLD2_TCK")
	)
	(segment
		(start 134.761986 -42.91711)
		(end 134.761986 -42.501566)
		(width 0.1016)
		(layer "B.Cu")
		(net "JTAG_CPLD2_TCK")
	)
	(segment
		(start 149.033992 -42.29227)
		(end 148.239734 -43.086528)
		(width 0.1016)
		(layer "B.Cu")
		(net "JTAG_CPLD2_TCK")
	)
	(segment
		(start 151.986996 -24.601678)
		(end 152.937972 -25.552654)
		(width 0.1016)
		(layer "B.Cu")
		(net "JTAG_CPLD2_TCK")
	)
	(segment
		(start 140.063982 -42.182288)
		(end 139.51712 -42.182288)
		(width 0.1016)
		(layer "B.Cu")
		(net "JTAG_CPLD2_TCK")
	)
	(segment
		(start 146.56308 -43.086528)
		(end 146.116802 -42.64025)
		(width 0.1016)
		(layer "B.Cu")
		(net "JTAG_CPLD2_TCK")
	)
	(segment
		(start 155.6004 -6.7818)
		(end 154.610562 -5.791962)
		(width 0.1016)
		(layer "B.Cu")
		(net "JTAG_CPLD2_TCK")
	)
	(segment
		(start 139.51712 -42.182288)
		(end 138.83132 -42.868088)
		(width 0.1016)
		(layer "B.Cu")
		(net "JTAG_CPLD2_TCK")
	)
	(segment
		(start 151.9682 -20.1676)
		(end 151.986996 -20.186396)
		(width 0.1016)
		(layer "B.Cu")
		(net "JTAG_CPLD2_TCK")
	)
	(segment
		(start 152.937972 -25.552654)
		(end 152.937972 -29.614368)
		(width 0.1016)
		(layer "B.Cu")
		(net "JTAG_CPLD2_TCK")
	)
	(segment
		(start 138.83132 -42.868088)
		(end 138.26744 -42.868088)
		(width 0.1016)
		(layer "B.Cu")
		(net "JTAG_CPLD2_TCK")
	)
	(segment
		(start 140.521944 -42.64025)
		(end 140.063982 -42.182288)
		(width 0.1016)
		(layer "B.Cu")
		(net "JTAG_CPLD2_TCK")
	)
	(segment
		(start 151.986996 -20.186396)
		(end 151.986996 -24.601678)
		(width 0.1016)
		(layer "B.Cu")
		(net "JTAG_CPLD2_TCK")
	)
	(segment
		(start 135.237728 -43.392852)
		(end 134.761986 -42.91711)
		(width 0.1016)
		(layer "B.Cu")
		(net "JTAG_CPLD2_TCK")
	)
	(segment
		(start 146.608038 -5.791962)
		(end 144.9578 -7.4422)
		(width 0.1016)
		(layer "B.Cu")
		(net "JTAG_CPLD2_TCK")
	)
	(segment
		(start 155.6004 -8.644128)
		(end 155.6004 -6.7818)
		(width 0.1016)
		(layer "B.Cu")
		(net "JTAG_CPLD2_TCK")
	)
	(segment
		(start 152.33396 -37.013134)
		(end 149.033992 -40.313102)
		(width 0.1016)
		(layer "B.Cu")
		(net "JTAG_CPLD2_TCK")
	)
	(segment
		(start 138.26744 -42.868088)
		(end 137.742676 -43.392852)
		(width 0.1016)
		(layer "B.Cu")
		(net "JTAG_CPLD2_TCK")
	)
	(segment
		(start 152.937972 -29.614368)
		(end 152.33396 -30.21838)
		(width 0.1016)
		(layer "B.Cu")
		(net "JTAG_CPLD2_TCK")
	)
	(segment
		(start 149.033992 -40.313102)
		(end 149.033992 -42.29227)
		(width 0.1016)
		(layer "B.Cu")
		(net "JTAG_CPLD2_TCK")
	)
	(segment
		(start 152.33396 -30.21838)
		(end 152.33396 -37.013134)
		(width 0.1016)
		(layer "B.Cu")
		(net "JTAG_CPLD2_TCK")
	)
	(segment
		(start 154.610562 -5.791962)
		(end 146.608038 -5.791962)
		(width 0.1016)
		(layer "B.Cu")
		(net "JTAG_CPLD2_TCK")
	)
	(segment
		(start 151.9682 -17.399)
		(end 151.9682 -20.1676)
		(width 0.1016)
		(layer "B.Cu")
		(net "JTAG_CPLD2_TCK")
	)
	(segment
		(start 109.62132 -172.067474)
		(end 110.825026 -173.27118)
		(width 0.1143)
		(layer "In2.Cu")
		(net "JTAG_CPLD2_TCK")
	)
	(segment
		(start 124.097796 -174.188628)
		(end 125.767084 -174.188628)
		(width 0.1143)
		(layer "In2.Cu")
		(net "JTAG_CPLD2_TCK")
	)
	(segment
		(start 141.734794 -163.992814)
		(end 144.314418 -163.992814)
		(width 0.1143)
		(layer "In2.Cu")
		(net "JTAG_CPLD2_TCK")
	)
	(segment
		(start 115.73637 -174.680372)
		(end 123.606052 -174.680372)
		(width 0.1143)
		(layer "In2.Cu")
		(net "JTAG_CPLD2_TCK")
	)
	(segment
		(start 156.2227 -148.616162)
		(end 157.226 -147.612862)
		(width 0.1143)
		(layer "In2.Cu")
		(net "JTAG_CPLD2_TCK")
	)
	(segment
		(start 107.8103 -172.733208)
		(end 108.417868 -172.12564)
		(width 0.1143)
		(layer "In2.Cu")
		(net "JTAG_CPLD2_TCK")
	)
	(segment
		(start 96.566228 -172.059854)
		(end 96.855788 -172.349414)
		(width 0.1143)
		(layer "In2.Cu")
		(net "JTAG_CPLD2_TCK")
	)
	(segment
		(start 156.2227 -154.584654)
		(end 156.2227 -148.616162)
		(width 0.1143)
		(layer "In2.Cu")
		(net "JTAG_CPLD2_TCK")
	)
	(segment
		(start 126.74346 -175.165004)
		(end 134.190994 -175.165004)
		(width 0.1143)
		(layer "In2.Cu")
		(net "JTAG_CPLD2_TCK")
	)
	(segment
		(start 109.197394 -172.12564)
		(end 109.25556 -172.067474)
		(width 0.1143)
		(layer "In2.Cu")
		(net "JTAG_CPLD2_TCK")
	)
	(segment
		(start 80.129126 -174.21987)
		(end 82.034634 -172.314616)
		(width 0.1143)
		(layer "In2.Cu")
		(net "JTAG_CPLD2_TCK")
	)
	(segment
		(start 94.076774 -172.059854)
		(end 96.566228 -172.059854)
		(width 0.1143)
		(layer "In2.Cu")
		(net "JTAG_CPLD2_TCK")
	)
	(segment
		(start 92.568268 -171.500292)
		(end 93.517212 -171.500292)
		(width 0.1143)
		(layer "In2.Cu")
		(net "JTAG_CPLD2_TCK")
	)
	(segment
		(start 123.606052 -174.680372)
		(end 124.097796 -174.188628)
		(width 0.1143)
		(layer "In2.Cu")
		(net "JTAG_CPLD2_TCK")
	)
	(segment
		(start 78.20533 -176.143666)
		(end 80.129126 -174.21987)
		(width 0.1143)
		(layer "In2.Cu")
		(net "JTAG_CPLD2_TCK")
	)
	(segment
		(start 134.0612 -169.41927)
		(end 138.117834 -165.362636)
		(width 0.1143)
		(layer "In2.Cu")
		(net "JTAG_CPLD2_TCK")
	)
	(segment
		(start 104.89311 -173.969934)
		(end 106.129836 -172.733208)
		(width 0.1143)
		(layer "In2.Cu")
		(net "JTAG_CPLD2_TCK")
	)
	(segment
		(start 96.855788 -172.349414)
		(end 101.651562 -172.349414)
		(width 0.1143)
		(layer "In2.Cu")
		(net "JTAG_CPLD2_TCK")
	)
	(segment
		(start 144.91208 -163.395152)
		(end 147.412202 -163.395152)
		(width 0.1143)
		(layer "In2.Cu")
		(net "JTAG_CPLD2_TCK")
	)
	(segment
		(start 93.517212 -171.500292)
		(end 94.076774 -172.059854)
		(width 0.1143)
		(layer "In2.Cu")
		(net "JTAG_CPLD2_TCK")
	)
	(segment
		(start 160.380172 -136.068816)
		(end 163.8681 -136.068816)
		(width 0.1143)
		(layer "In2.Cu")
		(net "JTAG_CPLD2_TCK")
	)
	(segment
		(start 147.412202 -163.395152)
		(end 156.2227 -154.584654)
		(width 0.1143)
		(layer "In2.Cu")
		(net "JTAG_CPLD2_TCK")
	)
	(segment
		(start 83.693 -172.314616)
		(end 84.992972 -171.014644)
		(width 0.1143)
		(layer "In2.Cu")
		(net "JTAG_CPLD2_TCK")
	)
	(segment
		(start 144.314418 -163.992814)
		(end 144.91208 -163.395152)
		(width 0.1143)
		(layer "In2.Cu")
		(net "JTAG_CPLD2_TCK")
	)
	(segment
		(start 109.25556 -172.067474)
		(end 109.62132 -172.067474)
		(width 0.1143)
		(layer "In2.Cu")
		(net "JTAG_CPLD2_TCK")
	)
	(segment
		(start 134.190994 -175.165004)
		(end 134.743444 -174.612554)
		(width 0.1143)
		(layer "In2.Cu")
		(net "JTAG_CPLD2_TCK")
	)
	(segment
		(start 108.417868 -172.12564)
		(end 109.197394 -172.12564)
		(width 0.1143)
		(layer "In2.Cu")
		(net "JTAG_CPLD2_TCK")
	)
	(segment
		(start 103.272082 -173.969934)
		(end 104.89311 -173.969934)
		(width 0.1143)
		(layer "In2.Cu")
		(net "JTAG_CPLD2_TCK")
	)
	(segment
		(start 125.767084 -174.188628)
		(end 126.74346 -175.165004)
		(width 0.1143)
		(layer "In2.Cu")
		(net "JTAG_CPLD2_TCK")
	)
	(segment
		(start 138.117834 -165.362636)
		(end 140.364972 -165.362636)
		(width 0.1143)
		(layer "In2.Cu")
		(net "JTAG_CPLD2_TCK")
	)
	(segment
		(start 74.494644 -178.690016)
		(end 74.538078 -178.690016)
		(width 0.1143)
		(layer "In2.Cu")
		(net "JTAG_CPLD2_TCK")
	)
	(segment
		(start 134.27456 -173.431962)
		(end 134.27456 -170.409616)
		(width 0.1143)
		(layer "In2.Cu")
		(net "JTAG_CPLD2_TCK")
	)
	(segment
		(start 82.034634 -172.314616)
		(end 83.693 -172.314616)
		(width 0.1143)
		(layer "In2.Cu")
		(net "JTAG_CPLD2_TCK")
	)
	(segment
		(start 74.538078 -178.690016)
		(end 77.084428 -176.143666)
		(width 0.1143)
		(layer "In2.Cu")
		(net "JTAG_CPLD2_TCK")
	)
	(segment
		(start 134.743444 -173.900846)
		(end 134.27456 -173.431962)
		(width 0.1143)
		(layer "In2.Cu")
		(net "JTAG_CPLD2_TCK")
	)
	(segment
		(start 106.129836 -172.733208)
		(end 107.8103 -172.733208)
		(width 0.1143)
		(layer "In2.Cu")
		(net "JTAG_CPLD2_TCK")
	)
	(segment
		(start 101.651562 -172.349414)
		(end 103.272082 -173.969934)
		(width 0.1143)
		(layer "In2.Cu")
		(net "JTAG_CPLD2_TCK")
	)
	(segment
		(start 134.0612 -170.196256)
		(end 134.0612 -169.41927)
		(width 0.1143)
		(layer "In2.Cu")
		(net "JTAG_CPLD2_TCK")
	)
	(segment
		(start 92.08262 -171.014644)
		(end 92.568268 -171.500292)
		(width 0.1143)
		(layer "In2.Cu")
		(net "JTAG_CPLD2_TCK")
	)
	(segment
		(start 77.084428 -176.143666)
		(end 78.20533 -176.143666)
		(width 0.1143)
		(layer "In2.Cu")
		(net "JTAG_CPLD2_TCK")
	)
	(segment
		(start 134.743444 -174.612554)
		(end 134.743444 -173.900846)
		(width 0.1143)
		(layer "In2.Cu")
		(net "JTAG_CPLD2_TCK")
	)
	(segment
		(start 84.992972 -171.014644)
		(end 92.08262 -171.014644)
		(width 0.1143)
		(layer "In2.Cu")
		(net "JTAG_CPLD2_TCK")
	)
	(segment
		(start 157.226 -139.222988)
		(end 160.380172 -136.068816)
		(width 0.1143)
		(layer "In2.Cu")
		(net "JTAG_CPLD2_TCK")
	)
	(segment
		(start 157.226 -147.612862)
		(end 157.226 -139.222988)
		(width 0.1143)
		(layer "In2.Cu")
		(net "JTAG_CPLD2_TCK")
	)
	(segment
		(start 114.327178 -173.27118)
		(end 115.73637 -174.680372)
		(width 0.1143)
		(layer "In2.Cu")
		(net "JTAG_CPLD2_TCK")
	)
	(segment
		(start 134.27456 -170.409616)
		(end 134.0612 -170.196256)
		(width 0.1143)
		(layer "In2.Cu")
		(net "JTAG_CPLD2_TCK")
	)
	(segment
		(start 140.364972 -165.362636)
		(end 141.734794 -163.992814)
		(width 0.1143)
		(layer "In2.Cu")
		(net "JTAG_CPLD2_TCK")
	)
	(segment
		(start 110.825026 -173.27118)
		(end 114.327178 -173.27118)
		(width 0.1143)
		(layer "In2.Cu")
		(net "JTAG_CPLD2_TCK")
	)
	(segment
		(start 163.8681 -136.068816)
		(end 166.87292 -136.068816)
		(width 0.1143)
		(layer "In6.Cu")
		(net "JTAG_CPLD2_TCK")
	)
	(segment
		(start 178.7144 -135.134604)
		(end 180.737764 -133.11124)
		(width 0.1143)
		(layer "In6.Cu")
		(net "JTAG_CPLD2_TCK")
	)
	(segment
		(start 167.20566 -34.398712)
		(end 167.20566 -19.45386)
		(width 0.1143)
		(layer "In6.Cu")
		(net "JTAG_CPLD2_TCK")
	)
	(segment
		(start 167.20566 -19.45386)
		(end 157.607 -9.8552)
		(width 0.1143)
		(layer "In6.Cu")
		(net "JTAG_CPLD2_TCK")
	)
	(segment
		(start 178.7144 -137.035032)
		(end 178.7144 -135.134604)
		(width 0.1143)
		(layer "In6.Cu")
		(net "JTAG_CPLD2_TCK")
	)
	(segment
		(start 177.306732 -138.4427)
		(end 178.7144 -137.035032)
		(width 0.1143)
		(layer "In6.Cu")
		(net "JTAG_CPLD2_TCK")
	)
	(segment
		(start 185.56605 -128.766316)
		(end 185.56605 -127.99695)
		(width 0.1143)
		(layer "In6.Cu")
		(net "JTAG_CPLD2_TCK")
	)
	(segment
		(start 166.87292 -136.068816)
		(end 169.246804 -138.4427)
		(width 0.1143)
		(layer "In6.Cu")
		(net "JTAG_CPLD2_TCK")
	)
	(segment
		(start 193.00952 -84.24672)
		(end 188.38672 -84.24672)
		(width 0.1143)
		(layer "In6.Cu")
		(net "JTAG_CPLD2_TCK")
	)
	(segment
		(start 193.514726 -84.751926)
		(end 193.00952 -84.24672)
		(width 0.1143)
		(layer "In6.Cu")
		(net "JTAG_CPLD2_TCK")
	)
	(segment
		(start 188.38672 -84.24672)
		(end 171.38904 -67.24904)
		(width 0.1143)
		(layer "In6.Cu")
		(net "JTAG_CPLD2_TCK")
	)
	(segment
		(start 169.246804 -138.4427)
		(end 177.306732 -138.4427)
		(width 0.1143)
		(layer "In6.Cu")
		(net "JTAG_CPLD2_TCK")
	)
	(segment
		(start 171.38904 -67.24904)
		(end 171.38904 -47.409354)
		(width 0.1143)
		(layer "In6.Cu")
		(net "JTAG_CPLD2_TCK")
	)
	(segment
		(start 171.38904 -47.409354)
		(end 168.90492 -44.925234)
		(width 0.1143)
		(layer "In6.Cu")
		(net "JTAG_CPLD2_TCK")
	)
	(segment
		(start 180.737764 -133.11124)
		(end 181.221126 -133.11124)
		(width 0.1143)
		(layer "In6.Cu")
		(net "JTAG_CPLD2_TCK")
	)
	(segment
		(start 181.221126 -133.11124)
		(end 185.56605 -128.766316)
		(width 0.1143)
		(layer "In6.Cu")
		(net "JTAG_CPLD2_TCK")
	)
	(segment
		(start 157.607 -9.8552)
		(end 156.812234 -9.8552)
		(width 0.1143)
		(layer "In6.Cu")
		(net "JTAG_CPLD2_TCK")
	)
	(segment
		(start 168.90492 -44.925234)
		(end 168.90492 -36.097972)
		(width 0.1143)
		(layer "In6.Cu")
		(net "JTAG_CPLD2_TCK")
	)
	(segment
		(start 168.90492 -36.097972)
		(end 167.20566 -34.398712)
		(width 0.1143)
		(layer "In6.Cu")
		(net "JTAG_CPLD2_TCK")
	)
	(segment
		(start 185.56605 -127.99695)
		(end 193.514726 -120.048274)
		(width 0.1143)
		(layer "In6.Cu")
		(net "JTAG_CPLD2_TCK")
	)
	(segment
		(start 156.812234 -9.8552)
		(end 156.812234 -9.855962)
		(width 0.1143)
		(layer "In6.Cu")
		(net "JTAG_CPLD2_TCK")
	)
	(segment
		(start 193.514726 -120.048274)
		(end 193.514726 -84.751926)
		(width 0.1143)
		(layer "In6.Cu")
		(net "JTAG_CPLD2_TCK")
	)
	(segment
		(start 75.366118 -183.15432)
		(end 75.366118 -182.429658)
		(width 0.1016)
		(layer "F.Cu")
		(net "JTAG_CPLD2_TDI")
	)
	(segment
		(start 75.40879 -182.386986)
		(end 74.9935 -181.971696)
		(width 0.1016)
		(layer "F.Cu")
		(net "JTAG_CPLD2_TDI")
	)
	(segment
		(start 74.99477 -180.726842)
		(end 74.99477 -179.874672)
		(width 0.1016)
		(layer "F.Cu")
		(net "JTAG_CPLD2_TDI")
	)
	(segment
		(start 75.366118 -182.429658)
		(end 75.40879 -182.386986)
		(width 0.1016)
		(layer "F.Cu")
		(net "JTAG_CPLD2_TDI")
	)
	(segment
		(start 74.9935 -181.971696)
		(end 74.9935 -180.728112)
		(width 0.1016)
		(layer "F.Cu")
		(net "JTAG_CPLD2_TDI")
	)
	(segment
		(start 74.9935 -180.728112)
		(end 74.99477 -180.726842)
		(width 0.1016)
		(layer "F.Cu")
		(net "JTAG_CPLD2_TDI")
	)
	(via
		(at 192.8876 -85.049106)
		(size 0.508)
		(drill 0.254)
		(layers "F.Cu" "B.Cu")
		(net "JTAG_CPLD2_TDI")
	)
	(via
		(at 75.40879 -182.386986)
		(size 0.508)
		(drill 0.254)
		(layers "F.Cu" "B.Cu")
		(net "JTAG_CPLD2_TDI")
	)
	(via
		(at 171.4754 -190.3222)
		(size 0.508)
		(drill 0.254)
		(layers "F.Cu" "B.Cu")
		(net "JTAG_CPLD2_TDI")
	)
	(segment
		(start 154.315922 -38.8874)
		(end 149.126194 -44.077128)
		(width 0.1016)
		(layer "B.Cu")
		(net "JTAG_CPLD2_TDI")
	)
	(segment
		(start 149.5044 -13.335)
		(end 149.50694 -13.335)
		(width 0.1016)
		(layer "B.Cu")
		(net "JTAG_CPLD2_TDI")
	)
	(segment
		(start 153.06294 -16.891)
		(end 153.06294 -21.832062)
		(width 0.1016)
		(layer "B.Cu")
		(net "JTAG_CPLD2_TDI")
	)
	(segment
		(start 138.124946 -44.383452)
		(end 134.705852 -44.383452)
		(width 0.1016)
		(layer "B.Cu")
		(net "JTAG_CPLD2_TDI")
	)
	(segment
		(start 130.49885 -39.477442)
		(end 130.911854 -39.064438)
		(width 0.1016)
		(layer "B.Cu")
		(net "JTAG_CPLD2_TDI")
	)
	(segment
		(start 140.56233 -44.089828)
		(end 140.56233 -44.450254)
		(width 0.1016)
		(layer "B.Cu")
		(net "JTAG_CPLD2_TDI")
	)
	(segment
		(start 146.652234 -10.482834)
		(end 149.5044 -13.335)
		(width 0.1016)
		(layer "B.Cu")
		(net "JTAG_CPLD2_TDI")
	)
	(segment
		(start 140.264896 -44.747688)
		(end 138.489182 -44.747688)
		(width 0.1016)
		(layer "B.Cu")
		(net "JTAG_CPLD2_TDI")
	)
	(segment
		(start 145.688812 -43.731688)
		(end 140.92047 -43.731688)
		(width 0.1016)
		(layer "B.Cu")
		(net "JTAG_CPLD2_TDI")
	)
	(segment
		(start 149.50694 -13.335)
		(end 153.06294 -16.891)
		(width 0.1016)
		(layer "B.Cu")
		(net "JTAG_CPLD2_TDI")
	)
	(segment
		(start 140.92047 -43.731688)
		(end 140.56233 -44.089828)
		(width 0.1016)
		(layer "B.Cu")
		(net "JTAG_CPLD2_TDI")
	)
	(segment
		(start 146.652234 -9.855962)
		(end 146.652234 -10.482834)
		(width 0.1016)
		(layer "B.Cu")
		(net "JTAG_CPLD2_TDI")
	)
	(segment
		(start 131.1148 -41.8338)
		(end 130.49885 -41.21785)
		(width 0.1016)
		(layer "B.Cu")
		(net "JTAG_CPLD2_TDI")
	)
	(segment
		(start 134.705852 -44.383452)
		(end 132.1562 -41.8338)
		(width 0.1016)
		(layer "B.Cu")
		(net "JTAG_CPLD2_TDI")
	)
	(segment
		(start 138.489182 -44.747688)
		(end 138.124946 -44.383452)
		(width 0.1016)
		(layer "B.Cu")
		(net "JTAG_CPLD2_TDI")
	)
	(segment
		(start 146.034252 -44.077128)
		(end 145.688812 -43.731688)
		(width 0.1016)
		(layer "B.Cu")
		(net "JTAG_CPLD2_TDI")
	)
	(segment
		(start 154.315922 -23.085044)
		(end 154.315922 -38.8874)
		(width 0.1016)
		(layer "B.Cu")
		(net "JTAG_CPLD2_TDI")
	)
	(segment
		(start 149.126194 -44.077128)
		(end 146.034252 -44.077128)
		(width 0.1016)
		(layer "B.Cu")
		(net "JTAG_CPLD2_TDI")
	)
	(segment
		(start 132.1562 -41.8338)
		(end 131.1148 -41.8338)
		(width 0.1016)
		(layer "B.Cu")
		(net "JTAG_CPLD2_TDI")
	)
	(segment
		(start 140.56233 -44.450254)
		(end 140.264896 -44.747688)
		(width 0.1016)
		(layer "B.Cu")
		(net "JTAG_CPLD2_TDI")
	)
	(segment
		(start 130.49885 -41.21785)
		(end 130.49885 -39.477442)
		(width 0.1016)
		(layer "B.Cu")
		(net "JTAG_CPLD2_TDI")
	)
	(segment
		(start 153.06294 -21.832062)
		(end 154.315922 -23.085044)
		(width 0.1016)
		(layer "B.Cu")
		(net "JTAG_CPLD2_TDI")
	)
	(segment
		(start 171.958 -189.8396)
		(end 171.4754 -190.3222)
		(width 0.1143)
		(layer "In2.Cu")
		(net "JTAG_CPLD2_TDI")
	)
	(segment
		(start 175.8442 -189.8396)
		(end 171.958 -189.8396)
		(width 0.1143)
		(layer "In2.Cu")
		(net "JTAG_CPLD2_TDI")
	)
	(segment
		(start 198.882 -90.3478)
		(end 198.882 -155.878022)
		(width 0.1143)
		(layer "In2.Cu")
		(net "JTAG_CPLD2_TDI")
	)
	(segment
		(start 185.2168 -169.543222)
		(end 185.2168 -180.467)
		(width 0.1143)
		(layer "In2.Cu")
		(net "JTAG_CPLD2_TDI")
	)
	(segment
		(start 198.882 -155.878022)
		(end 185.2168 -169.543222)
		(width 0.1143)
		(layer "In2.Cu")
		(net "JTAG_CPLD2_TDI")
	)
	(segment
		(start 185.2168 -180.467)
		(end 175.8442 -189.8396)
		(width 0.1143)
		(layer "In2.Cu")
		(net "JTAG_CPLD2_TDI")
	)
	(segment
		(start 192.8876 -85.049106)
		(end 193.583306 -85.049106)
		(width 0.1143)
		(layer "In2.Cu")
		(net "JTAG_CPLD2_TDI")
	)
	(segment
		(start 193.583306 -85.049106)
		(end 198.882 -90.3478)
		(width 0.1143)
		(layer "In2.Cu")
		(net "JTAG_CPLD2_TDI")
	)
	(segment
		(start 167.93337 -49.76114)
		(end 167.93337 -48.678338)
		(width 0.1143)
		(layer "In6.Cu")
		(net "JTAG_CPLD2_TDI")
	)
	(segment
		(start 192.60947 -85.706204)
		(end 192.07861 -86.237064)
		(width 0.1143)
		(layer "In6.Cu")
		(net "JTAG_CPLD2_TDI")
	)
	(segment
		(start 157.7594 -11.9126)
		(end 148.708872 -11.9126)
		(width 0.1143)
		(layer "In6.Cu")
		(net "JTAG_CPLD2_TDI")
	)
	(segment
		(start 105.259378 -184.51449)
		(end 104.3178 -183.572912)
		(width 0.1143)
		(layer "In6.Cu")
		(net "JTAG_CPLD2_TDI")
	)
	(segment
		(start 167.93337 -48.678338)
		(end 165.8239 -46.568868)
		(width 0.1143)
		(layer "In6.Cu")
		(net "JTAG_CPLD2_TDI")
	)
	(segment
		(start 165.8239 -19.9771)
		(end 157.7594 -11.9126)
		(width 0.1143)
		(layer "In6.Cu")
		(net "JTAG_CPLD2_TDI")
	)
	(segment
		(start 102.501192 -182.099966)
		(end 101.008942 -182.099966)
		(width 0.1143)
		(layer "In6.Cu")
		(net "JTAG_CPLD2_TDI")
	)
	(segment
		(start 131.22402 -183.805322)
		(end 131.22402 -183.745886)
		(width 0.1143)
		(layer "In6.Cu")
		(net "JTAG_CPLD2_TDI")
	)
	(segment
		(start 101.008942 -182.099966)
		(end 100.544884 -182.564024)
		(width 0.1143)
		(layer "In6.Cu")
		(net "JTAG_CPLD2_TDI")
	)
	(segment
		(start 164.0078 -187.654946)
		(end 163.524946 -188.1378)
		(width 0.1143)
		(layer "In6.Cu")
		(net "JTAG_CPLD2_TDI")
	)
	(segment
		(start 161.925 -188.1378)
		(end 161.558732 -187.771532)
		(width 0.1143)
		(layer "In6.Cu")
		(net "JTAG_CPLD2_TDI")
	)
	(segment
		(start 104.3178 -183.540654)
		(end 103.395018 -182.617872)
		(width 0.1143)
		(layer "In6.Cu")
		(net "JTAG_CPLD2_TDI")
	)
	(segment
		(start 85.416898 -184.955942)
		(end 85.3567 -185.01614)
		(width 0.1143)
		(layer "In6.Cu")
		(net "JTAG_CPLD2_TDI")
	)
	(segment
		(start 163.524946 -188.1378)
		(end 161.925 -188.1378)
		(width 0.1143)
		(layer "In6.Cu")
		(net "JTAG_CPLD2_TDI")
	)
	(segment
		(start 127.635 -182.866538)
		(end 127.292354 -183.209184)
		(width 0.1143)
		(layer "In6.Cu")
		(net "JTAG_CPLD2_TDI")
	)
	(segment
		(start 192.07861 -86.237064)
		(end 188.522864 -86.237064)
		(width 0.1143)
		(layer "In6.Cu")
		(net "JTAG_CPLD2_TDI")
	)
	(segment
		(start 92.104972 -183.361838)
		(end 91.930728 -183.536082)
		(width 0.1143)
		(layer "In6.Cu")
		(net "JTAG_CPLD2_TDI")
	)
	(segment
		(start 134.512558 -187.771532)
		(end 133.680454 -186.939428)
		(width 0.1143)
		(layer "In6.Cu")
		(net "JTAG_CPLD2_TDI")
	)
	(segment
		(start 90.204544 -183.536082)
		(end 88.784684 -184.955942)
		(width 0.1143)
		(layer "In6.Cu")
		(net "JTAG_CPLD2_TDI")
	)
	(segment
		(start 112.61598 -183.18734)
		(end 112.552988 -183.18734)
		(width 0.1143)
		(layer "In6.Cu")
		(net "JTAG_CPLD2_TDI")
	)
	(segment
		(start 165.8239 -46.568868)
		(end 165.8239 -19.9771)
		(width 0.1143)
		(layer "In6.Cu")
		(net "JTAG_CPLD2_TDI")
	)
	(segment
		(start 172.0215 -189.7761)
		(end 172.0215 -188.7093)
		(width 0.1143)
		(layer "In6.Cu")
		(net "JTAG_CPLD2_TDI")
	)
	(segment
		(start 112.552988 -183.18734)
		(end 111.225838 -184.51449)
		(width 0.1143)
		(layer "In6.Cu")
		(net "JTAG_CPLD2_TDI")
	)
	(segment
		(start 171.4754 -190.3222)
		(end 172.0215 -189.7761)
		(width 0.1143)
		(layer "In6.Cu")
		(net "JTAG_CPLD2_TDI")
	)
	(segment
		(start 188.522864 -86.237064)
		(end 169.77868 -67.49288)
		(width 0.1143)
		(layer "In6.Cu")
		(net "JTAG_CPLD2_TDI")
	)
	(segment
		(start 131.22402 -183.745886)
		(end 130.344672 -182.866538)
		(width 0.1143)
		(layer "In6.Cu")
		(net "JTAG_CPLD2_TDI")
	)
	(segment
		(start 103.019098 -182.617872)
		(end 102.501192 -182.099966)
		(width 0.1143)
		(layer "In6.Cu")
		(net "JTAG_CPLD2_TDI")
	)
	(segment
		(start 78.037944 -185.01614)
		(end 75.40879 -182.386986)
		(width 0.1143)
		(layer "In6.Cu")
		(net "JTAG_CPLD2_TDI")
	)
	(segment
		(start 88.784684 -184.955942)
		(end 85.416898 -184.955942)
		(width 0.1143)
		(layer "In6.Cu")
		(net "JTAG_CPLD2_TDI")
	)
	(segment
		(start 133.680454 -186.058048)
		(end 133.423914 -185.801508)
		(width 0.1143)
		(layer "In6.Cu")
		(net "JTAG_CPLD2_TDI")
	)
	(segment
		(start 91.930728 -183.536082)
		(end 90.204544 -183.536082)
		(width 0.1143)
		(layer "In6.Cu")
		(net "JTAG_CPLD2_TDI")
	)
	(segment
		(start 94.33306 -183.396382)
		(end 94.298516 -183.361838)
		(width 0.1143)
		(layer "In6.Cu")
		(net "JTAG_CPLD2_TDI")
	)
	(segment
		(start 100.544884 -182.564024)
		(end 97.311718 -182.564024)
		(width 0.1143)
		(layer "In6.Cu")
		(net "JTAG_CPLD2_TDI")
	)
	(segment
		(start 170.967146 -187.654946)
		(end 164.0078 -187.654946)
		(width 0.1143)
		(layer "In6.Cu")
		(net "JTAG_CPLD2_TDI")
	)
	(segment
		(start 192.60947 -85.327236)
		(end 192.60947 -85.706204)
		(width 0.1143)
		(layer "In6.Cu")
		(net "JTAG_CPLD2_TDI")
	)
	(segment
		(start 169.77868 -67.49288)
		(end 169.77868 -55.380128)
		(width 0.1143)
		(layer "In6.Cu")
		(net "JTAG_CPLD2_TDI")
	)
	(segment
		(start 123.315476 -183.209184)
		(end 122.995436 -182.889144)
		(width 0.1143)
		(layer "In6.Cu")
		(net "JTAG_CPLD2_TDI")
	)
	(segment
		(start 112.914176 -182.889144)
		(end 112.61598 -183.18734)
		(width 0.1143)
		(layer "In6.Cu")
		(net "JTAG_CPLD2_TDI")
	)
	(segment
		(start 103.395018 -182.617872)
		(end 103.019098 -182.617872)
		(width 0.1143)
		(layer "In6.Cu")
		(net "JTAG_CPLD2_TDI")
	)
	(segment
		(start 148.708872 -11.9126)
		(end 146.652234 -9.855962)
		(width 0.1143)
		(layer "In6.Cu")
		(net "JTAG_CPLD2_TDI")
	)
	(segment
		(start 161.558732 -187.771532)
		(end 134.512558 -187.771532)
		(width 0.1143)
		(layer "In6.Cu")
		(net "JTAG_CPLD2_TDI")
	)
	(segment
		(start 127.292354 -183.209184)
		(end 123.315476 -183.209184)
		(width 0.1143)
		(layer "In6.Cu")
		(net "JTAG_CPLD2_TDI")
	)
	(segment
		(start 133.220206 -185.801508)
		(end 131.22402 -183.805322)
		(width 0.1143)
		(layer "In6.Cu")
		(net "JTAG_CPLD2_TDI")
	)
	(segment
		(start 130.344672 -182.866538)
		(end 127.635 -182.866538)
		(width 0.1143)
		(layer "In6.Cu")
		(net "JTAG_CPLD2_TDI")
	)
	(segment
		(start 133.680454 -186.939428)
		(end 133.680454 -186.058048)
		(width 0.1143)
		(layer "In6.Cu")
		(net "JTAG_CPLD2_TDI")
	)
	(segment
		(start 94.298516 -183.361838)
		(end 92.104972 -183.361838)
		(width 0.1143)
		(layer "In6.Cu")
		(net "JTAG_CPLD2_TDI")
	)
	(segment
		(start 104.3178 -183.572912)
		(end 104.3178 -183.540654)
		(width 0.1143)
		(layer "In6.Cu")
		(net "JTAG_CPLD2_TDI")
	)
	(segment
		(start 169.48404 -51.31181)
		(end 167.93337 -49.76114)
		(width 0.1143)
		(layer "In6.Cu")
		(net "JTAG_CPLD2_TDI")
	)
	(segment
		(start 192.8876 -85.049106)
		(end 192.60947 -85.327236)
		(width 0.1143)
		(layer "In6.Cu")
		(net "JTAG_CPLD2_TDI")
	)
	(segment
		(start 133.423914 -185.801508)
		(end 133.220206 -185.801508)
		(width 0.1143)
		(layer "In6.Cu")
		(net "JTAG_CPLD2_TDI")
	)
	(segment
		(start 122.995436 -182.889144)
		(end 112.914176 -182.889144)
		(width 0.1143)
		(layer "In6.Cu")
		(net "JTAG_CPLD2_TDI")
	)
	(segment
		(start 85.3567 -185.01614)
		(end 78.037944 -185.01614)
		(width 0.1143)
		(layer "In6.Cu")
		(net "JTAG_CPLD2_TDI")
	)
	(segment
		(start 97.311718 -182.564024)
		(end 96.47936 -183.396382)
		(width 0.1143)
		(layer "In6.Cu")
		(net "JTAG_CPLD2_TDI")
	)
	(segment
		(start 169.48404 -55.085488)
		(end 169.48404 -51.31181)
		(width 0.1143)
		(layer "In6.Cu")
		(net "JTAG_CPLD2_TDI")
	)
	(segment
		(start 169.77868 -55.380128)
		(end 169.48404 -55.085488)
		(width 0.1143)
		(layer "In6.Cu")
		(net "JTAG_CPLD2_TDI")
	)
	(segment
		(start 111.225838 -184.51449)
		(end 105.259378 -184.51449)
		(width 0.1143)
		(layer "In6.Cu")
		(net "JTAG_CPLD2_TDI")
	)
	(segment
		(start 172.0215 -188.7093)
		(end 170.967146 -187.654946)
		(width 0.1143)
		(layer "In6.Cu")
		(net "JTAG_CPLD2_TDI")
	)
	(segment
		(start 96.47936 -183.396382)
		(end 94.33306 -183.396382)
		(width 0.1143)
		(layer "In6.Cu")
		(net "JTAG_CPLD2_TDI")
	)
	(segment
		(start 132.52577 -165.185598)
		(end 132.52577 -163.358576)
		(width 0.1016)
		(layer "F.Cu")
		(net "UART_T9_NODE1_RXD")
	)
	(segment
		(start 132.465064 -165.246304)
		(end 132.52577 -165.185598)
		(width 0.1016)
		(layer "F.Cu")
		(net "UART_T9_NODE1_RXD")
	)
	(via
		(at 134.881366 -186.218068)
		(size 0.508)
		(drill 0.254)
		(layers "F.Cu" "B.Cu")
		(net "UART_T9_NODE1_RXD")
	)
	(via
		(at 132.465064 -165.246304)
		(size 0.508)
		(drill 0.254)
		(layers "F.Cu" "B.Cu")
		(net "UART_T9_NODE1_RXD")
	)
	(segment
		(start 135.36676 -185.351674)
		(end 135.36676 -185.732674)
		(width 0.1016)
		(layer "B.Cu")
		(net "UART_T9_NODE1_RXD")
	)
	(segment
		(start 135.344154 -187.472574)
		(end 134.881366 -187.009786)
		(width 0.1016)
		(layer "B.Cu")
		(net "UART_T9_NODE1_RXD")
	)
	(segment
		(start 134.881366 -187.009786)
		(end 134.881366 -186.218068)
		(width 0.1016)
		(layer "B.Cu")
		(net "UART_T9_NODE1_RXD")
	)
	(segment
		(start 135.36676 -185.732674)
		(end 134.881366 -186.218068)
		(width 0.1016)
		(layer "B.Cu")
		(net "UART_T9_NODE1_RXD")
	)
	(segment
		(start 135.36676 -187.472574)
		(end 135.344154 -187.472574)
		(width 0.1016)
		(layer "B.Cu")
		(net "UART_T9_NODE1_RXD")
	)
	(segment
		(start 139.996672 -164.340032)
		(end 139.996672 -164.778944)
		(width 0.1143)
		(layer "In7.Cu")
		(net "UART_T9_NODE1_RXD")
	)
	(segment
		(start 139.168886 -165.60673)
		(end 139.168886 -166.134542)
		(width 0.1143)
		(layer "In7.Cu")
		(net "UART_T9_NODE1_RXD")
	)
	(segment
		(start 136.736836 -181.118256)
		(end 136.736836 -181.602634)
		(width 0.1143)
		(layer "In7.Cu")
		(net "UART_T9_NODE1_RXD")
	)
	(segment
		(start 133.660642 -164.050726)
		(end 139.707366 -164.050726)
		(width 0.1143)
		(layer "In7.Cu")
		(net "UART_T9_NODE1_RXD")
	)
	(segment
		(start 138.221212 -175.689006)
		(end 137.65276 -176.257458)
		(width 0.1143)
		(layer "In7.Cu")
		(net "UART_T9_NODE1_RXD")
	)
	(segment
		(start 135.53694 -184.840118)
		(end 134.87908 -185.497978)
		(width 0.1143)
		(layer "In7.Cu")
		(net "UART_T9_NODE1_RXD")
	)
	(segment
		(start 137.65276 -180.202332)
		(end 136.736836 -181.118256)
		(width 0.1143)
		(layer "In7.Cu")
		(net "UART_T9_NODE1_RXD")
	)
	(segment
		(start 135.53694 -182.80253)
		(end 135.53694 -184.840118)
		(width 0.1143)
		(layer "In7.Cu")
		(net "UART_T9_NODE1_RXD")
	)
	(segment
		(start 139.996672 -164.778944)
		(end 139.168886 -165.60673)
		(width 0.1143)
		(layer "In7.Cu")
		(net "UART_T9_NODE1_RXD")
	)
	(segment
		(start 139.707366 -164.050726)
		(end 139.996672 -164.340032)
		(width 0.1143)
		(layer "In7.Cu")
		(net "UART_T9_NODE1_RXD")
	)
	(segment
		(start 138.221212 -167.082216)
		(end 138.221212 -175.689006)
		(width 0.1143)
		(layer "In7.Cu")
		(net "UART_T9_NODE1_RXD")
	)
	(segment
		(start 132.465064 -165.246304)
		(end 133.660642 -164.050726)
		(width 0.1143)
		(layer "In7.Cu")
		(net "UART_T9_NODE1_RXD")
	)
	(segment
		(start 134.87908 -185.497978)
		(end 134.87908 -186.218068)
		(width 0.1143)
		(layer "In7.Cu")
		(net "UART_T9_NODE1_RXD")
	)
	(segment
		(start 137.65276 -176.257458)
		(end 137.65276 -180.202332)
		(width 0.1143)
		(layer "In7.Cu")
		(net "UART_T9_NODE1_RXD")
	)
	(segment
		(start 139.168886 -166.134542)
		(end 138.221212 -167.082216)
		(width 0.1143)
		(layer "In7.Cu")
		(net "UART_T9_NODE1_RXD")
	)
	(segment
		(start 134.87908 -186.218068)
		(end 134.881366 -186.218068)
		(width 0.1143)
		(layer "In7.Cu")
		(net "UART_T9_NODE1_RXD")
	)
	(segment
		(start 136.736836 -181.602634)
		(end 135.53694 -182.80253)
		(width 0.1143)
		(layer "In7.Cu")
		(net "UART_T9_NODE1_RXD")
	)
	(segment
		(start 148.682456 -170.759882)
		(end 146.837908 -170.759882)
		(width 0.1016)
		(layer "F.Cu")
		(net "UART_T12_NODE1_TXD")
	)
	(segment
		(start 146.686778 -170.608752)
		(end 145.275808 -170.608752)
		(width 0.1016)
		(layer "F.Cu")
		(net "UART_T12_NODE1_TXD")
	)
	(segment
		(start 146.837908 -170.759882)
		(end 146.686778 -170.608752)
		(width 0.1016)
		(layer "F.Cu")
		(net "UART_T12_NODE1_TXD")
	)
	(segment
		(start 151.04364 -178.959002)
		(end 151.04364 -173.121066)
		(width 0.1016)
		(layer "F.Cu")
		(net "UART_T12_NODE1_TXD")
	)
	(segment
		(start 150.91918 -182.69966)
		(end 150.91664 -182.7022)
		(width 0.1016)
		(layer "F.Cu")
		(net "UART_T12_NODE1_TXD")
	)
	(segment
		(start 150.91918 -182.69966)
		(end 150.586186 -182.366666)
		(width 0.1016)
		(layer "F.Cu")
		(net "UART_T12_NODE1_TXD")
	)
	(segment
		(start 150.91664 -184.34558)
		(end 150.47976 -184.78246)
		(width 0.1016)
		(layer "F.Cu")
		(net "UART_T12_NODE1_TXD")
	)
	(segment
		(start 150.79726 -181.150006)
		(end 150.79726 -179.205382)
		(width 0.1016)
		(layer "F.Cu")
		(net "UART_T12_NODE1_TXD")
	)
	(segment
		(start 150.91664 -182.7022)
		(end 150.91664 -184.34558)
		(width 0.1016)
		(layer "F.Cu")
		(net "UART_T12_NODE1_TXD")
	)
	(segment
		(start 150.586186 -181.36108)
		(end 150.79726 -181.150006)
		(width 0.1016)
		(layer "F.Cu")
		(net "UART_T12_NODE1_TXD")
	)
	(segment
		(start 151.04364 -173.121066)
		(end 148.682456 -170.759882)
		(width 0.1016)
		(layer "F.Cu")
		(net "UART_T12_NODE1_TXD")
	)
	(segment
		(start 150.586186 -182.366666)
		(end 150.586186 -181.36108)
		(width 0.1016)
		(layer "F.Cu")
		(net "UART_T12_NODE1_TXD")
	)
	(segment
		(start 150.47976 -184.78246)
		(end 150.47976 -184.805574)
		(width 0.1016)
		(layer "F.Cu")
		(net "UART_T12_NODE1_TXD")
	)
	(segment
		(start 150.79726 -179.205382)
		(end 151.04364 -178.959002)
		(width 0.1016)
		(layer "F.Cu")
		(net "UART_T12_NODE1_TXD")
	)
	(via
		(at 150.91918 -182.69966)
		(size 0.508)
		(drill 0.254)
		(layers "F.Cu" "B.Cu")
		(net "UART_T12_NODE1_TXD")
	)
	(segment
		(start 147.50796 -165.934644)
		(end 147.50796 -165.513004)
		(width 0.1016)
		(layer "F.Cu")
		(net "UART_T11_NODE1_TXD")
	)
	(segment
		(start 147.103592 -165.108636)
		(end 145.275808 -165.108636)
		(width 0.1016)
		(layer "F.Cu")
		(net "UART_T11_NODE1_TXD")
	)
	(segment
		(start 147.50796 -165.513004)
		(end 147.103592 -165.108636)
		(width 0.1016)
		(layer "F.Cu")
		(net "UART_T11_NODE1_TXD")
	)
	(via
		(at 151.3713 -180.085238)
		(size 0.508)
		(drill 0.254)
		(layers "F.Cu" "B.Cu")
		(net "UART_T11_NODE1_TXD")
	)
	(via
		(at 147.50796 -165.934644)
		(size 0.508)
		(drill 0.254)
		(layers "F.Cu" "B.Cu")
		(net "UART_T11_NODE1_TXD")
	)
	(segment
		(start 149.88032 -183.019954)
		(end 149.88032 -184.147206)
		(width 0.1016)
		(layer "B.Cu")
		(net "UART_T11_NODE1_TXD")
	)
	(segment
		(start 149.475952 -184.551574)
		(end 149.33676 -184.551574)
		(width 0.1016)
		(layer "B.Cu")
		(net "UART_T11_NODE1_TXD")
	)
	(segment
		(start 151.3713 -181.528974)
		(end 149.88032 -183.019954)
		(width 0.1016)
		(layer "B.Cu")
		(net "UART_T11_NODE1_TXD")
	)
	(segment
		(start 151.3713 -180.085238)
		(end 151.3713 -181.528974)
		(width 0.1016)
		(layer "B.Cu")
		(net "UART_T11_NODE1_TXD")
	)
	(segment
		(start 149.88032 -184.147206)
		(end 149.475952 -184.551574)
		(width 0.1016)
		(layer "B.Cu")
		(net "UART_T11_NODE1_TXD")
	)
	(segment
		(start 151.42718 -171.153074)
		(end 149.74062 -169.466514)
		(width 0.1143)
		(layer "In7.Cu")
		(net "UART_T11_NODE1_TXD")
	)
	(segment
		(start 151.78659 -177.52314)
		(end 151.42718 -177.16373)
		(width 0.1143)
		(layer "In7.Cu")
		(net "UART_T11_NODE1_TXD")
	)
	(segment
		(start 149.052788 -167.437562)
		(end 149.010878 -167.437562)
		(width 0.1143)
		(layer "In7.Cu")
		(net "UART_T11_NODE1_TXD")
	)
	(segment
		(start 151.3713 -179.596034)
		(end 151.78659 -179.180744)
		(width 0.1143)
		(layer "In7.Cu")
		(net "UART_T11_NODE1_TXD")
	)
	(segment
		(start 151.42718 -177.16373)
		(end 151.42718 -171.153074)
		(width 0.1143)
		(layer "In7.Cu")
		(net "UART_T11_NODE1_TXD")
	)
	(segment
		(start 151.78659 -179.180744)
		(end 151.78659 -177.52314)
		(width 0.1143)
		(layer "In7.Cu")
		(net "UART_T11_NODE1_TXD")
	)
	(segment
		(start 151.3713 -180.085238)
		(end 151.3713 -179.596034)
		(width 0.1143)
		(layer "In7.Cu")
		(net "UART_T11_NODE1_TXD")
	)
	(segment
		(start 149.74062 -168.125394)
		(end 149.052788 -167.437562)
		(width 0.1143)
		(layer "In7.Cu")
		(net "UART_T11_NODE1_TXD")
	)
	(segment
		(start 149.010878 -167.437562)
		(end 147.50796 -165.934644)
		(width 0.1143)
		(layer "In7.Cu")
		(net "UART_T11_NODE1_TXD")
	)
	(segment
		(start 149.74062 -169.466514)
		(end 149.74062 -168.125394)
		(width 0.1143)
		(layer "In7.Cu")
		(net "UART_T11_NODE1_TXD")
	)
	(segment
		(start 129.775712 -175.608742)
		(end 128.627886 -175.608742)
		(width 0.1016)
		(layer "F.Cu")
		(net "UART_T7_NODE2_RXD")
	)
	(via
		(at 113.71072 -186.325256)
		(size 0.508)
		(drill 0.254)
		(layers "F.Cu" "B.Cu")
		(net "UART_T7_NODE2_RXD")
	)
	(via
		(at 122.07748 -186.497976)
		(size 0.508)
		(drill 0.254)
		(layers "F.Cu" "B.Cu")
		(net "UART_T7_NODE2_RXD")
	)
	(via
		(at 128.627886 -175.608742)
		(size 0.508)
		(drill 0.254)
		(layers "F.Cu" "B.Cu")
		(net "UART_T7_NODE2_RXD")
	)
	(segment
		(start 126.308358 -182.667148)
		(end 125.428502 -182.667148)
		(width 0.1016)
		(layer "B.Cu")
		(net "UART_T7_NODE2_RXD")
	)
	(segment
		(start 128.08966 -177.445416)
		(end 128.08966 -180.885846)
		(width 0.1016)
		(layer "B.Cu")
		(net "UART_T7_NODE2_RXD")
	)
	(segment
		(start 113.71072 -186.325256)
		(end 113.72723 -186.341766)
		(width 0.1016)
		(layer "B.Cu")
		(net "UART_T7_NODE2_RXD")
	)
	(segment
		(start 122.41784 -185.67781)
		(end 122.41784 -186.134756)
		(width 0.1016)
		(layer "B.Cu")
		(net "UART_T7_NODE2_RXD")
	)
	(segment
		(start 128.0922 -176.91989)
		(end 128.03886 -176.97323)
		(width 0.1016)
		(layer "B.Cu")
		(net "UART_T7_NODE2_RXD")
	)
	(segment
		(start 113.72723 -187.038996)
		(end 114.15776 -187.469526)
		(width 0.1016)
		(layer "B.Cu")
		(net "UART_T7_NODE2_RXD")
	)
	(segment
		(start 122.41784 -186.134756)
		(end 122.07748 -186.475116)
		(width 0.1016)
		(layer "B.Cu")
		(net "UART_T7_NODE2_RXD")
	)
	(segment
		(start 125.428502 -182.667148)
		(end 122.41784 -185.67781)
		(width 0.1016)
		(layer "B.Cu")
		(net "UART_T7_NODE2_RXD")
	)
	(segment
		(start 128.0922 -176.450244)
		(end 128.0922 -176.91989)
		(width 0.1016)
		(layer "B.Cu")
		(net "UART_T7_NODE2_RXD")
	)
	(segment
		(start 113.72723 -186.341766)
		(end 113.72723 -187.038996)
		(width 0.1016)
		(layer "B.Cu")
		(net "UART_T7_NODE2_RXD")
	)
	(segment
		(start 122.07748 -186.475116)
		(end 122.07748 -186.497976)
		(width 0.1016)
		(layer "B.Cu")
		(net "UART_T7_NODE2_RXD")
	)
	(segment
		(start 128.03886 -177.394616)
		(end 128.08966 -177.445416)
		(width 0.1016)
		(layer "B.Cu")
		(net "UART_T7_NODE2_RXD")
	)
	(segment
		(start 113.14176 -185.605674)
		(end 113.14176 -185.756296)
		(width 0.1016)
		(layer "B.Cu")
		(net "UART_T7_NODE2_RXD")
	)
	(segment
		(start 114.15776 -187.469526)
		(end 114.15776 -187.726574)
		(width 0.1016)
		(layer "B.Cu")
		(net "UART_T7_NODE2_RXD")
	)
	(segment
		(start 128.627886 -175.914558)
		(end 128.0922 -176.450244)
		(width 0.1016)
		(layer "B.Cu")
		(net "UART_T7_NODE2_RXD")
	)
	(segment
		(start 128.08966 -180.885846)
		(end 126.308358 -182.667148)
		(width 0.1016)
		(layer "B.Cu")
		(net "UART_T7_NODE2_RXD")
	)
	(segment
		(start 128.03886 -176.97323)
		(end 128.03886 -177.394616)
		(width 0.1016)
		(layer "B.Cu")
		(net "UART_T7_NODE2_RXD")
	)
	(segment
		(start 113.14176 -185.756296)
		(end 113.71072 -186.325256)
		(width 0.1016)
		(layer "B.Cu")
		(net "UART_T7_NODE2_RXD")
	)
	(segment
		(start 128.627886 -175.608742)
		(end 128.627886 -175.914558)
		(width 0.1016)
		(layer "B.Cu")
		(net "UART_T7_NODE2_RXD")
	)
	(segment
		(start 122.05462 -186.497976)
		(end 121.091706 -185.535062)
		(width 0.1143)
		(layer "In7.Cu")
		(net "UART_T7_NODE2_RXD")
	)
	(segment
		(start 114.178842 -186.793378)
		(end 113.71072 -186.325256)
		(width 0.1143)
		(layer "In7.Cu")
		(net "UART_T7_NODE2_RXD")
	)
	(segment
		(start 115.845336 -185.535062)
		(end 114.58702 -186.793378)
		(width 0.1143)
		(layer "In7.Cu")
		(net "UART_T7_NODE2_RXD")
	)
	(segment
		(start 121.091706 -185.535062)
		(end 115.845336 -185.535062)
		(width 0.1143)
		(layer "In7.Cu")
		(net "UART_T7_NODE2_RXD")
	)
	(segment
		(start 114.58702 -186.793378)
		(end 114.178842 -186.793378)
		(width 0.1143)
		(layer "In7.Cu")
		(net "UART_T7_NODE2_RXD")
	)
	(segment
		(start 122.07748 -186.497976)
		(end 122.05462 -186.497976)
		(width 0.1143)
		(layer "In7.Cu")
		(net "UART_T7_NODE2_RXD")
	)
	(segment
		(start 145.275808 -169.6085)
		(end 146.43608 -169.6085)
		(width 0.1016)
		(layer "F.Cu")
		(net "UART_T11_NODE4_TXD")
	)
	(via
		(at 141.109954 -183.474868)
		(size 0.508)
		(drill 0.254)
		(layers "F.Cu" "B.Cu")
		(net "UART_T11_NODE4_TXD")
	)
	(via
		(at 146.43608 -169.6085)
		(size 0.508)
		(drill 0.254)
		(layers "F.Cu" "B.Cu")
		(net "UART_T11_NODE4_TXD")
	)
	(segment
		(start 141.08176 -183.496966)
		(end 141.103858 -183.474868)
		(width 0.1016)
		(layer "B.Cu")
		(net "UART_T11_NODE4_TXD")
	)
	(segment
		(start 141.103858 -183.474868)
		(end 141.109954 -183.474868)
		(width 0.1016)
		(layer "B.Cu")
		(net "UART_T11_NODE4_TXD")
	)
	(segment
		(start 141.08176 -184.551574)
		(end 141.08176 -183.496966)
		(width 0.1016)
		(layer "B.Cu")
		(net "UART_T11_NODE4_TXD")
	)
	(segment
		(start 141.918182 -183.474868)
		(end 145.614644 -179.778406)
		(width 0.1143)
		(layer "In7.Cu")
		(net "UART_T11_NODE4_TXD")
	)
	(segment
		(start 141.109954 -183.474868)
		(end 141.918182 -183.474868)
		(width 0.1143)
		(layer "In7.Cu")
		(net "UART_T11_NODE4_TXD")
	)
	(segment
		(start 145.614644 -170.429936)
		(end 146.43608 -169.6085)
		(width 0.1143)
		(layer "In7.Cu")
		(net "UART_T11_NODE4_TXD")
	)
	(segment
		(start 145.614644 -179.778406)
		(end 145.614644 -170.429936)
		(width 0.1143)
		(layer "In7.Cu")
		(net "UART_T11_NODE4_TXD")
	)
	(segment
		(start 145.275808 -168.10863)
		(end 146.131788 -168.10863)
		(width 0.1016)
		(layer "F.Cu")
		(net "UART_T11_NODE2_RXD")
	)
	(segment
		(start 146.131788 -168.10863)
		(end 146.554698 -167.68572)
		(width 0.1016)
		(layer "F.Cu")
		(net "UART_T11_NODE2_RXD")
	)
	(via
		(at 147.44954 -184.002934)
		(size 0.508)
		(drill 0.254)
		(layers "F.Cu" "B.Cu")
		(net "UART_T11_NODE2_RXD")
	)
	(via
		(at 146.554698 -167.68572)
		(size 0.508)
		(drill 0.254)
		(layers "F.Cu" "B.Cu")
		(net "UART_T11_NODE2_RXD")
	)
	(segment
		(start 146.79676 -187.599574)
		(end 146.79676 -187.40882)
		(width 0.1016)
		(layer "B.Cu")
		(net "UART_T11_NODE2_RXD")
	)
	(segment
		(start 147.211288 -186.994292)
		(end 147.211288 -185.908442)
		(width 0.1016)
		(layer "B.Cu")
		(net "UART_T11_NODE2_RXD")
	)
	(segment
		(start 146.79676 -187.40882)
		(end 147.211288 -186.994292)
		(width 0.1016)
		(layer "B.Cu")
		(net "UART_T11_NODE2_RXD")
	)
	(segment
		(start 146.79676 -185.493914)
		(end 146.79676 -185.351674)
		(width 0.1016)
		(layer "B.Cu")
		(net "UART_T11_NODE2_RXD")
	)
	(segment
		(start 147.44954 -185.102754)
		(end 147.44954 -184.002934)
		(width 0.1016)
		(layer "B.Cu")
		(net "UART_T11_NODE2_RXD")
	)
	(segment
		(start 147.20062 -185.351674)
		(end 147.44954 -185.102754)
		(width 0.1016)
		(layer "B.Cu")
		(net "UART_T11_NODE2_RXD")
	)
	(segment
		(start 147.211288 -185.908442)
		(end 146.79676 -185.493914)
		(width 0.1016)
		(layer "B.Cu")
		(net "UART_T11_NODE2_RXD")
	)
	(segment
		(start 146.79676 -185.351674)
		(end 147.20062 -185.351674)
		(width 0.1016)
		(layer "B.Cu")
		(net "UART_T11_NODE2_RXD")
	)
	(segment
		(start 151.04999 -178.818794)
		(end 150.522178 -179.346606)
		(width 0.1143)
		(layer "In7.Cu")
		(net "UART_T11_NODE2_RXD")
	)
	(segment
		(start 148.250656 -168.174162)
		(end 148.74748 -168.174162)
		(width 0.1143)
		(layer "In7.Cu")
		(net "UART_T11_NODE2_RXD")
	)
	(segment
		(start 151.04999 -177.892202)
		(end 151.04999 -178.818794)
		(width 0.1143)
		(layer "In7.Cu")
		(net "UART_T11_NODE2_RXD")
	)
	(segment
		(start 150.522178 -180.930296)
		(end 147.44954 -184.002934)
		(width 0.1143)
		(layer "In7.Cu")
		(net "UART_T11_NODE2_RXD")
	)
	(segment
		(start 150.522178 -179.346606)
		(end 150.522178 -180.930296)
		(width 0.1143)
		(layer "In7.Cu")
		(net "UART_T11_NODE2_RXD")
	)
	(segment
		(start 147.762214 -167.68572)
		(end 148.250656 -168.174162)
		(width 0.1143)
		(layer "In7.Cu")
		(net "UART_T11_NODE2_RXD")
	)
	(segment
		(start 149.003512 -168.430194)
		(end 149.003512 -169.916856)
		(width 0.1143)
		(layer "In7.Cu")
		(net "UART_T11_NODE2_RXD")
	)
	(segment
		(start 148.74748 -168.174162)
		(end 149.003512 -168.430194)
		(width 0.1143)
		(layer "In7.Cu")
		(net "UART_T11_NODE2_RXD")
	)
	(segment
		(start 150.54326 -171.456604)
		(end 150.54326 -177.385472)
		(width 0.1143)
		(layer "In7.Cu")
		(net "UART_T11_NODE2_RXD")
	)
	(segment
		(start 150.54326 -177.385472)
		(end 151.04999 -177.892202)
		(width 0.1143)
		(layer "In7.Cu")
		(net "UART_T11_NODE2_RXD")
	)
	(segment
		(start 146.554698 -167.68572)
		(end 147.762214 -167.68572)
		(width 0.1143)
		(layer "In7.Cu")
		(net "UART_T11_NODE2_RXD")
	)
	(segment
		(start 149.003512 -169.916856)
		(end 150.54326 -171.456604)
		(width 0.1143)
		(layer "In7.Cu")
		(net "UART_T11_NODE2_RXD")
	)
	(segment
		(start 129.775712 -166.608506)
		(end 131.297172 -166.608506)
		(width 0.1016)
		(layer "F.Cu")
		(net "UART_T8_NODE4_TXD")
	)
	(segment
		(start 131.297172 -166.608506)
		(end 131.401312 -166.504366)
		(width 0.1016)
		(layer "F.Cu")
		(net "UART_T8_NODE4_TXD")
	)
	(via
		(at 131.401312 -166.504366)
		(size 0.508)
		(drill 0.254)
		(layers "F.Cu" "B.Cu")
		(net "UART_T8_NODE4_TXD")
	)
	(segment
		(start 131.029456 -166.888414)
		(end 131.401312 -166.516558)
		(width 0.1016)
		(layer "B.Cu")
		(net "UART_T8_NODE4_TXD")
	)
	(segment
		(start 129.518918 -166.371778)
		(end 129.518918 -166.43985)
		(width 0.1016)
		(layer "B.Cu")
		(net "UART_T8_NODE4_TXD")
	)
	(segment
		(start 131.401312 -166.516558)
		(end 131.401312 -166.504366)
		(width 0.1016)
		(layer "B.Cu")
		(net "UART_T8_NODE4_TXD")
	)
	(segment
		(start 129.518918 -166.43985)
		(end 129.967482 -166.888414)
		(width 0.1016)
		(layer "B.Cu")
		(net "UART_T8_NODE4_TXD")
	)
	(segment
		(start 129.967482 -166.888414)
		(end 131.029456 -166.888414)
		(width 0.1016)
		(layer "B.Cu")
		(net "UART_T8_NODE4_TXD")
	)
	(segment
		(start 127.50292 -173.10862)
		(end 129.775712 -173.10862)
		(width 0.1016)
		(layer "F.Cu")
		(net "UART_T7_NODE3_RXD")
	)
	(segment
		(start 127.39116 -173.22038)
		(end 127.50292 -173.10862)
		(width 0.1016)
		(layer "F.Cu")
		(net "UART_T7_NODE3_RXD")
	)
	(via
		(at 111.5568 -183.411622)
		(size 0.508)
		(drill 0.254)
		(layers "F.Cu" "B.Cu")
		(net "UART_T7_NODE3_RXD")
	)
	(via
		(at 127.39116 -173.22038)
		(size 0.508)
		(drill 0.254)
		(layers "F.Cu" "B.Cu")
		(net "UART_T7_NODE3_RXD")
	)
	(segment
		(start 111.47552 -185.334148)
		(end 111.203994 -185.605674)
		(width 0.1016)
		(layer "B.Cu")
		(net "UART_T7_NODE3_RXD")
	)
	(segment
		(start 110.85576 -185.605674)
		(end 110.85576 -186.389264)
		(width 0.1016)
		(layer "B.Cu")
		(net "UART_T7_NODE3_RXD")
	)
	(segment
		(start 111.28756 -187.525914)
		(end 111.48822 -187.726574)
		(width 0.1016)
		(layer "B.Cu")
		(net "UART_T7_NODE3_RXD")
	)
	(segment
		(start 111.5568 -183.411622)
		(end 111.47552 -183.492902)
		(width 0.1016)
		(layer "B.Cu")
		(net "UART_T7_NODE3_RXD")
	)
	(segment
		(start 111.47552 -183.492902)
		(end 111.47552 -185.334148)
		(width 0.1016)
		(layer "B.Cu")
		(net "UART_T7_NODE3_RXD")
	)
	(segment
		(start 111.203994 -185.605674)
		(end 110.85576 -185.605674)
		(width 0.1016)
		(layer "B.Cu")
		(net "UART_T7_NODE3_RXD")
	)
	(segment
		(start 111.48822 -187.726574)
		(end 111.87176 -187.726574)
		(width 0.1016)
		(layer "B.Cu")
		(net "UART_T7_NODE3_RXD")
	)
	(segment
		(start 111.28756 -186.821064)
		(end 111.28756 -187.525914)
		(width 0.1016)
		(layer "B.Cu")
		(net "UART_T7_NODE3_RXD")
	)
	(segment
		(start 110.85576 -186.389264)
		(end 111.28756 -186.821064)
		(width 0.1016)
		(layer "B.Cu")
		(net "UART_T7_NODE3_RXD")
	)
	(segment
		(start 121.84634 -179.356004)
		(end 115.206018 -179.356004)
		(width 0.1143)
		(layer "In7.Cu")
		(net "UART_T7_NODE3_RXD")
	)
	(segment
		(start 126.76505 -177.923698)
		(end 126.50978 -178.178968)
		(width 0.1143)
		(layer "In7.Cu")
		(net "UART_T7_NODE3_RXD")
	)
	(segment
		(start 126.50978 -178.178968)
		(end 123.023884 -178.178968)
		(width 0.1143)
		(layer "In7.Cu")
		(net "UART_T7_NODE3_RXD")
	)
	(segment
		(start 127.254 -173.35754)
		(end 127.254 -176.612296)
		(width 0.1143)
		(layer "In7.Cu")
		(net "UART_T7_NODE3_RXD")
	)
	(segment
		(start 113.69548 -181.958742)
		(end 112.603788 -181.958742)
		(width 0.1143)
		(layer "In7.Cu")
		(net "UART_T7_NODE3_RXD")
	)
	(segment
		(start 126.974092 -176.892966)
		(end 126.76505 -177.102262)
		(width 0.1143)
		(layer "In7.Cu")
		(net "UART_T7_NODE3_RXD")
	)
	(segment
		(start 115.206018 -179.356004)
		(end 113.95202 -180.610002)
		(width 0.1143)
		(layer "In7.Cu")
		(net "UART_T7_NODE3_RXD")
	)
	(segment
		(start 127.254 -176.612296)
		(end 127.1651 -176.70145)
		(width 0.1143)
		(layer "In7.Cu")
		(net "UART_T7_NODE3_RXD")
	)
	(segment
		(start 111.5568 -183.00573)
		(end 111.5568 -183.411622)
		(width 0.1143)
		(layer "In7.Cu")
		(net "UART_T7_NODE3_RXD")
	)
	(segment
		(start 113.95202 -181.702202)
		(end 113.69548 -181.958742)
		(width 0.1143)
		(layer "In7.Cu")
		(net "UART_T7_NODE3_RXD")
	)
	(segment
		(start 113.95202 -180.610002)
		(end 113.95202 -181.702202)
		(width 0.1143)
		(layer "In7.Cu")
		(net "UART_T7_NODE3_RXD")
	)
	(segment
		(start 112.603788 -181.958742)
		(end 111.5568 -183.00573)
		(width 0.1143)
		(layer "In7.Cu")
		(net "UART_T7_NODE3_RXD")
	)
	(segment
		(start 127.39116 -173.22038)
		(end 127.254 -173.35754)
		(width 0.1143)
		(layer "In7.Cu")
		(net "UART_T7_NODE3_RXD")
	)
	(segment
		(start 127.1651 -176.701704)
		(end 126.974092 -176.892966)
		(width 0.1143)
		(layer "In7.Cu")
		(net "UART_T7_NODE3_RXD")
	)
	(segment
		(start 126.76505 -177.102262)
		(end 126.76505 -177.923698)
		(width 0.1143)
		(layer "In7.Cu")
		(net "UART_T7_NODE3_RXD")
	)
	(segment
		(start 127.1651 -176.70145)
		(end 127.1651 -176.701704)
		(width 0.1143)
		(layer "In7.Cu")
		(net "UART_T7_NODE3_RXD")
	)
	(segment
		(start 123.023884 -178.178968)
		(end 121.84634 -179.356004)
		(width 0.1143)
		(layer "In7.Cu")
		(net "UART_T7_NODE3_RXD")
	)
	(segment
		(start 132.025644 -163.358576)
		(end 132.025644 -167.89146)
		(width 0.1016)
		(layer "F.Cu")
		(net "UART_T9_NODE1_TXD")
	)
	(segment
		(start 132.025644 -167.89146)
		(end 132.861812 -168.727628)
		(width 0.1016)
		(layer "F.Cu")
		(net "UART_T9_NODE1_TXD")
	)
	(segment
		(start 132.861812 -168.727628)
		(end 132.861812 -170.683682)
		(width 0.1016)
		(layer "F.Cu")
		(net "UART_T9_NODE1_TXD")
	)
	(segment
		(start 132.861812 -170.683682)
		(end 133.7564 -171.57827)
		(width 0.1016)
		(layer "F.Cu")
		(net "UART_T9_NODE1_TXD")
	)
	(segment
		(start 133.7564 -171.57827)
		(end 133.7564 -172.495718)
		(width 0.1016)
		(layer "F.Cu")
		(net "UART_T9_NODE1_TXD")
	)
	(via
		(at 133.7564 -172.495718)
		(size 0.508)
		(drill 0.254)
		(layers "F.Cu" "B.Cu")
		(net "UART_T9_NODE1_TXD")
	)
	(segment
		(start 134.22376 -184.54751)
		(end 133.7564 -184.08015)
		(width 0.1016)
		(layer "B.Cu")
		(net "UART_T9_NODE1_TXD")
	)
	(segment
		(start 134.394194 -174.046642)
		(end 133.856476 -173.508924)
		(width 0.1016)
		(layer "B.Cu")
		(net "UART_T9_NODE1_TXD")
	)
	(segment
		(start 134.22376 -184.551574)
		(end 134.22376 -184.54751)
		(width 0.1016)
		(layer "B.Cu")
		(net "UART_T9_NODE1_TXD")
	)
	(segment
		(start 133.856476 -173.508924)
		(end 133.856476 -172.595794)
		(width 0.1016)
		(layer "B.Cu")
		(net "UART_T9_NODE1_TXD")
	)
	(segment
		(start 134.394194 -174.467774)
		(end 134.394194 -174.046642)
		(width 0.1016)
		(layer "B.Cu")
		(net "UART_T9_NODE1_TXD")
	)
	(segment
		(start 133.856476 -172.595794)
		(end 133.7564 -172.495718)
		(width 0.1016)
		(layer "B.Cu")
		(net "UART_T9_NODE1_TXD")
	)
	(segment
		(start 133.7564 -184.08015)
		(end 133.7564 -175.105568)
		(width 0.1016)
		(layer "B.Cu")
		(net "UART_T9_NODE1_TXD")
	)
	(segment
		(start 133.7564 -175.105568)
		(end 134.394194 -174.467774)
		(width 0.1016)
		(layer "B.Cu")
		(net "UART_T9_NODE1_TXD")
	)
	(segment
		(start 145.275808 -170.108626)
		(end 147.05584 -170.108626)
		(width 0.1016)
		(layer "F.Cu")
		(net "UART_T11_NODE4_RXD")
	)
	(segment
		(start 147.05584 -170.108626)
		(end 147.085304 -170.079162)
		(width 0.1016)
		(layer "F.Cu")
		(net "UART_T11_NODE4_RXD")
	)
	(via
		(at 147.085304 -170.079162)
		(size 0.508)
		(drill 0.254)
		(layers "F.Cu" "B.Cu")
		(net "UART_T11_NODE4_RXD")
	)
	(via
		(at 141.726412 -186.449462)
		(size 0.508)
		(drill 0.254)
		(layers "F.Cu" "B.Cu")
		(net "UART_T11_NODE4_RXD")
	)
	(segment
		(start 142.22476 -187.599574)
		(end 141.84884 -187.223654)
		(width 0.1016)
		(layer "B.Cu")
		(net "UART_T11_NODE4_RXD")
	)
	(segment
		(start 141.84884 -186.571382)
		(end 141.72692 -186.449462)
		(width 0.1016)
		(layer "B.Cu")
		(net "UART_T11_NODE4_RXD")
	)
	(segment
		(start 142.22476 -185.351674)
		(end 142.22476 -185.951114)
		(width 0.1016)
		(layer "B.Cu")
		(net "UART_T11_NODE4_RXD")
	)
	(segment
		(start 142.22476 -185.951114)
		(end 141.726412 -186.449462)
		(width 0.1016)
		(layer "B.Cu")
		(net "UART_T11_NODE4_RXD")
	)
	(segment
		(start 141.84884 -187.223654)
		(end 141.84884 -186.571382)
		(width 0.1016)
		(layer "B.Cu")
		(net "UART_T11_NODE4_RXD")
	)
	(segment
		(start 141.72692 -186.449462)
		(end 141.726412 -186.449462)
		(width 0.1016)
		(layer "B.Cu")
		(net "UART_T11_NODE4_RXD")
	)
	(segment
		(start 141.726412 -186.047126)
		(end 142.2527 -185.520838)
		(width 0.1143)
		(layer "In7.Cu")
		(net "UART_T11_NODE4_RXD")
	)
	(segment
		(start 142.2527 -185.520838)
		(end 142.2527 -183.662066)
		(width 0.1143)
		(layer "In7.Cu")
		(net "UART_T11_NODE4_RXD")
	)
	(segment
		(start 145.978118 -180.771546)
		(end 145.978118 -171.186348)
		(width 0.1143)
		(layer "In7.Cu")
		(net "UART_T11_NODE4_RXD")
	)
	(segment
		(start 145.978118 -171.186348)
		(end 147.085304 -170.079162)
		(width 0.1143)
		(layer "In7.Cu")
		(net "UART_T11_NODE4_RXD")
	)
	(segment
		(start 143.133064 -182.781702)
		(end 143.967962 -182.781702)
		(width 0.1143)
		(layer "In7.Cu")
		(net "UART_T11_NODE4_RXD")
	)
	(segment
		(start 141.726412 -186.449462)
		(end 141.726412 -186.047126)
		(width 0.1143)
		(layer "In7.Cu")
		(net "UART_T11_NODE4_RXD")
	)
	(segment
		(start 142.2527 -183.662066)
		(end 143.133064 -182.781702)
		(width 0.1143)
		(layer "In7.Cu")
		(net "UART_T11_NODE4_RXD")
	)
	(segment
		(start 143.967962 -182.781702)
		(end 145.978118 -180.771546)
		(width 0.1143)
		(layer "In7.Cu")
		(net "UART_T11_NODE4_RXD")
	)
	(segment
		(start 139.025884 -165.074346)
		(end 137.775696 -166.324534)
		(width 0.1016)
		(layer "F.Cu")
		(net "UART_T9_NODE4_TXD")
	)
	(segment
		(start 139.025884 -163.358576)
		(end 139.025884 -165.074346)
		(width 0.1016)
		(layer "F.Cu")
		(net "UART_T9_NODE4_TXD")
	)
	(via
		(at 137.775696 -166.324534)
		(size 0.508)
		(drill 0.254)
		(layers "F.Cu" "B.Cu")
		(net "UART_T9_NODE4_TXD")
	)
	(segment
		(start 138.438128 -165.662102)
		(end 137.775696 -166.324534)
		(width 0.1016)
		(layer "B.Cu")
		(net "UART_T9_NODE4_TXD")
	)
	(segment
		(start 138.438128 -165.170358)
		(end 138.438128 -165.662102)
		(width 0.1016)
		(layer "B.Cu")
		(net "UART_T9_NODE4_TXD")
	)
	(segment
		(start 140.525754 -164.93236)
		(end 140.257784 -165.20033)
		(width 0.1016)
		(layer "F.Cu")
		(net "UART_T10_NODE1_RXD")
	)
	(segment
		(start 140.525754 -163.358576)
		(end 140.525754 -164.93236)
		(width 0.1016)
		(layer "F.Cu")
		(net "UART_T10_NODE1_RXD")
	)
	(segment
		(start 140.257784 -165.577012)
		(end 140.01242 -165.822376)
		(width 0.1016)
		(layer "F.Cu")
		(net "UART_T10_NODE1_RXD")
	)
	(segment
		(start 135.36676 -186.64174)
		(end 135.36676 -185.605674)
		(width 0.1016)
		(layer "F.Cu")
		(net "UART_T10_NODE1_RXD")
	)
	(segment
		(start 135.74776 -187.726574)
		(end 135.74776 -187.02274)
		(width 0.1016)
		(layer "F.Cu")
		(net "UART_T10_NODE1_RXD")
	)
	(segment
		(start 135.74776 -187.02274)
		(end 135.36676 -186.64174)
		(width 0.1016)
		(layer "F.Cu")
		(net "UART_T10_NODE1_RXD")
	)
	(segment
		(start 140.257784 -165.20033)
		(end 140.257784 -165.577012)
		(width 0.1016)
		(layer "F.Cu")
		(net "UART_T10_NODE1_RXD")
	)
	(via
		(at 140.01242 -165.822376)
		(size 0.508)
		(drill 0.254)
		(layers "F.Cu" "B.Cu")
		(net "UART_T10_NODE1_RXD")
	)
	(via
		(at 135.36676 -186.64174)
		(size 0.508)
		(drill 0.254)
		(layers "F.Cu" "B.Cu")
		(net "UART_T10_NODE1_RXD")
	)
	(segment
		(start 138.889994 -180.240686)
		(end 138.889994 -179.003452)
		(width 0.1143)
		(layer "In7.Cu")
		(net "UART_T10_NODE1_RXD")
	)
	(segment
		(start 138.538712 -175.820578)
		(end 138.538712 -167.909748)
		(width 0.1143)
		(layer "In7.Cu")
		(net "UART_T10_NODE1_RXD")
	)
	(segment
		(start 138.889994 -179.003452)
		(end 137.97026 -178.083718)
		(width 0.1143)
		(layer "In7.Cu")
		(net "UART_T10_NODE1_RXD")
	)
	(segment
		(start 137.97026 -176.38903)
		(end 138.538712 -175.820578)
		(width 0.1143)
		(layer "In7.Cu")
		(net "UART_T10_NODE1_RXD")
	)
	(segment
		(start 137.431272 -181.420516)
		(end 137.710164 -181.420516)
		(width 0.1143)
		(layer "In7.Cu")
		(net "UART_T10_NODE1_RXD")
	)
	(segment
		(start 140.01242 -166.43604)
		(end 140.01242 -165.822376)
		(width 0.1143)
		(layer "In7.Cu")
		(net "UART_T10_NODE1_RXD")
	)
	(segment
		(start 135.36676 -185.705496)
		(end 135.939276 -185.13298)
		(width 0.1143)
		(layer "In7.Cu")
		(net "UART_T10_NODE1_RXD")
	)
	(segment
		(start 137.710164 -181.420516)
		(end 138.889994 -180.240686)
		(width 0.1143)
		(layer "In7.Cu")
		(net "UART_T10_NODE1_RXD")
	)
	(segment
		(start 135.939276 -182.912512)
		(end 137.431272 -181.420516)
		(width 0.1143)
		(layer "In7.Cu")
		(net "UART_T10_NODE1_RXD")
	)
	(segment
		(start 138.538712 -167.909748)
		(end 140.01242 -166.43604)
		(width 0.1143)
		(layer "In7.Cu")
		(net "UART_T10_NODE1_RXD")
	)
	(segment
		(start 137.97026 -178.083718)
		(end 137.97026 -176.38903)
		(width 0.1143)
		(layer "In7.Cu")
		(net "UART_T10_NODE1_RXD")
	)
	(segment
		(start 135.939276 -185.13298)
		(end 135.939276 -182.912512)
		(width 0.1143)
		(layer "In7.Cu")
		(net "UART_T10_NODE1_RXD")
	)
	(segment
		(start 135.36676 -186.64174)
		(end 135.36676 -185.705496)
		(width 0.1143)
		(layer "In7.Cu")
		(net "UART_T10_NODE1_RXD")
	)
	(segment
		(start 140.025882 -166.71798)
		(end 140.025882 -170.3832)
		(width 0.1016)
		(layer "F.Cu")
		(net "UART_T10_NODE1_TXD")
	)
	(segment
		(start 134.22376 -184.805574)
		(end 134.22376 -183.617362)
		(width 0.1016)
		(layer "F.Cu")
		(net "UART_T10_NODE1_TXD")
	)
	(segment
		(start 140.025882 -163.358576)
		(end 140.025882 -164.78885)
		(width 0.1016)
		(layer "F.Cu")
		(net "UART_T10_NODE1_TXD")
	)
	(segment
		(start 134.22376 -183.617362)
		(end 134.210552 -183.617362)
		(width 0.1016)
		(layer "F.Cu")
		(net "UART_T10_NODE1_TXD")
	)
	(segment
		(start 139.52474 -166.216838)
		(end 140.025882 -166.71798)
		(width 0.1016)
		(layer "F.Cu")
		(net "UART_T10_NODE1_TXD")
	)
	(segment
		(start 140.025882 -164.78885)
		(end 139.52474 -165.289992)
		(width 0.1016)
		(layer "F.Cu")
		(net "UART_T10_NODE1_TXD")
	)
	(segment
		(start 139.52474 -165.289992)
		(end 139.52474 -166.216838)
		(width 0.1016)
		(layer "F.Cu")
		(net "UART_T10_NODE1_TXD")
	)
	(via
		(at 134.210552 -183.617362)
		(size 0.508)
		(drill 0.254)
		(layers "F.Cu" "B.Cu")
		(net "UART_T10_NODE1_TXD")
	)
	(via
		(at 140.025882 -170.3832)
		(size 0.508)
		(drill 0.254)
		(layers "F.Cu" "B.Cu")
		(net "UART_T10_NODE1_TXD")
	)
	(segment
		(start 139.488164 -170.920918)
		(end 140.025882 -170.3832)
		(width 0.1016)
		(layer "B.Cu")
		(net "UART_T10_NODE1_TXD")
	)
	(segment
		(start 139.488164 -179.680616)
		(end 139.488164 -170.920918)
		(width 0.1016)
		(layer "B.Cu")
		(net "UART_T10_NODE1_TXD")
	)
	(segment
		(start 134.210552 -183.617362)
		(end 134.516114 -183.617362)
		(width 0.1016)
		(layer "B.Cu")
		(net "UART_T10_NODE1_TXD")
	)
	(segment
		(start 134.516114 -183.617362)
		(end 136.020302 -182.113174)
		(width 0.1016)
		(layer "B.Cu")
		(net "UART_T10_NODE1_TXD")
	)
	(segment
		(start 136.020302 -182.113174)
		(end 137.055606 -182.113174)
		(width 0.1016)
		(layer "B.Cu")
		(net "UART_T10_NODE1_TXD")
	)
	(segment
		(start 137.055606 -182.113174)
		(end 139.488164 -179.680616)
		(width 0.1016)
		(layer "B.Cu")
		(net "UART_T10_NODE1_TXD")
	)
	(segment
		(start 141.02588 -162.717988)
		(end 141.02588 -163.358576)
		(width 0.1016)
		(layer "F.Cu")
		(net "UART_T10_NODE2_TXD")
	)
	(segment
		(start 139.96162 -161.8488)
		(end 140.156692 -161.8488)
		(width 0.1016)
		(layer "F.Cu")
		(net "UART_T10_NODE2_TXD")
	)
	(segment
		(start 140.156692 -161.8488)
		(end 141.02588 -162.717988)
		(width 0.1016)
		(layer "F.Cu")
		(net "UART_T10_NODE2_TXD")
	)
	(via
		(at 139.96162 -161.8488)
		(size 0.508)
		(drill 0.254)
		(layers "F.Cu" "B.Cu")
		(net "UART_T10_NODE2_TXD")
	)
	(segment
		(start 140.117322 -162.004502)
		(end 139.96162 -161.8488)
		(width 0.1016)
		(layer "B.Cu")
		(net "UART_T10_NODE2_TXD")
	)
	(segment
		(start 140.117322 -163.363402)
		(end 140.117322 -162.004502)
		(width 0.1016)
		(layer "B.Cu")
		(net "UART_T10_NODE2_TXD")
	)
	(segment
		(start 142.025878 -163.358576)
		(end 142.025878 -162.221164)
		(width 0.1016)
		(layer "F.Cu")
		(net "UART_T10_NODE3_TXD")
	)
	(segment
		(start 142.025878 -162.221164)
		(end 141.816074 -162.01136)
		(width 0.1016)
		(layer "F.Cu")
		(net "UART_T10_NODE3_TXD")
	)
	(segment
		(start 141.816074 -162.01136)
		(end 141.803374 -162.01136)
		(width 0.1016)
		(layer "F.Cu")
		(net "UART_T10_NODE3_TXD")
	)
	(via
		(at 141.803374 -162.01136)
		(size 0.508)
		(drill 0.254)
		(layers "F.Cu" "B.Cu")
		(net "UART_T10_NODE3_TXD")
	)
	(segment
		(start 141.099032 -163.097972)
		(end 141.099032 -162.715702)
		(width 0.1016)
		(layer "B.Cu")
		(net "UART_T10_NODE3_TXD")
	)
	(segment
		(start 141.099032 -162.715702)
		(end 141.803374 -162.01136)
		(width 0.1016)
		(layer "B.Cu")
		(net "UART_T10_NODE3_TXD")
	)
	(segment
		(start 133.46176 -186.459114)
		(end 133.242304 -186.239658)
		(width 0.1016)
		(layer "F.Cu")
		(net "UART_T10_NODE2_RXD")
	)
	(segment
		(start 140.56614 -170.50512)
		(end 139.61618 -171.45508)
		(width 0.1016)
		(layer "F.Cu")
		(net "UART_T10_NODE2_RXD")
	)
	(segment
		(start 139.61618 -171.45508)
		(end 137.092436 -171.45508)
		(width 0.1016)
		(layer "F.Cu")
		(net "UART_T10_NODE2_RXD")
	)
	(segment
		(start 133.46176 -187.726574)
		(end 133.46176 -186.459114)
		(width 0.1016)
		(layer "F.Cu")
		(net "UART_T10_NODE2_RXD")
	)
	(segment
		(start 141.525752 -165.904164)
		(end 140.56614 -166.863776)
		(width 0.1016)
		(layer "F.Cu")
		(net "UART_T10_NODE2_RXD")
	)
	(segment
		(start 141.525752 -163.358576)
		(end 141.525752 -165.904164)
		(width 0.1016)
		(layer "F.Cu")
		(net "UART_T10_NODE2_RXD")
	)
	(segment
		(start 133.08076 -185.605674)
		(end 133.08076 -186.078114)
		(width 0.1016)
		(layer "F.Cu")
		(net "UART_T10_NODE2_RXD")
	)
	(segment
		(start 140.56614 -166.863776)
		(end 140.56614 -170.50512)
		(width 0.1016)
		(layer "F.Cu")
		(net "UART_T10_NODE2_RXD")
	)
	(segment
		(start 133.08076 -186.078114)
		(end 133.242304 -186.239658)
		(width 0.1016)
		(layer "F.Cu")
		(net "UART_T10_NODE2_RXD")
	)
	(via
		(at 137.092436 -171.45508)
		(size 0.508)
		(drill 0.254)
		(layers "F.Cu" "B.Cu")
		(net "UART_T10_NODE2_RXD")
	)
	(via
		(at 133.242304 -186.239658)
		(size 0.508)
		(drill 0.254)
		(layers "F.Cu" "B.Cu")
		(net "UART_T10_NODE2_RXD")
	)
	(segment
		(start 135.079232 -181.143148)
		(end 135.079232 -179.179728)
		(width 0.1143)
		(layer "In7.Cu")
		(net "UART_T10_NODE2_RXD")
	)
	(segment
		(start 137.092436 -175.919638)
		(end 137.092436 -171.45508)
		(width 0.1143)
		(layer "In7.Cu")
		(net "UART_T10_NODE2_RXD")
	)
	(segment
		(start 133.58622 -184.542938)
		(end 133.58622 -182.63616)
		(width 0.1143)
		(layer "In7.Cu")
		(net "UART_T10_NODE2_RXD")
	)
	(segment
		(start 135.079232 -179.179728)
		(end 136.808972 -177.449988)
		(width 0.1143)
		(layer "In7.Cu")
		(net "UART_T10_NODE2_RXD")
	)
	(segment
		(start 133.58622 -182.63616)
		(end 135.079232 -181.143148)
		(width 0.1143)
		(layer "In7.Cu")
		(net "UART_T10_NODE2_RXD")
	)
	(segment
		(start 133.242304 -184.886854)
		(end 133.58622 -184.542938)
		(width 0.1143)
		(layer "In7.Cu")
		(net "UART_T10_NODE2_RXD")
	)
	(segment
		(start 133.242304 -186.239658)
		(end 133.242304 -184.886854)
		(width 0.1143)
		(layer "In7.Cu")
		(net "UART_T10_NODE2_RXD")
	)
	(segment
		(start 136.808972 -176.203102)
		(end 137.092436 -175.919638)
		(width 0.1143)
		(layer "In7.Cu")
		(net "UART_T10_NODE2_RXD")
	)
	(segment
		(start 136.808972 -177.449988)
		(end 136.808972 -176.203102)
		(width 0.1143)
		(layer "In7.Cu")
		(net "UART_T10_NODE2_RXD")
	)
	(segment
		(start 127.911098 -186.300618)
		(end 129.06756 -187.45708)
		(width 0.1016)
		(layer "F.Cu")
		(net "UART_T10_NODE4_RXD")
	)
	(segment
		(start 143.21536 -165.752018)
		(end 143.21536 -165.99281)
		(width 0.1016)
		(layer "F.Cu")
		(net "UART_T10_NODE4_RXD")
	)
	(segment
		(start 143.525748 -163.358576)
		(end 143.525748 -165.44163)
		(width 0.1016)
		(layer "F.Cu")
		(net "UART_T10_NODE4_RXD")
	)
	(segment
		(start 143.525748 -165.44163)
		(end 143.21536 -165.752018)
		(width 0.1016)
		(layer "F.Cu")
		(net "UART_T10_NODE4_RXD")
	)
	(segment
		(start 127.407416 -186.182762)
		(end 127.525272 -186.300618)
		(width 0.1016)
		(layer "F.Cu")
		(net "UART_T10_NODE4_RXD")
	)
	(segment
		(start 127.525272 -186.300618)
		(end 127.911098 -186.300618)
		(width 0.1016)
		(layer "F.Cu")
		(net "UART_T10_NODE4_RXD")
	)
	(segment
		(start 129.06756 -187.45708)
		(end 129.06756 -187.726574)
		(width 0.1016)
		(layer "F.Cu")
		(net "UART_T10_NODE4_RXD")
	)
	(segment
		(start 128.25476 -185.605674)
		(end 127.865632 -185.605674)
		(width 0.1016)
		(layer "F.Cu")
		(net "UART_T10_NODE4_RXD")
	)
	(segment
		(start 127.865632 -185.605674)
		(end 127.407416 -186.06389)
		(width 0.1016)
		(layer "F.Cu")
		(net "UART_T10_NODE4_RXD")
	)
	(segment
		(start 127.407416 -186.06389)
		(end 127.407416 -186.182762)
		(width 0.1016)
		(layer "F.Cu")
		(net "UART_T10_NODE4_RXD")
	)
	(via
		(at 143.21536 -165.99281)
		(size 0.508)
		(drill 0.254)
		(layers "F.Cu" "B.Cu")
		(net "UART_T10_NODE4_RXD")
	)
	(via
		(at 127.407416 -186.182762)
		(size 0.508)
		(drill 0.254)
		(layers "F.Cu" "B.Cu")
		(net "UART_T10_NODE4_RXD")
	)
	(segment
		(start 136.136888 -187.105544)
		(end 135.456676 -187.785756)
		(width 0.1143)
		(layer "In7.Cu")
		(net "UART_T10_NODE4_RXD")
	)
	(segment
		(start 138.939524 -182.166514)
		(end 137.587736 -182.166514)
		(width 0.1143)
		(layer "In7.Cu")
		(net "UART_T10_NODE4_RXD")
	)
	(segment
		(start 143.21536 -165.99281)
		(end 140.521944 -168.686226)
		(width 0.1143)
		(layer "In7.Cu")
		(net "UART_T10_NODE4_RXD")
	)
	(segment
		(start 140.521944 -180.584094)
		(end 138.939524 -182.166514)
		(width 0.1143)
		(layer "In7.Cu")
		(net "UART_T10_NODE4_RXD")
	)
	(segment
		(start 136.588754 -183.165496)
		(end 136.588754 -186.035188)
		(width 0.1143)
		(layer "In7.Cu")
		(net "UART_T10_NODE4_RXD")
	)
	(segment
		(start 136.588754 -186.035188)
		(end 136.136888 -186.487054)
		(width 0.1143)
		(layer "In7.Cu")
		(net "UART_T10_NODE4_RXD")
	)
	(segment
		(start 127.854964 -186.182762)
		(end 127.407416 -186.182762)
		(width 0.1143)
		(layer "In7.Cu")
		(net "UART_T10_NODE4_RXD")
	)
	(segment
		(start 136.136888 -186.487054)
		(end 136.136888 -187.105544)
		(width 0.1143)
		(layer "In7.Cu")
		(net "UART_T10_NODE4_RXD")
	)
	(segment
		(start 137.587736 -182.166514)
		(end 136.588754 -183.165496)
		(width 0.1143)
		(layer "In7.Cu")
		(net "UART_T10_NODE4_RXD")
	)
	(segment
		(start 129.457958 -187.785756)
		(end 127.854964 -186.182762)
		(width 0.1143)
		(layer "In7.Cu")
		(net "UART_T10_NODE4_RXD")
	)
	(segment
		(start 140.521944 -168.686226)
		(end 140.521944 -180.584094)
		(width 0.1143)
		(layer "In7.Cu")
		(net "UART_T10_NODE4_RXD")
	)
	(segment
		(start 135.456676 -187.785756)
		(end 129.457958 -187.785756)
		(width 0.1143)
		(layer "In7.Cu")
		(net "UART_T10_NODE4_RXD")
	)
	(segment
		(start 129.021332 -171.95419)
		(end 128.180592 -171.95419)
		(width 0.1016)
		(layer "F.Cu")
		(net "UART_T7_NODE4_RXD")
	)
	(segment
		(start 129.175764 -172.108622)
		(end 129.021332 -171.95419)
		(width 0.1016)
		(layer "F.Cu")
		(net "UART_T7_NODE4_RXD")
	)
	(segment
		(start 128.180592 -171.95419)
		(end 127.875792 -172.25899)
		(width 0.1016)
		(layer "F.Cu")
		(net "UART_T7_NODE4_RXD")
	)
	(segment
		(start 127.875792 -172.25899)
		(end 126.054358 -172.25899)
		(width 0.1016)
		(layer "F.Cu")
		(net "UART_T7_NODE4_RXD")
	)
	(segment
		(start 129.775712 -172.108622)
		(end 129.175764 -172.108622)
		(width 0.1016)
		(layer "F.Cu")
		(net "UART_T7_NODE4_RXD")
	)
	(via
		(at 126.054358 -172.25899)
		(size 0.508)
		(drill 0.254)
		(layers "F.Cu" "B.Cu")
		(net "UART_T7_NODE4_RXD")
	)
	(via
		(at 109.58576 -183.88457)
		(size 0.508)
		(drill 0.254)
		(layers "F.Cu" "B.Cu")
		(net "UART_T7_NODE4_RXD")
	)
	(segment
		(start 108.56976 -186.018424)
		(end 108.56976 -185.605674)
		(width 0.1016)
		(layer "B.Cu")
		(net "UART_T7_NODE4_RXD")
	)
	(segment
		(start 109.3851 -187.726574)
		(end 109.00664 -187.348114)
		(width 0.1016)
		(layer "B.Cu")
		(net "UART_T7_NODE4_RXD")
	)
	(segment
		(start 109.12856 -184.34177)
		(end 109.12856 -185.320686)
		(width 0.1016)
		(layer "B.Cu")
		(net "UART_T7_NODE4_RXD")
	)
	(segment
		(start 109.12856 -185.320686)
		(end 108.843572 -185.605674)
		(width 0.1016)
		(layer "B.Cu")
		(net "UART_T7_NODE4_RXD")
	)
	(segment
		(start 108.843572 -185.605674)
		(end 108.56976 -185.605674)
		(width 0.1016)
		(layer "B.Cu")
		(net "UART_T7_NODE4_RXD")
	)
	(segment
		(start 109.00664 -187.348114)
		(end 109.00664 -186.455304)
		(width 0.1016)
		(layer "B.Cu")
		(net "UART_T7_NODE4_RXD")
	)
	(segment
		(start 109.00664 -186.455304)
		(end 108.56976 -186.018424)
		(width 0.1016)
		(layer "B.Cu")
		(net "UART_T7_NODE4_RXD")
	)
	(segment
		(start 109.58576 -187.726574)
		(end 109.3851 -187.726574)
		(width 0.1016)
		(layer "B.Cu")
		(net "UART_T7_NODE4_RXD")
	)
	(segment
		(start 109.58576 -183.88457)
		(end 109.12856 -184.34177)
		(width 0.1016)
		(layer "B.Cu")
		(net "UART_T7_NODE4_RXD")
	)
	(segment
		(start 114.901726 -178.559714)
		(end 121.396506 -178.559714)
		(width 0.1143)
		(layer "In7.Cu")
		(net "UART_T7_NODE4_RXD")
	)
	(segment
		(start 110.800388 -182.669688)
		(end 110.800388 -182.661052)
		(width 0.1143)
		(layer "In7.Cu")
		(net "UART_T7_NODE4_RXD")
	)
	(segment
		(start 110.800388 -182.661052)
		(end 114.901726 -178.559714)
		(width 0.1143)
		(layer "In7.Cu")
		(net "UART_T7_NODE4_RXD")
	)
	(segment
		(start 126.58598 -173.289468)
		(end 126.054358 -172.757846)
		(width 0.1143)
		(layer "In7.Cu")
		(net "UART_T7_NODE4_RXD")
	)
	(segment
		(start 126.05385 -176.912524)
		(end 126.58598 -176.380394)
		(width 0.1143)
		(layer "In7.Cu")
		(net "UART_T7_NODE4_RXD")
	)
	(segment
		(start 126.054358 -172.757846)
		(end 126.054358 -172.25899)
		(width 0.1143)
		(layer "In7.Cu")
		(net "UART_T7_NODE4_RXD")
	)
	(segment
		(start 121.396506 -178.559714)
		(end 123.043696 -176.912524)
		(width 0.1143)
		(layer "In7.Cu")
		(net "UART_T7_NODE4_RXD")
	)
	(segment
		(start 109.58576 -183.88457)
		(end 110.800388 -182.669688)
		(width 0.1143)
		(layer "In7.Cu")
		(net "UART_T7_NODE4_RXD")
	)
	(segment
		(start 123.043696 -176.912524)
		(end 126.05385 -176.912524)
		(width 0.1143)
		(layer "In7.Cu")
		(net "UART_T7_NODE4_RXD")
	)
	(segment
		(start 126.58598 -176.380394)
		(end 126.58598 -173.289468)
		(width 0.1143)
		(layer "In7.Cu")
		(net "UART_T7_NODE4_RXD")
	)
	(segment
		(start 129.775712 -172.608748)
		(end 128.533398 -172.608748)
		(width 0.1016)
		(layer "F.Cu")
		(net "UART_T7_NODE4_TXD")
	)
	(segment
		(start 128.533398 -172.608748)
		(end 128.41732 -172.49267)
		(width 0.1016)
		(layer "F.Cu")
		(net "UART_T7_NODE4_TXD")
	)
	(via
		(at 128.41732 -172.49267)
		(size 0.508)
		(drill 0.254)
		(layers "F.Cu" "B.Cu")
		(net "UART_T7_NODE4_TXD")
	)
	(segment
		(start 129.424176 -172.49267)
		(end 129.446528 -172.515022)
		(width 0.1016)
		(layer "B.Cu")
		(net "UART_T7_NODE4_TXD")
	)
	(segment
		(start 128.41732 -172.49267)
		(end 129.424176 -172.49267)
		(width 0.1016)
		(layer "B.Cu")
		(net "UART_T7_NODE4_TXD")
	)
	(segment
		(start 129.446528 -172.515022)
		(end 129.495042 -172.466508)
		(width 0.1016)
		(layer "B.Cu")
		(net "UART_T7_NODE4_TXD")
	)
	(segment
		(start 129.775712 -177.108612)
		(end 130.918966 -177.108612)
		(width 0.1016)
		(layer "F.Cu")
		(net "UART_T7_NODE1_TXD")
	)
	(via
		(at 130.918966 -177.108612)
		(size 0.508)
		(drill 0.254)
		(layers "F.Cu" "B.Cu")
		(net "UART_T7_NODE1_TXD")
	)
	(via
		(at 114.63528 -184.161176)
		(size 0.508)
		(drill 0.254)
		(layers "F.Cu" "B.Cu")
		(net "UART_T7_NODE1_TXD")
	)
	(segment
		(start 114.28476 -184.805574)
		(end 114.28476 -184.511696)
		(width 0.1016)
		(layer "B.Cu")
		(net "UART_T7_NODE1_TXD")
	)
	(segment
		(start 114.28476 -184.511696)
		(end 114.63528 -184.161176)
		(width 0.1016)
		(layer "B.Cu")
		(net "UART_T7_NODE1_TXD")
	)
	(segment
		(start 121.15546 -183.902096)
		(end 125.769116 -183.902096)
		(width 0.1143)
		(layer "In7.Cu")
		(net "UART_T7_NODE1_TXD")
	)
	(segment
		(start 130.77444 -177.851054)
		(end 130.77444 -177.253138)
		(width 0.1143)
		(layer "In7.Cu")
		(net "UART_T7_NODE1_TXD")
	)
	(segment
		(start 120.311672 -183.058308)
		(end 121.15546 -183.902096)
		(width 0.1143)
		(layer "In7.Cu")
		(net "UART_T7_NODE1_TXD")
	)
	(segment
		(start 127.6858 -180.939694)
		(end 130.77444 -177.851054)
		(width 0.1143)
		(layer "In7.Cu")
		(net "UART_T7_NODE1_TXD")
	)
	(segment
		(start 115.30584 -183.058308)
		(end 120.311672 -183.058308)
		(width 0.1143)
		(layer "In7.Cu")
		(net "UART_T7_NODE1_TXD")
	)
	(segment
		(start 114.86642 -183.497728)
		(end 115.30584 -183.058308)
		(width 0.1143)
		(layer "In7.Cu")
		(net "UART_T7_NODE1_TXD")
	)
	(segment
		(start 127.6858 -181.985412)
		(end 127.6858 -180.939694)
		(width 0.1143)
		(layer "In7.Cu")
		(net "UART_T7_NODE1_TXD")
	)
	(segment
		(start 114.63528 -184.161176)
		(end 114.63528 -183.938672)
		(width 0.1143)
		(layer "In7.Cu")
		(net "UART_T7_NODE1_TXD")
	)
	(segment
		(start 125.769116 -183.902096)
		(end 127.6858 -181.985412)
		(width 0.1143)
		(layer "In7.Cu")
		(net "UART_T7_NODE1_TXD")
	)
	(segment
		(start 130.77444 -177.253138)
		(end 130.918966 -177.108612)
		(width 0.1143)
		(layer "In7.Cu")
		(net "UART_T7_NODE1_TXD")
	)
	(segment
		(start 114.86642 -183.707532)
		(end 114.86642 -183.497728)
		(width 0.1143)
		(layer "In7.Cu")
		(net "UART_T7_NODE1_TXD")
	)
	(segment
		(start 114.63528 -183.938672)
		(end 114.86642 -183.707532)
		(width 0.1143)
		(layer "In7.Cu")
		(net "UART_T7_NODE1_TXD")
	)
	(segment
		(start 151.155146 -187.25896)
		(end 151.155146 -186.715654)
		(width 0.1016)
		(layer "F.Cu")
		(net "UART_T12_NODE1_RXD")
	)
	(segment
		(start 151.155146 -186.715654)
		(end 151.62276 -186.24804)
		(width 0.1016)
		(layer "F.Cu")
		(net "UART_T12_NODE1_RXD")
	)
	(segment
		(start 151.62276 -187.726574)
		(end 151.155146 -187.25896)
		(width 0.1016)
		(layer "F.Cu")
		(net "UART_T12_NODE1_RXD")
	)
	(segment
		(start 152.191466 -182.760874)
		(end 152.191466 -185.34888)
		(width 0.1016)
		(layer "F.Cu")
		(net "UART_T12_NODE1_RXD")
	)
	(segment
		(start 151.62276 -186.24804)
		(end 151.62276 -185.605674)
		(width 0.1016)
		(layer "F.Cu")
		(net "UART_T12_NODE1_RXD")
	)
	(segment
		(start 145.275808 -171.108624)
		(end 144.57934 -171.108624)
		(width 0.1016)
		(layer "F.Cu")
		(net "UART_T12_NODE1_RXD")
	)
	(segment
		(start 152.11552 -182.684928)
		(end 152.191466 -182.760874)
		(width 0.1016)
		(layer "F.Cu")
		(net "UART_T12_NODE1_RXD")
	)
	(segment
		(start 152.191466 -185.34888)
		(end 151.934672 -185.605674)
		(width 0.1016)
		(layer "F.Cu")
		(net "UART_T12_NODE1_RXD")
	)
	(segment
		(start 144.57934 -171.108624)
		(end 143.552672 -170.081956)
		(width 0.1016)
		(layer "F.Cu")
		(net "UART_T12_NODE1_RXD")
	)
	(segment
		(start 151.934672 -185.605674)
		(end 151.62276 -185.605674)
		(width 0.1016)
		(layer "F.Cu")
		(net "UART_T12_NODE1_RXD")
	)
	(via
		(at 143.552672 -170.081956)
		(size 0.508)
		(drill 0.254)
		(layers "F.Cu" "B.Cu")
		(net "UART_T12_NODE1_RXD")
	)
	(via
		(at 152.11552 -182.684928)
		(size 0.508)
		(drill 0.254)
		(layers "F.Cu" "B.Cu")
		(net "UART_T12_NODE1_RXD")
	)
	(segment
		(start 146.879056 -170.930824)
		(end 148.39442 -172.446188)
		(width 0.1143)
		(layer "In2.Cu")
		(net "UART_T12_NODE1_RXD")
	)
	(segment
		(start 150.7871 -181.766718)
		(end 151.70531 -182.684928)
		(width 0.1143)
		(layer "In2.Cu")
		(net "UART_T12_NODE1_RXD")
	)
	(segment
		(start 144.40154 -170.930824)
		(end 146.879056 -170.930824)
		(width 0.1143)
		(layer "In2.Cu")
		(net "UART_T12_NODE1_RXD")
	)
	(segment
		(start 150.7871 -179.827936)
		(end 150.7871 -181.766718)
		(width 0.1143)
		(layer "In2.Cu")
		(net "UART_T12_NODE1_RXD")
	)
	(segment
		(start 143.552672 -170.081956)
		(end 144.40154 -170.930824)
		(width 0.1143)
		(layer "In2.Cu")
		(net "UART_T12_NODE1_RXD")
	)
	(segment
		(start 148.39442 -174.748698)
		(end 148.25345 -174.889668)
		(width 0.1143)
		(layer "In2.Cu")
		(net "UART_T12_NODE1_RXD")
	)
	(segment
		(start 148.25345 -174.889668)
		(end 148.25345 -177.294286)
		(width 0.1143)
		(layer "In2.Cu")
		(net "UART_T12_NODE1_RXD")
	)
	(segment
		(start 148.25345 -177.294286)
		(end 150.7871 -179.827936)
		(width 0.1143)
		(layer "In2.Cu")
		(net "UART_T12_NODE1_RXD")
	)
	(segment
		(start 148.39442 -172.446188)
		(end 148.39442 -174.748698)
		(width 0.1143)
		(layer "In2.Cu")
		(net "UART_T12_NODE1_RXD")
	)
	(segment
		(start 151.70531 -182.684928)
		(end 152.11552 -182.684928)
		(width 0.1143)
		(layer "In2.Cu")
		(net "UART_T12_NODE1_RXD")
	)
	(segment
		(start 146.37766 -174.608744)
		(end 146.435826 -174.66691)
		(width 0.1016)
		(layer "F.Cu")
		(net "UART_T12_NODE4_TXD")
	)
	(segment
		(start 142.22476 -183.931052)
		(end 142.872714 -183.283098)
		(width 0.1016)
		(layer "F.Cu")
		(net "UART_T12_NODE4_TXD")
	)
	(segment
		(start 142.22476 -184.805574)
		(end 142.22476 -183.931052)
		(width 0.1016)
		(layer "F.Cu")
		(net "UART_T12_NODE4_TXD")
	)
	(segment
		(start 145.275808 -174.608744)
		(end 146.37766 -174.608744)
		(width 0.1016)
		(layer "F.Cu")
		(net "UART_T12_NODE4_TXD")
	)
	(segment
		(start 142.872714 -183.283098)
		(end 143.337026 -183.283098)
		(width 0.1016)
		(layer "F.Cu")
		(net "UART_T12_NODE4_TXD")
	)
	(via
		(at 146.435826 -174.66691)
		(size 0.508)
		(drill 0.254)
		(layers "F.Cu" "B.Cu")
		(net "UART_T12_NODE4_TXD")
	)
	(via
		(at 143.337026 -183.283098)
		(size 0.508)
		(drill 0.254)
		(layers "F.Cu" "B.Cu")
		(net "UART_T12_NODE4_TXD")
	)
	(segment
		(start 145.374106 -175.72863)
		(end 145.374106 -181.343808)
		(width 0.1143)
		(layer "In2.Cu")
		(net "UART_T12_NODE4_TXD")
	)
	(segment
		(start 146.435826 -174.66691)
		(end 145.374106 -175.72863)
		(width 0.1143)
		(layer "In2.Cu")
		(net "UART_T12_NODE4_TXD")
	)
	(segment
		(start 143.434816 -183.283098)
		(end 143.337026 -183.283098)
		(width 0.1143)
		(layer "In2.Cu")
		(net "UART_T12_NODE4_TXD")
	)
	(segment
		(start 145.374106 -181.343808)
		(end 143.434816 -183.283098)
		(width 0.1143)
		(layer "In2.Cu")
		(net "UART_T12_NODE4_TXD")
	)
	(segment
		(start 146.258788 -173.10862)
		(end 146.56054 -173.410372)
		(width 0.1016)
		(layer "F.Cu")
		(net "UART_T12_NODE3_RXD")
	)
	(segment
		(start 146.024346 -187.726574)
		(end 146.291554 -187.459366)
		(width 0.1016)
		(layer "F.Cu")
		(net "UART_T12_NODE3_RXD")
	)
	(segment
		(start 145.65376 -186.057794)
		(end 145.7325 -186.136534)
		(width 0.1016)
		(layer "F.Cu")
		(net "UART_T12_NODE3_RXD")
	)
	(segment
		(start 145.7325 -186.136534)
		(end 146.373342 -186.136534)
		(width 0.1016)
		(layer "F.Cu")
		(net "UART_T12_NODE3_RXD")
	)
	(segment
		(start 146.291554 -187.459366)
		(end 146.291554 -186.877198)
		(width 0.1016)
		(layer "F.Cu")
		(net "UART_T12_NODE3_RXD")
	)
	(segment
		(start 145.275808 -173.10862)
		(end 146.258788 -173.10862)
		(width 0.1016)
		(layer "F.Cu")
		(net "UART_T12_NODE3_RXD")
	)
	(segment
		(start 146.373342 -186.136534)
		(end 146.70278 -186.465972)
		(width 0.1016)
		(layer "F.Cu")
		(net "UART_T12_NODE3_RXD")
	)
	(segment
		(start 146.291554 -186.877198)
		(end 146.70278 -186.465972)
		(width 0.1016)
		(layer "F.Cu")
		(net "UART_T12_NODE3_RXD")
	)
	(segment
		(start 145.65376 -185.605674)
		(end 145.65376 -186.057794)
		(width 0.1016)
		(layer "F.Cu")
		(net "UART_T12_NODE3_RXD")
	)
	(segment
		(start 145.65376 -187.726574)
		(end 146.024346 -187.726574)
		(width 0.1016)
		(layer "F.Cu")
		(net "UART_T12_NODE3_RXD")
	)
	(via
		(at 146.70278 -186.465972)
		(size 0.508)
		(drill 0.254)
		(layers "F.Cu" "B.Cu")
		(net "UART_T12_NODE3_RXD")
	)
	(via
		(at 146.56054 -173.410372)
		(size 0.508)
		(drill 0.254)
		(layers "F.Cu" "B.Cu")
		(net "UART_T12_NODE3_RXD")
	)
	(segment
		(start 147.25777 -174.869094)
		(end 146.56054 -174.171864)
		(width 0.1143)
		(layer "In2.Cu")
		(net "UART_T12_NODE3_RXD")
	)
	(segment
		(start 147.25777 -178.973226)
		(end 147.25777 -174.869094)
		(width 0.1143)
		(layer "In2.Cu")
		(net "UART_T12_NODE3_RXD")
	)
	(segment
		(start 146.56054 -174.171864)
		(end 146.56054 -173.410372)
		(width 0.1143)
		(layer "In2.Cu")
		(net "UART_T12_NODE3_RXD")
	)
	(segment
		(start 146.35861 -186.164474)
		(end 146.35861 -183.745378)
		(width 0.1143)
		(layer "In2.Cu")
		(net "UART_T12_NODE3_RXD")
	)
	(segment
		(start 146.48688 -179.744116)
		(end 147.25777 -178.973226)
		(width 0.1143)
		(layer "In2.Cu")
		(net "UART_T12_NODE3_RXD")
	)
	(segment
		(start 146.35861 -183.745378)
		(end 146.48688 -183.617108)
		(width 0.1143)
		(layer "In2.Cu")
		(net "UART_T12_NODE3_RXD")
	)
	(segment
		(start 146.48688 -183.617108)
		(end 146.48688 -179.744116)
		(width 0.1143)
		(layer "In2.Cu")
		(net "UART_T12_NODE3_RXD")
	)
	(segment
		(start 146.66976 -186.465972)
		(end 146.66976 -186.475624)
		(width 0.1143)
		(layer "In2.Cu")
		(net "UART_T12_NODE3_RXD")
	)
	(segment
		(start 146.70278 -186.465972)
		(end 146.66976 -186.465972)
		(width 0.1143)
		(layer "In2.Cu")
		(net "UART_T12_NODE3_RXD")
	)
	(segment
		(start 146.66976 -186.475624)
		(end 146.35861 -186.164474)
		(width 0.1143)
		(layer "In2.Cu")
		(net "UART_T12_NODE3_RXD")
	)
	(segment
		(start 145.275808 -171.608496)
		(end 146.42719 -171.608496)
		(width 0.1016)
		(layer "F.Cu")
		(net "UART_T12_NODE2_TXD")
	)
	(segment
		(start 148.19376 -184.805574)
		(end 148.19376 -184.131458)
		(width 0.1016)
		(layer "F.Cu")
		(net "UART_T12_NODE2_TXD")
	)
	(segment
		(start 146.42719 -171.608496)
		(end 146.518884 -171.70019)
		(width 0.1016)
		(layer "F.Cu")
		(net "UART_T12_NODE2_TXD")
	)
	(via
		(at 148.19376 -184.131458)
		(size 0.508)
		(drill 0.254)
		(layers "F.Cu" "B.Cu")
		(net "UART_T12_NODE2_TXD")
	)
	(via
		(at 146.518884 -171.70019)
		(size 0.508)
		(drill 0.254)
		(layers "F.Cu" "B.Cu")
		(net "UART_T12_NODE2_TXD")
	)
	(segment
		(start 147.75307 -173.70044)
		(end 147.606004 -173.847506)
		(width 0.1143)
		(layer "In2.Cu")
		(net "UART_T12_NODE2_TXD")
	)
	(segment
		(start 146.518884 -171.70019)
		(end 147.75307 -172.934376)
		(width 0.1143)
		(layer "In2.Cu")
		(net "UART_T12_NODE2_TXD")
	)
	(segment
		(start 147.75307 -172.934376)
		(end 147.75307 -173.70044)
		(width 0.1143)
		(layer "In2.Cu")
		(net "UART_T12_NODE2_TXD")
	)
	(segment
		(start 148.19376 -183.250078)
		(end 148.19376 -184.131458)
		(width 0.1143)
		(layer "In2.Cu")
		(net "UART_T12_NODE2_TXD")
	)
	(segment
		(start 147.606004 -173.847506)
		(end 147.606004 -182.662322)
		(width 0.1143)
		(layer "In2.Cu")
		(net "UART_T12_NODE2_TXD")
	)
	(segment
		(start 147.606004 -182.662322)
		(end 148.19376 -183.250078)
		(width 0.1143)
		(layer "In2.Cu")
		(net "UART_T12_NODE2_TXD")
	)
	(segment
		(start 134.594346 -164.819584)
		(end 134.594346 -167.89908)
		(width 0.1016)
		(layer "F.Cu")
		(net "UART_T9_NODE3_RXD")
	)
	(segment
		(start 134.525766 -164.751004)
		(end 134.594346 -164.819584)
		(width 0.1016)
		(layer "F.Cu")
		(net "UART_T9_NODE3_RXD")
	)
	(segment
		(start 134.525766 -163.358576)
		(end 134.525766 -164.751004)
		(width 0.1016)
		(layer "F.Cu")
		(net "UART_T9_NODE3_RXD")
	)
	(via
		(at 134.594346 -167.89908)
		(size 0.508)
		(drill 0.254)
		(layers "F.Cu" "B.Cu")
		(net "UART_T9_NODE3_RXD")
	)
	(via
		(at 130.66268 -186.215274)
		(size 0.508)
		(drill 0.254)
		(layers "F.Cu" "B.Cu")
		(net "UART_T9_NODE3_RXD")
	)
	(segment
		(start 130.79476 -186.347354)
		(end 130.66268 -186.215274)
		(width 0.1016)
		(layer "B.Cu")
		(net "UART_T9_NODE3_RXD")
	)
	(segment
		(start 130.79476 -186.083194)
		(end 130.79476 -185.351674)
		(width 0.1016)
		(layer "B.Cu")
		(net "UART_T9_NODE3_RXD")
	)
	(segment
		(start 130.79476 -187.472574)
		(end 130.79476 -186.347354)
		(width 0.1016)
		(layer "B.Cu")
		(net "UART_T9_NODE3_RXD")
	)
	(segment
		(start 130.66268 -186.215274)
		(end 130.79476 -186.083194)
		(width 0.1016)
		(layer "B.Cu")
		(net "UART_T9_NODE3_RXD")
	)
	(segment
		(start 130.66268 -186.215274)
		(end 130.66268 -185.769758)
		(width 0.1143)
		(layer "In7.Cu")
		(net "UART_T9_NODE3_RXD")
	)
	(segment
		(start 132.18033 -184.251854)
		(end 132.18033 -183.091582)
		(width 0.1143)
		(layer "In7.Cu")
		(net "UART_T9_NODE3_RXD")
	)
	(segment
		(start 130.66268 -185.769758)
		(end 132.18033 -184.251854)
		(width 0.1143)
		(layer "In7.Cu")
		(net "UART_T9_NODE3_RXD")
	)
	(segment
		(start 132.18033 -183.091582)
		(end 133.842252 -181.42966)
		(width 0.1143)
		(layer "In7.Cu")
		(net "UART_T9_NODE3_RXD")
	)
	(segment
		(start 133.842252 -181.42966)
		(end 133.842252 -179.127658)
		(width 0.1143)
		(layer "In7.Cu")
		(net "UART_T9_NODE3_RXD")
	)
	(segment
		(start 134.594346 -168.129458)
		(end 134.594346 -167.89908)
		(width 0.1143)
		(layer "In7.Cu")
		(net "UART_T9_NODE3_RXD")
	)
	(segment
		(start 135.969756 -177.000154)
		(end 135.969756 -169.504868)
		(width 0.1143)
		(layer "In7.Cu")
		(net "UART_T9_NODE3_RXD")
	)
	(segment
		(start 135.969756 -169.504868)
		(end 134.594346 -168.129458)
		(width 0.1143)
		(layer "In7.Cu")
		(net "UART_T9_NODE3_RXD")
	)
	(segment
		(start 133.842252 -179.127658)
		(end 135.969756 -177.000154)
		(width 0.1143)
		(layer "In7.Cu")
		(net "UART_T9_NODE3_RXD")
	)
	(segment
		(start 146.32178 -175.108616)
		(end 146.533108 -175.319944)
		(width 0.1016)
		(layer "F.Cu")
		(net "UART_T12_NODE4_RXD")
	)
	(segment
		(start 143.36776 -187.726574)
		(end 143.61033 -187.726574)
		(width 0.1016)
		(layer "F.Cu")
		(net "UART_T12_NODE4_RXD")
	)
	(segment
		(start 143.36776 -185.84291)
		(end 143.966692 -186.441842)
		(width 0.1016)
		(layer "F.Cu")
		(net "UART_T12_NODE4_RXD")
	)
	(segment
		(start 143.61033 -187.726574)
		(end 143.870172 -187.466732)
		(width 0.1016)
		(layer "F.Cu")
		(net "UART_T12_NODE4_RXD")
	)
	(segment
		(start 146.533108 -175.319944)
		(end 146.81962 -175.319944)
		(width 0.1016)
		(layer "F.Cu")
		(net "UART_T12_NODE4_RXD")
	)
	(segment
		(start 143.36776 -185.605674)
		(end 143.36776 -185.84291)
		(width 0.1016)
		(layer "F.Cu")
		(net "UART_T12_NODE4_RXD")
	)
	(segment
		(start 143.870172 -187.466732)
		(end 143.870172 -186.538362)
		(width 0.1016)
		(layer "F.Cu")
		(net "UART_T12_NODE4_RXD")
	)
	(segment
		(start 145.275808 -175.108616)
		(end 146.32178 -175.108616)
		(width 0.1016)
		(layer "F.Cu")
		(net "UART_T12_NODE4_RXD")
	)
	(segment
		(start 143.870172 -186.538362)
		(end 143.966692 -186.441842)
		(width 0.1016)
		(layer "F.Cu")
		(net "UART_T12_NODE4_RXD")
	)
	(via
		(at 146.81962 -175.319944)
		(size 0.508)
		(drill 0.254)
		(layers "F.Cu" "B.Cu")
		(net "UART_T12_NODE4_RXD")
	)
	(via
		(at 143.966692 -186.441842)
		(size 0.508)
		(drill 0.254)
		(layers "F.Cu" "B.Cu")
		(net "UART_T12_NODE4_RXD")
	)
	(segment
		(start 145.20799 -185.200544)
		(end 143.966692 -186.441842)
		(width 0.1143)
		(layer "In2.Cu")
		(net "UART_T12_NODE4_RXD")
	)
	(segment
		(start 145.69186 -181.47538)
		(end 145.20799 -181.95925)
		(width 0.1143)
		(layer "In2.Cu")
		(net "UART_T12_NODE4_RXD")
	)
	(segment
		(start 145.69186 -176.447704)
		(end 145.69186 -181.47538)
		(width 0.1143)
		(layer "In2.Cu")
		(net "UART_T12_NODE4_RXD")
	)
	(segment
		(start 145.20799 -181.95925)
		(end 145.20799 -185.200544)
		(width 0.1143)
		(layer "In2.Cu")
		(net "UART_T12_NODE4_RXD")
	)
	(segment
		(start 146.81962 -175.319944)
		(end 145.69186 -176.447704)
		(width 0.1143)
		(layer "In2.Cu")
		(net "UART_T12_NODE4_RXD")
	)
	(segment
		(start 114.40414 -186.355228)
		(end 113.90376 -186.855608)
		(width 0.1016)
		(layer "F.Cu")
		(net "UART_T8_NODE4_RXD")
	)
	(segment
		(start 129.775712 -166.108634)
		(end 128.559052 -166.108634)
		(width 0.1016)
		(layer "F.Cu")
		(net "UART_T8_NODE4_RXD")
	)
	(segment
		(start 128.559052 -166.108634)
		(end 128.44526 -166.222426)
		(width 0.1016)
		(layer "F.Cu")
		(net "UART_T8_NODE4_RXD")
	)
	(segment
		(start 113.90376 -186.855608)
		(end 113.90376 -187.726574)
		(width 0.1016)
		(layer "F.Cu")
		(net "UART_T8_NODE4_RXD")
	)
	(segment
		(start 113.90376 -185.605674)
		(end 113.90376 -185.854848)
		(width 0.1016)
		(layer "F.Cu")
		(net "UART_T8_NODE4_RXD")
	)
	(segment
		(start 113.90376 -185.854848)
		(end 114.40414 -186.355228)
		(width 0.1016)
		(layer "F.Cu")
		(net "UART_T8_NODE4_RXD")
	)
	(via
		(at 114.40414 -186.355228)
		(size 0.508)
		(drill 0.254)
		(layers "F.Cu" "B.Cu")
		(net "UART_T8_NODE4_RXD")
	)
	(via
		(at 128.44526 -166.222426)
		(size 0.508)
		(drill 0.254)
		(layers "F.Cu" "B.Cu")
		(net "UART_T8_NODE4_RXD")
	)
	(segment
		(start 126.253748 -185.217562)
		(end 115.541806 -185.217562)
		(width 0.1143)
		(layer "In7.Cu")
		(net "UART_T8_NODE4_RXD")
	)
	(segment
		(start 115.541806 -185.217562)
		(end 114.40414 -186.355228)
		(width 0.1143)
		(layer "In7.Cu")
		(net "UART_T8_NODE4_RXD")
	)
	(segment
		(start 130.365246 -165.034468)
		(end 130.73888 -164.660834)
		(width 0.1143)
		(layer "In7.Cu")
		(net "UART_T8_NODE4_RXD")
	)
	(segment
		(start 128.98882 -182.48249)
		(end 126.253748 -185.217562)
		(width 0.1143)
		(layer "In7.Cu")
		(net "UART_T8_NODE4_RXD")
	)
	(segment
		(start 129.633218 -165.034468)
		(end 130.365246 -165.034468)
		(width 0.1143)
		(layer "In7.Cu")
		(net "UART_T8_NODE4_RXD")
	)
	(segment
		(start 133.208268 -177.277268)
		(end 128.98882 -181.496716)
		(width 0.1143)
		(layer "In7.Cu")
		(net "UART_T8_NODE4_RXD")
	)
	(segment
		(start 128.98882 -181.496716)
		(end 128.98882 -182.48249)
		(width 0.1143)
		(layer "In7.Cu")
		(net "UART_T8_NODE4_RXD")
	)
	(segment
		(start 132.277104 -165.833298)
		(end 132.277104 -168.735248)
		(width 0.1143)
		(layer "In7.Cu")
		(net "UART_T8_NODE4_RXD")
	)
	(segment
		(start 130.73888 -164.660834)
		(end 131.10464 -164.660834)
		(width 0.1143)
		(layer "In7.Cu")
		(net "UART_T8_NODE4_RXD")
	)
	(segment
		(start 132.277104 -168.735248)
		(end 133.208268 -169.666412)
		(width 0.1143)
		(layer "In7.Cu")
		(net "UART_T8_NODE4_RXD")
	)
	(segment
		(start 133.208268 -169.666412)
		(end 133.208268 -177.277268)
		(width 0.1143)
		(layer "In7.Cu")
		(net "UART_T8_NODE4_RXD")
	)
	(segment
		(start 128.44526 -166.222426)
		(end 129.633218 -165.034468)
		(width 0.1143)
		(layer "In7.Cu")
		(net "UART_T8_NODE4_RXD")
	)
	(segment
		(start 131.10464 -164.660834)
		(end 132.277104 -165.833298)
		(width 0.1143)
		(layer "In7.Cu")
		(net "UART_T8_NODE4_RXD")
	)
	(segment
		(start 145.84426 -182.32247)
		(end 145.84426 -182.91556)
		(width 0.1016)
		(layer "F.Cu")
		(net "UART_T12_NODE3_TXD")
	)
	(segment
		(start 145.275808 -172.608748)
		(end 146.467576 -172.608748)
		(width 0.1016)
		(layer "F.Cu")
		(net "UART_T12_NODE3_TXD")
	)
	(segment
		(start 145.84426 -182.91556)
		(end 145.05559 -183.70423)
		(width 0.1016)
		(layer "F.Cu")
		(net "UART_T12_NODE3_TXD")
	)
	(segment
		(start 145.05559 -183.70423)
		(end 145.05559 -184.260744)
		(width 0.1016)
		(layer "F.Cu")
		(net "UART_T12_NODE3_TXD")
	)
	(segment
		(start 145.05559 -184.260744)
		(end 144.51076 -184.805574)
		(width 0.1016)
		(layer "F.Cu")
		(net "UART_T12_NODE3_TXD")
	)
	(via
		(at 146.467576 -172.608748)
		(size 0.508)
		(drill 0.254)
		(layers "F.Cu" "B.Cu")
		(net "UART_T12_NODE3_TXD")
	)
	(via
		(at 145.84426 -182.32247)
		(size 0.508)
		(drill 0.254)
		(layers "F.Cu" "B.Cu")
		(net "UART_T12_NODE3_TXD")
	)
	(segment
		(start 145.84426 -182.32247)
		(end 147.55368 -180.61305)
		(width 0.1143)
		(layer "In7.Cu")
		(net "UART_T12_NODE3_TXD")
	)
	(segment
		(start 147.75307 -173.33595)
		(end 147.025868 -172.608748)
		(width 0.1143)
		(layer "In7.Cu")
		(net "UART_T12_NODE3_TXD")
	)
	(segment
		(start 147.55368 -180.61305)
		(end 147.55368 -173.89983)
		(width 0.1143)
		(layer "In7.Cu")
		(net "UART_T12_NODE3_TXD")
	)
	(segment
		(start 147.55368 -173.89983)
		(end 147.75307 -173.70044)
		(width 0.1143)
		(layer "In7.Cu")
		(net "UART_T12_NODE3_TXD")
	)
	(segment
		(start 147.75307 -173.70044)
		(end 147.75307 -173.33595)
		(width 0.1143)
		(layer "In7.Cu")
		(net "UART_T12_NODE3_TXD")
	)
	(segment
		(start 147.025868 -172.608748)
		(end 146.467576 -172.608748)
		(width 0.1143)
		(layer "In7.Cu")
		(net "UART_T12_NODE3_TXD")
	)
	(segment
		(start 129.775712 -176.108614)
		(end 130.648964 -176.108614)
		(width 0.1016)
		(layer "F.Cu")
		(net "UART_T7_NODE2_TXD")
	)
	(segment
		(start 130.648964 -176.108614)
		(end 130.918966 -175.838612)
		(width 0.1016)
		(layer "F.Cu")
		(net "UART_T7_NODE2_TXD")
	)
	(via
		(at 112.29848 -184.094374)
		(size 0.508)
		(drill 0.254)
		(layers "F.Cu" "B.Cu")
		(net "UART_T7_NODE2_TXD")
	)
	(via
		(at 130.918966 -175.838612)
		(size 0.508)
		(drill 0.254)
		(layers "F.Cu" "B.Cu")
		(net "UART_T7_NODE2_TXD")
	)
	(segment
		(start 112.29848 -184.094374)
		(end 112.29848 -184.377838)
		(width 0.1016)
		(layer "B.Cu")
		(net "UART_T7_NODE2_TXD")
	)
	(segment
		(start 112.29848 -184.377838)
		(end 111.99876 -184.677558)
		(width 0.1016)
		(layer "B.Cu")
		(net "UART_T7_NODE2_TXD")
	)
	(segment
		(start 111.99876 -184.677558)
		(end 111.99876 -184.805574)
		(width 0.1016)
		(layer "B.Cu")
		(net "UART_T7_NODE2_TXD")
	)
	(segment
		(start 130.918966 -175.838612)
		(end 130.532378 -176.2252)
		(width 0.1143)
		(layer "In7.Cu")
		(net "UART_T7_NODE2_TXD")
	)
	(segment
		(start 126.676404 -180.925978)
		(end 125.498098 -182.104538)
		(width 0.1143)
		(layer "In7.Cu")
		(net "UART_T7_NODE2_TXD")
	)
	(segment
		(start 127.14224 -180.925978)
		(end 126.676404 -180.925978)
		(width 0.1143)
		(layer "In7.Cu")
		(net "UART_T7_NODE2_TXD")
	)
	(segment
		(start 114.50066 -183.414416)
		(end 114.50066 -183.507634)
		(width 0.1143)
		(layer "In7.Cu")
		(net "UART_T7_NODE2_TXD")
	)
	(segment
		(start 114.03838 -183.969914)
		(end 114.03838 -184.27446)
		(width 0.1143)
		(layer "In7.Cu")
		(net "UART_T7_NODE2_TXD")
	)
	(segment
		(start 122.395488 -182.740808)
		(end 115.174268 -182.740808)
		(width 0.1143)
		(layer "In7.Cu")
		(net "UART_T7_NODE2_TXD")
	)
	(segment
		(start 114.50066 -183.507634)
		(end 114.03838 -183.969914)
		(width 0.1143)
		(layer "In7.Cu")
		(net "UART_T7_NODE2_TXD")
	)
	(segment
		(start 112.736376 -184.53227)
		(end 112.29848 -184.094374)
		(width 0.1143)
		(layer "In7.Cu")
		(net "UART_T7_NODE2_TXD")
	)
	(segment
		(start 115.174268 -182.740808)
		(end 114.50066 -183.414416)
		(width 0.1143)
		(layer "In7.Cu")
		(net "UART_T7_NODE2_TXD")
	)
	(segment
		(start 114.03838 -184.27446)
		(end 113.78057 -184.53227)
		(width 0.1143)
		(layer "In7.Cu")
		(net "UART_T7_NODE2_TXD")
	)
	(segment
		(start 123.031758 -182.104538)
		(end 122.395488 -182.740808)
		(width 0.1143)
		(layer "In7.Cu")
		(net "UART_T7_NODE2_TXD")
	)
	(segment
		(start 129.44221 -178.626008)
		(end 127.14224 -180.925978)
		(width 0.1143)
		(layer "In7.Cu")
		(net "UART_T7_NODE2_TXD")
	)
	(segment
		(start 125.498098 -182.104538)
		(end 123.031758 -182.104538)
		(width 0.1143)
		(layer "In7.Cu")
		(net "UART_T7_NODE2_TXD")
	)
	(segment
		(start 130.532378 -176.2252)
		(end 129.44221 -178.626008)
		(width 0.1143)
		(layer "In7.Cu")
		(net "UART_T7_NODE2_TXD")
	)
	(segment
		(start 113.78057 -184.53227)
		(end 112.736376 -184.53227)
		(width 0.1143)
		(layer "In7.Cu")
		(net "UART_T7_NODE2_TXD")
	)
	(segment
		(start 149.33676 -186.085734)
		(end 149.33676 -185.605674)
		(width 0.1016)
		(layer "F.Cu")
		(net "UART_T12_NODE2_RXD")
	)
	(segment
		(start 144.309338 -172.108622)
		(end 143.552672 -171.351956)
		(width 0.1016)
		(layer "F.Cu")
		(net "UART_T12_NODE2_RXD")
	)
	(segment
		(start 148.959316 -185.605674)
		(end 149.33676 -185.605674)
		(width 0.1016)
		(layer "F.Cu")
		(net "UART_T12_NODE2_RXD")
	)
	(segment
		(start 149.33676 -187.726574)
		(end 148.873464 -187.263278)
		(width 0.1016)
		(layer "F.Cu")
		(net "UART_T12_NODE2_RXD")
	)
	(segment
		(start 148.873464 -187.263278)
		(end 148.873464 -186.54903)
		(width 0.1016)
		(layer "F.Cu")
		(net "UART_T12_NODE2_RXD")
	)
	(segment
		(start 148.873464 -186.54903)
		(end 149.33676 -186.085734)
		(width 0.1016)
		(layer "F.Cu")
		(net "UART_T12_NODE2_RXD")
	)
	(segment
		(start 148.766022 -185.41238)
		(end 148.959316 -185.605674)
		(width 0.1016)
		(layer "F.Cu")
		(net "UART_T12_NODE2_RXD")
	)
	(segment
		(start 145.275808 -172.108622)
		(end 144.309338 -172.108622)
		(width 0.1016)
		(layer "F.Cu")
		(net "UART_T12_NODE2_RXD")
	)
	(segment
		(start 148.766022 -183.496712)
		(end 148.766022 -185.41238)
		(width 0.1016)
		(layer "F.Cu")
		(net "UART_T12_NODE2_RXD")
	)
	(via
		(at 148.766022 -183.496712)
		(size 0.508)
		(drill 0.254)
		(layers "F.Cu" "B.Cu")
		(net "UART_T12_NODE2_RXD")
	)
	(via
		(at 143.552672 -171.351956)
		(size 0.508)
		(drill 0.254)
		(layers "F.Cu" "B.Cu")
		(net "UART_T12_NODE2_RXD")
	)
	(segment
		(start 148.766022 -183.496712)
		(end 148.766022 -183.373268)
		(width 0.1143)
		(layer "In2.Cu")
		(net "UART_T12_NODE2_RXD")
	)
	(segment
		(start 147.923504 -174.769272)
		(end 148.07692 -174.615856)
		(width 0.1143)
		(layer "In2.Cu")
		(net "UART_T12_NODE2_RXD")
	)
	(segment
		(start 148.07692 -172.57776)
		(end 146.7612 -171.26204)
		(width 0.1143)
		(layer "In2.Cu")
		(net "UART_T12_NODE2_RXD")
	)
	(segment
		(start 143.642588 -171.26204)
		(end 143.552672 -171.351956)
		(width 0.1143)
		(layer "In2.Cu")
		(net "UART_T12_NODE2_RXD")
	)
	(segment
		(start 147.923504 -182.53075)
		(end 147.923504 -174.769272)
		(width 0.1143)
		(layer "In2.Cu")
		(net "UART_T12_NODE2_RXD")
	)
	(segment
		(start 146.7612 -171.26204)
		(end 143.642588 -171.26204)
		(width 0.1143)
		(layer "In2.Cu")
		(net "UART_T12_NODE2_RXD")
	)
	(segment
		(start 148.07692 -174.615856)
		(end 148.07692 -172.57776)
		(width 0.1143)
		(layer "In2.Cu")
		(net "UART_T12_NODE2_RXD")
	)
	(segment
		(start 148.766022 -183.373268)
		(end 147.923504 -182.53075)
		(width 0.1143)
		(layer "In2.Cu")
		(net "UART_T12_NODE2_RXD")
	)
	(segment
		(start 133.025642 -163.358576)
		(end 133.025642 -165.443408)
		(width 0.1016)
		(layer "F.Cu")
		(net "UART_T9_NODE2_TXD")
	)
	(segment
		(start 133.025642 -165.443408)
		(end 132.799582 -165.669468)
		(width 0.1016)
		(layer "F.Cu")
		(net "UART_T9_NODE2_TXD")
	)
	(segment
		(start 132.799582 -165.669468)
		(end 132.799582 -167.927782)
		(width 0.1016)
		(layer "F.Cu")
		(net "UART_T9_NODE2_TXD")
	)
	(segment
		(start 132.799582 -167.927782)
		(end 133.71322 -168.84142)
		(width 0.1016)
		(layer "F.Cu")
		(net "UART_T9_NODE2_TXD")
	)
	(via
		(at 133.71322 -168.84142)
		(size 0.508)
		(drill 0.254)
		(layers "F.Cu" "B.Cu")
		(net "UART_T9_NODE2_TXD")
	)
	(segment
		(start 131.93776 -184.551574)
		(end 131.93776 -184.377076)
		(width 0.1016)
		(layer "B.Cu")
		(net "UART_T9_NODE2_TXD")
	)
	(segment
		(start 133.21792 -169.33672)
		(end 133.71322 -168.84142)
		(width 0.1016)
		(layer "B.Cu")
		(net "UART_T9_NODE2_TXD")
	)
	(segment
		(start 133.21792 -177.388774)
		(end 133.21792 -169.33672)
		(width 0.1016)
		(layer "B.Cu")
		(net "UART_T9_NODE2_TXD")
	)
	(segment
		(start 132.154676 -184.16016)
		(end 132.154676 -178.452018)
		(width 0.1016)
		(layer "B.Cu")
		(net "UART_T9_NODE2_TXD")
	)
	(segment
		(start 132.154676 -178.452018)
		(end 133.21792 -177.388774)
		(width 0.1016)
		(layer "B.Cu")
		(net "UART_T9_NODE2_TXD")
	)
	(segment
		(start 131.93776 -184.377076)
		(end 132.154676 -184.16016)
		(width 0.1016)
		(layer "B.Cu")
		(net "UART_T9_NODE2_TXD")
	)
	(segment
		(start 133.525768 -163.358576)
		(end 133.525768 -166.334948)
		(width 0.1016)
		(layer "F.Cu")
		(net "UART_T9_NODE2_RXD")
	)
	(via
		(at 133.525768 -166.334948)
		(size 0.508)
		(drill 0.254)
		(layers "F.Cu" "B.Cu")
		(net "UART_T9_NODE2_RXD")
	)
	(via
		(at 132.5372 -186.097418)
		(size 0.508)
		(drill 0.254)
		(layers "F.Cu" "B.Cu")
		(net "UART_T9_NODE2_RXD")
	)
	(segment
		(start 133.08076 -186.676284)
		(end 133.08076 -187.472574)
		(width 0.1016)
		(layer "B.Cu")
		(net "UART_T9_NODE2_RXD")
	)
	(segment
		(start 132.5372 -186.097418)
		(end 132.5372 -186.132724)
		(width 0.1016)
		(layer "B.Cu")
		(net "UART_T9_NODE2_RXD")
	)
	(segment
		(start 133.08076 -185.351674)
		(end 133.08076 -185.553858)
		(width 0.1016)
		(layer "B.Cu")
		(net "UART_T9_NODE2_RXD")
	)
	(segment
		(start 133.06806 -186.676284)
		(end 133.08076 -186.676284)
		(width 0.1016)
		(layer "B.Cu")
		(net "UART_T9_NODE2_RXD")
	)
	(segment
		(start 132.80898 -186.417204)
		(end 133.06806 -186.676284)
		(width 0.1016)
		(layer "B.Cu")
		(net "UART_T9_NODE2_RXD")
	)
	(segment
		(start 132.5372 -186.132724)
		(end 132.80898 -186.404504)
		(width 0.1016)
		(layer "B.Cu")
		(net "UART_T9_NODE2_RXD")
	)
	(segment
		(start 133.08076 -185.553858)
		(end 132.5372 -186.097418)
		(width 0.1016)
		(layer "B.Cu")
		(net "UART_T9_NODE2_RXD")
	)
	(segment
		(start 132.80898 -186.404504)
		(end 132.80898 -186.417204)
		(width 0.1016)
		(layer "B.Cu")
		(net "UART_T9_NODE2_RXD")
	)
	(segment
		(start 132.5372 -186.097418)
		(end 132.5372 -184.151524)
		(width 0.1143)
		(layer "In7.Cu")
		(net "UART_T9_NODE2_RXD")
	)
	(segment
		(start 136.412732 -177.362104)
		(end 136.412732 -168.794176)
		(width 0.1143)
		(layer "In7.Cu")
		(net "UART_T9_NODE2_RXD")
	)
	(segment
		(start 134.166102 -181.556406)
		(end 134.166102 -179.608734)
		(width 0.1143)
		(layer "In7.Cu")
		(net "UART_T9_NODE2_RXD")
	)
	(segment
		(start 132.49783 -184.112154)
		(end 132.49783 -183.224678)
		(width 0.1143)
		(layer "In7.Cu")
		(net "UART_T9_NODE2_RXD")
	)
	(segment
		(start 133.959092 -166.340536)
		(end 133.531356 -166.340536)
		(width 0.1143)
		(layer "In7.Cu")
		(net "UART_T9_NODE2_RXD")
	)
	(segment
		(start 136.412732 -168.794176)
		(end 133.959092 -166.340536)
		(width 0.1143)
		(layer "In7.Cu")
		(net "UART_T9_NODE2_RXD")
	)
	(segment
		(start 132.49783 -183.224678)
		(end 134.166102 -181.556406)
		(width 0.1143)
		(layer "In7.Cu")
		(net "UART_T9_NODE2_RXD")
	)
	(segment
		(start 133.531356 -166.340536)
		(end 133.525768 -166.334948)
		(width 0.1143)
		(layer "In7.Cu")
		(net "UART_T9_NODE2_RXD")
	)
	(segment
		(start 134.166102 -179.608734)
		(end 136.412732 -177.362104)
		(width 0.1143)
		(layer "In7.Cu")
		(net "UART_T9_NODE2_RXD")
	)
	(segment
		(start 132.5372 -184.151524)
		(end 132.49783 -184.112154)
		(width 0.1143)
		(layer "In7.Cu")
		(net "UART_T9_NODE2_RXD")
	)
	(segment
		(start 125.07976 -184.805574)
		(end 126.22276 -184.805574)
		(width 0.1016)
		(layer "F.Cu")
		(net "UART_T9_NODE4_RXD")
	)
	(segment
		(start 126.681738 -184.805574)
		(end 127.06604 -185.189876)
		(width 0.1016)
		(layer "F.Cu")
		(net "UART_T9_NODE4_RXD")
	)
	(segment
		(start 126.22276 -184.805574)
		(end 126.681738 -184.805574)
		(width 0.1016)
		(layer "F.Cu")
		(net "UART_T9_NODE4_RXD")
	)
	(segment
		(start 139.525756 -163.358576)
		(end 139.525756 -164.488876)
		(width 0.1016)
		(layer "F.Cu")
		(net "UART_T9_NODE4_RXD")
	)
	(via
		(at 139.525756 -164.488876)
		(size 0.508)
		(drill 0.254)
		(layers "F.Cu" "B.Cu")
		(net "UART_T9_NODE4_RXD")
	)
	(via
		(at 127.06604 -185.189876)
		(size 0.508)
		(drill 0.254)
		(layers "F.Cu" "B.Cu")
		(net "UART_T9_NODE4_RXD")
	)
	(segment
		(start 137.225278 -176.235868)
		(end 137.225278 -177.483262)
		(width 0.1143)
		(layer "In7.Cu")
		(net "UART_T9_NODE4_RXD")
	)
	(segment
		(start 135.41248 -179.29606)
		(end 135.41248 -182.306468)
		(width 0.1143)
		(layer "In7.Cu")
		(net "UART_T9_NODE4_RXD")
	)
	(segment
		(start 129.980182 -186.360308)
		(end 128.983232 -186.360308)
		(width 0.1143)
		(layer "In7.Cu")
		(net "UART_T9_NODE4_RXD")
	)
	(segment
		(start 139.525756 -164.488876)
		(end 138.767312 -165.24732)
		(width 0.1143)
		(layer "In7.Cu")
		(net "UART_T9_NODE4_RXD")
	)
	(segment
		(start 133.706108 -186.722004)
		(end 132.444236 -186.722004)
		(width 0.1143)
		(layer "In7.Cu")
		(net "UART_T9_NODE4_RXD")
	)
	(segment
		(start 134.64921 -184.279286)
		(end 134.233666 -184.69483)
		(width 0.1143)
		(layer "In7.Cu")
		(net "UART_T9_NODE4_RXD")
	)
	(segment
		(start 132.147056 -186.424824)
		(end 131.120388 -186.424824)
		(width 0.1143)
		(layer "In7.Cu")
		(net "UART_T9_NODE4_RXD")
	)
	(segment
		(start 131.120388 -186.424824)
		(end 130.891788 -186.653424)
		(width 0.1143)
		(layer "In7.Cu")
		(net "UART_T9_NODE4_RXD")
	)
	(segment
		(start 138.767312 -165.24732)
		(end 138.767312 -166.026592)
		(width 0.1143)
		(layer "In7.Cu")
		(net "UART_T9_NODE4_RXD")
	)
	(segment
		(start 132.444236 -186.722004)
		(end 132.147056 -186.424824)
		(width 0.1143)
		(layer "In7.Cu")
		(net "UART_T9_NODE4_RXD")
	)
	(segment
		(start 137.903712 -175.557434)
		(end 137.225278 -176.235868)
		(width 0.1143)
		(layer "In7.Cu")
		(net "UART_T9_NODE4_RXD")
	)
	(segment
		(start 134.233666 -186.194446)
		(end 133.706108 -186.722004)
		(width 0.1143)
		(layer "In7.Cu")
		(net "UART_T9_NODE4_RXD")
	)
	(segment
		(start 134.64921 -183.069738)
		(end 134.64921 -184.279286)
		(width 0.1143)
		(layer "In7.Cu")
		(net "UART_T9_NODE4_RXD")
	)
	(segment
		(start 127.8128 -185.189876)
		(end 127.06604 -185.189876)
		(width 0.1143)
		(layer "In7.Cu")
		(net "UART_T9_NODE4_RXD")
	)
	(segment
		(start 135.41248 -182.306468)
		(end 134.64921 -183.069738)
		(width 0.1143)
		(layer "In7.Cu")
		(net "UART_T9_NODE4_RXD")
	)
	(segment
		(start 128.983232 -186.360308)
		(end 127.8128 -185.189876)
		(width 0.1143)
		(layer "In7.Cu")
		(net "UART_T9_NODE4_RXD")
	)
	(segment
		(start 130.273298 -186.653424)
		(end 129.980182 -186.360308)
		(width 0.1143)
		(layer "In7.Cu")
		(net "UART_T9_NODE4_RXD")
	)
	(segment
		(start 138.767312 -166.026592)
		(end 137.903712 -166.890192)
		(width 0.1143)
		(layer "In7.Cu")
		(net "UART_T9_NODE4_RXD")
	)
	(segment
		(start 137.903712 -166.890192)
		(end 137.903712 -175.557434)
		(width 0.1143)
		(layer "In7.Cu")
		(net "UART_T9_NODE4_RXD")
	)
	(segment
		(start 134.233666 -184.69483)
		(end 134.233666 -186.194446)
		(width 0.1143)
		(layer "In7.Cu")
		(net "UART_T9_NODE4_RXD")
	)
	(segment
		(start 137.225278 -177.483262)
		(end 135.41248 -179.29606)
		(width 0.1143)
		(layer "In7.Cu")
		(net "UART_T9_NODE4_RXD")
	)
	(segment
		(start 130.891788 -186.653424)
		(end 130.273298 -186.653424)
		(width 0.1143)
		(layer "In7.Cu")
		(net "UART_T9_NODE4_RXD")
	)
	(segment
		(start 146.934936 -169.108628)
		(end 147.481798 -168.561766)
		(width 0.1016)
		(layer "F.Cu")
		(net "UART_T11_NODE3_RXD")
	)
	(segment
		(start 145.275808 -169.108628)
		(end 146.934936 -169.108628)
		(width 0.1016)
		(layer "F.Cu")
		(net "UART_T11_NODE3_RXD")
	)
	(via
		(at 147.481798 -168.561766)
		(size 0.508)
		(drill 0.254)
		(layers "F.Cu" "B.Cu")
		(net "UART_T11_NODE3_RXD")
	)
	(via
		(at 145.092928 -186.06643)
		(size 0.508)
		(drill 0.254)
		(layers "F.Cu" "B.Cu")
		(net "UART_T11_NODE3_RXD")
	)
	(segment
		(start 144.51076 -185.351674)
		(end 144.51076 -185.484262)
		(width 0.1016)
		(layer "B.Cu")
		(net "UART_T11_NODE3_RXD")
	)
	(segment
		(start 144.51076 -185.484262)
		(end 145.092928 -186.06643)
		(width 0.1016)
		(layer "B.Cu")
		(net "UART_T11_NODE3_RXD")
	)
	(segment
		(start 145.092928 -187.171584)
		(end 145.092928 -186.06643)
		(width 0.1016)
		(layer "B.Cu")
		(net "UART_T11_NODE3_RXD")
	)
	(segment
		(start 144.664938 -187.599574)
		(end 145.092928 -187.171584)
		(width 0.1016)
		(layer "B.Cu")
		(net "UART_T11_NODE3_RXD")
	)
	(segment
		(start 144.51076 -187.599574)
		(end 144.664938 -187.599574)
		(width 0.1016)
		(layer "B.Cu")
		(net "UART_T11_NODE3_RXD")
	)
	(segment
		(start 149.29866 -173.085252)
		(end 149.29866 -173.557438)
		(width 0.1143)
		(layer "In7.Cu")
		(net "UART_T11_NODE3_RXD")
	)
	(segment
		(start 148.24202 -174.614078)
		(end 148.24202 -178.476402)
		(width 0.1143)
		(layer "In7.Cu")
		(net "UART_T11_NODE3_RXD")
	)
	(segment
		(start 148.34362 -172.130212)
		(end 149.29866 -173.085252)
		(width 0.1143)
		(layer "In7.Cu")
		(net "UART_T11_NODE3_RXD")
	)
	(segment
		(start 148.87702 -180.702204)
		(end 146.27352 -183.305704)
		(width 0.1143)
		(layer "In7.Cu")
		(net "UART_T11_NODE3_RXD")
	)
	(segment
		(start 148.34362 -170.267376)
		(end 148.34362 -172.130212)
		(width 0.1143)
		(layer "In7.Cu")
		(net "UART_T11_NODE3_RXD")
	)
	(segment
		(start 148.24202 -178.476402)
		(end 148.87702 -179.111402)
		(width 0.1143)
		(layer "In7.Cu")
		(net "UART_T11_NODE3_RXD")
	)
	(segment
		(start 146.27352 -184.24906)
		(end 145.092928 -185.429652)
		(width 0.1143)
		(layer "In7.Cu")
		(net "UART_T11_NODE3_RXD")
	)
	(segment
		(start 149.29866 -173.557438)
		(end 148.24202 -174.614078)
		(width 0.1143)
		(layer "In7.Cu")
		(net "UART_T11_NODE3_RXD")
	)
	(segment
		(start 145.092928 -185.429652)
		(end 145.092928 -186.06643)
		(width 0.1143)
		(layer "In7.Cu")
		(net "UART_T11_NODE3_RXD")
	)
	(segment
		(start 147.481798 -168.561766)
		(end 147.481798 -169.405554)
		(width 0.1143)
		(layer "In7.Cu")
		(net "UART_T11_NODE3_RXD")
	)
	(segment
		(start 146.27352 -183.305704)
		(end 146.27352 -184.24906)
		(width 0.1143)
		(layer "In7.Cu")
		(net "UART_T11_NODE3_RXD")
	)
	(segment
		(start 147.481798 -169.405554)
		(end 148.34362 -170.267376)
		(width 0.1143)
		(layer "In7.Cu")
		(net "UART_T11_NODE3_RXD")
	)
	(segment
		(start 148.87702 -179.111402)
		(end 148.87702 -180.702204)
		(width 0.1143)
		(layer "In7.Cu")
		(net "UART_T11_NODE3_RXD")
	)
	(segment
		(start 183.644286 -125.600714)
		(end 182.9181 -124.874528)
		(width 0.1016)
		(layer "F.Cu")
		(net "JTAG_CPLD1_TDO")
	)
	(segment
		(start 180.010562 -124.365766)
		(end 180.519324 -124.874528)
		(width 0.1016)
		(layer "F.Cu")
		(net "JTAG_CPLD1_TDO")
	)
	(segment
		(start 184.404 -128.016)
		(end 183.644286 -127.256286)
		(width 0.1016)
		(layer "F.Cu")
		(net "JTAG_CPLD1_TDO")
	)
	(segment
		(start 183.644286 -127.256286)
		(end 183.644286 -125.600714)
		(width 0.1016)
		(layer "F.Cu")
		(net "JTAG_CPLD1_TDO")
	)
	(segment
		(start 184.999884 -128.029716)
		(end 184.999884 -128.016)
		(width 0.1016)
		(layer "F.Cu")
		(net "JTAG_CPLD1_TDO")
	)
	(segment
		(start 185.731658 -128.029716)
		(end 184.999884 -128.029716)
		(width 0.1016)
		(layer "F.Cu")
		(net "JTAG_CPLD1_TDO")
	)
	(segment
		(start 184.999884 -128.016)
		(end 184.404 -128.016)
		(width 0.1016)
		(layer "F.Cu")
		(net "JTAG_CPLD1_TDO")
	)
	(segment
		(start 180.519324 -124.874528)
		(end 182.9181 -124.874528)
		(width 0.1016)
		(layer "F.Cu")
		(net "JTAG_CPLD1_TDO")
	)
	(via
		(at 182.9181 -124.874528)
		(size 0.508)
		(drill 0.254)
		(layers "F.Cu" "B.Cu")
		(net "JTAG_CPLD1_TDO")
	)
	(segment
		(start 141.294358 -12.7762)
		(end 138.37412 -9.855962)
		(width 0.1143)
		(layer "In6.Cu")
		(net "JTAG_CPLD1_TDO")
	)
	(segment
		(start 164.82822 -20.20062)
		(end 157.4038 -12.7762)
		(width 0.1143)
		(layer "In6.Cu")
		(net "JTAG_CPLD1_TDO")
	)
	(segment
		(start 166.9161 -54.332378)
		(end 166.9161 -48.925734)
		(width 0.1143)
		(layer "In6.Cu")
		(net "JTAG_CPLD1_TDO")
	)
	(segment
		(start 168.92778 -67.88658)
		(end 168.92778 -56.344058)
		(width 0.1143)
		(layer "In6.Cu")
		(net "JTAG_CPLD1_TDO")
	)
	(segment
		(start 191.032892 -89.991692)
		(end 168.92778 -67.88658)
		(width 0.1143)
		(layer "In6.Cu")
		(net "JTAG_CPLD1_TDO")
	)
	(segment
		(start 191.032892 -118.57482)
		(end 191.032892 -89.991692)
		(width 0.1143)
		(layer "In6.Cu")
		(net "JTAG_CPLD1_TDO")
	)
	(segment
		(start 168.92778 -56.344058)
		(end 166.9161 -54.332378)
		(width 0.1143)
		(layer "In6.Cu")
		(net "JTAG_CPLD1_TDO")
	)
	(segment
		(start 164.82822 -46.837854)
		(end 164.82822 -20.20062)
		(width 0.1143)
		(layer "In6.Cu")
		(net "JTAG_CPLD1_TDO")
	)
	(segment
		(start 184.733184 -124.874528)
		(end 191.032892 -118.57482)
		(width 0.1143)
		(layer "In6.Cu")
		(net "JTAG_CPLD1_TDO")
	)
	(segment
		(start 182.9181 -124.874528)
		(end 184.733184 -124.874528)
		(width 0.1143)
		(layer "In6.Cu")
		(net "JTAG_CPLD1_TDO")
	)
	(segment
		(start 157.4038 -12.7762)
		(end 141.294358 -12.7762)
		(width 0.1143)
		(layer "In6.Cu")
		(net "JTAG_CPLD1_TDO")
	)
	(segment
		(start 166.9161 -48.925734)
		(end 164.82822 -46.837854)
		(width 0.1143)
		(layer "In6.Cu")
		(net "JTAG_CPLD1_TDO")
	)
	(segment
		(start 143.88846 -168.061386)
		(end 144.435576 -168.608502)
		(width 0.1016)
		(layer "F.Cu")
		(net "UART_T11_NODE3_TXD")
	)
	(segment
		(start 143.74495 -168.061386)
		(end 143.88846 -168.061386)
		(width 0.1016)
		(layer "F.Cu")
		(net "UART_T11_NODE3_TXD")
	)
	(segment
		(start 143.2179 -167.53205)
		(end 143.2179 -167.534336)
		(width 0.1016)
		(layer "F.Cu")
		(net "UART_T11_NODE3_TXD")
	)
	(segment
		(start 143.2179 -167.534336)
		(end 143.74495 -168.061386)
		(width 0.1016)
		(layer "F.Cu")
		(net "UART_T11_NODE3_TXD")
	)
	(segment
		(start 144.435576 -168.608502)
		(end 145.275808 -168.608502)
		(width 0.1016)
		(layer "F.Cu")
		(net "UART_T11_NODE3_TXD")
	)
	(via
		(at 144.679416 -183.196992)
		(size 0.508)
		(drill 0.254)
		(layers "F.Cu" "B.Cu")
		(net "UART_T11_NODE3_TXD")
	)
	(via
		(at 143.2179 -167.53205)
		(size 0.508)
		(drill 0.254)
		(layers "F.Cu" "B.Cu")
		(net "UART_T11_NODE3_TXD")
	)
	(segment
		(start 143.36776 -184.390284)
		(end 144.561052 -183.196992)
		(width 0.1016)
		(layer "B.Cu")
		(net "UART_T11_NODE3_TXD")
	)
	(segment
		(start 144.561052 -183.196992)
		(end 144.679416 -183.196992)
		(width 0.1016)
		(layer "B.Cu")
		(net "UART_T11_NODE3_TXD")
	)
	(segment
		(start 143.36776 -184.551574)
		(end 143.36776 -184.390284)
		(width 0.1016)
		(layer "B.Cu")
		(net "UART_T11_NODE3_TXD")
	)
	(segment
		(start 145.781776 -183.196992)
		(end 147.87118 -181.107588)
		(width 0.1143)
		(layer "In7.Cu")
		(net "UART_T11_NODE3_TXD")
	)
	(segment
		(start 148.00326 -170.377358)
		(end 146.323812 -168.69791)
		(width 0.1143)
		(layer "In7.Cu")
		(net "UART_T11_NODE3_TXD")
	)
	(segment
		(start 147.87118 -181.107588)
		(end 147.87118 -174.238412)
		(width 0.1143)
		(layer "In7.Cu")
		(net "UART_T11_NODE3_TXD")
	)
	(segment
		(start 146.323812 -168.69791)
		(end 144.38376 -168.69791)
		(width 0.1143)
		(layer "In7.Cu")
		(net "UART_T11_NODE3_TXD")
	)
	(segment
		(start 144.38376 -168.69791)
		(end 143.2179 -167.53205)
		(width 0.1143)
		(layer "In7.Cu")
		(net "UART_T11_NODE3_TXD")
	)
	(segment
		(start 147.87118 -174.238412)
		(end 148.07057 -174.039022)
		(width 0.1143)
		(layer "In7.Cu")
		(net "UART_T11_NODE3_TXD")
	)
	(segment
		(start 144.679416 -183.196992)
		(end 145.781776 -183.196992)
		(width 0.1143)
		(layer "In7.Cu")
		(net "UART_T11_NODE3_TXD")
	)
	(segment
		(start 148.07057 -174.039022)
		(end 148.07057 -173.203108)
		(width 0.1143)
		(layer "In7.Cu")
		(net "UART_T11_NODE3_TXD")
	)
	(segment
		(start 148.00326 -173.135798)
		(end 148.00326 -170.377358)
		(width 0.1143)
		(layer "In7.Cu")
		(net "UART_T11_NODE3_TXD")
	)
	(segment
		(start 148.07057 -173.203108)
		(end 148.00326 -173.135798)
		(width 0.1143)
		(layer "In7.Cu")
		(net "UART_T11_NODE3_TXD")
	)
	(segment
		(start 134.525766 -174.370238)
		(end 135.45058 -173.445424)
		(width 0.1016)
		(layer "F.Cu")
		(net "UART_RX_P3")
	)
	(segment
		(start 134.261606 -47.199804)
		(end 134.261606 -48.194976)
		(width 0.1016)
		(layer "F.Cu")
		(net "UART_RX_P3")
	)
	(segment
		(start 134.525766 -178.858672)
		(end 134.525766 -174.370238)
		(width 0.1016)
		(layer "F.Cu")
		(net "UART_RX_P3")
	)
	(segment
		(start 135.45058 -173.445424)
		(end 135.45058 -172.555154)
		(width 0.1016)
		(layer "F.Cu")
		(net "UART_RX_P3")
	)
	(segment
		(start 133.763512 -48.69307)
		(end 133.424422 -48.69307)
		(width 0.1016)
		(layer "F.Cu")
		(net "UART_RX_P3")
	)
	(segment
		(start 134.261606 -48.194976)
		(end 133.763512 -48.69307)
		(width 0.1016)
		(layer "F.Cu")
		(net "UART_RX_P3")
	)
	(via
		(at 135.45058 -172.555154)
		(size 0.508)
		(drill 0.254)
		(layers "F.Cu" "B.Cu")
		(net "UART_RX_P3")
	)
	(via
		(at 133.424422 -48.69307)
		(size 0.508)
		(drill 0.254)
		(layers "F.Cu" "B.Cu")
		(net "UART_RX_P3")
	)
	(segment
		(start 148.70049 -86.36254)
		(end 136.79678 -74.45883)
		(width 0.1143)
		(layer "In2.Cu")
		(net "UART_RX_P3")
	)
	(segment
		(start 190.754 -122.682)
		(end 190.613792 -122.541792)
		(width 0.1143)
		(layer "In2.Cu")
		(net "UART_RX_P3")
	)
	(segment
		(start 141.451584 -166.684706)
		(end 142.90294 -165.23335)
		(width 0.1143)
		(layer "In2.Cu")
		(net "UART_RX_P3")
	)
	(segment
		(start 133.278372 -49.58334)
		(end 133.278372 -48.83912)
		(width 0.1143)
		(layer "In2.Cu")
		(net "UART_RX_P3")
	)
	(segment
		(start 190.754 -127.889)
		(end 190.754 -122.682)
		(width 0.1143)
		(layer "In2.Cu")
		(net "UART_RX_P3")
	)
	(segment
		(start 155.921456 -163.410138)
		(end 156.284676 -163.410138)
		(width 0.1143)
		(layer "In2.Cu")
		(net "UART_RX_P3")
	)
	(segment
		(start 162.064446 -86.36254)
		(end 148.70049 -86.36254)
		(width 0.1143)
		(layer "In2.Cu")
		(net "UART_RX_P3")
	)
	(segment
		(start 190.613792 -128.016)
		(end 190.627 -128.016)
		(width 0.1143)
		(layer "In2.Cu")
		(net "UART_RX_P3")
	)
	(segment
		(start 146.1516 -164.535358)
		(end 148.932392 -164.535358)
		(width 0.1143)
		(layer "In2.Cu")
		(net "UART_RX_P3")
	)
	(segment
		(start 162.54222 -85.884766)
		(end 162.064446 -86.36254)
		(width 0.1143)
		(layer "In2.Cu")
		(net "UART_RX_P3")
	)
	(segment
		(start 139.323064 -168.073832)
		(end 140.71219 -166.684706)
		(width 0.1143)
		(layer "In2.Cu")
		(net "UART_RX_P3")
	)
	(segment
		(start 135.8138 -172.191934)
		(end 135.8138 -169.736516)
		(width 0.1143)
		(layer "In2.Cu")
		(net "UART_RX_P3")
	)
	(segment
		(start 136.79678 -74.45883)
		(end 136.79678 -72.426576)
		(width 0.1143)
		(layer "In2.Cu")
		(net "UART_RX_P3")
	)
	(segment
		(start 169.191178 -163.873942)
		(end 171.01185 -162.05327)
		(width 0.1143)
		(layer "In2.Cu")
		(net "UART_RX_P3")
	)
	(segment
		(start 171.01185 -162.05327)
		(end 174.553626 -162.05327)
		(width 0.1143)
		(layer "In2.Cu")
		(net "UART_RX_P3")
	)
	(segment
		(start 145.453608 -165.23335)
		(end 146.1516 -164.535358)
		(width 0.1143)
		(layer "In2.Cu")
		(net "UART_RX_P3")
	)
	(segment
		(start 190.613792 -145.993104)
		(end 190.613792 -128.016)
		(width 0.1143)
		(layer "In2.Cu")
		(net "UART_RX_P3")
	)
	(segment
		(start 135.8138 -169.736516)
		(end 137.476484 -168.073832)
		(width 0.1143)
		(layer "In2.Cu")
		(net "UART_RX_P3")
	)
	(segment
		(start 149.58314 -163.88461)
		(end 155.446984 -163.88461)
		(width 0.1143)
		(layer "In2.Cu")
		(net "UART_RX_P3")
	)
	(segment
		(start 156.74848 -163.873942)
		(end 169.191178 -163.873942)
		(width 0.1143)
		(layer "In2.Cu")
		(net "UART_RX_P3")
	)
	(segment
		(start 178.572668 -86.504526)
		(end 163.68014 -86.504526)
		(width 0.1143)
		(layer "In2.Cu")
		(net "UART_RX_P3")
	)
	(segment
		(start 190.627 -128.016)
		(end 190.754 -127.889)
		(width 0.1143)
		(layer "In2.Cu")
		(net "UART_RX_P3")
	)
	(segment
		(start 133.278372 -48.83912)
		(end 133.424422 -48.69307)
		(width 0.1143)
		(layer "In2.Cu")
		(net "UART_RX_P3")
	)
	(segment
		(start 156.284676 -163.410138)
		(end 156.74848 -163.873942)
		(width 0.1143)
		(layer "In2.Cu")
		(net "UART_RX_P3")
	)
	(segment
		(start 148.932392 -164.535358)
		(end 149.58314 -163.88461)
		(width 0.1143)
		(layer "In2.Cu")
		(net "UART_RX_P3")
	)
	(segment
		(start 163.06038 -85.884766)
		(end 162.54222 -85.884766)
		(width 0.1143)
		(layer "In2.Cu")
		(net "UART_RX_P3")
	)
	(segment
		(start 132.5118 -68.141596)
		(end 132.5118 -53.309012)
		(width 0.1143)
		(layer "In2.Cu")
		(net "UART_RX_P3")
	)
	(segment
		(start 133.48335 -49.788318)
		(end 133.278372 -49.58334)
		(width 0.1143)
		(layer "In2.Cu")
		(net "UART_RX_P3")
	)
	(segment
		(start 137.476484 -168.073832)
		(end 139.323064 -168.073832)
		(width 0.1143)
		(layer "In2.Cu")
		(net "UART_RX_P3")
	)
	(segment
		(start 190.613792 -98.54565)
		(end 178.572668 -86.504526)
		(width 0.1143)
		(layer "In2.Cu")
		(net "UART_RX_P3")
	)
	(segment
		(start 155.446984 -163.88461)
		(end 155.921456 -163.410138)
		(width 0.1143)
		(layer "In2.Cu")
		(net "UART_RX_P3")
	)
	(segment
		(start 142.90294 -165.23335)
		(end 145.453608 -165.23335)
		(width 0.1143)
		(layer "In2.Cu")
		(net "UART_RX_P3")
	)
	(segment
		(start 135.45058 -172.555154)
		(end 135.8138 -172.191934)
		(width 0.1143)
		(layer "In2.Cu")
		(net "UART_RX_P3")
	)
	(segment
		(start 174.553626 -162.05327)
		(end 190.613792 -145.993104)
		(width 0.1143)
		(layer "In2.Cu")
		(net "UART_RX_P3")
	)
	(segment
		(start 132.5118 -53.309012)
		(end 133.48335 -52.337462)
		(width 0.1143)
		(layer "In2.Cu")
		(net "UART_RX_P3")
	)
	(segment
		(start 163.68014 -86.504526)
		(end 163.06038 -85.884766)
		(width 0.1143)
		(layer "In2.Cu")
		(net "UART_RX_P3")
	)
	(segment
		(start 190.613792 -122.541792)
		(end 190.613792 -98.54565)
		(width 0.1143)
		(layer "In2.Cu")
		(net "UART_RX_P3")
	)
	(segment
		(start 133.48335 -52.337462)
		(end 133.48335 -49.788318)
		(width 0.1143)
		(layer "In2.Cu")
		(net "UART_RX_P3")
	)
	(segment
		(start 136.79678 -72.426576)
		(end 132.5118 -68.141596)
		(width 0.1143)
		(layer "In2.Cu")
		(net "UART_RX_P3")
	)
	(segment
		(start 140.71219 -166.684706)
		(end 141.451584 -166.684706)
		(width 0.1143)
		(layer "In2.Cu")
		(net "UART_RX_P3")
	)
	(segment
		(start 149.289262 -27.550618)
		(end 144.77492 -32.06496)
		(width 0.1143)
		(layer "In7.Cu")
		(net "UART_RX_P3")
	)
	(segment
		(start 154.01798 -21.927312)
		(end 154.01798 -24.461724)
		(width 0.1143)
		(layer "In7.Cu")
		(net "UART_RX_P3")
	)
	(segment
		(start 134.351522 -47.76597)
		(end 133.424422 -48.69307)
		(width 0.1143)
		(layer "In7.Cu")
		(net "UART_RX_P3")
	)
	(segment
		(start 144.77492 -45.905674)
		(end 142.914624 -47.76597)
		(width 0.1143)
		(layer "In7.Cu")
		(net "UART_RX_P3")
	)
	(segment
		(start 156.376878 -19.568414)
		(end 154.01798 -21.927312)
		(width 0.1143)
		(layer "In7.Cu")
		(net "UART_RX_P3")
	)
	(segment
		(start 154.01798 -24.461724)
		(end 150.929086 -27.550618)
		(width 0.1143)
		(layer "In7.Cu")
		(net "UART_RX_P3")
	)
	(segment
		(start 144.77492 -32.06496)
		(end 144.77492 -45.905674)
		(width 0.1143)
		(layer "In7.Cu")
		(net "UART_RX_P3")
	)
	(segment
		(start 142.914624 -47.76597)
		(end 134.351522 -47.76597)
		(width 0.1143)
		(layer "In7.Cu")
		(net "UART_RX_P3")
	)
	(segment
		(start 150.929086 -27.550618)
		(end 149.289262 -27.550618)
		(width 0.1143)
		(layer "In7.Cu")
		(net "UART_RX_P3")
	)
	(segment
		(start 187.81395 -125.095)
		(end 187.15609 -124.43714)
		(width 0.1016)
		(layer "F.Cu")
		(net "JTAG_CPLD1_TCK")
	)
	(segment
		(start 179.010564 -123.365768)
		(end 178.950112 -123.365768)
		(width 0.1016)
		(layer "F.Cu")
		(net "JTAG_CPLD1_TCK")
	)
	(segment
		(start 186.591702 -123.860306)
		(end 186.135518 -124.31649)
		(width 0.1016)
		(layer "F.Cu")
		(net "JTAG_CPLD1_TCK")
	)
	(segment
		(start 187.15609 -123.860306)
		(end 186.591702 -123.860306)
		(width 0.1016)
		(layer "F.Cu")
		(net "JTAG_CPLD1_TCK")
	)
	(segment
		(start 187.15609 -124.43714)
		(end 187.15609 -123.860306)
		(width 0.1016)
		(layer "F.Cu")
		(net "JTAG_CPLD1_TCK")
	)
	(segment
		(start 178.950112 -123.365768)
		(end 178.45659 -122.872246)
		(width 0.1016)
		(layer "F.Cu")
		(net "JTAG_CPLD1_TCK")
	)
	(via
		(at 178.45659 -122.872246)
		(size 0.49022)
		(drill 0.254)
		(layers "F.Cu" "B.Cu")
		(net "JTAG_CPLD1_TCK")
	)
	(via
		(at 186.135518 -124.31649)
		(size 0.508)
		(drill 0.254)
		(layers "F.Cu" "B.Cu")
		(net "JTAG_CPLD1_TCK")
	)
	(segment
		(start 179.900834 -124.31649)
		(end 178.45659 -122.872246)
		(width 0.1143)
		(layer "In2.Cu")
		(net "JTAG_CPLD1_TCK")
	)
	(segment
		(start 186.135518 -124.31649)
		(end 179.900834 -124.31649)
		(width 0.1143)
		(layer "In2.Cu")
		(net "JTAG_CPLD1_TCK")
	)
	(segment
		(start 193.095626 -117.99824)
		(end 193.095626 -91.419426)
		(width 0.1143)
		(layer "In6.Cu")
		(net "JTAG_CPLD1_TCK")
	)
	(segment
		(start 169.34688 -55.743856)
		(end 168.3385 -54.735476)
		(width 0.1143)
		(layer "In6.Cu")
		(net "JTAG_CPLD1_TCK")
	)
	(segment
		(start 157.5816 -12.3444)
		(end 143.402558 -12.3444)
		(width 0.1143)
		(layer "In6.Cu")
		(net "JTAG_CPLD1_TCK")
	)
	(segment
		(start 186.135518 -124.31649)
		(end 188.354208 -122.0978)
		(width 0.1143)
		(layer "In6.Cu")
		(net "JTAG_CPLD1_TCK")
	)
	(segment
		(start 169.34688 -67.67068)
		(end 169.34688 -55.743856)
		(width 0.1143)
		(layer "In6.Cu")
		(net "JTAG_CPLD1_TCK")
	)
	(segment
		(start 168.3385 -51.26736)
		(end 167.38854 -50.3174)
		(width 0.1143)
		(layer "In6.Cu")
		(net "JTAG_CPLD1_TCK")
	)
	(segment
		(start 168.3385 -54.735476)
		(end 168.3385 -51.26736)
		(width 0.1143)
		(layer "In6.Cu")
		(net "JTAG_CPLD1_TCK")
	)
	(segment
		(start 165.32098 -46.660816)
		(end 165.32098 -20.08378)
		(width 0.1143)
		(layer "In6.Cu")
		(net "JTAG_CPLD1_TCK")
	)
	(segment
		(start 143.402558 -12.3444)
		(end 140.91412 -9.855962)
		(width 0.1143)
		(layer "In6.Cu")
		(net "JTAG_CPLD1_TCK")
	)
	(segment
		(start 165.32098 -20.08378)
		(end 157.5816 -12.3444)
		(width 0.1143)
		(layer "In6.Cu")
		(net "JTAG_CPLD1_TCK")
	)
	(segment
		(start 188.996066 -122.0978)
		(end 193.095626 -117.99824)
		(width 0.1143)
		(layer "In6.Cu")
		(net "JTAG_CPLD1_TCK")
	)
	(segment
		(start 167.38854 -50.3174)
		(end 167.38854 -48.728376)
		(width 0.1143)
		(layer "In6.Cu")
		(net "JTAG_CPLD1_TCK")
	)
	(segment
		(start 193.095626 -91.419426)
		(end 169.34688 -67.67068)
		(width 0.1143)
		(layer "In6.Cu")
		(net "JTAG_CPLD1_TCK")
	)
	(segment
		(start 188.354208 -122.0978)
		(end 188.996066 -122.0978)
		(width 0.1143)
		(layer "In6.Cu")
		(net "JTAG_CPLD1_TCK")
	)
	(segment
		(start 167.38854 -48.728376)
		(end 165.32098 -46.660816)
		(width 0.1143)
		(layer "In6.Cu")
		(net "JTAG_CPLD1_TCK")
	)
	(segment
		(start 115.852448 -185.605674)
		(end 116.18976 -185.605674)
		(width 0.1016)
		(layer "F.Cu")
		(net "UART_T8_NODE3_RXD")
	)
	(segment
		(start 128.84404 -169.108628)
		(end 128.401572 -168.66616)
		(width 0.1016)
		(layer "F.Cu")
		(net "UART_T8_NODE3_RXD")
	)
	(segment
		(start 116.09324 -183.581294)
		(end 115.63096 -184.043574)
		(width 0.1016)
		(layer "F.Cu")
		(net "UART_T8_NODE3_RXD")
	)
	(segment
		(start 116.18976 -185.605674)
		(end 116.18976 -187.726574)
		(width 0.1016)
		(layer "F.Cu")
		(net "UART_T8_NODE3_RXD")
	)
	(segment
		(start 126.617984 -168.66616)
		(end 126.31928 -168.964864)
		(width 0.1016)
		(layer "F.Cu")
		(net "UART_T8_NODE3_RXD")
	)
	(segment
		(start 129.775712 -169.108628)
		(end 128.84404 -169.108628)
		(width 0.1016)
		(layer "F.Cu")
		(net "UART_T8_NODE3_RXD")
	)
	(segment
		(start 128.401572 -168.66616)
		(end 126.617984 -168.66616)
		(width 0.1016)
		(layer "F.Cu")
		(net "UART_T8_NODE3_RXD")
	)
	(segment
		(start 115.63096 -185.384186)
		(end 115.852448 -185.605674)
		(width 0.1016)
		(layer "F.Cu")
		(net "UART_T8_NODE3_RXD")
	)
	(segment
		(start 116.09324 -183.496458)
		(end 116.09324 -183.581294)
		(width 0.1016)
		(layer "F.Cu")
		(net "UART_T8_NODE3_RXD")
	)
	(segment
		(start 115.63096 -184.043574)
		(end 115.63096 -185.384186)
		(width 0.1016)
		(layer "F.Cu")
		(net "UART_T8_NODE3_RXD")
	)
	(via
		(at 126.31928 -168.964864)
		(size 0.508)
		(drill 0.254)
		(layers "F.Cu" "B.Cu")
		(net "UART_T8_NODE3_RXD")
	)
	(via
		(at 116.09324 -183.496458)
		(size 0.508)
		(drill 0.254)
		(layers "F.Cu" "B.Cu")
		(net "UART_T8_NODE3_RXD")
	)
	(segment
		(start 124.323094 -170.381422)
		(end 124.5489 -170.155616)
		(width 0.1016)
		(layer "B.Cu")
		(net "UART_T8_NODE3_RXD")
	)
	(segment
		(start 115.63604 -180.601874)
		(end 115.63604 -173.24705)
		(width 0.1016)
		(layer "B.Cu")
		(net "UART_T8_NODE3_RXD")
	)
	(segment
		(start 116.12118 -181.087014)
		(end 115.63604 -180.601874)
		(width 0.1016)
		(layer "B.Cu")
		(net "UART_T8_NODE3_RXD")
	)
	(segment
		(start 118.555516 -171.964858)
		(end 119.12219 -171.398184)
		(width 0.1016)
		(layer "B.Cu")
		(net "UART_T8_NODE3_RXD")
	)
	(segment
		(start 124.5489 -170.155616)
		(end 125.128528 -170.155616)
		(width 0.1016)
		(layer "B.Cu")
		(net "UART_T8_NODE3_RXD")
	)
	(segment
		(start 120.26646 -171.398184)
		(end 121.283222 -170.381422)
		(width 0.1016)
		(layer "B.Cu")
		(net "UART_T8_NODE3_RXD")
	)
	(segment
		(start 116.918232 -171.964858)
		(end 118.555516 -171.964858)
		(width 0.1016)
		(layer "B.Cu")
		(net "UART_T8_NODE3_RXD")
	)
	(segment
		(start 119.12219 -171.398184)
		(end 120.26646 -171.398184)
		(width 0.1016)
		(layer "B.Cu")
		(net "UART_T8_NODE3_RXD")
	)
	(segment
		(start 116.09324 -183.496458)
		(end 116.12118 -183.468518)
		(width 0.1016)
		(layer "B.Cu")
		(net "UART_T8_NODE3_RXD")
	)
	(segment
		(start 116.12118 -183.468518)
		(end 116.12118 -181.087014)
		(width 0.1016)
		(layer "B.Cu")
		(net "UART_T8_NODE3_RXD")
	)
	(segment
		(start 121.283222 -170.381422)
		(end 124.323094 -170.381422)
		(width 0.1016)
		(layer "B.Cu")
		(net "UART_T8_NODE3_RXD")
	)
	(segment
		(start 125.128528 -170.155616)
		(end 126.31928 -168.964864)
		(width 0.1016)
		(layer "B.Cu")
		(net "UART_T8_NODE3_RXD")
	)
	(segment
		(start 115.63604 -173.24705)
		(end 116.918232 -171.964858)
		(width 0.1016)
		(layer "B.Cu")
		(net "UART_T8_NODE3_RXD")
	)
	(segment
		(start 185.78195 -125.984)
		(end 185.78195 -125.66015)
		(width 0.1016)
		(layer "F.Cu")
		(net "JTAG_CPLD1_TMS")
	)
	(segment
		(start 186.146186 -122.844814)
		(end 185.32856 -123.66244)
		(width 0.1016)
		(layer "F.Cu")
		(net "JTAG_CPLD1_TMS")
	)
	(segment
		(start 185.78195 -125.66015)
		(end 185.5724 -125.4506)
		(width 0.1016)
		(layer "F.Cu")
		(net "JTAG_CPLD1_TMS")
	)
	(segment
		(start 187.186316 -122.844814)
		(end 186.146186 -122.844814)
		(width 0.1016)
		(layer "F.Cu")
		(net "JTAG_CPLD1_TMS")
	)
	(segment
		(start 185.5724 -125.4506)
		(end 185.5724 -123.903232)
		(width 0.1016)
		(layer "F.Cu")
		(net "JTAG_CPLD1_TMS")
	)
	(segment
		(start 184.622186 -124.365766)
		(end 185.32856 -123.659392)
		(width 0.1016)
		(layer "F.Cu")
		(net "JTAG_CPLD1_TMS")
	)
	(segment
		(start 181.01056 -124.365766)
		(end 184.622186 -124.365766)
		(width 0.1016)
		(layer "F.Cu")
		(net "JTAG_CPLD1_TMS")
	)
	(segment
		(start 185.5724 -123.903232)
		(end 185.32856 -123.659392)
		(width 0.1016)
		(layer "F.Cu")
		(net "JTAG_CPLD1_TMS")
	)
	(segment
		(start 185.32856 -123.66244)
		(end 185.32856 -123.659392)
		(width 0.1016)
		(layer "F.Cu")
		(net "JTAG_CPLD1_TMS")
	)
	(via
		(at 185.32856 -123.659392)
		(size 0.508)
		(drill 0.254)
		(layers "F.Cu" "B.Cu")
		(net "JTAG_CPLD1_TMS")
	)
	(segment
		(start 190.613792 -118.37416)
		(end 190.613792 -90.182192)
		(width 0.1143)
		(layer "In6.Cu")
		(net "JTAG_CPLD1_TMS")
	)
	(segment
		(start 157.2006 -13.208)
		(end 139.186158 -13.208)
		(width 0.1143)
		(layer "In6.Cu")
		(net "JTAG_CPLD1_TMS")
	)
	(segment
		(start 164.38118 -20.38858)
		(end 157.2006 -13.208)
		(width 0.1143)
		(layer "In6.Cu")
		(net "JTAG_CPLD1_TMS")
	)
	(segment
		(start 164.38118 -47.063152)
		(end 164.38118 -20.38858)
		(width 0.1143)
		(layer "In6.Cu")
		(net "JTAG_CPLD1_TMS")
	)
	(segment
		(start 185.32856 -123.659392)
		(end 190.613792 -118.37416)
		(width 0.1143)
		(layer "In6.Cu")
		(net "JTAG_CPLD1_TMS")
	)
	(segment
		(start 139.186158 -13.208)
		(end 135.83412 -9.855962)
		(width 0.1143)
		(layer "In6.Cu")
		(net "JTAG_CPLD1_TMS")
	)
	(segment
		(start 168.50868 -68.07708)
		(end 168.50868 -56.52135)
		(width 0.1143)
		(layer "In6.Cu")
		(net "JTAG_CPLD1_TMS")
	)
	(segment
		(start 168.50868 -56.52135)
		(end 166.39286 -54.40553)
		(width 0.1143)
		(layer "In6.Cu")
		(net "JTAG_CPLD1_TMS")
	)
	(segment
		(start 166.39286 -49.074832)
		(end 164.38118 -47.063152)
		(width 0.1143)
		(layer "In6.Cu")
		(net "JTAG_CPLD1_TMS")
	)
	(segment
		(start 166.39286 -54.40553)
		(end 166.39286 -49.074832)
		(width 0.1143)
		(layer "In6.Cu")
		(net "JTAG_CPLD1_TMS")
	)
	(segment
		(start 190.613792 -90.182192)
		(end 168.50868 -68.07708)
		(width 0.1143)
		(layer "In6.Cu")
		(net "JTAG_CPLD1_TMS")
	)
	(segment
		(start 128.841754 -169.6085)
		(end 128.34874 -169.115486)
		(width 0.1016)
		(layer "F.Cu")
		(net "UART_T8_NODE3_TXD")
	)
	(segment
		(start 129.775712 -169.6085)
		(end 128.841754 -169.6085)
		(width 0.1016)
		(layer "F.Cu")
		(net "UART_T8_NODE3_TXD")
	)
	(segment
		(start 128.34874 -169.115486)
		(end 128.077214 -169.115486)
		(width 0.1016)
		(layer "F.Cu")
		(net "UART_T8_NODE3_TXD")
	)
	(via
		(at 128.077214 -169.115486)
		(size 0.508)
		(drill 0.254)
		(layers "F.Cu" "B.Cu")
		(net "UART_T8_NODE3_TXD")
	)
	(segment
		(start 129.178812 -169.264838)
		(end 128.226566 -169.264838)
		(width 0.1016)
		(layer "B.Cu")
		(net "UART_T8_NODE3_TXD")
	)
	(segment
		(start 128.226566 -169.264838)
		(end 128.077214 -169.115486)
		(width 0.1016)
		(layer "B.Cu")
		(net "UART_T8_NODE3_TXD")
	)
	(segment
		(start 180.010562 -123.365768)
		(end 180.557424 -123.91263)
		(width 0.1016)
		(layer "F.Cu")
		(net "JTAG_CPLD1_TDI")
	)
	(segment
		(start 187.191904 -121.65965)
		(end 186.319922 -121.65965)
		(width 0.1016)
		(layer "F.Cu")
		(net "JTAG_CPLD1_TDI")
	)
	(segment
		(start 186.319922 -121.65965)
		(end 184.33542 -123.644152)
		(width 0.1016)
		(layer "F.Cu")
		(net "JTAG_CPLD1_TDI")
	)
	(segment
		(start 180.557424 -123.91263)
		(end 184.066942 -123.91263)
		(width 0.1016)
		(layer "F.Cu")
		(net "JTAG_CPLD1_TDI")
	)
	(segment
		(start 184.066942 -123.91263)
		(end 184.33542 -123.644152)
		(width 0.1016)
		(layer "F.Cu")
		(net "JTAG_CPLD1_TDI")
	)
	(segment
		(start 187.17895 -120.65)
		(end 187.17895 -121.646696)
		(width 0.1016)
		(layer "F.Cu")
		(net "JTAG_CPLD1_TDI")
	)
	(segment
		(start 187.17895 -121.646696)
		(end 187.191904 -121.65965)
		(width 0.1016)
		(layer "F.Cu")
		(net "JTAG_CPLD1_TDI")
	)
	(via
		(at 184.33542 -123.644152)
		(size 0.508)
		(drill 0.254)
		(layers "F.Cu" "B.Cu")
		(net "JTAG_CPLD1_TDI")
	)
	(segment
		(start 165.87216 -66.05016)
		(end 165.87216 -49.173638)
		(width 0.1143)
		(layer "In6.Cu")
		(net "JTAG_CPLD1_TDI")
	)
	(segment
		(start 163.90874 -47.210218)
		(end 163.90874 -20.52574)
		(width 0.1143)
		(layer "In6.Cu")
		(net "JTAG_CPLD1_TDI")
	)
	(segment
		(start 184.33542 -123.644152)
		(end 184.524142 -123.644152)
		(width 0.1143)
		(layer "In6.Cu")
		(net "JTAG_CPLD1_TDI")
	)
	(segment
		(start 189.249304 -118.91899)
		(end 189.249304 -89.427304)
		(width 0.1143)
		(layer "In6.Cu")
		(net "JTAG_CPLD1_TDI")
	)
	(segment
		(start 165.87216 -49.173638)
		(end 163.90874 -47.210218)
		(width 0.1143)
		(layer "In6.Cu")
		(net "JTAG_CPLD1_TDI")
	)
	(segment
		(start 163.90874 -20.52574)
		(end 157.099 -13.716)
		(width 0.1143)
		(layer "In6.Cu")
		(net "JTAG_CPLD1_TDI")
	)
	(segment
		(start 189.249304 -89.427304)
		(end 165.87216 -66.05016)
		(width 0.1143)
		(layer "In6.Cu")
		(net "JTAG_CPLD1_TDI")
	)
	(segment
		(start 184.524142 -123.644152)
		(end 189.249304 -118.91899)
		(width 0.1143)
		(layer "In6.Cu")
		(net "JTAG_CPLD1_TDI")
	)
	(segment
		(start 157.099 -13.716)
		(end 134.614158 -13.716)
		(width 0.1143)
		(layer "In6.Cu")
		(net "JTAG_CPLD1_TDI")
	)
	(segment
		(start 134.614158 -13.716)
		(end 130.75412 -9.855962)
		(width 0.1143)
		(layer "In6.Cu")
		(net "JTAG_CPLD1_TDI")
	)
	(segment
		(start 129.45618 -184.780682)
		(end 129.45618 -183.970168)
		(width 0.1016)
		(layer "F.Cu")
		(net "UART_T9_NODE3_TXD")
	)
	(segment
		(start 134.02564 -163.358576)
		(end 134.02564 -168.31691)
		(width 0.1016)
		(layer "F.Cu")
		(net "UART_T9_NODE3_TXD")
	)
	(segment
		(start 134.02564 -168.31691)
		(end 134.49935 -168.79062)
		(width 0.1016)
		(layer "F.Cu")
		(net "UART_T9_NODE3_TXD")
	)
	(segment
		(start 129.45618 -183.970168)
		(end 129.50317 -183.923178)
		(width 0.1016)
		(layer "F.Cu")
		(net "UART_T9_NODE3_TXD")
	)
	(segment
		(start 134.49935 -168.79062)
		(end 134.49935 -170.014646)
		(width 0.1016)
		(layer "F.Cu")
		(net "UART_T9_NODE3_TXD")
	)
	(via
		(at 129.50317 -183.923178)
		(size 0.508)
		(drill 0.254)
		(layers "F.Cu" "B.Cu")
		(net "UART_T9_NODE3_TXD")
	)
	(via
		(at 134.49935 -170.014646)
		(size 0.508)
		(drill 0.254)
		(layers "F.Cu" "B.Cu")
		(net "UART_T9_NODE3_TXD")
	)
	(segment
		(start 130.966464 -184.36463)
		(end 131.223512 -184.107582)
		(width 0.1143)
		(layer "In7.Cu")
		(net "UART_T9_NODE3_TXD")
	)
	(segment
		(start 129.50317 -183.923178)
		(end 129.944622 -184.36463)
		(width 0.1143)
		(layer "In7.Cu")
		(net "UART_T9_NODE3_TXD")
	)
	(segment
		(start 133.453632 -181.097682)
		(end 133.453632 -179.002436)
		(width 0.1143)
		(layer "In7.Cu")
		(net "UART_T9_NODE3_TXD")
	)
	(segment
		(start 134.49935 -177.956718)
		(end 134.49935 -170.014646)
		(width 0.1143)
		(layer "In7.Cu")
		(net "UART_T9_NODE3_TXD")
	)
	(segment
		(start 131.223512 -183.327802)
		(end 133.453632 -181.097682)
		(width 0.1143)
		(layer "In7.Cu")
		(net "UART_T9_NODE3_TXD")
	)
	(segment
		(start 133.453632 -179.002436)
		(end 134.49935 -177.956718)
		(width 0.1143)
		(layer "In7.Cu")
		(net "UART_T9_NODE3_TXD")
	)
	(segment
		(start 129.944622 -184.36463)
		(end 130.966464 -184.36463)
		(width 0.1143)
		(layer "In7.Cu")
		(net "UART_T9_NODE3_TXD")
	)
	(segment
		(start 131.223512 -184.107582)
		(end 131.223512 -183.327802)
		(width 0.1143)
		(layer "In7.Cu")
		(net "UART_T9_NODE3_TXD")
	)
	(segment
		(start 146.613118 -165.608508)
		(end 145.275808 -165.608508)
		(width 0.1016)
		(layer "F.Cu")
		(net "UART_T11_NODE1_RXD")
	)
	(via
		(at 152.5651 -179.79009)
		(size 0.508)
		(drill 0.254)
		(layers "F.Cu" "B.Cu")
		(net "UART_T11_NODE1_RXD")
	)
	(via
		(at 146.613118 -165.608508)
		(size 0.508)
		(drill 0.254)
		(layers "F.Cu" "B.Cu")
		(net "UART_T11_NODE1_RXD")
	)
	(segment
		(start 151.66721 -182.94858)
		(end 151.03856 -183.57723)
		(width 0.1016)
		(layer "B.Cu")
		(net "UART_T11_NODE1_RXD")
	)
	(segment
		(start 151.89454 -182.24373)
		(end 151.66721 -182.47106)
		(width 0.1016)
		(layer "B.Cu")
		(net "UART_T11_NODE1_RXD")
	)
	(segment
		(start 151.89454 -180.46065)
		(end 151.89454 -182.24373)
		(width 0.1016)
		(layer "B.Cu")
		(net "UART_T11_NODE1_RXD")
	)
	(segment
		(start 151.66721 -182.47106)
		(end 151.66721 -182.94858)
		(width 0.1016)
		(layer "B.Cu")
		(net "UART_T11_NODE1_RXD")
	)
	(segment
		(start 150.47976 -185.74004)
		(end 150.47976 -185.351674)
		(width 0.1016)
		(layer "B.Cu")
		(net "UART_T11_NODE1_RXD")
	)
	(segment
		(start 150.161498 -187.472574)
		(end 150.161498 -186.058302)
		(width 0.1016)
		(layer "B.Cu")
		(net "UART_T11_NODE1_RXD")
	)
	(segment
		(start 151.03856 -183.57723)
		(end 151.03856 -184.785254)
		(width 0.1016)
		(layer "B.Cu")
		(net "UART_T11_NODE1_RXD")
	)
	(segment
		(start 151.03856 -184.785254)
		(end 151.03348 -184.790334)
		(width 0.1016)
		(layer "B.Cu")
		(net "UART_T11_NODE1_RXD")
	)
	(segment
		(start 151.03348 -184.790334)
		(end 151.03348 -185.071766)
		(width 0.1016)
		(layer "B.Cu")
		(net "UART_T11_NODE1_RXD")
	)
	(segment
		(start 151.03348 -185.071766)
		(end 150.753572 -185.351674)
		(width 0.1016)
		(layer "B.Cu")
		(net "UART_T11_NODE1_RXD")
	)
	(segment
		(start 152.5651 -179.79009)
		(end 151.89454 -180.46065)
		(width 0.1016)
		(layer "B.Cu")
		(net "UART_T11_NODE1_RXD")
	)
	(segment
		(start 150.161498 -186.058302)
		(end 150.47976 -185.74004)
		(width 0.1016)
		(layer "B.Cu")
		(net "UART_T11_NODE1_RXD")
	)
	(segment
		(start 150.47976 -187.472574)
		(end 150.161498 -187.472574)
		(width 0.1016)
		(layer "B.Cu")
		(net "UART_T11_NODE1_RXD")
	)
	(segment
		(start 150.753572 -185.351674)
		(end 150.47976 -185.351674)
		(width 0.1016)
		(layer "B.Cu")
		(net "UART_T11_NODE1_RXD")
	)
	(segment
		(start 150.05812 -169.244264)
		(end 151.74468 -170.930824)
		(width 0.1143)
		(layer "In7.Cu")
		(net "UART_T11_NODE1_RXD")
	)
	(segment
		(start 149.66188 -167.526462)
		(end 150.05812 -167.922702)
		(width 0.1143)
		(layer "In7.Cu")
		(net "UART_T11_NODE1_RXD")
	)
	(segment
		(start 147.027392 -165.194234)
		(end 148.418296 -165.194234)
		(width 0.1143)
		(layer "In7.Cu")
		(net "UART_T11_NODE1_RXD")
	)
	(segment
		(start 151.74468 -170.930824)
		(end 151.74468 -176.647856)
		(width 0.1143)
		(layer "In7.Cu")
		(net "UART_T11_NODE1_RXD")
	)
	(segment
		(start 151.74468 -176.647856)
		(end 152.15108 -177.054256)
		(width 0.1143)
		(layer "In7.Cu")
		(net "UART_T11_NODE1_RXD")
	)
	(segment
		(start 148.418296 -165.194234)
		(end 149.66188 -166.437818)
		(width 0.1143)
		(layer "In7.Cu")
		(net "UART_T11_NODE1_RXD")
	)
	(segment
		(start 150.05812 -167.922702)
		(end 150.05812 -169.244264)
		(width 0.1143)
		(layer "In7.Cu")
		(net "UART_T11_NODE1_RXD")
	)
	(segment
		(start 152.15108 -177.054256)
		(end 152.15108 -179.37607)
		(width 0.1143)
		(layer "In7.Cu")
		(net "UART_T11_NODE1_RXD")
	)
	(segment
		(start 149.66188 -166.437818)
		(end 149.66188 -167.526462)
		(width 0.1143)
		(layer "In7.Cu")
		(net "UART_T11_NODE1_RXD")
	)
	(segment
		(start 152.15108 -179.37607)
		(end 152.5651 -179.79009)
		(width 0.1143)
		(layer "In7.Cu")
		(net "UART_T11_NODE1_RXD")
	)
	(segment
		(start 146.613118 -165.608508)
		(end 147.027392 -165.194234)
		(width 0.1143)
		(layer "In7.Cu")
		(net "UART_T11_NODE1_RXD")
	)
	(segment
		(start 127.486156 -171.608496)
		(end 129.775712 -171.608496)
		(width 0.1016)
		(layer "F.Cu")
		(net "UART_T8_NODE1_TXD")
	)
	(via
		(at 127.486156 -171.608496)
		(size 0.508)
		(drill 0.254)
		(layers "F.Cu" "B.Cu")
		(net "UART_T8_NODE1_TXD")
	)
	(segment
		(start 127.731012 -171.36364)
		(end 127.486156 -171.608496)
		(width 0.1016)
		(layer "B.Cu")
		(net "UART_T8_NODE1_TXD")
	)
	(segment
		(start 129.068322 -171.36364)
		(end 127.731012 -171.36364)
		(width 0.1016)
		(layer "B.Cu")
		(net "UART_T8_NODE1_TXD")
	)
	(segment
		(start 143.666718 -161.97707)
		(end 143.674338 -161.97707)
		(width 0.1016)
		(layer "F.Cu")
		(net "UART_T10_NODE4_TXD")
	)
	(segment
		(start 143.025876 -163.358576)
		(end 143.025876 -162.617912)
		(width 0.1016)
		(layer "F.Cu")
		(net "UART_T10_NODE4_TXD")
	)
	(segment
		(start 143.025876 -162.617912)
		(end 143.666718 -161.97707)
		(width 0.1016)
		(layer "F.Cu")
		(net "UART_T10_NODE4_TXD")
	)
	(via
		(at 143.674338 -161.97707)
		(size 0.508)
		(drill 0.254)
		(layers "F.Cu" "B.Cu")
		(net "UART_T10_NODE4_TXD")
	)
	(segment
		(start 142.870682 -162.780726)
		(end 143.674338 -161.97707)
		(width 0.1016)
		(layer "B.Cu")
		(net "UART_T10_NODE4_TXD")
	)
	(segment
		(start 142.870682 -163.353242)
		(end 142.870682 -162.780726)
		(width 0.1016)
		(layer "B.Cu")
		(net "UART_T10_NODE4_TXD")
	)
	(segment
		(start 130.750564 -55.168038)
		(end 130.750564 -52.888388)
		(width 0.1016)
		(layer "F.Cu")
		(net "UART_TX_P4")
	)
	(segment
		(start 78.994762 -179.874672)
		(end 78.994762 -181.057804)
		(width 0.1016)
		(layer "F.Cu")
		(net "UART_TX_P4")
	)
	(segment
		(start 78.994762 -181.057804)
		(end 78.620874 -181.431692)
		(width 0.1016)
		(layer "F.Cu")
		(net "UART_TX_P4")
	)
	(segment
		(start 130.683 -49.3522)
		(end 130.683 -52.820824)
		(width 0.1016)
		(layer "F.Cu")
		(net "UART_TX_P4")
	)
	(segment
		(start 128.614424 -55.769002)
		(end 130.1496 -55.769002)
		(width 0.1016)
		(layer "F.Cu")
		(net "UART_TX_P4")
	)
	(segment
		(start 130.683 -52.820824)
		(end 130.750564 -52.888388)
		(width 0.1016)
		(layer "F.Cu")
		(net "UART_TX_P4")
	)
	(segment
		(start 136.525762 -178.858672)
		(end 136.525762 -180.362352)
		(width 0.1016)
		(layer "F.Cu")
		(net "UART_TX_P4")
	)
	(segment
		(start 130.1496 -55.769002)
		(end 130.750564 -55.168038)
		(width 0.1016)
		(layer "F.Cu")
		(net "UART_TX_P4")
	)
	(via
		(at 130.683 -49.3522)
		(size 0.508)
		(drill 0.254)
		(layers "F.Cu" "B.Cu")
		(net "UART_TX_P4")
	)
	(via
		(at 136.525762 -180.362352)
		(size 0.508)
		(drill 0.254)
		(layers "F.Cu" "B.Cu")
		(net "UART_TX_P4")
	)
	(via
		(at 78.620874 -181.431692)
		(size 0.508)
		(drill 0.254)
		(layers "F.Cu" "B.Cu")
		(net "UART_TX_P4")
	)
	(via
		(at 152.64892 -162.949382)
		(size 0.508)
		(drill 0.254)
		(layers "F.Cu" "B.Cu")
		(net "UART_TX_P4")
	)
	(via
		(at 130.750564 -52.888388)
		(size 0.508)
		(drill 0.254)
		(layers "F.Cu" "B.Cu")
		(net "UART_TX_P4")
	)
	(segment
		(start 140.979652 -167.80891)
		(end 138.552174 -170.236388)
		(width 0.1016)
		(layer "B.Cu")
		(net "UART_TX_P4")
	)
	(segment
		(start 141.640306 -167.80891)
		(end 140.979652 -167.80891)
		(width 0.1016)
		(layer "B.Cu")
		(net "UART_TX_P4")
	)
	(segment
		(start 138.552174 -170.236388)
		(end 138.552174 -172.176948)
		(width 0.1016)
		(layer "B.Cu")
		(net "UART_TX_P4")
	)
	(segment
		(start 137.485374 -178.904392)
		(end 136.525762 -179.864004)
		(width 0.1016)
		(layer "B.Cu")
		(net "UART_TX_P4")
	)
	(segment
		(start 143.44904 -167.014652)
		(end 142.434564 -167.014652)
		(width 0.1016)
		(layer "B.Cu")
		(net "UART_TX_P4")
	)
	(segment
		(start 137.485374 -173.243748)
		(end 137.485374 -178.904392)
		(width 0.1016)
		(layer "B.Cu")
		(net "UART_TX_P4")
	)
	(segment
		(start 142.434564 -167.014652)
		(end 141.640306 -167.80891)
		(width 0.1016)
		(layer "B.Cu")
		(net "UART_TX_P4")
	)
	(segment
		(start 136.525762 -179.864004)
		(end 136.525762 -180.362352)
		(width 0.1016)
		(layer "B.Cu")
		(net "UART_TX_P4")
	)
	(segment
		(start 138.552174 -172.176948)
		(end 137.485374 -173.243748)
		(width 0.1016)
		(layer "B.Cu")
		(net "UART_TX_P4")
	)
	(segment
		(start 152.64892 -162.949382)
		(end 148.518372 -162.949382)
		(width 0.1016)
		(layer "B.Cu")
		(net "UART_TX_P4")
	)
	(segment
		(start 144.789652 -166.678102)
		(end 143.78559 -166.678102)
		(width 0.1016)
		(layer "B.Cu")
		(net "UART_TX_P4")
	)
	(segment
		(start 143.78559 -166.678102)
		(end 143.44904 -167.014652)
		(width 0.1016)
		(layer "B.Cu")
		(net "UART_TX_P4")
	)
	(segment
		(start 148.518372 -162.949382)
		(end 144.789652 -166.678102)
		(width 0.1016)
		(layer "B.Cu")
		(net "UART_TX_P4")
	)
	(segment
		(start 159.723074 -160.530286)
		(end 156.945076 -160.530286)
		(width 0.1143)
		(layer "In2.Cu")
		(net "UART_TX_P4")
	)
	(segment
		(start 187.3123 -147.368006)
		(end 176.073562 -158.606744)
		(width 0.1143)
		(layer "In2.Cu")
		(net "UART_TX_P4")
	)
	(segment
		(start 178.361594 -88.08974)
		(end 187.77839 -97.506536)
		(width 0.1143)
		(layer "In2.Cu")
		(net "UART_TX_P4")
	)
	(segment
		(start 160.330388 -161.1376)
		(end 159.723074 -160.530286)
		(width 0.1143)
		(layer "In2.Cu")
		(net "UART_TX_P4")
	)
	(segment
		(start 156.8323 -160.41751)
		(end 156.46654 -160.41751)
		(width 0.1143)
		(layer "In2.Cu")
		(net "UART_TX_P4")
	)
	(segment
		(start 176.073562 -158.606744)
		(end 171.50842 -158.606744)
		(width 0.1143)
		(layer "In2.Cu")
		(net "UART_TX_P4")
	)
	(segment
		(start 162.212782 -88.08974)
		(end 178.361594 -88.08974)
		(width 0.1143)
		(layer "In2.Cu")
		(net "UART_TX_P4")
	)
	(segment
		(start 130.750564 -52.948078)
		(end 129.33299 -54.365652)
		(width 0.1143)
		(layer "In2.Cu")
		(net "UART_TX_P4")
	)
	(segment
		(start 187.3123 -142.507208)
		(end 187.3123 -147.368006)
		(width 0.1143)
		(layer "In2.Cu")
		(net "UART_TX_P4")
	)
	(segment
		(start 154.917648 -161.966402)
		(end 153.6319 -161.966402)
		(width 0.1143)
		(layer "In2.Cu")
		(net "UART_TX_P4")
	)
	(segment
		(start 133.16458 -70.686422)
		(end 133.16458 -71.854568)
		(width 0.1143)
		(layer "In2.Cu")
		(net "UART_TX_P4")
	)
	(segment
		(start 148.881084 -88.339422)
		(end 161.9631 -88.339422)
		(width 0.1143)
		(layer "In2.Cu")
		(net "UART_TX_P4")
	)
	(segment
		(start 171.50842 -158.606744)
		(end 168.977564 -161.1376)
		(width 0.1143)
		(layer "In2.Cu")
		(net "UART_TX_P4")
	)
	(segment
		(start 161.9631 -88.339422)
		(end 162.212782 -88.08974)
		(width 0.1143)
		(layer "In2.Cu")
		(net "UART_TX_P4")
	)
	(segment
		(start 187.77839 -97.506536)
		(end 187.77839 -125.08738)
		(width 0.1143)
		(layer "In2.Cu")
		(net "UART_TX_P4")
	)
	(segment
		(start 135.52678 -74.216768)
		(end 135.52678 -74.985118)
		(width 0.1143)
		(layer "In2.Cu")
		(net "UART_TX_P4")
	)
	(segment
		(start 188.24067 -125.54966)
		(end 188.24067 -141.579092)
		(width 0.1143)
		(layer "In2.Cu")
		(net "UART_TX_P4")
	)
	(segment
		(start 135.52678 -74.985118)
		(end 148.881084 -88.339422)
		(width 0.1143)
		(layer "In2.Cu")
		(net "UART_TX_P4")
	)
	(segment
		(start 153.6319 -161.966402)
		(end 152.64892 -162.949382)
		(width 0.1143)
		(layer "In2.Cu")
		(net "UART_TX_P4")
	)
	(segment
		(start 130.750564 -52.888388)
		(end 130.750564 -52.948078)
		(width 0.1143)
		(layer "In2.Cu")
		(net "UART_TX_P4")
	)
	(segment
		(start 188.24067 -141.579092)
		(end 187.312554 -142.507208)
		(width 0.1143)
		(layer "In2.Cu")
		(net "UART_TX_P4")
	)
	(segment
		(start 187.312554 -142.507208)
		(end 187.3123 -142.507208)
		(width 0.1143)
		(layer "In2.Cu")
		(net "UART_TX_P4")
	)
	(segment
		(start 156.46654 -160.41751)
		(end 154.917648 -161.966402)
		(width 0.1143)
		(layer "In2.Cu")
		(net "UART_TX_P4")
	)
	(segment
		(start 129.33299 -66.854832)
		(end 133.16458 -70.686422)
		(width 0.1143)
		(layer "In2.Cu")
		(net "UART_TX_P4")
	)
	(segment
		(start 168.977564 -161.1376)
		(end 160.330388 -161.1376)
		(width 0.1143)
		(layer "In2.Cu")
		(net "UART_TX_P4")
	)
	(segment
		(start 129.33299 -54.365652)
		(end 129.33299 -66.854832)
		(width 0.1143)
		(layer "In2.Cu")
		(net "UART_TX_P4")
	)
	(segment
		(start 187.77839 -125.08738)
		(end 188.24067 -125.54966)
		(width 0.1143)
		(layer "In2.Cu")
		(net "UART_TX_P4")
	)
	(segment
		(start 156.945076 -160.530286)
		(end 156.8323 -160.41751)
		(width 0.1143)
		(layer "In2.Cu")
		(net "UART_TX_P4")
	)
	(segment
		(start 133.16458 -71.854568)
		(end 135.52678 -74.216768)
		(width 0.1143)
		(layer "In2.Cu")
		(net "UART_TX_P4")
	)
	(segment
		(start 100.569522 -181.045866)
		(end 100.105464 -181.509924)
		(width 0.1143)
		(layer "In6.Cu")
		(net "UART_TX_P4")
	)
	(segment
		(start 111.43869 -181.973474)
		(end 108.74629 -181.973474)
		(width 0.1143)
		(layer "In6.Cu")
		(net "UART_TX_P4")
	)
	(segment
		(start 88.030304 -182.154322)
		(end 87.679276 -182.50535)
		(width 0.1143)
		(layer "In6.Cu")
		(net "UART_TX_P4")
	)
	(segment
		(start 85.21446 -182.50535)
		(end 85.082634 -182.373524)
		(width 0.1143)
		(layer "In6.Cu")
		(net "UART_TX_P4")
	)
	(segment
		(start 90.194638 -181.708044)
		(end 89.74836 -182.154322)
		(width 0.1143)
		(layer "In6.Cu")
		(net "UART_TX_P4")
	)
	(segment
		(start 108.501434 -181.728618)
		(end 104.784906 -181.728618)
		(width 0.1143)
		(layer "In6.Cu")
		(net "UART_TX_P4")
	)
	(segment
		(start 104.62006 -181.563772)
		(end 103.697786 -181.563772)
		(width 0.1143)
		(layer "In6.Cu")
		(net "UART_TX_P4")
	)
	(segment
		(start 136.525762 -180.00472)
		(end 135.754364 -179.233322)
		(width 0.1143)
		(layer "In6.Cu")
		(net "UART_TX_P4")
	)
	(segment
		(start 136.525762 -180.362352)
		(end 136.525762 -180.00472)
		(width 0.1143)
		(layer "In6.Cu")
		(net "UART_TX_P4")
	)
	(segment
		(start 94.651322 -181.509924)
		(end 94.453202 -181.708044)
		(width 0.1143)
		(layer "In6.Cu")
		(net "UART_TX_P4")
	)
	(segment
		(start 89.74836 -182.154322)
		(end 88.030304 -182.154322)
		(width 0.1143)
		(layer "In6.Cu")
		(net "UART_TX_P4")
	)
	(segment
		(start 127.537464 -180.04155)
		(end 124.617226 -180.04155)
		(width 0.1143)
		(layer "In6.Cu")
		(net "UART_TX_P4")
	)
	(segment
		(start 104.784906 -181.728618)
		(end 104.62006 -181.563772)
		(width 0.1143)
		(layer "In6.Cu")
		(net "UART_TX_P4")
	)
	(segment
		(start 85.082634 -182.373524)
		(end 81.397348 -182.373524)
		(width 0.1143)
		(layer "In6.Cu")
		(net "UART_TX_P4")
	)
	(segment
		(start 113.497106 -179.915058)
		(end 111.43869 -181.973474)
		(width 0.1143)
		(layer "In6.Cu")
		(net "UART_TX_P4")
	)
	(segment
		(start 108.74629 -181.973474)
		(end 108.501434 -181.728618)
		(width 0.1143)
		(layer "In6.Cu")
		(net "UART_TX_P4")
	)
	(segment
		(start 100.105464 -181.509924)
		(end 94.651322 -181.509924)
		(width 0.1143)
		(layer "In6.Cu")
		(net "UART_TX_P4")
	)
	(segment
		(start 103.17988 -181.045866)
		(end 100.569522 -181.045866)
		(width 0.1143)
		(layer "In6.Cu")
		(net "UART_TX_P4")
	)
	(segment
		(start 124.490734 -179.915058)
		(end 113.497106 -179.915058)
		(width 0.1143)
		(layer "In6.Cu")
		(net "UART_TX_P4")
	)
	(segment
		(start 94.453202 -181.708044)
		(end 90.194638 -181.708044)
		(width 0.1143)
		(layer "In6.Cu")
		(net "UART_TX_P4")
	)
	(segment
		(start 103.697786 -181.563772)
		(end 103.17988 -181.045866)
		(width 0.1143)
		(layer "In6.Cu")
		(net "UART_TX_P4")
	)
	(segment
		(start 135.754364 -179.233322)
		(end 128.345692 -179.233322)
		(width 0.1143)
		(layer "In6.Cu")
		(net "UART_TX_P4")
	)
	(segment
		(start 128.345692 -179.233322)
		(end 127.537464 -180.04155)
		(width 0.1143)
		(layer "In6.Cu")
		(net "UART_TX_P4")
	)
	(segment
		(start 124.617226 -180.04155)
		(end 124.490734 -179.915058)
		(width 0.1143)
		(layer "In6.Cu")
		(net "UART_TX_P4")
	)
	(segment
		(start 81.36636 -182.404512)
		(end 80.044798 -182.404512)
		(width 0.1143)
		(layer "In6.Cu")
		(net "UART_TX_P4")
	)
	(segment
		(start 81.397348 -182.373524)
		(end 81.36636 -182.404512)
		(width 0.1143)
		(layer "In6.Cu")
		(net "UART_TX_P4")
	)
	(segment
		(start 87.679276 -182.50535)
		(end 85.21446 -182.50535)
		(width 0.1143)
		(layer "In6.Cu")
		(net "UART_TX_P4")
	)
	(segment
		(start 79.071978 -181.431692)
		(end 78.620874 -181.431692)
		(width 0.1143)
		(layer "In6.Cu")
		(net "UART_TX_P4")
	)
	(segment
		(start 80.044798 -182.404512)
		(end 79.071978 -181.431692)
		(width 0.1143)
		(layer "In6.Cu")
		(net "UART_TX_P4")
	)
	(segment
		(start 142.56512 -47.36846)
		(end 144.34058 -45.593)
		(width 0.1143)
		(layer "In7.Cu")
		(net "UART_TX_P4")
	)
	(segment
		(start 132.965698 -47.36846)
		(end 142.56512 -47.36846)
		(width 0.1143)
		(layer "In7.Cu")
		(net "UART_TX_P4")
	)
	(segment
		(start 144.34058 -31.815786)
		(end 149.04974 -27.106626)
		(width 0.1143)
		(layer "In7.Cu")
		(net "UART_TX_P4")
	)
	(segment
		(start 149.04974 -22.632416)
		(end 150.113746 -21.56841)
		(width 0.1143)
		(layer "In7.Cu")
		(net "UART_TX_P4")
	)
	(segment
		(start 144.34058 -45.593)
		(end 144.34058 -31.815786)
		(width 0.1143)
		(layer "In7.Cu")
		(net "UART_TX_P4")
	)
	(segment
		(start 130.683 -49.3522)
		(end 130.981958 -49.3522)
		(width 0.1143)
		(layer "In7.Cu")
		(net "UART_TX_P4")
	)
	(segment
		(start 149.04974 -27.106626)
		(end 149.04974 -22.632416)
		(width 0.1143)
		(layer "In7.Cu")
		(net "UART_TX_P4")
	)
	(segment
		(start 130.981958 -49.3522)
		(end 132.965698 -47.36846)
		(width 0.1143)
		(layer "In7.Cu")
		(net "UART_TX_P4")
	)
	(segment
		(start 144.116298 -167.608504)
		(end 145.275808 -167.608504)
		(width 0.1016)
		(layer "F.Cu")
		(net "UART_T11_NODE2_TXD")
	)
	(segment
		(start 144.0053 -167.497506)
		(end 144.116298 -167.608504)
		(width 0.1016)
		(layer "F.Cu")
		(net "UART_T11_NODE2_TXD")
	)
	(via
		(at 147.12188 -183.077104)
		(size 0.508)
		(drill 0.254)
		(layers "F.Cu" "B.Cu")
		(net "UART_T11_NODE2_TXD")
	)
	(via
		(at 144.0053 -167.497506)
		(size 0.508)
		(drill 0.254)
		(layers "F.Cu" "B.Cu")
		(net "UART_T11_NODE2_TXD")
	)
	(segment
		(start 146.685508 -183.2991)
		(end 146.15541 -183.829198)
		(width 0.1016)
		(layer "B.Cu")
		(net "UART_T11_NODE2_TXD")
	)
	(segment
		(start 147.12188 -183.077104)
		(end 146.899884 -183.2991)
		(width 0.1016)
		(layer "B.Cu")
		(net "UART_T11_NODE2_TXD")
	)
	(segment
		(start 146.15541 -184.049924)
		(end 145.65376 -184.551574)
		(width 0.1016)
		(layer "B.Cu")
		(net "UART_T11_NODE2_TXD")
	)
	(segment
		(start 146.15541 -183.829198)
		(end 146.15541 -184.049924)
		(width 0.1016)
		(layer "B.Cu")
		(net "UART_T11_NODE2_TXD")
	)
	(segment
		(start 146.899884 -183.2991)
		(end 146.685508 -183.2991)
		(width 0.1016)
		(layer "B.Cu")
		(net "UART_T11_NODE2_TXD")
	)
	(segment
		(start 146.861276 -168.12387)
		(end 146.86153 -168.123616)
		(width 0.1143)
		(layer "In7.Cu")
		(net "UART_T11_NODE2_TXD")
	)
	(segment
		(start 144.0053 -167.497506)
		(end 144.631664 -168.12387)
		(width 0.1143)
		(layer "In7.Cu")
		(net "UART_T11_NODE2_TXD")
	)
	(segment
		(start 150.17115 -172.504862)
		(end 150.17115 -180.027834)
		(width 0.1143)
		(layer "In7.Cu")
		(net "UART_T11_NODE2_TXD")
	)
	(segment
		(start 150.17115 -180.027834)
		(end 147.12188 -183.077104)
		(width 0.1143)
		(layer "In7.Cu")
		(net "UART_T11_NODE2_TXD")
	)
	(segment
		(start 144.631664 -168.12387)
		(end 146.861276 -168.12387)
		(width 0.1143)
		(layer "In7.Cu")
		(net "UART_T11_NODE2_TXD")
	)
	(segment
		(start 148.66112 -170.994832)
		(end 150.17115 -172.504862)
		(width 0.1143)
		(layer "In7.Cu")
		(net "UART_T11_NODE2_TXD")
	)
	(segment
		(start 148.66112 -170.135804)
		(end 148.66112 -170.994832)
		(width 0.1143)
		(layer "In7.Cu")
		(net "UART_T11_NODE2_TXD")
	)
	(segment
		(start 147.700492 -168.123616)
		(end 147.92198 -168.345104)
		(width 0.1143)
		(layer "In7.Cu")
		(net "UART_T11_NODE2_TXD")
	)
	(segment
		(start 147.92198 -169.396664)
		(end 148.66112 -170.135804)
		(width 0.1143)
		(layer "In7.Cu")
		(net "UART_T11_NODE2_TXD")
	)
	(segment
		(start 146.86153 -168.123616)
		(end 147.700492 -168.123616)
		(width 0.1143)
		(layer "In7.Cu")
		(net "UART_T11_NODE2_TXD")
	)
	(segment
		(start 147.92198 -168.345104)
		(end 147.92198 -169.396664)
		(width 0.1143)
		(layer "In7.Cu")
		(net "UART_T11_NODE2_TXD")
	)
	(segment
		(start 129.775712 -176.60874)
		(end 129.129028 -176.60874)
		(width 0.1016)
		(layer "F.Cu")
		(net "UART_T7_NODE1_RXD")
	)
	(segment
		(start 129.129028 -176.60874)
		(end 128.553718 -177.18405)
		(width 0.1016)
		(layer "F.Cu")
		(net "UART_T7_NODE1_RXD")
	)
	(segment
		(start 128.553718 -177.18405)
		(end 128.547368 -177.18405)
		(width 0.1016)
		(layer "F.Cu")
		(net "UART_T7_NODE1_RXD")
	)
	(via
		(at 128.547368 -177.18405)
		(size 0.508)
		(drill 0.254)
		(layers "F.Cu" "B.Cu")
		(net "UART_T7_NODE1_RXD")
	)
	(via
		(at 115.67414 -186.464702)
		(size 0.508)
		(drill 0.254)
		(layers "F.Cu" "B.Cu")
		(net "UART_T7_NODE1_RXD")
	)
	(via
		(at 120.94464 -186.48807)
		(size 0.508)
		(drill 0.254)
		(layers "F.Cu" "B.Cu")
		(net "UART_T7_NODE1_RXD")
	)
	(segment
		(start 126.43485 -182.971948)
		(end 128.39446 -181.012338)
		(width 0.1016)
		(layer "B.Cu")
		(net "UART_T7_NODE1_RXD")
	)
	(segment
		(start 121.187718 -186.48807)
		(end 121.747026 -187.047378)
		(width 0.1016)
		(layer "B.Cu")
		(net "UART_T7_NODE1_RXD")
	)
	(segment
		(start 120.94464 -186.48807)
		(end 121.187718 -186.48807)
		(width 0.1016)
		(layer "B.Cu")
		(net "UART_T7_NODE1_RXD")
	)
	(segment
		(start 115.42776 -185.605674)
		(end 115.42776 -186.218322)
		(width 0.1016)
		(layer "B.Cu")
		(net "UART_T7_NODE1_RXD")
	)
	(segment
		(start 116.44376 -187.234322)
		(end 116.44376 -187.726574)
		(width 0.1016)
		(layer "B.Cu")
		(net "UART_T7_NODE1_RXD")
	)
	(segment
		(start 122.9614 -186.029854)
		(end 126.019306 -182.971948)
		(width 0.1016)
		(layer "B.Cu")
		(net "UART_T7_NODE1_RXD")
	)
	(segment
		(start 121.747026 -187.047378)
		(end 122.138948 -187.047378)
		(width 0.1016)
		(layer "B.Cu")
		(net "UART_T7_NODE1_RXD")
	)
	(segment
		(start 126.019306 -182.971948)
		(end 126.43485 -182.971948)
		(width 0.1016)
		(layer "B.Cu")
		(net "UART_T7_NODE1_RXD")
	)
	(segment
		(start 115.67414 -186.464702)
		(end 116.44376 -187.234322)
		(width 0.1016)
		(layer "B.Cu")
		(net "UART_T7_NODE1_RXD")
	)
	(segment
		(start 122.138948 -187.047378)
		(end 122.9614 -186.224926)
		(width 0.1016)
		(layer "B.Cu")
		(net "UART_T7_NODE1_RXD")
	)
	(segment
		(start 115.42776 -186.218322)
		(end 115.67414 -186.464702)
		(width 0.1016)
		(layer "B.Cu")
		(net "UART_T7_NODE1_RXD")
	)
	(segment
		(start 128.39446 -181.012338)
		(end 128.39446 -177.336958)
		(width 0.1016)
		(layer "B.Cu")
		(net "UART_T7_NODE1_RXD")
	)
	(segment
		(start 128.39446 -177.336958)
		(end 128.547368 -177.18405)
		(width 0.1016)
		(layer "B.Cu")
		(net "UART_T7_NODE1_RXD")
	)
	(segment
		(start 122.9614 -186.224926)
		(end 122.9614 -186.029854)
		(width 0.1016)
		(layer "B.Cu")
		(net "UART_T7_NODE1_RXD")
	)
	(segment
		(start 116.28628 -185.852562)
		(end 115.67414 -186.464702)
		(width 0.1143)
		(layer "In7.Cu")
		(net "UART_T7_NODE1_RXD")
	)
	(segment
		(start 120.94464 -186.48807)
		(end 120.875298 -186.418728)
		(width 0.1143)
		(layer "In7.Cu")
		(net "UART_T7_NODE1_RXD")
	)
	(segment
		(start 120.240044 -185.852562)
		(end 116.28628 -185.852562)
		(width 0.1143)
		(layer "In7.Cu")
		(net "UART_T7_NODE1_RXD")
	)
	(segment
		(start 120.875298 -186.418728)
		(end 120.80621 -186.418728)
		(width 0.1143)
		(layer "In7.Cu")
		(net "UART_T7_NODE1_RXD")
	)
	(segment
		(start 120.80621 -186.418728)
		(end 120.240044 -185.852562)
		(width 0.1143)
		(layer "In7.Cu")
		(net "UART_T7_NODE1_RXD")
	)
	(segment
		(start 121.516394 -165.60673)
		(end 122.238262 -166.328598)
		(width 0.1016)
		(layer "F.Cu")
		(net "CPLD_WDT1_R")
	)
	(segment
		(start 123.30811 -166.523416)
		(end 122.43308 -166.523416)
		(width 0.1016)
		(layer "F.Cu")
		(net "CPLD_WDT1_R")
	)
	(segment
		(start 120.60936 -165.60673)
		(end 121.516394 -165.60673)
		(width 0.1016)
		(layer "F.Cu")
		(net "CPLD_WDT1_R")
	)
	(segment
		(start 122.43308 -166.523416)
		(end 122.238262 -166.328598)
		(width 0.1016)
		(layer "F.Cu")
		(net "CPLD_WDT1_R")
	)
	(via
		(at 122.238262 -166.328598)
		(size 0.508)
		(drill 0.254)
		(layers "F.Cu" "B.Cu")
		(net "CPLD_WDT1_R")
	)
	(segment
		(start 127.7874 -52.705)
		(end 127.508 -52.9844)
		(width 0.1016)
		(layer "F.Cu")
		(net "UART_RX_P4")
	)
	(segment
		(start 135.026146 -175.218852)
		(end 135.026146 -175.740568)
		(width 0.1016)
		(layer "F.Cu")
		(net "UART_RX_P4")
	)
	(segment
		(start 127.508 -53.49875)
		(end 127.078232 -53.928518)
		(width 0.1016)
		(layer "F.Cu")
		(net "UART_RX_P4")
	)
	(segment
		(start 127.078232 -53.928518)
		(end 126.670054 -53.928518)
		(width 0.1016)
		(layer "F.Cu")
		(net "UART_RX_P4")
	)
	(segment
		(start 127.508 -52.9844)
		(end 127.508 -53.49875)
		(width 0.1016)
		(layer "F.Cu")
		(net "UART_RX_P4")
	)
	(segment
		(start 78.85811 -178.42611)
		(end 78.494636 -178.789584)
		(width 0.1016)
		(layer "F.Cu")
		(net "UART_RX_P4")
	)
	(segment
		(start 128.583436 -52.671472)
		(end 128.549908 -52.705)
		(width 0.1016)
		(layer "F.Cu")
		(net "UART_RX_P4")
	)
	(segment
		(start 135.026146 -175.740568)
		(end 136.025636 -176.740058)
		(width 0.1016)
		(layer "F.Cu")
		(net "UART_RX_P4")
	)
	(segment
		(start 128.549908 -52.705)
		(end 127.7874 -52.705)
		(width 0.1016)
		(layer "F.Cu")
		(net "UART_RX_P4")
	)
	(segment
		(start 136.025636 -176.740058)
		(end 136.025636 -178.858672)
		(width 0.1016)
		(layer "F.Cu")
		(net "UART_RX_P4")
	)
	(segment
		(start 79.56042 -178.42611)
		(end 78.85811 -178.42611)
		(width 0.1016)
		(layer "F.Cu")
		(net "UART_RX_P4")
	)
	(segment
		(start 78.494636 -178.789584)
		(end 78.494636 -179.874672)
		(width 0.1016)
		(layer "F.Cu")
		(net "UART_RX_P4")
	)
	(via
		(at 128.583436 -52.671472)
		(size 0.508)
		(drill 0.254)
		(layers "F.Cu" "B.Cu")
		(net "UART_RX_P4")
	)
	(via
		(at 79.56042 -178.42611)
		(size 0.508)
		(drill 0.254)
		(layers "F.Cu" "B.Cu")
		(net "UART_RX_P4")
	)
	(via
		(at 135.026146 -175.218852)
		(size 0.508)
		(drill 0.254)
		(layers "F.Cu" "B.Cu")
		(net "UART_RX_P4")
	)
	(segment
		(start 139.31011 -167.144446)
		(end 137.507726 -167.144446)
		(width 0.1143)
		(layer "In2.Cu")
		(net "UART_RX_P4")
	)
	(segment
		(start 126.998984 -176.276762)
		(end 133.968236 -176.276762)
		(width 0.1143)
		(layer "In2.Cu")
		(net "UART_RX_P4")
	)
	(segment
		(start 154.906218 -161.528252)
		(end 151.040338 -161.528252)
		(width 0.1143)
		(layer "In2.Cu")
		(net "UART_RX_P4")
	)
	(segment
		(start 187.92317 -125.681232)
		(end 187.92317 -141.261592)
		(width 0.1143)
		(layer "In2.Cu")
		(net "UART_RX_P4")
	)
	(segment
		(start 132.84708 -71.006208)
		(end 132.84708 -71.98614)
		(width 0.1143)
		(layer "In2.Cu")
		(net "UART_RX_P4")
	)
	(segment
		(start 162.09518 -88.656922)
		(end 162.344862 -88.40724)
		(width 0.1143)
		(layer "In2.Cu")
		(net "UART_RX_P4")
	)
	(segment
		(start 135.20928 -74.34834)
		(end 135.20928 -75.11669)
		(width 0.1143)
		(layer "In2.Cu")
		(net "UART_RX_P4")
	)
	(segment
		(start 100.520246 -174.040292)
		(end 101.33965 -174.859696)
		(width 0.1143)
		(layer "In2.Cu")
		(net "UART_RX_P4")
	)
	(segment
		(start 128.7272 -66.886328)
		(end 132.84708 -71.006208)
		(width 0.1143)
		(layer "In2.Cu")
		(net "UART_RX_P4")
	)
	(segment
		(start 160.637982 -160.8201)
		(end 159.989774 -160.171892)
		(width 0.1143)
		(layer "In2.Cu")
		(net "UART_RX_P4")
	)
	(segment
		(start 114.987578 -174.526194)
		(end 116.506498 -176.045114)
		(width 0.1143)
		(layer "In2.Cu")
		(net "UART_RX_P4")
	)
	(segment
		(start 108.053632 -173.084236)
		(end 109.5629 -173.084236)
		(width 0.1143)
		(layer "In2.Cu")
		(net "UART_RX_P4")
	)
	(segment
		(start 168.749726 -160.8201)
		(end 160.637982 -160.8201)
		(width 0.1143)
		(layer "In2.Cu")
		(net "UART_RX_P4")
	)
	(segment
		(start 80.48752 -176.562766)
		(end 84.23783 -172.812456)
		(width 0.1143)
		(layer "In2.Cu")
		(net "UART_RX_P4")
	)
	(segment
		(start 78.441804 -178.42611)
		(end 77.28331 -177.267616)
		(width 0.1143)
		(layer "In2.Cu")
		(net "UART_RX_P4")
	)
	(segment
		(start 187.92317 -141.261592)
		(end 186.995054 -142.189708)
		(width 0.1143)
		(layer "In2.Cu")
		(net "UART_RX_P4")
	)
	(segment
		(start 162.344862 -88.40724)
		(end 178.230022 -88.40724)
		(width 0.1143)
		(layer "In2.Cu")
		(net "UART_RX_P4")
	)
	(segment
		(start 135.196834 -173.594776)
		(end 135.196834 -175.048164)
		(width 0.1143)
		(layer "In2.Cu")
		(net "UART_RX_P4")
	)
	(segment
		(start 134.69493 -173.092872)
		(end 135.196834 -173.594776)
		(width 0.1143)
		(layer "In2.Cu")
		(net "UART_RX_P4")
	)
	(segment
		(start 171.280582 -158.289244)
		(end 168.749726 -160.8201)
		(width 0.1143)
		(layer "In2.Cu")
		(net "UART_RX_P4")
	)
	(segment
		(start 156.33446 -160.10001)
		(end 154.906218 -161.528252)
		(width 0.1143)
		(layer "In2.Cu")
		(net "UART_RX_P4")
	)
	(segment
		(start 104.157526 -175.197008)
		(end 105.869994 -175.197008)
		(width 0.1143)
		(layer "In2.Cu")
		(net "UART_RX_P4")
	)
	(segment
		(start 186.9948 -147.236434)
		(end 175.94199 -158.289244)
		(width 0.1143)
		(layer "In2.Cu")
		(net "UART_RX_P4")
	)
	(segment
		(start 96.378522 -174.040292)
		(end 100.520246 -174.040292)
		(width 0.1143)
		(layer "In2.Cu")
		(net "UART_RX_P4")
	)
	(segment
		(start 144.434306 -164.46627)
		(end 141.857476 -164.46627)
		(width 0.1143)
		(layer "In2.Cu")
		(net "UART_RX_P4")
	)
	(segment
		(start 133.968236 -176.276762)
		(end 135.026146 -175.218852)
		(width 0.1143)
		(layer "In2.Cu")
		(net "UART_RX_P4")
	)
	(segment
		(start 187.46089 -116.001292)
		(end 186.84875 -116.613432)
		(width 0.1143)
		(layer "In2.Cu")
		(net "UART_RX_P4")
	)
	(segment
		(start 145.05178 -163.848796)
		(end 144.434306 -164.46627)
		(width 0.1143)
		(layer "In2.Cu")
		(net "UART_RX_P4")
	)
	(segment
		(start 128.2192 -58.8772)
		(end 128.2192 -64.2366)
		(width 0.1143)
		(layer "In2.Cu")
		(net "UART_RX_P4")
	)
	(segment
		(start 124.55779 -175.234092)
		(end 125.956314 -175.234092)
		(width 0.1143)
		(layer "In2.Cu")
		(net "UART_RX_P4")
	)
	(segment
		(start 128.8034 -58.293)
		(end 128.2192 -58.8772)
		(width 0.1143)
		(layer "In2.Cu")
		(net "UART_RX_P4")
	)
	(segment
		(start 178.230022 -88.40724)
		(end 187.46089 -97.638108)
		(width 0.1143)
		(layer "In2.Cu")
		(net "UART_RX_P4")
	)
	(segment
		(start 135.1534 -169.980356)
		(end 134.69493 -170.438826)
		(width 0.1143)
		(layer "In2.Cu")
		(net "UART_RX_P4")
	)
	(segment
		(start 79.56042 -178.42611)
		(end 78.441804 -178.42611)
		(width 0.1143)
		(layer "In2.Cu")
		(net "UART_RX_P4")
	)
	(segment
		(start 92.8878 -172.559726)
		(end 94.897956 -172.559726)
		(width 0.1143)
		(layer "In2.Cu")
		(net "UART_RX_P4")
	)
	(segment
		(start 128.2192 -64.2366)
		(end 128.7272 -64.7446)
		(width 0.1143)
		(layer "In2.Cu")
		(net "UART_RX_P4")
	)
	(segment
		(start 135.1534 -169.498772)
		(end 135.1534 -169.980356)
		(width 0.1143)
		(layer "In2.Cu")
		(net "UART_RX_P4")
	)
	(segment
		(start 123.746768 -176.045114)
		(end 124.55779 -175.234092)
		(width 0.1143)
		(layer "In2.Cu")
		(net "UART_RX_P4")
	)
	(segment
		(start 175.94199 -158.289244)
		(end 171.280582 -158.289244)
		(width 0.1143)
		(layer "In2.Cu")
		(net "UART_RX_P4")
	)
	(segment
		(start 137.507726 -167.144446)
		(end 135.1534 -169.498772)
		(width 0.1143)
		(layer "In2.Cu")
		(net "UART_RX_P4")
	)
	(segment
		(start 103.820214 -174.859696)
		(end 104.157526 -175.197008)
		(width 0.1143)
		(layer "In2.Cu")
		(net "UART_RX_P4")
	)
	(segment
		(start 151.040338 -161.528252)
		(end 148.719794 -163.848796)
		(width 0.1143)
		(layer "In2.Cu")
		(net "UART_RX_P4")
	)
	(segment
		(start 128.7272 -64.7446)
		(end 128.7272 -66.886328)
		(width 0.1143)
		(layer "In2.Cu")
		(net "UART_RX_P4")
	)
	(segment
		(start 125.956314 -175.234092)
		(end 126.998984 -176.276762)
		(width 0.1143)
		(layer "In2.Cu")
		(net "UART_RX_P4")
	)
	(segment
		(start 90.109294 -172.392086)
		(end 92.72016 -172.392086)
		(width 0.1143)
		(layer "In2.Cu")
		(net "UART_RX_P4")
	)
	(segment
		(start 141.34084 -165.113716)
		(end 139.31011 -167.144446)
		(width 0.1143)
		(layer "In2.Cu")
		(net "UART_RX_P4")
	)
	(segment
		(start 92.72016 -172.392086)
		(end 92.8878 -172.559726)
		(width 0.1143)
		(layer "In2.Cu")
		(net "UART_RX_P4")
	)
	(segment
		(start 135.196834 -175.048164)
		(end 135.026146 -175.218852)
		(width 0.1143)
		(layer "In2.Cu")
		(net "UART_RX_P4")
	)
	(segment
		(start 134.69493 -170.438826)
		(end 134.69493 -173.092872)
		(width 0.1143)
		(layer "In2.Cu")
		(net "UART_RX_P4")
	)
	(segment
		(start 111.004858 -174.526194)
		(end 114.987578 -174.526194)
		(width 0.1143)
		(layer "In2.Cu")
		(net "UART_RX_P4")
	)
	(segment
		(start 186.84875 -116.613432)
		(end 186.84875 -124.606812)
		(width 0.1143)
		(layer "In2.Cu")
		(net "UART_RX_P4")
	)
	(segment
		(start 94.897956 -172.559726)
		(end 96.378522 -174.040292)
		(width 0.1143)
		(layer "In2.Cu")
		(net "UART_RX_P4")
	)
	(segment
		(start 128.583436 -52.671472)
		(end 128.8034 -52.891436)
		(width 0.1143)
		(layer "In2.Cu")
		(net "UART_RX_P4")
	)
	(segment
		(start 77.62494 -176.562766)
		(end 80.48752 -176.562766)
		(width 0.1143)
		(layer "In2.Cu")
		(net "UART_RX_P4")
	)
	(segment
		(start 101.33965 -174.859696)
		(end 103.820214 -174.859696)
		(width 0.1143)
		(layer "In2.Cu")
		(net "UART_RX_P4")
	)
	(segment
		(start 148.749512 -88.656922)
		(end 162.09518 -88.656922)
		(width 0.1143)
		(layer "In2.Cu")
		(net "UART_RX_P4")
	)
	(segment
		(start 135.20928 -75.11669)
		(end 148.749512 -88.656922)
		(width 0.1143)
		(layer "In2.Cu")
		(net "UART_RX_P4")
	)
	(segment
		(start 84.23783 -172.812456)
		(end 89.688924 -172.812456)
		(width 0.1143)
		(layer "In2.Cu")
		(net "UART_RX_P4")
	)
	(segment
		(start 159.989774 -160.171892)
		(end 157.037024 -160.171892)
		(width 0.1143)
		(layer "In2.Cu")
		(net "UART_RX_P4")
	)
	(segment
		(start 157.037024 -160.171892)
		(end 156.965142 -160.10001)
		(width 0.1143)
		(layer "In2.Cu")
		(net "UART_RX_P4")
	)
	(segment
		(start 116.506498 -176.045114)
		(end 123.746768 -176.045114)
		(width 0.1143)
		(layer "In2.Cu")
		(net "UART_RX_P4")
	)
	(segment
		(start 141.857476 -164.46627)
		(end 141.34084 -164.982906)
		(width 0.1143)
		(layer "In2.Cu")
		(net "UART_RX_P4")
	)
	(segment
		(start 77.28331 -176.904396)
		(end 77.62494 -176.562766)
		(width 0.1143)
		(layer "In2.Cu")
		(net "UART_RX_P4")
	)
	(segment
		(start 141.34084 -164.982906)
		(end 141.34084 -165.113716)
		(width 0.1143)
		(layer "In2.Cu")
		(net "UART_RX_P4")
	)
	(segment
		(start 89.688924 -172.812456)
		(end 90.109294 -172.392086)
		(width 0.1143)
		(layer "In2.Cu")
		(net "UART_RX_P4")
	)
	(segment
		(start 132.84708 -71.98614)
		(end 135.20928 -74.34834)
		(width 0.1143)
		(layer "In2.Cu")
		(net "UART_RX_P4")
	)
	(segment
		(start 128.8034 -52.891436)
		(end 128.8034 -58.293)
		(width 0.1143)
		(layer "In2.Cu")
		(net "UART_RX_P4")
	)
	(segment
		(start 187.46089 -97.638108)
		(end 187.46089 -116.001292)
		(width 0.1143)
		(layer "In2.Cu")
		(net "UART_RX_P4")
	)
	(segment
		(start 107.914694 -173.152308)
		(end 107.98556 -173.152308)
		(width 0.1143)
		(layer "In2.Cu")
		(net "UART_RX_P4")
	)
	(segment
		(start 107.98556 -173.152308)
		(end 108.053632 -173.084236)
		(width 0.1143)
		(layer "In2.Cu")
		(net "UART_RX_P4")
	)
	(segment
		(start 186.9948 -142.189708)
		(end 186.9948 -147.236434)
		(width 0.1143)
		(layer "In2.Cu")
		(net "UART_RX_P4")
	)
	(segment
		(start 105.869994 -175.197008)
		(end 107.914694 -173.152308)
		(width 0.1143)
		(layer "In2.Cu")
		(net "UART_RX_P4")
	)
	(segment
		(start 186.84875 -124.606812)
		(end 187.92317 -125.681232)
		(width 0.1143)
		(layer "In2.Cu")
		(net "UART_RX_P4")
	)
	(segment
		(start 109.5629 -173.084236)
		(end 111.004858 -174.526194)
		(width 0.1143)
		(layer "In2.Cu")
		(net "UART_RX_P4")
	)
	(segment
		(start 77.28331 -177.267616)
		(end 77.28331 -176.904396)
		(width 0.1143)
		(layer "In2.Cu")
		(net "UART_RX_P4")
	)
	(segment
		(start 186.995054 -142.189708)
		(end 186.9948 -142.189708)
		(width 0.1143)
		(layer "In2.Cu")
		(net "UART_RX_P4")
	)
	(segment
		(start 156.965142 -160.10001)
		(end 156.33446 -160.10001)
		(width 0.1143)
		(layer "In2.Cu")
		(net "UART_RX_P4")
	)
	(segment
		(start 148.719794 -163.848796)
		(end 145.05178 -163.848796)
		(width 0.1143)
		(layer "In2.Cu")
		(net "UART_RX_P4")
	)
	(segment
		(start 142.134336 -165.294818)
		(end 142.09776 -165.294818)
		(width 0.1016)
		(layer "F.Cu")
		(net "UART_T10_NODE3_RXD")
	)
	(segment
		(start 131.81076 -185.779664)
		(end 131.81076 -185.453274)
		(width 0.1016)
		(layer "F.Cu")
		(net "UART_T10_NODE3_RXD")
	)
	(segment
		(start 131.30276 -187.726574)
		(end 131.30276 -186.863482)
		(width 0.1016)
		(layer "F.Cu")
		(net "UART_T10_NODE3_RXD")
	)
	(segment
		(start 131.30276 -186.863482)
		(end 131.400296 -186.765946)
		(width 0.1016)
		(layer "F.Cu")
		(net "UART_T10_NODE3_RXD")
	)
	(segment
		(start 131.400296 -186.190128)
		(end 131.81076 -185.779664)
		(width 0.1016)
		(layer "F.Cu")
		(net "UART_T10_NODE3_RXD")
	)
	(segment
		(start 131.400296 -186.765946)
		(end 131.400296 -186.190128)
		(width 0.1016)
		(layer "F.Cu")
		(net "UART_T10_NODE3_RXD")
	)
	(segment
		(start 142.52575 -164.903404)
		(end 142.134336 -165.294818)
		(width 0.1016)
		(layer "F.Cu")
		(net "UART_T10_NODE3_RXD")
	)
	(segment
		(start 142.52575 -163.358576)
		(end 142.52575 -164.903404)
		(width 0.1016)
		(layer "F.Cu")
		(net "UART_T10_NODE3_RXD")
	)
	(via
		(at 131.30276 -186.863482)
		(size 0.508)
		(drill 0.254)
		(layers "F.Cu" "B.Cu")
		(net "UART_T10_NODE3_RXD")
	)
	(via
		(at 142.09776 -165.294818)
		(size 0.508)
		(drill 0.254)
		(layers "F.Cu" "B.Cu")
		(net "UART_T10_NODE3_RXD")
	)
	(segment
		(start 137.465054 -181.835806)
		(end 138.82116 -181.835806)
		(width 0.1143)
		(layer "In7.Cu")
		(net "UART_T10_NODE3_RXD")
	)
	(segment
		(start 140.152374 -180.504592)
		(end 140.152374 -178.644042)
		(width 0.1143)
		(layer "In7.Cu")
		(net "UART_T10_NODE3_RXD")
	)
	(segment
		(start 136.266936 -185.621168)
		(end 136.266936 -183.033924)
		(width 0.1143)
		(layer "In7.Cu")
		(net "UART_T10_NODE3_RXD")
	)
	(segment
		(start 138.82116 -181.835806)
		(end 140.152374 -180.504592)
		(width 0.1143)
		(layer "In7.Cu")
		(net "UART_T10_NODE3_RXD")
	)
	(segment
		(start 135.815324 -186.882786)
		(end 135.815324 -186.07278)
		(width 0.1143)
		(layer "In7.Cu")
		(net "UART_T10_NODE3_RXD")
	)
	(segment
		(start 139.533122 -178.02479)
		(end 139.533122 -167.859456)
		(width 0.1143)
		(layer "In7.Cu")
		(net "UART_T10_NODE3_RXD")
	)
	(segment
		(start 131.30276 -186.863482)
		(end 131.318508 -186.863482)
		(width 0.1143)
		(layer "In7.Cu")
		(net "UART_T10_NODE3_RXD")
	)
	(segment
		(start 135.357362 -187.340748)
		(end 135.815324 -186.882786)
		(width 0.1143)
		(layer "In7.Cu")
		(net "UART_T10_NODE3_RXD")
	)
	(segment
		(start 131.318508 -186.863482)
		(end 131.795774 -187.340748)
		(width 0.1143)
		(layer "In7.Cu")
		(net "UART_T10_NODE3_RXD")
	)
	(segment
		(start 135.815324 -186.07278)
		(end 136.266936 -185.621168)
		(width 0.1143)
		(layer "In7.Cu")
		(net "UART_T10_NODE3_RXD")
	)
	(segment
		(start 131.795774 -187.340748)
		(end 135.357362 -187.340748)
		(width 0.1143)
		(layer "In7.Cu")
		(net "UART_T10_NODE3_RXD")
	)
	(segment
		(start 140.152374 -178.644042)
		(end 139.533122 -178.02479)
		(width 0.1143)
		(layer "In7.Cu")
		(net "UART_T10_NODE3_RXD")
	)
	(segment
		(start 139.533122 -167.859456)
		(end 142.09776 -165.294818)
		(width 0.1143)
		(layer "In7.Cu")
		(net "UART_T10_NODE3_RXD")
	)
	(segment
		(start 136.266936 -183.033924)
		(end 137.465054 -181.835806)
		(width 0.1143)
		(layer "In7.Cu")
		(net "UART_T10_NODE3_RXD")
	)
	(segment
		(start 133.716522 -51.312572)
		(end 133.716522 -49.305464)
		(width 0.1016)
		(layer "F.Cu")
		(net "UART_TX_P3")
	)
	(segment
		(start 135.01878 -181.15153)
		(end 135.01878 -180.573172)
		(width 0.1016)
		(layer "F.Cu")
		(net "UART_TX_P3")
	)
	(segment
		(start 133.206744 -53.975)
		(end 133.19887 -53.982874)
		(width 0.1016)
		(layer "F.Cu")
		(net "UART_TX_P3")
	)
	(segment
		(start 135.01878 -180.573172)
		(end 135.054848 -180.537104)
		(width 0.1016)
		(layer "F.Cu")
		(net "UART_TX_P3")
	)
	(segment
		(start 134.239 -51.83505)
		(end 134.366 -51.96205)
		(width 0.1016)
		(layer "F.Cu")
		(net "UART_TX_P3")
	)
	(segment
		(start 134.366 -51.96205)
		(end 134.366 -53.467)
		(width 0.1016)
		(layer "F.Cu")
		(net "UART_TX_P3")
	)
	(segment
		(start 135.054848 -180.537104)
		(end 135.054848 -179.669186)
		(width 0.1016)
		(layer "F.Cu")
		(net "UART_TX_P3")
	)
	(segment
		(start 135.025638 -179.639976)
		(end 135.025638 -178.858672)
		(width 0.1016)
		(layer "F.Cu")
		(net "UART_TX_P3")
	)
	(segment
		(start 135.054848 -179.669186)
		(end 135.025638 -179.639976)
		(width 0.1016)
		(layer "F.Cu")
		(net "UART_TX_P3")
	)
	(segment
		(start 134.239 -51.83505)
		(end 133.716522 -51.312572)
		(width 0.1016)
		(layer "F.Cu")
		(net "UART_TX_P3")
	)
	(segment
		(start 133.858 -53.975)
		(end 133.206744 -53.975)
		(width 0.1016)
		(layer "F.Cu")
		(net "UART_TX_P3")
	)
	(segment
		(start 135.025638 -177.167286)
		(end 135.025638 -178.858672)
		(width 0.1016)
		(layer "F.Cu")
		(net "UART_TX_P3")
	)
	(segment
		(start 134.366 -53.467)
		(end 133.858 -53.975)
		(width 0.1016)
		(layer "F.Cu")
		(net "UART_TX_P3")
	)
	(via
		(at 133.716522 -49.305464)
		(size 0.508)
		(drill 0.254)
		(layers "F.Cu" "B.Cu")
		(net "UART_TX_P3")
	)
	(via
		(at 133.19887 -53.982874)
		(size 0.508)
		(drill 0.254)
		(layers "F.Cu" "B.Cu")
		(net "UART_TX_P3")
	)
	(via
		(at 135.025638 -177.167286)
		(size 0.508)
		(drill 0.254)
		(layers "F.Cu" "B.Cu")
		(net "UART_TX_P3")
	)
	(segment
		(start 136.144 -169.855388)
		(end 137.608056 -168.391332)
		(width 0.1143)
		(layer "In2.Cu")
		(net "UART_TX_P3")
	)
	(segment
		(start 156.689552 -164.33292)
		(end 156.75864 -164.263832)
		(width 0.1143)
		(layer "In2.Cu")
		(net "UART_TX_P3")
	)
	(segment
		(start 153.366216 -164.67963)
		(end 153.505662 -164.819076)
		(width 0.1143)
		(layer "In2.Cu")
		(net "UART_TX_P3")
	)
	(segment
		(start 191.135 -128.27)
		(end 191.135 -122.301)
		(width 0.1143)
		(layer "In2.Cu")
		(net "UART_TX_P3")
	)
	(segment
		(start 175.66386 -85.567266)
		(end 162.41014 -85.567266)
		(width 0.1143)
		(layer "In2.Cu")
		(net "UART_TX_P3")
	)
	(segment
		(start 181.617874 -162.37077)
		(end 190.5 -153.488644)
		(width 0.1143)
		(layer "In2.Cu")
		(net "UART_TX_P3")
	)
	(segment
		(start 156.75864 -164.263832)
		(end 169.328338 -164.263832)
		(width 0.1143)
		(layer "In2.Cu")
		(net "UART_TX_P3")
	)
	(segment
		(start 148.300186 -85.513164)
		(end 137.11428 -74.327258)
		(width 0.1143)
		(layer "In2.Cu")
		(net "UART_TX_P3")
	)
	(segment
		(start 190.5 -147.913598)
		(end 190.931292 -147.482306)
		(width 0.1143)
		(layer "In2.Cu")
		(net "UART_TX_P3")
	)
	(segment
		(start 155.136596 -85.48624)
		(end 152.813004 -85.48624)
		(width 0.1143)
		(layer "In2.Cu")
		(net "UART_TX_P3")
	)
	(segment
		(start 171.2214 -162.37077)
		(end 181.617874 -162.37077)
		(width 0.1143)
		(layer "In2.Cu")
		(net "UART_TX_P3")
	)
	(segment
		(start 161.944812 -86.032594)
		(end 155.68295 -86.032594)
		(width 0.1143)
		(layer "In2.Cu")
		(net "UART_TX_P3")
	)
	(segment
		(start 162.41014 -85.567266)
		(end 161.944812 -86.032594)
		(width 0.1143)
		(layer "In2.Cu")
		(net "UART_TX_P3")
	)
	(segment
		(start 155.68295 -86.032594)
		(end 155.136596 -85.48624)
		(width 0.1143)
		(layer "In2.Cu")
		(net "UART_TX_P3")
	)
	(segment
		(start 137.11428 -74.327258)
		(end 137.11428 -72.293988)
		(width 0.1143)
		(layer "In2.Cu")
		(net "UART_TX_P3")
	)
	(segment
		(start 145.586704 -165.55085)
		(end 146.284696 -164.852858)
		(width 0.1143)
		(layer "In2.Cu")
		(net "UART_TX_P3")
	)
	(segment
		(start 175.66386 -85.568282)
		(end 175.66386 -85.567266)
		(width 0.1143)
		(layer "In2.Cu")
		(net "UART_TX_P3")
	)
	(segment
		(start 139.456414 -168.391332)
		(end 140.84554 -167.002206)
		(width 0.1143)
		(layer "In2.Cu")
		(net "UART_TX_P3")
	)
	(segment
		(start 178.270916 -85.753702)
		(end 175.84928 -85.753702)
		(width 0.1143)
		(layer "In2.Cu")
		(net "UART_TX_P3")
	)
	(segment
		(start 190.931292 -98.414078)
		(end 178.270916 -85.753702)
		(width 0.1143)
		(layer "In2.Cu")
		(net "UART_TX_P3")
	)
	(segment
		(start 175.84928 -85.753702)
		(end 175.66386 -85.568282)
		(width 0.1143)
		(layer "In2.Cu")
		(net "UART_TX_P3")
	)
	(segment
		(start 190.931292 -128.473708)
		(end 191.135 -128.27)
		(width 0.1143)
		(layer "In2.Cu")
		(net "UART_TX_P3")
	)
	(segment
		(start 143.036036 -165.55085)
		(end 145.586704 -165.55085)
		(width 0.1143)
		(layer "In2.Cu")
		(net "UART_TX_P3")
	)
	(segment
		(start 153.505662 -164.819076)
		(end 155.236164 -164.819076)
		(width 0.1143)
		(layer "In2.Cu")
		(net "UART_TX_P3")
	)
	(segment
		(start 149.064472 -164.852858)
		(end 149.2377 -164.67963)
		(width 0.1143)
		(layer "In2.Cu")
		(net "UART_TX_P3")
	)
	(segment
		(start 134.156196 -68.352416)
		(end 132.8293 -67.02552)
		(width 0.1143)
		(layer "In2.Cu")
		(net "UART_TX_P3")
	)
	(segment
		(start 137.608056 -168.391332)
		(end 139.456414 -168.391332)
		(width 0.1143)
		(layer "In2.Cu")
		(net "UART_TX_P3")
	)
	(segment
		(start 135.025638 -177.116486)
		(end 136.144 -175.998124)
		(width 0.1143)
		(layer "In2.Cu")
		(net "UART_TX_P3")
	)
	(segment
		(start 140.84554 -167.002206)
		(end 141.58468 -167.002206)
		(width 0.1143)
		(layer "In2.Cu")
		(net "UART_TX_P3")
	)
	(segment
		(start 149.2377 -164.67963)
		(end 153.366216 -164.67963)
		(width 0.1143)
		(layer "In2.Cu")
		(net "UART_TX_P3")
	)
	(segment
		(start 136.144 -175.998124)
		(end 136.144 -169.855388)
		(width 0.1143)
		(layer "In2.Cu")
		(net "UART_TX_P3")
	)
	(segment
		(start 132.8293 -67.02552)
		(end 132.8293 -54.352444)
		(width 0.1143)
		(layer "In2.Cu")
		(net "UART_TX_P3")
	)
	(segment
		(start 152.813004 -85.48624)
		(end 152.78608 -85.513164)
		(width 0.1143)
		(layer "In2.Cu")
		(net "UART_TX_P3")
	)
	(segment
		(start 132.8293 -54.352444)
		(end 133.19887 -53.982874)
		(width 0.1143)
		(layer "In2.Cu")
		(net "UART_TX_P3")
	)
	(segment
		(start 155.236164 -164.819076)
		(end 155.72232 -164.33292)
		(width 0.1143)
		(layer "In2.Cu")
		(net "UART_TX_P3")
	)
	(segment
		(start 152.78608 -85.513164)
		(end 148.300186 -85.513164)
		(width 0.1143)
		(layer "In2.Cu")
		(net "UART_TX_P3")
	)
	(segment
		(start 146.284696 -164.852858)
		(end 149.064472 -164.852858)
		(width 0.1143)
		(layer "In2.Cu")
		(net "UART_TX_P3")
	)
	(segment
		(start 134.156196 -69.335904)
		(end 134.156196 -68.352416)
		(width 0.1143)
		(layer "In2.Cu")
		(net "UART_TX_P3")
	)
	(segment
		(start 190.931292 -147.482306)
		(end 190.931292 -128.473708)
		(width 0.1143)
		(layer "In2.Cu")
		(net "UART_TX_P3")
	)
	(segment
		(start 190.931292 -122.097292)
		(end 190.931292 -98.414078)
		(width 0.1143)
		(layer "In2.Cu")
		(net "UART_TX_P3")
	)
	(segment
		(start 155.72232 -164.33292)
		(end 156.689552 -164.33292)
		(width 0.1143)
		(layer "In2.Cu")
		(net "UART_TX_P3")
	)
	(segment
		(start 141.58468 -167.002206)
		(end 143.036036 -165.55085)
		(width 0.1143)
		(layer "In2.Cu")
		(net "UART_TX_P3")
	)
	(segment
		(start 169.328338 -164.263832)
		(end 171.2214 -162.37077)
		(width 0.1143)
		(layer "In2.Cu")
		(net "UART_TX_P3")
	)
	(segment
		(start 191.135 -122.301)
		(end 190.931292 -122.097292)
		(width 0.1143)
		(layer "In2.Cu")
		(net "UART_TX_P3")
	)
	(segment
		(start 135.025638 -177.167286)
		(end 135.025638 -177.116486)
		(width 0.1143)
		(layer "In2.Cu")
		(net "UART_TX_P3")
	)
	(segment
		(start 137.11428 -72.293988)
		(end 134.156196 -69.335904)
		(width 0.1143)
		(layer "In2.Cu")
		(net "UART_TX_P3")
	)
	(segment
		(start 190.5 -153.488644)
		(end 190.5 -147.913598)
		(width 0.1143)
		(layer "In2.Cu")
		(net "UART_TX_P3")
	)
	(segment
		(start 133.716522 -49.036478)
		(end 133.716522 -49.305464)
		(width 0.1143)
		(layer "In7.Cu")
		(net "UART_TX_P3")
	)
	(segment
		(start 134.663942 -48.089058)
		(end 133.716522 -49.036478)
		(width 0.1143)
		(layer "In7.Cu")
		(net "UART_TX_P3")
	)
	(segment
		(start 145.19656 -46.068234)
		(end 143.175736 -48.089058)
		(width 0.1143)
		(layer "In7.Cu")
		(net "UART_TX_P3")
	)
	(segment
		(start 151.135588 -27.902916)
		(end 149.505162 -27.902916)
		(width 0.1143)
		(layer "In7.Cu")
		(net "UART_TX_P3")
	)
	(segment
		(start 154.54122 -24.497284)
		(end 151.135588 -27.902916)
		(width 0.1143)
		(layer "In7.Cu")
		(net "UART_TX_P3")
	)
	(segment
		(start 156.376878 -21.56841)
		(end 154.54122 -23.404068)
		(width 0.1143)
		(layer "In7.Cu")
		(net "UART_TX_P3")
	)
	(segment
		(start 143.175736 -48.089058)
		(end 134.663942 -48.089058)
		(width 0.1143)
		(layer "In7.Cu")
		(net "UART_TX_P3")
	)
	(segment
		(start 154.54122 -23.404068)
		(end 154.54122 -24.497284)
		(width 0.1143)
		(layer "In7.Cu")
		(net "UART_TX_P3")
	)
	(segment
		(start 149.505162 -27.902916)
		(end 145.19656 -32.211518)
		(width 0.1143)
		(layer "In7.Cu")
		(net "UART_TX_P3")
	)
	(segment
		(start 145.19656 -32.211518)
		(end 145.19656 -46.068234)
		(width 0.1143)
		(layer "In7.Cu")
		(net "UART_TX_P3")
	)
	(segment
		(start 125.59284 -171.691808)
		(end 126.347728 -170.93692)
		(width 0.1016)
		(layer "F.Cu")
		(net "UART_T8_NODE1_RXD")
	)
	(segment
		(start 121.65076 -187.726574)
		(end 121.65076 -187.592716)
		(width 0.1016)
		(layer "F.Cu")
		(net "UART_T8_NODE1_RXD")
	)
	(segment
		(start 125.59284 -173.338744)
		(end 125.59284 -171.691808)
		(width 0.1016)
		(layer "F.Cu")
		(net "UART_T8_NODE1_RXD")
	)
	(segment
		(start 128.12522 -170.93692)
		(end 128.296924 -171.108624)
		(width 0.1016)
		(layer "F.Cu")
		(net "UART_T8_NODE1_RXD")
	)
	(segment
		(start 120.63476 -187.613036)
		(end 121.15292 -187.094876)
		(width 0.1016)
		(layer "F.Cu")
		(net "UART_T8_NODE1_RXD")
	)
	(segment
		(start 120.63476 -187.726574)
		(end 120.63476 -187.613036)
		(width 0.1016)
		(layer "F.Cu")
		(net "UART_T8_NODE1_RXD")
	)
	(segment
		(start 121.65076 -187.592716)
		(end 121.15292 -187.094876)
		(width 0.1016)
		(layer "F.Cu")
		(net "UART_T8_NODE1_RXD")
	)
	(segment
		(start 126.347728 -170.93692)
		(end 128.12522 -170.93692)
		(width 0.1016)
		(layer "F.Cu")
		(net "UART_T8_NODE1_RXD")
	)
	(segment
		(start 128.296924 -171.108624)
		(end 129.775712 -171.108624)
		(width 0.1016)
		(layer "F.Cu")
		(net "UART_T8_NODE1_RXD")
	)
	(segment
		(start 126.130558 -173.876462)
		(end 125.59284 -173.338744)
		(width 0.1016)
		(layer "F.Cu")
		(net "UART_T8_NODE1_RXD")
	)
	(via
		(at 126.130558 -173.876462)
		(size 0.508)
		(drill 0.254)
		(layers "F.Cu" "B.Cu")
		(net "UART_T8_NODE1_RXD")
	)
	(via
		(at 121.15292 -187.094876)
		(size 0.508)
		(drill 0.254)
		(layers "F.Cu" "B.Cu")
		(net "UART_T8_NODE1_RXD")
	)
	(segment
		(start 121.713244 -187.6552)
		(end 122.755914 -187.6552)
		(width 0.1016)
		(layer "B.Cu")
		(net "UART_T8_NODE1_RXD")
	)
	(segment
		(start 128.69926 -177.752756)
		(end 129.0574 -177.394616)
		(width 0.1016)
		(layer "B.Cu")
		(net "UART_T8_NODE1_RXD")
	)
	(segment
		(start 129.151634 -175.861218)
		(end 129.151634 -175.413924)
		(width 0.1016)
		(layer "B.Cu")
		(net "UART_T8_NODE1_RXD")
	)
	(segment
		(start 123.2662 -186.1566)
		(end 126.145798 -183.276748)
		(width 0.1016)
		(layer "B.Cu")
		(net "UART_T8_NODE1_RXD")
	)
	(segment
		(start 128.008126 -183.276748)
		(end 128.69926 -182.585614)
		(width 0.1016)
		(layer "B.Cu")
		(net "UART_T8_NODE1_RXD")
	)
	(segment
		(start 129.0574 -176.973484)
		(end 128.79578 -176.711864)
		(width 0.1016)
		(layer "B.Cu")
		(net "UART_T8_NODE1_RXD")
	)
	(segment
		(start 129.0574 -177.394616)
		(end 129.0574 -176.973484)
		(width 0.1016)
		(layer "B.Cu")
		(net "UART_T8_NODE1_RXD")
	)
	(segment
		(start 128.824482 -175.086772)
		(end 127.340868 -175.086772)
		(width 0.1016)
		(layer "B.Cu")
		(net "UART_T8_NODE1_RXD")
	)
	(segment
		(start 127.340868 -175.086772)
		(end 126.130558 -173.876462)
		(width 0.1016)
		(layer "B.Cu")
		(net "UART_T8_NODE1_RXD")
	)
	(segment
		(start 122.755914 -187.6552)
		(end 123.2662 -187.144914)
		(width 0.1016)
		(layer "B.Cu")
		(net "UART_T8_NODE1_RXD")
	)
	(segment
		(start 121.15292 -187.094876)
		(end 121.713244 -187.6552)
		(width 0.1016)
		(layer "B.Cu")
		(net "UART_T8_NODE1_RXD")
	)
	(segment
		(start 123.2662 -187.144914)
		(end 123.2662 -186.1566)
		(width 0.1016)
		(layer "B.Cu")
		(net "UART_T8_NODE1_RXD")
	)
	(segment
		(start 128.79578 -176.711864)
		(end 128.79578 -176.217072)
		(width 0.1016)
		(layer "B.Cu")
		(net "UART_T8_NODE1_RXD")
	)
	(segment
		(start 128.69926 -182.585614)
		(end 128.69926 -177.752756)
		(width 0.1016)
		(layer "B.Cu")
		(net "UART_T8_NODE1_RXD")
	)
	(segment
		(start 126.145798 -183.276748)
		(end 128.008126 -183.276748)
		(width 0.1016)
		(layer "B.Cu")
		(net "UART_T8_NODE1_RXD")
	)
	(segment
		(start 128.79578 -176.217072)
		(end 129.151634 -175.861218)
		(width 0.1016)
		(layer "B.Cu")
		(net "UART_T8_NODE1_RXD")
	)
	(segment
		(start 129.151634 -175.413924)
		(end 128.824482 -175.086772)
		(width 0.1016)
		(layer "B.Cu")
		(net "UART_T8_NODE1_RXD")
	)
	(segment
		(start 127.521208 -169.799254)
		(end 126.917958 -170.402504)
		(width 0.1016)
		(layer "F.Cu")
		(net "UART_T8_NODE2_RXD")
	)
	(segment
		(start 118.3259 -186.290712)
		(end 118.04396 -186.572652)
		(width 0.1016)
		(layer "F.Cu")
		(net "UART_T8_NODE2_RXD")
	)
	(segment
		(start 128.453896 -169.799254)
		(end 127.521208 -169.799254)
		(width 0.1016)
		(layer "F.Cu")
		(net "UART_T8_NODE2_RXD")
	)
	(segment
		(start 118.47576 -186.140852)
		(end 118.3259 -186.290712)
		(width 0.1016)
		(layer "F.Cu")
		(net "UART_T8_NODE2_RXD")
	)
	(segment
		(start 129.775712 -170.108626)
		(end 128.763268 -170.108626)
		(width 0.1016)
		(layer "F.Cu")
		(net "UART_T8_NODE2_RXD")
	)
	(segment
		(start 118.47576 -185.605674)
		(end 118.47576 -186.140852)
		(width 0.1016)
		(layer "F.Cu")
		(net "UART_T8_NODE2_RXD")
	)
	(segment
		(start 118.04396 -187.294774)
		(end 118.47576 -187.726574)
		(width 0.1016)
		(layer "F.Cu")
		(net "UART_T8_NODE2_RXD")
	)
	(segment
		(start 118.04396 -186.572652)
		(end 118.04396 -187.294774)
		(width 0.1016)
		(layer "F.Cu")
		(net "UART_T8_NODE2_RXD")
	)
	(segment
		(start 126.917958 -170.402504)
		(end 126.099062 -170.402504)
		(width 0.1016)
		(layer "F.Cu")
		(net "UART_T8_NODE2_RXD")
	)
	(segment
		(start 128.763268 -170.108626)
		(end 128.453896 -169.799254)
		(width 0.1016)
		(layer "F.Cu")
		(net "UART_T8_NODE2_RXD")
	)
	(via
		(at 126.099062 -170.402504)
		(size 0.508)
		(drill 0.254)
		(layers "F.Cu" "B.Cu")
		(net "UART_T8_NODE2_RXD")
	)
	(via
		(at 118.3259 -186.290712)
		(size 0.508)
		(drill 0.254)
		(layers "F.Cu" "B.Cu")
		(net "UART_T8_NODE2_RXD")
	)
	(segment
		(start 112.27816 -187.000134)
		(end 112.27816 -186.164982)
		(width 0.1143)
		(layer "In7.Cu")
		(net "UART_T8_NODE2_RXD")
	)
	(segment
		(start 114.872008 -179.038504)
		(end 121.713752 -179.038504)
		(width 0.1143)
		(layer "In7.Cu")
		(net "UART_T8_NODE2_RXD")
	)
	(segment
		(start 112.27816 -186.164982)
		(end 111.29391 -185.180732)
		(width 0.1143)
		(layer "In7.Cu")
		(net "UART_T8_NODE2_RXD")
	)
	(segment
		(start 111.11865 -183.7182)
		(end 111.11865 -182.791862)
		(width 0.1143)
		(layer "In7.Cu")
		(net "UART_T8_NODE2_RXD")
	)
	(segment
		(start 126.9365 -176.480724)
		(end 126.9365 -172.975778)
		(width 0.1143)
		(layer "In7.Cu")
		(net "UART_T8_NODE2_RXD")
	)
	(segment
		(start 111.29391 -185.180732)
		(end 111.29391 -183.89346)
		(width 0.1143)
		(layer "In7.Cu")
		(net "UART_T8_NODE2_RXD")
	)
	(segment
		(start 126.905512 -176.511712)
		(end 126.90602 -176.511712)
		(width 0.1143)
		(layer "In7.Cu")
		(net "UART_T8_NODE2_RXD")
	)
	(segment
		(start 123.522232 -177.230024)
		(end 126.1872 -177.230024)
		(width 0.1143)
		(layer "In7.Cu")
		(net "UART_T8_NODE2_RXD")
	)
	(segment
		(start 126.9365 -172.975778)
		(end 126.94031 -172.971968)
		(width 0.1143)
		(layer "In7.Cu")
		(net "UART_T8_NODE2_RXD")
	)
	(segment
		(start 126.90602 -176.511712)
		(end 126.90602 -176.511204)
		(width 0.1143)
		(layer "In7.Cu")
		(net "UART_T8_NODE2_RXD")
	)
	(segment
		(start 118.03761 -187.123578)
		(end 117.72519 -187.435998)
		(width 0.1143)
		(layer "In7.Cu")
		(net "UART_T8_NODE2_RXD")
	)
	(segment
		(start 121.713752 -179.038504)
		(end 123.522232 -177.230024)
		(width 0.1143)
		(layer "In7.Cu")
		(net "UART_T8_NODE2_RXD")
	)
	(segment
		(start 118.3259 -186.290712)
		(end 118.03761 -186.579002)
		(width 0.1143)
		(layer "In7.Cu")
		(net "UART_T8_NODE2_RXD")
	)
	(segment
		(start 117.72519 -187.435998)
		(end 112.714024 -187.435998)
		(width 0.1143)
		(layer "In7.Cu")
		(net "UART_T8_NODE2_RXD")
	)
	(segment
		(start 118.03761 -186.579002)
		(end 118.03761 -187.123578)
		(width 0.1143)
		(layer "In7.Cu")
		(net "UART_T8_NODE2_RXD")
	)
	(segment
		(start 126.90602 -176.511204)
		(end 126.9365 -176.480724)
		(width 0.1143)
		(layer "In7.Cu")
		(net "UART_T8_NODE2_RXD")
	)
	(segment
		(start 126.1872 -177.230024)
		(end 126.905512 -176.511712)
		(width 0.1143)
		(layer "In7.Cu")
		(net "UART_T8_NODE2_RXD")
	)
	(segment
		(start 111.11865 -182.791862)
		(end 114.872008 -179.038504)
		(width 0.1143)
		(layer "In7.Cu")
		(net "UART_T8_NODE2_RXD")
	)
	(segment
		(start 111.29391 -183.89346)
		(end 111.11865 -183.7182)
		(width 0.1143)
		(layer "In7.Cu")
		(net "UART_T8_NODE2_RXD")
	)
	(segment
		(start 126.94031 -172.971968)
		(end 126.94031 -171.243752)
		(width 0.1143)
		(layer "In7.Cu")
		(net "UART_T8_NODE2_RXD")
	)
	(segment
		(start 112.714024 -187.435998)
		(end 112.27816 -187.000134)
		(width 0.1143)
		(layer "In7.Cu")
		(net "UART_T8_NODE2_RXD")
	)
	(segment
		(start 126.94031 -171.243752)
		(end 126.099062 -170.402504)
		(width 0.1143)
		(layer "In7.Cu")
		(net "UART_T8_NODE2_RXD")
	)
	(segment
		(start 128.262888 -170.608752)
		(end 128.044956 -170.39082)
		(width 0.1016)
		(layer "F.Cu")
		(net "UART_T8_NODE2_TXD")
	)
	(segment
		(start 129.775712 -170.608752)
		(end 128.262888 -170.608752)
		(width 0.1016)
		(layer "F.Cu")
		(net "UART_T8_NODE2_TXD")
	)
	(via
		(at 128.044956 -170.39082)
		(size 0.508)
		(drill 0.254)
		(layers "F.Cu" "B.Cu")
		(net "UART_T8_NODE2_TXD")
	)
	(segment
		(start 128.131824 -170.303952)
		(end 128.044956 -170.39082)
		(width 0.1016)
		(layer "B.Cu")
		(net "UART_T8_NODE2_TXD")
	)
	(segment
		(start 129.510536 -170.303952)
		(end 128.131824 -170.303952)
		(width 0.1016)
		(layer "B.Cu")
		(net "UART_T8_NODE2_TXD")
	)
	(segment
		(start 128.646682 -173.608746)
		(end 129.775712 -173.608746)
		(width 0.1016)
		(layer "F.Cu")
		(net "UART_T7_NODE3_TXD")
	)
	(segment
		(start 128.64338 -173.612048)
		(end 128.646682 -173.608746)
		(width 0.1016)
		(layer "F.Cu")
		(net "UART_T7_NODE3_TXD")
	)
	(via
		(at 128.64338 -173.612048)
		(size 0.508)
		(drill 0.254)
		(layers "F.Cu" "B.Cu")
		(net "UART_T7_NODE3_TXD")
	)
	(via
		(at 114.06124 -183.327294)
		(size 0.508)
		(drill 0.254)
		(layers "F.Cu" "B.Cu")
		(net "UART_T7_NODE3_TXD")
	)
	(segment
		(start 111.730282 -182.658512)
		(end 111.10722 -182.658512)
		(width 0.1016)
		(layer "B.Cu")
		(net "UART_T7_NODE3_TXD")
	)
	(segment
		(start 114.06124 -183.327294)
		(end 113.693702 -182.959756)
		(width 0.1016)
		(layer "B.Cu")
		(net "UART_T7_NODE3_TXD")
	)
	(segment
		(start 112.834674 -182.959756)
		(end 112.61344 -183.18099)
		(width 0.1016)
		(layer "B.Cu")
		(net "UART_T7_NODE3_TXD")
	)
	(segment
		(start 112.25276 -183.18099)
		(end 111.730282 -182.658512)
		(width 0.1016)
		(layer "B.Cu")
		(net "UART_T7_NODE3_TXD")
	)
	(segment
		(start 113.693702 -182.959756)
		(end 112.834674 -182.959756)
		(width 0.1016)
		(layer "B.Cu")
		(net "UART_T7_NODE3_TXD")
	)
	(segment
		(start 112.61344 -183.18099)
		(end 112.25276 -183.18099)
		(width 0.1016)
		(layer "B.Cu")
		(net "UART_T7_NODE3_TXD")
	)
	(segment
		(start 129.066036 -177.26787)
		(end 129.066036 -174.034704)
		(width 0.1143)
		(layer "In7.Cu")
		(net "UART_T7_NODE3_TXD")
	)
	(segment
		(start 124.372624 -180.817774)
		(end 127.211836 -178.906932)
		(width 0.1143)
		(layer "In7.Cu")
		(net "UART_T7_NODE3_TXD")
	)
	(segment
		(start 127.430276 -178.906932)
		(end 128.715008 -177.6222)
		(width 0.1143)
		(layer "In7.Cu")
		(net "UART_T7_NODE3_TXD")
	)
	(segment
		(start 129.066036 -174.034704)
		(end 128.64338 -173.612048)
		(width 0.1143)
		(layer "In7.Cu")
		(net "UART_T7_NODE3_TXD")
	)
	(segment
		(start 123.844304 -181.165246)
		(end 124.372624 -180.96484)
		(width 0.1143)
		(layer "In7.Cu")
		(net "UART_T7_NODE3_TXD")
	)
	(segment
		(start 114.06124 -183.327294)
		(end 115.04295 -182.345584)
		(width 0.1143)
		(layer "In7.Cu")
		(net "UART_T7_NODE3_TXD")
	)
	(segment
		(start 128.728978 -177.6222)
		(end 129.055114 -177.296064)
		(width 0.1143)
		(layer "In7.Cu")
		(net "UART_T7_NODE3_TXD")
	)
	(segment
		(start 128.715008 -177.6222)
		(end 128.728978 -177.6222)
		(width 0.1143)
		(layer "In7.Cu")
		(net "UART_T7_NODE3_TXD")
	)
	(segment
		(start 124.372624 -180.96484)
		(end 124.372624 -180.817774)
		(width 0.1143)
		(layer "In7.Cu")
		(net "UART_T7_NODE3_TXD")
	)
	(segment
		(start 118.02364 -182.345584)
		(end 123.844304 -181.165246)
		(width 0.1143)
		(layer "In7.Cu")
		(net "UART_T7_NODE3_TXD")
	)
	(segment
		(start 127.211836 -178.906932)
		(end 127.430276 -178.906932)
		(width 0.1143)
		(layer "In7.Cu")
		(net "UART_T7_NODE3_TXD")
	)
	(segment
		(start 129.055114 -177.296064)
		(end 129.066036 -177.26787)
		(width 0.1143)
		(layer "In7.Cu")
		(net "UART_T7_NODE3_TXD")
	)
	(segment
		(start 115.04295 -182.345584)
		(end 118.02364 -182.345584)
		(width 0.1143)
		(layer "In7.Cu")
		(net "UART_T7_NODE3_TXD")
	)
	(segment
		(start 153.90876 -183.441086)
		(end 153.90876 -184.805574)
		(width 0.1016)
		(layer "F.Cu")
		(net "T12_NODE2_EN")
	)
	(segment
		(start 152.10282 -180.035454)
		(end 152.344882 -180.277516)
		(width 0.1016)
		(layer "F.Cu")
		(net "T12_NODE2_EN")
	)
	(segment
		(start 152.584658 -174.466504)
		(end 152.10282 -174.948342)
		(width 0.1016)
		(layer "F.Cu")
		(net "T12_NODE2_EN")
	)
	(segment
		(start 152.344882 -181.877208)
		(end 153.90876 -183.441086)
		(width 0.1016)
		(layer "F.Cu")
		(net "T12_NODE2_EN")
	)
	(segment
		(start 152.10282 -174.948342)
		(end 152.10282 -180.035454)
		(width 0.1016)
		(layer "F.Cu")
		(net "T12_NODE2_EN")
	)
	(segment
		(start 152.344882 -180.277516)
		(end 152.344882 -181.877208)
		(width 0.1016)
		(layer "F.Cu")
		(net "T12_NODE2_EN")
	)
	(via
		(at 152.584658 -174.466504)
		(size 0.508)
		(drill 0.254)
		(layers "F.Cu" "B.Cu")
		(net "T12_NODE2_EN")
	)
	(segment
		(start 153.66111 -174.537624)
		(end 152.655778 -174.537624)
		(width 0.1016)
		(layer "B.Cu")
		(net "T12_NODE2_EN")
	)
	(segment
		(start 152.655778 -174.537624)
		(end 152.584658 -174.466504)
		(width 0.1016)
		(layer "B.Cu")
		(net "T12_NODE2_EN")
	)
	(segment
		(start 151.964898 -173.846744)
		(end 152.584658 -174.466504)
		(width 0.1016)
		(layer "B.Cu")
		(net "T12_NODE2_EN")
	)
	(segment
		(start 150.98776 -173.846744)
		(end 151.964898 -173.846744)
		(width 0.1016)
		(layer "B.Cu")
		(net "T12_NODE2_EN")
	)
	(via
		(at 106.00182 -182.22468)
		(size 0.508)
		(drill 0.254)
		(layers "F.Cu" "B.Cu")
		(net "T5_NODE2_EN")
	)
	(via
		(at 111.934752 -176.387252)
		(size 0.508)
		(drill 0.254)
		(layers "F.Cu" "B.Cu")
		(net "T5_NODE2_EN")
	)
	(segment
		(start 105.83418 -183.54929)
		(end 105.83418 -182.39232)
		(width 0.1016)
		(layer "B.Cu")
		(net "T5_NODE2_EN")
	)
	(segment
		(start 105.14076 -184.805574)
		(end 105.14076 -184.24271)
		(width 0.1016)
		(layer "B.Cu")
		(net "T5_NODE2_EN")
	)
	(segment
		(start 111.101124 -175.553624)
		(end 111.934752 -176.387252)
		(width 0.1016)
		(layer "B.Cu")
		(net "T5_NODE2_EN")
	)
	(segment
		(start 112.63884 -176.229518)
		(end 112.481106 -176.387252)
		(width 0.1016)
		(layer "B.Cu")
		(net "T5_NODE2_EN")
	)
	(segment
		(start 113.52276 -176.229518)
		(end 112.63884 -176.229518)
		(width 0.1016)
		(layer "B.Cu")
		(net "T5_NODE2_EN")
	)
	(segment
		(start 110.84941 -175.553624)
		(end 111.101124 -175.553624)
		(width 0.1016)
		(layer "B.Cu")
		(net "T5_NODE2_EN")
	)
	(segment
		(start 112.481106 -176.387252)
		(end 111.934752 -176.387252)
		(width 0.1016)
		(layer "B.Cu")
		(net "T5_NODE2_EN")
	)
	(segment
		(start 105.14076 -184.24271)
		(end 105.83418 -183.54929)
		(width 0.1016)
		(layer "B.Cu")
		(net "T5_NODE2_EN")
	)
	(segment
		(start 105.83418 -182.39232)
		(end 106.00182 -182.22468)
		(width 0.1016)
		(layer "B.Cu")
		(net "T5_NODE2_EN")
	)
	(segment
		(start 109.207808 -178.163474)
		(end 107.98556 -179.385722)
		(width 0.1143)
		(layer "In7.Cu")
		(net "T5_NODE2_EN")
	)
	(segment
		(start 110.15853 -178.163474)
		(end 109.207808 -178.163474)
		(width 0.1143)
		(layer "In7.Cu")
		(net "T5_NODE2_EN")
	)
	(segment
		(start 107.98556 -179.385722)
		(end 107.98556 -180.039518)
		(width 0.1143)
		(layer "In7.Cu")
		(net "T5_NODE2_EN")
	)
	(segment
		(start 111.934752 -176.387252)
		(end 110.15853 -178.163474)
		(width 0.1143)
		(layer "In7.Cu")
		(net "T5_NODE2_EN")
	)
	(segment
		(start 106.00182 -182.023258)
		(end 106.00182 -182.22468)
		(width 0.1143)
		(layer "In7.Cu")
		(net "T5_NODE2_EN")
	)
	(segment
		(start 107.98556 -180.039518)
		(end 106.00182 -182.023258)
		(width 0.1143)
		(layer "In7.Cu")
		(net "T5_NODE2_EN")
	)
	(segment
		(start 67.849496 -180.254148)
		(end 66.261234 -181.84241)
		(width 0.1016)
		(layer "F.Cu")
		(net "T1_NODE3_EN")
	)
	(segment
		(start 66.261234 -181.84241)
		(end 64.84874 -181.84241)
		(width 0.1016)
		(layer "F.Cu")
		(net "T1_NODE3_EN")
	)
	(segment
		(start 67.849496 -179.804568)
		(end 67.849496 -180.254148)
		(width 0.1016)
		(layer "F.Cu")
		(net "T1_NODE3_EN")
	)
	(via
		(at 67.849496 -179.804568)
		(size 0.508)
		(drill 0.254)
		(layers "F.Cu" "B.Cu")
		(net "T1_NODE3_EN")
	)
	(via
		(at 64.84874 -181.84241)
		(size 0.508)
		(drill 0.254)
		(layers "F.Cu" "B.Cu")
		(net "T1_NODE3_EN")
	)
	(segment
		(start 80.31226 -172.505624)
		(end 79.23149 -172.505624)
		(width 0.1016)
		(layer "B.Cu")
		(net "T1_NODE3_EN")
	)
	(segment
		(start 79.12354 -173.02988)
		(end 76.204572 -173.02988)
		(width 0.1016)
		(layer "B.Cu")
		(net "T1_NODE3_EN")
	)
	(segment
		(start 72.85355 -175.9204)
		(end 68.969382 -179.804568)
		(width 0.1016)
		(layer "B.Cu")
		(net "T1_NODE3_EN")
	)
	(segment
		(start 68.969382 -179.804568)
		(end 67.849496 -179.804568)
		(width 0.1016)
		(layer "B.Cu")
		(net "T1_NODE3_EN")
	)
	(segment
		(start 79.23149 -172.92193)
		(end 79.12354 -173.02988)
		(width 0.1016)
		(layer "B.Cu")
		(net "T1_NODE3_EN")
	)
	(segment
		(start 79.23149 -172.505624)
		(end 79.23149 -172.92193)
		(width 0.1016)
		(layer "B.Cu")
		(net "T1_NODE3_EN")
	)
	(segment
		(start 64.84874 -184.203594)
		(end 64.84874 -181.84241)
		(width 0.1016)
		(layer "B.Cu")
		(net "T1_NODE3_EN")
	)
	(segment
		(start 73.314052 -175.9204)
		(end 72.85355 -175.9204)
		(width 0.1016)
		(layer "B.Cu")
		(net "T1_NODE3_EN")
	)
	(segment
		(start 76.204572 -173.02988)
		(end 73.314052 -175.9204)
		(width 0.1016)
		(layer "B.Cu")
		(net "T1_NODE3_EN")
	)
	(segment
		(start 80.87614 -173.069504)
		(end 80.31226 -172.505624)
		(width 0.1016)
		(layer "B.Cu")
		(net "T1_NODE3_EN")
	)
	(segment
		(start 64.24676 -184.805574)
		(end 64.84874 -184.203594)
		(width 0.1016)
		(layer "B.Cu")
		(net "T1_NODE3_EN")
	)
	(segment
		(start 81.89976 -173.069504)
		(end 80.87614 -173.069504)
		(width 0.1016)
		(layer "B.Cu")
		(net "T1_NODE3_EN")
	)
	(segment
		(start 93.834712 -183.799988)
		(end 93.834712 -183.63946)
		(width 0.1016)
		(layer "F.Cu")
		(net "T5_NODE3_EN")
	)
	(segment
		(start 93.834712 -183.63946)
		(end 94.51594 -182.958232)
		(width 0.1016)
		(layer "F.Cu")
		(net "T5_NODE3_EN")
	)
	(via
		(at 105.17632 -183.218836)
		(size 0.508)
		(drill 0.254)
		(layers "F.Cu" "B.Cu")
		(net "T5_NODE3_EN")
	)
	(via
		(at 94.51594 -182.958232)
		(size 0.508)
		(drill 0.254)
		(layers "F.Cu" "B.Cu")
		(net "T5_NODE3_EN")
	)
	(segment
		(start 112.498124 -176.879504)
		(end 113.52276 -176.879504)
		(width 0.1016)
		(layer "B.Cu")
		(net "T5_NODE3_EN")
	)
	(segment
		(start 110.291118 -177.128424)
		(end 110.84941 -176.570132)
		(width 0.1016)
		(layer "B.Cu")
		(net "T5_NODE3_EN")
	)
	(segment
		(start 104.23652 -182.455566)
		(end 105.692448 -180.999638)
		(width 0.1016)
		(layer "B.Cu")
		(net "T5_NODE3_EN")
	)
	(segment
		(start 110.84941 -176.570132)
		(end 110.84941 -176.569624)
		(width 0.1016)
		(layer "B.Cu")
		(net "T5_NODE3_EN")
	)
	(segment
		(start 105.17632 -183.218836)
		(end 104.64165 -183.218836)
		(width 0.1016)
		(layer "B.Cu")
		(net "T5_NODE3_EN")
	)
	(segment
		(start 112.427258 -176.95037)
		(end 112.498124 -176.879504)
		(width 0.1016)
		(layer "B.Cu")
		(net "T5_NODE3_EN")
	)
	(segment
		(start 109.187488 -177.128424)
		(end 110.291118 -177.128424)
		(width 0.1016)
		(layer "B.Cu")
		(net "T5_NODE3_EN")
	)
	(segment
		(start 104.64165 -183.218836)
		(end 104.23652 -182.813706)
		(width 0.1016)
		(layer "B.Cu")
		(net "T5_NODE3_EN")
	)
	(segment
		(start 110.84941 -176.569624)
		(end 111.230156 -176.95037)
		(width 0.1016)
		(layer "B.Cu")
		(net "T5_NODE3_EN")
	)
	(segment
		(start 106.02722 -179.682394)
		(end 107.238038 -178.471576)
		(width 0.1016)
		(layer "B.Cu")
		(net "T5_NODE3_EN")
	)
	(segment
		(start 105.77449 -180.999638)
		(end 106.02722 -180.746908)
		(width 0.1016)
		(layer "B.Cu")
		(net "T5_NODE3_EN")
	)
	(segment
		(start 106.02722 -180.746908)
		(end 106.02722 -179.682394)
		(width 0.1016)
		(layer "B.Cu")
		(net "T5_NODE3_EN")
	)
	(segment
		(start 104.23652 -182.813706)
		(end 104.23652 -182.455566)
		(width 0.1016)
		(layer "B.Cu")
		(net "T5_NODE3_EN")
	)
	(segment
		(start 108.64977 -177.666142)
		(end 109.187488 -177.128424)
		(width 0.1016)
		(layer "B.Cu")
		(net "T5_NODE3_EN")
	)
	(segment
		(start 107.31881 -178.471576)
		(end 108.124244 -177.666142)
		(width 0.1016)
		(layer "B.Cu")
		(net "T5_NODE3_EN")
	)
	(segment
		(start 111.230156 -176.95037)
		(end 112.427258 -176.95037)
		(width 0.1016)
		(layer "B.Cu")
		(net "T5_NODE3_EN")
	)
	(segment
		(start 108.124244 -177.666142)
		(end 108.64977 -177.666142)
		(width 0.1016)
		(layer "B.Cu")
		(net "T5_NODE3_EN")
	)
	(segment
		(start 105.692448 -180.999638)
		(end 105.77449 -180.999638)
		(width 0.1016)
		(layer "B.Cu")
		(net "T5_NODE3_EN")
	)
	(segment
		(start 107.238038 -178.471576)
		(end 107.31881 -178.471576)
		(width 0.1016)
		(layer "B.Cu")
		(net "T5_NODE3_EN")
	)
	(segment
		(start 103.82377 -182.569866)
		(end 101.448108 -182.569866)
		(width 0.1143)
		(layer "In2.Cu")
		(net "T5_NODE3_EN")
	)
	(segment
		(start 101.059742 -182.958232)
		(end 94.51594 -182.958232)
		(width 0.1143)
		(layer "In2.Cu")
		(net "T5_NODE3_EN")
	)
	(segment
		(start 104.47274 -183.218836)
		(end 103.82377 -182.569866)
		(width 0.1143)
		(layer "In2.Cu")
		(net "T5_NODE3_EN")
	)
	(segment
		(start 105.17632 -183.218836)
		(end 104.47274 -183.218836)
		(width 0.1143)
		(layer "In2.Cu")
		(net "T5_NODE3_EN")
	)
	(segment
		(start 101.448108 -182.569866)
		(end 101.059742 -182.958232)
		(width 0.1143)
		(layer "In2.Cu")
		(net "T5_NODE3_EN")
	)
	(segment
		(start 122.79376 -184.805574)
		(end 122.79376 -184.026302)
		(width 0.1016)
		(layer "F.Cu")
		(net "T8_NODE2_EN")
	)
	(segment
		(start 123.20778 -183.612282)
		(end 123.20778 -178.624992)
		(width 0.1016)
		(layer "F.Cu")
		(net "T8_NODE2_EN")
	)
	(segment
		(start 125.06579 -177.280824)
		(end 125.87224 -176.474374)
		(width 0.1016)
		(layer "F.Cu")
		(net "T8_NODE2_EN")
	)
	(segment
		(start 124.551948 -177.280824)
		(end 125.06579 -177.280824)
		(width 0.1016)
		(layer "F.Cu")
		(net "T8_NODE2_EN")
	)
	(segment
		(start 122.79376 -184.026302)
		(end 123.20778 -183.612282)
		(width 0.1016)
		(layer "F.Cu")
		(net "T8_NODE2_EN")
	)
	(segment
		(start 123.20778 -178.624992)
		(end 124.551948 -177.280824)
		(width 0.1016)
		(layer "F.Cu")
		(net "T8_NODE2_EN")
	)
	(via
		(at 125.87224 -176.474374)
		(size 0.508)
		(drill 0.254)
		(layers "F.Cu" "B.Cu")
		(net "T8_NODE2_EN")
	)
	(segment
		(start 122.8979 -176.852834)
		(end 122.8979 -177.20564)
		(width 0.1016)
		(layer "B.Cu")
		(net "T8_NODE2_EN")
	)
	(segment
		(start 122.8979 -177.20564)
		(end 122.573796 -177.529744)
		(width 0.1016)
		(layer "B.Cu")
		(net "T8_NODE2_EN")
	)
	(segment
		(start 122.573796 -177.529744)
		(end 119.36476 -177.529744)
		(width 0.1016)
		(layer "B.Cu")
		(net "T8_NODE2_EN")
	)
	(segment
		(start 125.019054 -175.975518)
		(end 123.775216 -175.975518)
		(width 0.1016)
		(layer "B.Cu")
		(net "T8_NODE2_EN")
	)
	(segment
		(start 123.30811 -176.442624)
		(end 122.8979 -176.852834)
		(width 0.1016)
		(layer "B.Cu")
		(net "T8_NODE2_EN")
	)
	(segment
		(start 125.87224 -176.474374)
		(end 125.51791 -176.474374)
		(width 0.1016)
		(layer "B.Cu")
		(net "T8_NODE2_EN")
	)
	(segment
		(start 125.51791 -176.474374)
		(end 125.019054 -175.975518)
		(width 0.1016)
		(layer "B.Cu")
		(net "T8_NODE2_EN")
	)
	(segment
		(start 123.775216 -175.975518)
		(end 123.30811 -176.442624)
		(width 0.1016)
		(layer "B.Cu")
		(net "T8_NODE2_EN")
	)
	(segment
		(start 108.31576 -184.805574)
		(end 108.31576 -183.95696)
		(width 0.1016)
		(layer "F.Cu")
		(net "T6_NODE4_EN")
	)
	(via
		(at 111.92764 -180.86451)
		(size 0.508)
		(drill 0.254)
		(layers "F.Cu" "B.Cu")
		(net "T6_NODE4_EN")
	)
	(via
		(at 108.31576 -183.95696)
		(size 0.508)
		(drill 0.254)
		(layers "F.Cu" "B.Cu")
		(net "T6_NODE4_EN")
	)
	(segment
		(start 113.52276 -180.129688)
		(end 112.480852 -180.129688)
		(width 0.1016)
		(layer "B.Cu")
		(net "T6_NODE4_EN")
	)
	(segment
		(start 112.480852 -180.129688)
		(end 112.064292 -180.546248)
		(width 0.1016)
		(layer "B.Cu")
		(net "T6_NODE4_EN")
	)
	(segment
		(start 112.064292 -180.546248)
		(end 112.064292 -180.727858)
		(width 0.1016)
		(layer "B.Cu")
		(net "T6_NODE4_EN")
	)
	(segment
		(start 111.65459 -181.13756)
		(end 111.47298 -181.13756)
		(width 0.1016)
		(layer "B.Cu")
		(net "T6_NODE4_EN")
	)
	(segment
		(start 112.064292 -180.727858)
		(end 111.92764 -180.86451)
		(width 0.1016)
		(layer "B.Cu")
		(net "T6_NODE4_EN")
	)
	(segment
		(start 111.92764 -180.86451)
		(end 111.65459 -181.13756)
		(width 0.1016)
		(layer "B.Cu")
		(net "T6_NODE4_EN")
	)
	(segment
		(start 111.47298 -181.13756)
		(end 110.960916 -181.649624)
		(width 0.1016)
		(layer "B.Cu")
		(net "T6_NODE4_EN")
	)
	(segment
		(start 110.960916 -181.649624)
		(end 110.84941 -181.649624)
		(width 0.1016)
		(layer "B.Cu")
		(net "T6_NODE4_EN")
	)
	(segment
		(start 111.92764 -180.86451)
		(end 108.83519 -183.95696)
		(width 0.1143)
		(layer "In7.Cu")
		(net "T6_NODE4_EN")
	)
	(segment
		(start 108.83519 -183.95696)
		(end 108.31576 -183.95696)
		(width 0.1143)
		(layer "In7.Cu")
		(net "T6_NODE4_EN")
	)
	(via
		(at 71.727314 -174.746412)
		(size 0.6604)
		(drill 0.3302)
		(layers "F.Cu" "B.Cu")
		(net "T1_NODE1_EN")
	)
	(segment
		(start 79.93634 -170.473624)
		(end 81.232248 -171.769532)
		(width 0.1016)
		(layer "B.Cu")
		(net "T1_NODE1_EN")
	)
	(segment
		(start 79.23149 -170.708574)
		(end 79.23149 -170.473624)
		(width 0.1016)
		(layer "B.Cu")
		(net "T1_NODE1_EN")
	)
	(segment
		(start 67.818 -178.429666)
		(end 71.501254 -174.746412)
		(width 0.1016)
		(layer "B.Cu")
		(net "T1_NODE1_EN")
	)
	(segment
		(start 72.49541 -173.978316)
		(end 74.456544 -173.978316)
		(width 0.1016)
		(layer "B.Cu")
		(net "T1_NODE1_EN")
	)
	(segment
		(start 79.23149 -170.473624)
		(end 79.93634 -170.473624)
		(width 0.1016)
		(layer "B.Cu")
		(net "T1_NODE1_EN")
	)
	(segment
		(start 66.53276 -184.805574)
		(end 66.53276 -183.478424)
		(width 0.1016)
		(layer "B.Cu")
		(net "T1_NODE1_EN")
	)
	(segment
		(start 71.727314 -174.746412)
		(end 72.49541 -173.978316)
		(width 0.1016)
		(layer "B.Cu")
		(net "T1_NODE1_EN")
	)
	(segment
		(start 66.78676 -179.460906)
		(end 67.474592 -178.773074)
		(width 0.1016)
		(layer "B.Cu")
		(net "T1_NODE1_EN")
	)
	(segment
		(start 77.402436 -171.032424)
		(end 78.90764 -171.032424)
		(width 0.1016)
		(layer "B.Cu")
		(net "T1_NODE1_EN")
	)
	(segment
		(start 71.501254 -174.746412)
		(end 71.727314 -174.746412)
		(width 0.1016)
		(layer "B.Cu")
		(net "T1_NODE1_EN")
	)
	(segment
		(start 67.474592 -178.773074)
		(end 67.56654 -178.773074)
		(width 0.1016)
		(layer "B.Cu")
		(net "T1_NODE1_EN")
	)
	(segment
		(start 81.232248 -171.769532)
		(end 81.89976 -171.769532)
		(width 0.1016)
		(layer "B.Cu")
		(net "T1_NODE1_EN")
	)
	(segment
		(start 67.56654 -178.771804)
		(end 67.818 -178.520344)
		(width 0.1016)
		(layer "B.Cu")
		(net "T1_NODE1_EN")
	)
	(segment
		(start 74.456544 -173.978316)
		(end 77.402436 -171.032424)
		(width 0.1016)
		(layer "B.Cu")
		(net "T1_NODE1_EN")
	)
	(segment
		(start 67.818 -178.520344)
		(end 67.818 -178.429666)
		(width 0.1016)
		(layer "B.Cu")
		(net "T1_NODE1_EN")
	)
	(segment
		(start 67.56654 -178.773074)
		(end 67.56654 -178.771804)
		(width 0.1016)
		(layer "B.Cu")
		(net "T1_NODE1_EN")
	)
	(segment
		(start 66.78676 -183.224424)
		(end 66.78676 -179.460906)
		(width 0.1016)
		(layer "B.Cu")
		(net "T1_NODE1_EN")
	)
	(segment
		(start 78.90764 -171.032424)
		(end 79.23149 -170.708574)
		(width 0.1016)
		(layer "B.Cu")
		(net "T1_NODE1_EN")
	)
	(segment
		(start 66.53276 -183.478424)
		(end 66.78676 -183.224424)
		(width 0.1016)
		(layer "B.Cu")
		(net "T1_NODE1_EN")
	)
	(segment
		(start 123.30811 -165.507416)
		(end 122.34672 -165.507416)
		(width 0.1016)
		(layer "F.Cu")
		(net "COM3_WAKEUP")
	)
	(segment
		(start 121.796048 -164.956744)
		(end 120.60936 -164.956744)
		(width 0.1016)
		(layer "F.Cu")
		(net "COM3_WAKEUP")
	)
	(segment
		(start 122.34672 -165.507416)
		(end 121.796048 -164.956744)
		(width 0.1016)
		(layer "F.Cu")
		(net "COM3_WAKEUP")
	)
	(segment
		(start 123.30811 -164.491416)
		(end 123.30811 -165.507416)
		(width 0.1016)
		(layer "F.Cu")
		(net "COM3_WAKEUP")
	)
	(via
		(at 121.796048 -164.956744)
		(size 0.508)
		(drill 0.254)
		(layers "F.Cu" "B.Cu")
		(net "COM3_WAKEUP")
	)
	(segment
		(start 122.231658 -176.876964)
		(end 122.86996 -177.515266)
		(width 0.1016)
		(layer "F.Cu")
		(net "T8_NODE3_EN")
	)
	(segment
		(start 122.86996 -177.515266)
		(end 122.86996 -183.166512)
		(width 0.1016)
		(layer "F.Cu")
		(net "T8_NODE3_EN")
	)
	(segment
		(start 122.86996 -183.166512)
		(end 121.77522 -184.261252)
		(width 0.1016)
		(layer "F.Cu")
		(net "T8_NODE3_EN")
	)
	(segment
		(start 121.77522 -184.261252)
		(end 121.77522 -184.809892)
		(width 0.1016)
		(layer "F.Cu")
		(net "T8_NODE3_EN")
	)
	(via
		(at 122.231658 -176.876964)
		(size 0.508)
		(drill 0.254)
		(layers "F.Cu" "B.Cu")
		(net "T8_NODE3_EN")
	)
	(segment
		(start 119.36476 -176.879504)
		(end 122.229118 -176.879504)
		(width 0.1016)
		(layer "B.Cu")
		(net "T8_NODE3_EN")
	)
	(segment
		(start 123.229116 -175.426624)
		(end 122.231658 -176.424082)
		(width 0.1016)
		(layer "B.Cu")
		(net "T8_NODE3_EN")
	)
	(segment
		(start 122.229118 -176.879504)
		(end 122.231658 -176.876964)
		(width 0.1016)
		(layer "B.Cu")
		(net "T8_NODE3_EN")
	)
	(segment
		(start 123.30811 -175.426624)
		(end 123.229116 -175.426624)
		(width 0.1016)
		(layer "B.Cu")
		(net "T8_NODE3_EN")
	)
	(segment
		(start 122.231658 -176.424082)
		(end 122.231658 -176.876964)
		(width 0.1016)
		(layer "B.Cu")
		(net "T8_NODE3_EN")
	)
	(segment
		(start 141.08176 -184.805574)
		(end 141.08176 -184.511188)
		(width 0.1016)
		(layer "F.Cu")
		(net "T10_NODE1_EN")
	)
	(segment
		(start 141.08176 -184.511188)
		(end 141.586204 -184.006744)
		(width 0.1016)
		(layer "F.Cu")
		(net "T10_NODE1_EN")
	)
	(via
		(at 143.552672 -175.161956)
		(size 0.508)
		(drill 0.254)
		(layers "F.Cu" "B.Cu")
		(net "T10_NODE1_EN")
	)
	(via
		(at 141.586204 -184.006744)
		(size 0.508)
		(drill 0.254)
		(layers "F.Cu" "B.Cu")
		(net "T10_NODE1_EN")
	)
	(segment
		(start 142.845536 -175.161956)
		(end 143.552672 -175.161956)
		(width 0.1016)
		(layer "B.Cu")
		(net "T10_NODE1_EN")
	)
	(segment
		(start 142.47241 -175.045624)
		(end 142.729204 -175.045624)
		(width 0.1016)
		(layer "B.Cu")
		(net "T10_NODE1_EN")
	)
	(segment
		(start 142.729204 -175.045624)
		(end 142.845536 -175.161956)
		(width 0.1016)
		(layer "B.Cu")
		(net "T10_NODE1_EN")
	)
	(segment
		(start 145.14576 -174.49673)
		(end 144.217898 -174.49673)
		(width 0.1016)
		(layer "B.Cu")
		(net "T10_NODE1_EN")
	)
	(segment
		(start 144.217898 -174.49673)
		(end 143.552672 -175.161956)
		(width 0.1016)
		(layer "B.Cu")
		(net "T10_NODE1_EN")
	)
	(segment
		(start 142.492984 -183.099964)
		(end 142.670276 -183.099964)
		(width 0.1143)
		(layer "In2.Cu")
		(net "T10_NODE1_EN")
	)
	(segment
		(start 144.76476 -176.374044)
		(end 143.552672 -175.161956)
		(width 0.1143)
		(layer "In2.Cu")
		(net "T10_NODE1_EN")
	)
	(segment
		(start 143.85798 -181.91226)
		(end 143.85798 -181.61635)
		(width 0.1143)
		(layer "In2.Cu")
		(net "T10_NODE1_EN")
	)
	(segment
		(start 142.670276 -183.099964)
		(end 143.85798 -181.91226)
		(width 0.1143)
		(layer "In2.Cu")
		(net "T10_NODE1_EN")
	)
	(segment
		(start 141.586204 -184.006744)
		(end 142.492984 -183.099964)
		(width 0.1143)
		(layer "In2.Cu")
		(net "T10_NODE1_EN")
	)
	(segment
		(start 143.85798 -181.61635)
		(end 144.76476 -180.70957)
		(width 0.1143)
		(layer "In2.Cu")
		(net "T10_NODE1_EN")
	)
	(segment
		(start 144.76476 -180.70957)
		(end 144.76476 -176.374044)
		(width 0.1143)
		(layer "In2.Cu")
		(net "T10_NODE1_EN")
	)
	(segment
		(start 122.61596 -177.915824)
		(end 122.61596 -182.797196)
		(width 0.1016)
		(layer "F.Cu")
		(net "T8_NODE4_EN")
	)
	(segment
		(start 122.231658 -175.606964)
		(end 121.799858 -176.038764)
		(width 0.1016)
		(layer "F.Cu")
		(net "T8_NODE4_EN")
	)
	(segment
		(start 122.61596 -182.797196)
		(end 120.63222 -184.780936)
		(width 0.1016)
		(layer "F.Cu")
		(net "T8_NODE4_EN")
	)
	(segment
		(start 121.799858 -177.099722)
		(end 122.61596 -177.915824)
		(width 0.1016)
		(layer "F.Cu")
		(net "T8_NODE4_EN")
	)
	(segment
		(start 121.799858 -176.038764)
		(end 121.799858 -177.099722)
		(width 0.1016)
		(layer "F.Cu")
		(net "T8_NODE4_EN")
	)
	(segment
		(start 120.63222 -184.780936)
		(end 120.63222 -184.809892)
		(width 0.1016)
		(layer "F.Cu")
		(net "T8_NODE4_EN")
	)
	(via
		(at 122.231658 -175.606964)
		(size 0.508)
		(drill 0.254)
		(layers "F.Cu" "B.Cu")
		(net "T8_NODE4_EN")
	)
	(segment
		(start 123.30811 -174.506382)
		(end 122.231658 -175.582834)
		(width 0.1016)
		(layer "B.Cu")
		(net "T8_NODE4_EN")
	)
	(segment
		(start 122.231658 -175.582834)
		(end 122.231658 -175.606964)
		(width 0.1016)
		(layer "B.Cu")
		(net "T8_NODE4_EN")
	)
	(segment
		(start 123.30811 -174.410624)
		(end 123.30811 -174.506382)
		(width 0.1016)
		(layer "B.Cu")
		(net "T8_NODE4_EN")
	)
	(segment
		(start 121.609104 -176.229518)
		(end 122.231658 -175.606964)
		(width 0.1016)
		(layer "B.Cu")
		(net "T8_NODE4_EN")
	)
	(segment
		(start 119.36476 -176.229518)
		(end 121.609104 -176.229518)
		(width 0.1016)
		(layer "B.Cu")
		(net "T8_NODE4_EN")
	)
	(via
		(at 84.497164 -179.330604)
		(size 0.6604)
		(drill 0.3302)
		(layers "F.Cu" "B.Cu")
		(net "T3_NODE3_EN")
	)
	(segment
		(start 84.497164 -179.330604)
		(end 85.31606 -178.511708)
		(width 0.1016)
		(layer "B.Cu")
		(net "T3_NODE3_EN")
	)
	(segment
		(start 86.616286 -175.668178)
		(end 87.74176 -175.668178)
		(width 0.1016)
		(layer "B.Cu")
		(net "T3_NODE3_EN")
	)
	(segment
		(start 77.69733 -184.859168)
		(end 79.132176 -183.424322)
		(width 0.1016)
		(layer "B.Cu")
		(net "T3_NODE3_EN")
	)
	(segment
		(start 81.072228 -183.424322)
		(end 82.41538 -182.08117)
		(width 0.1016)
		(layer "B.Cu")
		(net "T3_NODE3_EN")
	)
	(segment
		(start 77.63256 -184.859168)
		(end 77.69733 -184.859168)
		(width 0.1016)
		(layer "B.Cu")
		(net "T3_NODE3_EN")
	)
	(segment
		(start 90.41257 -176.054512)
		(end 89.15781 -176.054512)
		(width 0.1016)
		(layer "B.Cu")
		(net "T3_NODE3_EN")
	)
	(segment
		(start 83.4898 -181.48173)
		(end 83.4898 -180.337968)
		(width 0.1016)
		(layer "B.Cu")
		(net "T3_NODE3_EN")
	)
	(segment
		(start 79.132176 -183.424322)
		(end 81.072228 -183.424322)
		(width 0.1016)
		(layer "B.Cu")
		(net "T3_NODE3_EN")
	)
	(segment
		(start 85.31606 -178.511708)
		(end 85.31606 -176.968404)
		(width 0.1016)
		(layer "B.Cu")
		(net "T3_NODE3_EN")
	)
	(segment
		(start 82.41538 -182.08117)
		(end 82.89036 -182.08117)
		(width 0.1016)
		(layer "B.Cu")
		(net "T3_NODE3_EN")
	)
	(segment
		(start 88.773 -175.669702)
		(end 87.74176 -175.669702)
		(width 0.1016)
		(layer "B.Cu")
		(net "T3_NODE3_EN")
	)
	(segment
		(start 82.89036 -182.08117)
		(end 83.4898 -181.48173)
		(width 0.1016)
		(layer "B.Cu")
		(net "T3_NODE3_EN")
	)
	(segment
		(start 89.15781 -176.054512)
		(end 88.773 -175.669702)
		(width 0.1016)
		(layer "B.Cu")
		(net "T3_NODE3_EN")
	)
	(segment
		(start 83.4898 -180.337968)
		(end 84.497164 -179.330604)
		(width 0.1016)
		(layer "B.Cu")
		(net "T3_NODE3_EN")
	)
	(segment
		(start 87.74176 -175.668178)
		(end 87.74176 -175.669702)
		(width 0.1016)
		(layer "B.Cu")
		(net "T3_NODE3_EN")
	)
	(segment
		(start 85.31606 -176.968404)
		(end 86.616286 -175.668178)
		(width 0.1016)
		(layer "B.Cu")
		(net "T3_NODE3_EN")
	)
	(via
		(at 137.052558 -183.360314)
		(size 0.508)
		(drill 0.254)
		(layers "F.Cu" "B.Cu")
		(net "T9_NODE4_EN")
	)
	(via
		(at 143.101822 -174.474632)
		(size 0.508)
		(drill 0.254)
		(layers "F.Cu" "B.Cu")
		(net "T9_NODE4_EN")
	)
	(segment
		(start 143.805402 -174.474632)
		(end 143.101822 -174.474632)
		(width 0.1016)
		(layer "B.Cu")
		(net "T9_NODE4_EN")
	)
	(segment
		(start 136.50976 -183.903112)
		(end 137.052558 -183.360314)
		(width 0.1016)
		(layer "B.Cu")
		(net "T9_NODE4_EN")
	)
	(segment
		(start 142.917418 -174.474632)
		(end 143.101822 -174.474632)
		(width 0.1016)
		(layer "B.Cu")
		(net "T9_NODE4_EN")
	)
	(segment
		(start 145.14576 -173.846744)
		(end 144.43329 -173.846744)
		(width 0.1016)
		(layer "B.Cu")
		(net "T9_NODE4_EN")
	)
	(segment
		(start 144.43329 -173.846744)
		(end 143.805402 -174.474632)
		(width 0.1016)
		(layer "B.Cu")
		(net "T9_NODE4_EN")
	)
	(segment
		(start 136.50976 -184.551574)
		(end 136.50976 -183.903112)
		(width 0.1016)
		(layer "B.Cu")
		(net "T9_NODE4_EN")
	)
	(segment
		(start 142.47241 -174.029624)
		(end 142.917418 -174.474632)
		(width 0.1016)
		(layer "B.Cu")
		(net "T9_NODE4_EN")
	)
	(segment
		(start 137.395966 -183.360314)
		(end 138.147552 -182.608728)
		(width 0.1143)
		(layer "In7.Cu")
		(net "T9_NODE4_EN")
	)
	(segment
		(start 141.448536 -178.571398)
		(end 142.192502 -177.827432)
		(width 0.1143)
		(layer "In7.Cu")
		(net "T9_NODE4_EN")
	)
	(segment
		(start 142.192502 -177.827432)
		(end 142.192502 -175.383952)
		(width 0.1143)
		(layer "In7.Cu")
		(net "T9_NODE4_EN")
	)
	(segment
		(start 139.018264 -182.608728)
		(end 141.448536 -180.178456)
		(width 0.1143)
		(layer "In7.Cu")
		(net "T9_NODE4_EN")
	)
	(segment
		(start 137.052558 -183.360314)
		(end 137.395966 -183.360314)
		(width 0.1143)
		(layer "In7.Cu")
		(net "T9_NODE4_EN")
	)
	(segment
		(start 142.192502 -175.383952)
		(end 143.101822 -174.474632)
		(width 0.1143)
		(layer "In7.Cu")
		(net "T9_NODE4_EN")
	)
	(segment
		(start 138.147552 -182.608728)
		(end 139.018264 -182.608728)
		(width 0.1143)
		(layer "In7.Cu")
		(net "T9_NODE4_EN")
	)
	(segment
		(start 141.448536 -180.178456)
		(end 141.448536 -178.571398)
		(width 0.1143)
		(layer "In7.Cu")
		(net "T9_NODE4_EN")
	)
	(via
		(at 154.16276 -182.039768)
		(size 0.6604)
		(drill 0.3302)
		(layers "F.Cu" "B.Cu")
		(net "T11_NODE1_EN")
	)
	(segment
		(start 150.059898 -177.098706)
		(end 150.98776 -177.098706)
		(width 0.1016)
		(layer "B.Cu")
		(net "T11_NODE1_EN")
	)
	(segment
		(start 152.82672 -178.015138)
		(end 151.996648 -177.185066)
		(width 0.1016)
		(layer "B.Cu")
		(net "T11_NODE1_EN")
	)
	(segment
		(start 151.07412 -177.185066)
		(end 150.98776 -177.098706)
		(width 0.1016)
		(layer "B.Cu")
		(net "T11_NODE1_EN")
	)
	(segment
		(start 149.390354 -177.76825)
		(end 150.059898 -177.098706)
		(width 0.1016)
		(layer "B.Cu")
		(net "T11_NODE1_EN")
	)
	(segment
		(start 154.16276 -183.662574)
		(end 154.16276 -182.039768)
		(width 0.1016)
		(layer "B.Cu")
		(net "T11_NODE1_EN")
	)
	(segment
		(start 154.16276 -181.54904)
		(end 154.392884 -181.318916)
		(width 0.1016)
		(layer "B.Cu")
		(net "T11_NODE1_EN")
	)
	(segment
		(start 154.16276 -182.039768)
		(end 154.16276 -181.54904)
		(width 0.1016)
		(layer "B.Cu")
		(net "T11_NODE1_EN")
	)
	(segment
		(start 155.05176 -184.551574)
		(end 154.16276 -183.662574)
		(width 0.1016)
		(layer "B.Cu")
		(net "T11_NODE1_EN")
	)
	(segment
		(start 151.996648 -177.185066)
		(end 151.07412 -177.185066)
		(width 0.1016)
		(layer "B.Cu")
		(net "T11_NODE1_EN")
	)
	(segment
		(start 149.390354 -178.384454)
		(end 149.390354 -177.76825)
		(width 0.1016)
		(layer "B.Cu")
		(net "T11_NODE1_EN")
	)
	(segment
		(start 154.392884 -180.61686)
		(end 152.82672 -179.050696)
		(width 0.1016)
		(layer "B.Cu")
		(net "T11_NODE1_EN")
	)
	(segment
		(start 150.98776 -177.098706)
		(end 150.98776 -177.096674)
		(width 0.1016)
		(layer "B.Cu")
		(net "T11_NODE1_EN")
	)
	(segment
		(start 154.392884 -181.318916)
		(end 154.392884 -180.61686)
		(width 0.1016)
		(layer "B.Cu")
		(net "T11_NODE1_EN")
	)
	(segment
		(start 152.82672 -179.050696)
		(end 152.82672 -178.015138)
		(width 0.1016)
		(layer "B.Cu")
		(net "T11_NODE1_EN")
	)
	(via
		(at 143.552672 -172.621956)
		(size 0.508)
		(drill 0.254)
		(layers "F.Cu" "B.Cu")
		(net "T9_NODE2_EN")
	)
	(via
		(at 139.458446 -184.000648)
		(size 0.508)
		(drill 0.254)
		(layers "F.Cu" "B.Cu")
		(net "T9_NODE2_EN")
	)
	(segment
		(start 139.458446 -184.04713)
		(end 139.458446 -184.000648)
		(width 0.1016)
		(layer "B.Cu")
		(net "T9_NODE2_EN")
	)
	(segment
		(start 144.250664 -172.546518)
		(end 144.175226 -172.621956)
		(width 0.1016)
		(layer "B.Cu")
		(net "T9_NODE2_EN")
	)
	(segment
		(start 138.954002 -184.551574)
		(end 139.458446 -184.04713)
		(width 0.1016)
		(layer "B.Cu")
		(net "T9_NODE2_EN")
	)
	(segment
		(start 138.79576 -184.551574)
		(end 138.954002 -184.551574)
		(width 0.1016)
		(layer "B.Cu")
		(net "T9_NODE2_EN")
	)
	(segment
		(start 142.47241 -171.997624)
		(end 143.096742 -172.621956)
		(width 0.1016)
		(layer "B.Cu")
		(net "T9_NODE2_EN")
	)
	(segment
		(start 143.096742 -172.621956)
		(end 143.552672 -172.621956)
		(width 0.1016)
		(layer "B.Cu")
		(net "T9_NODE2_EN")
	)
	(segment
		(start 145.14576 -172.546518)
		(end 144.250664 -172.546518)
		(width 0.1016)
		(layer "B.Cu")
		(net "T9_NODE2_EN")
	)
	(segment
		(start 144.175226 -172.621956)
		(end 143.552672 -172.621956)
		(width 0.1016)
		(layer "B.Cu")
		(net "T9_NODE2_EN")
	)
	(segment
		(start 144.76476 -179.385214)
		(end 143.542258 -180.607716)
		(width 0.1143)
		(layer "In7.Cu")
		(net "T9_NODE2_EN")
	)
	(segment
		(start 139.902692 -184.000648)
		(end 139.458446 -184.000648)
		(width 0.1143)
		(layer "In7.Cu")
		(net "T9_NODE2_EN")
	)
	(segment
		(start 142.875 -180.607716)
		(end 142.375382 -181.107334)
		(width 0.1143)
		(layer "In7.Cu")
		(net "T9_NODE2_EN")
	)
	(segment
		(start 144.76476 -173.834044)
		(end 144.76476 -179.385214)
		(width 0.1143)
		(layer "In7.Cu")
		(net "T9_NODE2_EN")
	)
	(segment
		(start 143.542258 -180.607716)
		(end 142.875 -180.607716)
		(width 0.1143)
		(layer "In7.Cu")
		(net "T9_NODE2_EN")
	)
	(segment
		(start 142.375382 -181.527958)
		(end 139.902692 -184.000648)
		(width 0.1143)
		(layer "In7.Cu")
		(net "T9_NODE2_EN")
	)
	(segment
		(start 143.552672 -172.621956)
		(end 144.76476 -173.834044)
		(width 0.1143)
		(layer "In7.Cu")
		(net "T9_NODE2_EN")
	)
	(segment
		(start 142.375382 -181.107334)
		(end 142.375382 -181.527958)
		(width 0.1143)
		(layer "In7.Cu")
		(net "T9_NODE2_EN")
	)
	(via
		(at 78.7527 -199.624442)
		(size 0.6604)
		(drill 0.3302)
		(layers "F.Cu" "B.Cu")
		(net "T3_NODE3_EN_R")
	)
	(segment
		(start 78.55204 -199.423782)
		(end 78.7527 -199.624442)
		(width 0.1016)
		(layer "B.Cu")
		(net "T3_NODE3_EN_R")
	)
	(segment
		(start 77.07376 -188.526674)
		(end 77.07376 -188.73343)
		(width 0.1016)
		(layer "B.Cu")
		(net "T3_NODE3_EN_R")
	)
	(segment
		(start 77.07376 -188.526674)
		(end 77.07376 -188.482224)
		(width 0.1016)
		(layer "B.Cu")
		(net "T3_NODE3_EN_R")
	)
	(segment
		(start 77.53096 -188.025024)
		(end 77.53096 -185.760868)
		(width 0.1016)
		(layer "B.Cu")
		(net "T3_NODE3_EN_R")
	)
	(segment
		(start 77.53096 -185.760868)
		(end 77.63256 -185.659268)
		(width 0.1016)
		(layer "B.Cu")
		(net "T3_NODE3_EN_R")
	)
	(segment
		(start 77.96276 -189.62243)
		(end 77.96276 -194.09283)
		(width 0.1016)
		(layer "B.Cu")
		(net "T3_NODE3_EN_R")
	)
	(segment
		(start 77.07376 -188.73343)
		(end 77.96276 -189.62243)
		(width 0.1016)
		(layer "B.Cu")
		(net "T3_NODE3_EN_R")
	)
	(segment
		(start 78.55204 -194.68211)
		(end 78.55204 -199.423782)
		(width 0.1016)
		(layer "B.Cu")
		(net "T3_NODE3_EN_R")
	)
	(segment
		(start 78.015084 -205.199488)
		(end 78.015084 -200.362058)
		(width 0.1016)
		(layer "B.Cu")
		(net "T3_NODE3_EN_R")
	)
	(segment
		(start 77.96276 -194.09283)
		(end 78.55204 -194.68211)
		(width 0.1016)
		(layer "B.Cu")
		(net "T3_NODE3_EN_R")
	)
	(segment
		(start 77.07376 -188.482224)
		(end 77.53096 -188.025024)
		(width 0.1016)
		(layer "B.Cu")
		(net "T3_NODE3_EN_R")
	)
	(segment
		(start 78.015084 -200.362058)
		(end 78.7527 -199.624442)
		(width 0.1016)
		(layer "B.Cu")
		(net "T3_NODE3_EN_R")
	)
	(via
		(at 105.18902 -198.041006)
		(size 0.6604)
		(drill 0.3302)
		(layers "F.Cu" "B.Cu")
		(net "T5_NODE2_EN_R")
	)
	(segment
		(start 104.68102 -201.782172)
		(end 104.68102 -198.549006)
		(width 0.1016)
		(layer "B.Cu")
		(net "T5_NODE2_EN_R")
	)
	(segment
		(start 104.01554 -205.199488)
		(end 104.01554 -202.447652)
		(width 0.1016)
		(layer "B.Cu")
		(net "T5_NODE2_EN_R")
	)
	(segment
		(start 105.0544 -188.613034)
		(end 105.0544 -197.906386)
		(width 0.1016)
		(layer "B.Cu")
		(net "T5_NODE2_EN_R")
	)
	(segment
		(start 105.14076 -188.526674)
		(end 104.59212 -187.978034)
		(width 0.1016)
		(layer "B.Cu")
		(net "T5_NODE2_EN_R")
	)
	(segment
		(start 104.68102 -198.549006)
		(end 105.18902 -198.041006)
		(width 0.1016)
		(layer "B.Cu")
		(net "T5_NODE2_EN_R")
	)
	(segment
		(start 104.01554 -202.447652)
		(end 104.68102 -201.782172)
		(width 0.1016)
		(layer "B.Cu")
		(net "T5_NODE2_EN_R")
	)
	(segment
		(start 105.14076 -188.526674)
		(end 105.0544 -188.613034)
		(width 0.1016)
		(layer "B.Cu")
		(net "T5_NODE2_EN_R")
	)
	(segment
		(start 105.0544 -197.906386)
		(end 105.18902 -198.041006)
		(width 0.1016)
		(layer "B.Cu")
		(net "T5_NODE2_EN_R")
	)
	(segment
		(start 104.59212 -187.978034)
		(end 104.59212 -186.564778)
		(width 0.1016)
		(layer "B.Cu")
		(net "T5_NODE2_EN_R")
	)
	(segment
		(start 105.14076 -186.016138)
		(end 105.14076 -185.605674)
		(width 0.1016)
		(layer "B.Cu")
		(net "T5_NODE2_EN_R")
	)
	(segment
		(start 104.59212 -186.564778)
		(end 105.14076 -186.016138)
		(width 0.1016)
		(layer "B.Cu")
		(net "T5_NODE2_EN_R")
	)
	(segment
		(start 65.38976 -184.640728)
		(end 65.67678 -184.353708)
		(width 0.1016)
		(layer "F.Cu")
		(net "T2_NODE4_EN")
	)
	(segment
		(start 65.67678 -184.353708)
		(end 65.67678 -183.637174)
		(width 0.1016)
		(layer "F.Cu")
		(net "T2_NODE4_EN")
	)
	(segment
		(start 65.38976 -184.805574)
		(end 65.38976 -184.640728)
		(width 0.1016)
		(layer "F.Cu")
		(net "T2_NODE4_EN")
	)
	(via
		(at 72.14108 -184.138824)
		(size 0.508)
		(drill 0.254)
		(layers "F.Cu" "B.Cu")
		(net "T2_NODE4_EN")
	)
	(via
		(at 65.67678 -183.637174)
		(size 0.508)
		(drill 0.254)
		(layers "F.Cu" "B.Cu")
		(net "T2_NODE4_EN")
	)
	(segment
		(start 76.294488 -177.051716)
		(end 76.70546 -177.051716)
		(width 0.1016)
		(layer "B.Cu")
		(net "T2_NODE4_EN")
	)
	(segment
		(start 78.920594 -178.042824)
		(end 79.23149 -177.731928)
		(width 0.1016)
		(layer "B.Cu")
		(net "T2_NODE4_EN")
	)
	(segment
		(start 81.273142 -176.319688)
		(end 80.007206 -177.585624)
		(width 0.1016)
		(layer "B.Cu")
		(net "T2_NODE4_EN")
	)
	(segment
		(start 80.007206 -177.585624)
		(end 79.23149 -177.585624)
		(width 0.1016)
		(layer "B.Cu")
		(net "T2_NODE4_EN")
	)
	(segment
		(start 76.70546 -177.051716)
		(end 77.696568 -178.042824)
		(width 0.1016)
		(layer "B.Cu")
		(net "T2_NODE4_EN")
	)
	(segment
		(start 75.657456 -177.688748)
		(end 76.294488 -177.051716)
		(width 0.1016)
		(layer "B.Cu")
		(net "T2_NODE4_EN")
	)
	(segment
		(start 77.696568 -178.042824)
		(end 78.920594 -178.042824)
		(width 0.1016)
		(layer "B.Cu")
		(net "T2_NODE4_EN")
	)
	(segment
		(start 72.07758 -184.075324)
		(end 72.07758 -182.530242)
		(width 0.1016)
		(layer "B.Cu")
		(net "T2_NODE4_EN")
	)
	(segment
		(start 81.89976 -176.319688)
		(end 81.273142 -176.319688)
		(width 0.1016)
		(layer "B.Cu")
		(net "T2_NODE4_EN")
	)
	(segment
		(start 74.885042 -177.688748)
		(end 75.657456 -177.688748)
		(width 0.1016)
		(layer "B.Cu")
		(net "T2_NODE4_EN")
	)
	(segment
		(start 79.23149 -177.731928)
		(end 79.23149 -177.585624)
		(width 0.1016)
		(layer "B.Cu")
		(net "T2_NODE4_EN")
	)
	(segment
		(start 74.062336 -180.545486)
		(end 74.062336 -178.511454)
		(width 0.1016)
		(layer "B.Cu")
		(net "T2_NODE4_EN")
	)
	(segment
		(start 74.062336 -178.511454)
		(end 74.885042 -177.688748)
		(width 0.1016)
		(layer "B.Cu")
		(net "T2_NODE4_EN")
	)
	(segment
		(start 72.07758 -182.530242)
		(end 74.062336 -180.545486)
		(width 0.1016)
		(layer "B.Cu")
		(net "T2_NODE4_EN")
	)
	(segment
		(start 72.14108 -184.138824)
		(end 72.07758 -184.075324)
		(width 0.1016)
		(layer "B.Cu")
		(net "T2_NODE4_EN")
	)
	(segment
		(start 72.14108 -184.140348)
		(end 71.65848 -184.622948)
		(width 0.1143)
		(layer "In2.Cu")
		(net "T2_NODE4_EN")
	)
	(segment
		(start 66.662554 -184.622948)
		(end 65.67678 -183.637174)
		(width 0.1143)
		(layer "In2.Cu")
		(net "T2_NODE4_EN")
	)
	(segment
		(start 72.14108 -184.138824)
		(end 72.14108 -184.140348)
		(width 0.1143)
		(layer "In2.Cu")
		(net "T2_NODE4_EN")
	)
	(segment
		(start 71.65848 -184.622948)
		(end 66.662554 -184.622948)
		(width 0.1143)
		(layer "In2.Cu")
		(net "T2_NODE4_EN")
	)
	(segment
		(start 110.829852 -184.805574)
		(end 111.28756 -184.347866)
		(width 0.1016)
		(layer "F.Cu")
		(net "T6_NODE2_EN")
	)
	(segment
		(start 110.096046 -182.705756)
		(end 108.735622 -182.705756)
		(width 0.1016)
		(layer "F.Cu")
		(net "T6_NODE2_EN")
	)
	(segment
		(start 108.309918 -182.771034)
		(end 108.01985 -182.480966)
		(width 0.1016)
		(layer "F.Cu")
		(net "T6_NODE2_EN")
	)
	(segment
		(start 111.28756 -183.89727)
		(end 110.096046 -182.705756)
		(width 0.1016)
		(layer "F.Cu")
		(net "T6_NODE2_EN")
	)
	(segment
		(start 108.01985 -182.480966)
		(end 107.80014 -182.480966)
		(width 0.1016)
		(layer "F.Cu")
		(net "T6_NODE2_EN")
	)
	(segment
		(start 108.670344 -182.771034)
		(end 108.309918 -182.771034)
		(width 0.1016)
		(layer "F.Cu")
		(net "T6_NODE2_EN")
	)
	(segment
		(start 108.735622 -182.705756)
		(end 108.670344 -182.771034)
		(width 0.1016)
		(layer "F.Cu")
		(net "T6_NODE2_EN")
	)
	(segment
		(start 111.28756 -184.347866)
		(end 111.28756 -183.89727)
		(width 0.1016)
		(layer "F.Cu")
		(net "T6_NODE2_EN")
	)
	(segment
		(start 110.60176 -184.805574)
		(end 110.829852 -184.805574)
		(width 0.1016)
		(layer "F.Cu")
		(net "T6_NODE2_EN")
	)
	(via
		(at 108.51642 -179.673758)
		(size 0.508)
		(drill 0.254)
		(layers "F.Cu" "B.Cu")
		(net "T6_NODE2_EN")
	)
	(via
		(at 107.80014 -182.480966)
		(size 0.508)
		(drill 0.254)
		(layers "F.Cu" "B.Cu")
		(net "T6_NODE2_EN")
	)
	(segment
		(start 113.52276 -178.829716)
		(end 112.61344 -178.829716)
		(width 0.1016)
		(layer "B.Cu")
		(net "T6_NODE2_EN")
	)
	(segment
		(start 112.61344 -178.829716)
		(end 112.446308 -178.996848)
		(width 0.1016)
		(layer "B.Cu")
		(net "T6_NODE2_EN")
	)
	(segment
		(start 111.877856 -178.996848)
		(end 111.25708 -179.617624)
		(width 0.1016)
		(layer "B.Cu")
		(net "T6_NODE2_EN")
	)
	(segment
		(start 108.51642 -179.673758)
		(end 109.087158 -179.10302)
		(width 0.1016)
		(layer "B.Cu")
		(net "T6_NODE2_EN")
	)
	(segment
		(start 111.25708 -179.617624)
		(end 110.84941 -179.617624)
		(width 0.1016)
		(layer "B.Cu")
		(net "T6_NODE2_EN")
	)
	(segment
		(start 110.334806 -179.10302)
		(end 110.84941 -179.617624)
		(width 0.1016)
		(layer "B.Cu")
		(net "T6_NODE2_EN")
	)
	(segment
		(start 112.446308 -178.996848)
		(end 111.877856 -178.996848)
		(width 0.1016)
		(layer "B.Cu")
		(net "T6_NODE2_EN")
	)
	(segment
		(start 109.087158 -179.10302)
		(end 110.334806 -179.10302)
		(width 0.1016)
		(layer "B.Cu")
		(net "T6_NODE2_EN")
	)
	(segment
		(start 106.93781 -182.657242)
		(end 107.623864 -182.657242)
		(width 0.1143)
		(layer "In7.Cu")
		(net "T6_NODE2_EN")
	)
	(segment
		(start 108.51642 -179.673758)
		(end 108.3437 -179.846478)
		(width 0.1143)
		(layer "In7.Cu")
		(net "T6_NODE2_EN")
	)
	(segment
		(start 106.68127 -182.400702)
		(end 106.93781 -182.657242)
		(width 0.1143)
		(layer "In7.Cu")
		(net "T6_NODE2_EN")
	)
	(segment
		(start 107.623864 -182.657242)
		(end 107.80014 -182.480966)
		(width 0.1143)
		(layer "In7.Cu")
		(net "T6_NODE2_EN")
	)
	(segment
		(start 108.3437 -180.217064)
		(end 106.68127 -181.879494)
		(width 0.1143)
		(layer "In7.Cu")
		(net "T6_NODE2_EN")
	)
	(segment
		(start 108.3437 -179.846478)
		(end 108.3437 -180.217064)
		(width 0.1143)
		(layer "In7.Cu")
		(net "T6_NODE2_EN")
	)
	(segment
		(start 106.68127 -181.879494)
		(end 106.68127 -182.400702)
		(width 0.1143)
		(layer "In7.Cu")
		(net "T6_NODE2_EN")
	)
	(segment
		(start 137.65276 -184.805574)
		(end 137.65276 -184.528714)
		(width 0.1016)
		(layer "F.Cu")
		(net "T10_NODE4_EN")
	)
	(segment
		(start 138.196828 -183.984646)
		(end 138.196828 -184.01284)
		(width 0.1016)
		(layer "F.Cu")
		(net "T10_NODE4_EN")
	)
	(segment
		(start 137.65276 -184.528714)
		(end 138.196828 -183.984646)
		(width 0.1016)
		(layer "F.Cu")
		(net "T10_NODE4_EN")
	)
	(via
		(at 143.552672 -177.701956)
		(size 0.508)
		(drill 0.254)
		(layers "F.Cu" "B.Cu")
		(net "T10_NODE4_EN")
	)
	(via
		(at 138.196828 -184.01284)
		(size 0.508)
		(drill 0.254)
		(layers "F.Cu" "B.Cu")
		(net "T10_NODE4_EN")
	)
	(segment
		(start 143.148304 -178.093624)
		(end 143.539972 -177.701956)
		(width 0.1016)
		(layer "B.Cu")
		(net "T10_NODE4_EN")
	)
	(segment
		(start 144.059656 -177.200052)
		(end 143.557752 -177.701956)
		(width 0.1016)
		(layer "B.Cu")
		(net "T10_NODE4_EN")
	)
	(segment
		(start 143.557752 -177.701956)
		(end 143.552672 -177.701956)
		(width 0.1016)
		(layer "B.Cu")
		(net "T10_NODE4_EN")
	)
	(segment
		(start 142.47241 -178.093624)
		(end 143.148304 -178.093624)
		(width 0.1016)
		(layer "B.Cu")
		(net "T10_NODE4_EN")
	)
	(segment
		(start 143.539972 -177.701956)
		(end 143.552672 -177.701956)
		(width 0.1016)
		(layer "B.Cu")
		(net "T10_NODE4_EN")
	)
	(segment
		(start 144.059656 -176.901856)
		(end 144.059656 -177.200052)
		(width 0.1016)
		(layer "B.Cu")
		(net "T10_NODE4_EN")
	)
	(segment
		(start 144.514824 -176.446688)
		(end 144.059656 -176.901856)
		(width 0.1016)
		(layer "B.Cu")
		(net "T10_NODE4_EN")
	)
	(segment
		(start 145.14576 -176.446688)
		(end 144.514824 -176.446688)
		(width 0.1016)
		(layer "B.Cu")
		(net "T10_NODE4_EN")
	)
	(segment
		(start 138.196828 -183.937402)
		(end 138.687302 -183.446928)
		(width 0.1143)
		(layer "In7.Cu")
		(net "T10_NODE4_EN")
	)
	(segment
		(start 142.057374 -181.446424)
		(end 142.057374 -180.84927)
		(width 0.1143)
		(layer "In7.Cu")
		(net "T10_NODE4_EN")
	)
	(segment
		(start 138.196828 -184.01284)
		(end 138.196828 -183.937402)
		(width 0.1143)
		(layer "In7.Cu")
		(net "T10_NODE4_EN")
	)
	(segment
		(start 139.820396 -182.744618)
		(end 140.75918 -182.744618)
		(width 0.1143)
		(layer "In7.Cu")
		(net "T10_NODE4_EN")
	)
	(segment
		(start 143.552672 -179.353972)
		(end 143.552672 -177.701956)
		(width 0.1143)
		(layer "In7.Cu")
		(net "T10_NODE4_EN")
	)
	(segment
		(start 139.118086 -183.446928)
		(end 139.820396 -182.744618)
		(width 0.1143)
		(layer "In7.Cu")
		(net "T10_NODE4_EN")
	)
	(segment
		(start 138.687302 -183.446928)
		(end 139.118086 -183.446928)
		(width 0.1143)
		(layer "In7.Cu")
		(net "T10_NODE4_EN")
	)
	(segment
		(start 142.057374 -180.84927)
		(end 143.552672 -179.353972)
		(width 0.1143)
		(layer "In7.Cu")
		(net "T10_NODE4_EN")
	)
	(segment
		(start 140.75918 -182.744618)
		(end 142.057374 -181.446424)
		(width 0.1143)
		(layer "In7.Cu")
		(net "T10_NODE4_EN")
	)
	(segment
		(start 123.97486 -180.47843)
		(end 123.97486 -180.487828)
		(width 0.1016)
		(layer "F.Cu")
		(net "T7_NODE3_EN")
	)
	(segment
		(start 123.97486 -180.487828)
		(end 125.335538 -180.487828)
		(width 0.1016)
		(layer "F.Cu")
		(net "T7_NODE3_EN")
	)
	(via
		(at 123.97486 -180.47843)
		(size 0.508)
		(drill 0.254)
		(layers "F.Cu" "B.Cu")
		(net "T7_NODE3_EN")
	)
	(segment
		(start 123.97486 -180.47843)
		(end 123.058936 -180.47843)
		(width 0.1016)
		(layer "B.Cu")
		(net "T7_NODE3_EN")
	)
	(segment
		(start 117.59692 -180.368702)
		(end 117.59692 -184.668414)
		(width 0.1016)
		(layer "B.Cu")
		(net "T7_NODE3_EN")
	)
	(segment
		(start 118.48592 -179.479702)
		(end 117.59692 -180.368702)
		(width 0.1016)
		(layer "B.Cu")
		(net "T7_NODE3_EN")
	)
	(segment
		(start 123.058936 -180.47843)
		(end 122.060208 -179.479702)
		(width 0.1016)
		(layer "B.Cu")
		(net "T7_NODE3_EN")
	)
	(segment
		(start 119.36476 -179.479702)
		(end 118.48592 -179.479702)
		(width 0.1016)
		(layer "B.Cu")
		(net "T7_NODE3_EN")
	)
	(segment
		(start 122.060208 -179.479702)
		(end 119.36476 -179.479702)
		(width 0.1016)
		(layer "B.Cu")
		(net "T7_NODE3_EN")
	)
	(segment
		(start 117.59692 -184.668414)
		(end 117.45976 -184.805574)
		(width 0.1016)
		(layer "B.Cu")
		(net "T7_NODE3_EN")
	)
	(via
		(at 143.114014 -171.925488)
		(size 0.508)
		(drill 0.254)
		(layers "F.Cu" "B.Cu")
		(net "T9_NODE1_EN")
	)
	(via
		(at 142.378176 -182.395114)
		(size 0.508)
		(drill 0.254)
		(layers "F.Cu" "B.Cu")
		(net "T9_NODE1_EN")
	)
	(segment
		(start 142.47241 -170.981624)
		(end 142.47241 -171.110148)
		(width 0.1016)
		(layer "B.Cu")
		(net "T9_NODE1_EN")
	)
	(segment
		(start 142.47241 -171.110148)
		(end 143.114014 -171.751752)
		(width 0.1016)
		(layer "B.Cu")
		(net "T9_NODE1_EN")
	)
	(segment
		(start 143.114014 -171.751752)
		(end 143.114014 -171.925488)
		(width 0.1016)
		(layer "B.Cu")
		(net "T9_NODE1_EN")
	)
	(segment
		(start 139.93876 -184.551574)
		(end 139.93876 -184.07253)
		(width 0.1016)
		(layer "B.Cu")
		(net "T9_NODE1_EN")
	)
	(segment
		(start 145.14576 -171.896532)
		(end 144.030446 -171.896532)
		(width 0.1016)
		(layer "B.Cu")
		(net "T9_NODE1_EN")
	)
	(segment
		(start 139.93876 -184.07253)
		(end 140.55344 -183.45785)
		(width 0.1016)
		(layer "B.Cu")
		(net "T9_NODE1_EN")
	)
	(segment
		(start 140.55344 -183.312816)
		(end 141.471142 -182.395114)
		(width 0.1016)
		(layer "B.Cu")
		(net "T9_NODE1_EN")
	)
	(segment
		(start 144.030446 -171.896532)
		(end 144.00149 -171.925488)
		(width 0.1016)
		(layer "B.Cu")
		(net "T9_NODE1_EN")
	)
	(segment
		(start 144.00149 -171.925488)
		(end 143.114014 -171.925488)
		(width 0.1016)
		(layer "B.Cu")
		(net "T9_NODE1_EN")
	)
	(segment
		(start 141.471142 -182.395114)
		(end 142.378176 -182.395114)
		(width 0.1016)
		(layer "B.Cu")
		(net "T9_NODE1_EN")
	)
	(segment
		(start 140.55344 -183.45785)
		(end 140.55344 -183.312816)
		(width 0.1016)
		(layer "B.Cu")
		(net "T9_NODE1_EN")
	)
	(segment
		(start 143.89227 -171.925488)
		(end 145.111978 -173.145196)
		(width 0.1143)
		(layer "In7.Cu")
		(net "T9_NODE1_EN")
	)
	(segment
		(start 142.387828 -182.395114)
		(end 142.378176 -182.395114)
		(width 0.1143)
		(layer "In7.Cu")
		(net "T9_NODE1_EN")
	)
	(segment
		(start 143.114014 -171.925488)
		(end 143.89227 -171.925488)
		(width 0.1143)
		(layer "In7.Cu")
		(net "T9_NODE1_EN")
	)
	(segment
		(start 145.111978 -173.145196)
		(end 145.111978 -179.670964)
		(width 0.1143)
		(layer "In7.Cu")
		(net "T9_NODE1_EN")
	)
	(segment
		(start 145.111978 -179.670964)
		(end 142.387828 -182.395114)
		(width 0.1143)
		(layer "In7.Cu")
		(net "T9_NODE1_EN")
	)
	(segment
		(start 108.89234 -184.055766)
		(end 109.45876 -184.622186)
		(width 0.1016)
		(layer "F.Cu")
		(net "T6_NODE3_EN")
	)
	(segment
		(start 108.89234 -183.274716)
		(end 108.89234 -184.055766)
		(width 0.1016)
		(layer "F.Cu")
		(net "T6_NODE3_EN")
	)
	(segment
		(start 109.02696 -183.137556)
		(end 109.0295 -183.137556)
		(width 0.1016)
		(layer "F.Cu")
		(net "T6_NODE3_EN")
	)
	(segment
		(start 109.02442 -183.142636)
		(end 108.89234 -183.274716)
		(width 0.1016)
		(layer "F.Cu")
		(net "T6_NODE3_EN")
	)
	(segment
		(start 109.0295 -183.13781)
		(end 109.02442 -183.13781)
		(width 0.1016)
		(layer "F.Cu")
		(net "T6_NODE3_EN")
	)
	(segment
		(start 109.02442 -183.13781)
		(end 109.02442 -183.142636)
		(width 0.1016)
		(layer "F.Cu")
		(net "T6_NODE3_EN")
	)
	(segment
		(start 109.0295 -183.137556)
		(end 109.0295 -183.13781)
		(width 0.1016)
		(layer "F.Cu")
		(net "T6_NODE3_EN")
	)
	(segment
		(start 109.45876 -184.622186)
		(end 109.45876 -184.805574)
		(width 0.1016)
		(layer "F.Cu")
		(net "T6_NODE3_EN")
	)
	(via
		(at 109.02696 -183.137556)
		(size 0.508)
		(drill 0.254)
		(layers "F.Cu" "B.Cu")
		(net "T6_NODE3_EN")
	)
	(segment
		(start 109.17428 -181.419246)
		(end 108.950252 -181.195218)
		(width 0.1016)
		(layer "B.Cu")
		(net "T6_NODE3_EN")
	)
	(segment
		(start 109.0295 -183.13781)
		(end 109.02442 -183.13781)
		(width 0.1016)
		(layer "B.Cu")
		(net "T6_NODE3_EN")
	)
	(segment
		(start 108.950252 -181.195218)
		(end 108.950252 -180.44414)
		(width 0.1016)
		(layer "B.Cu")
		(net "T6_NODE3_EN")
	)
	(segment
		(start 110.332012 -180.176424)
		(end 110.789212 -180.633624)
		(width 0.1016)
		(layer "B.Cu")
		(net "T6_NODE3_EN")
	)
	(segment
		(start 109.02442 -183.13781)
		(end 109.02442 -183.13273)
		(width 0.1016)
		(layer "B.Cu")
		(net "T6_NODE3_EN")
	)
	(segment
		(start 109.0295 -183.137556)
		(end 109.0295 -183.13781)
		(width 0.1016)
		(layer "B.Cu")
		(net "T6_NODE3_EN")
	)
	(segment
		(start 110.91545 -180.567584)
		(end 110.84941 -180.633624)
		(width 0.1016)
		(layer "B.Cu")
		(net "T6_NODE3_EN")
	)
	(segment
		(start 109.217968 -180.176424)
		(end 110.332012 -180.176424)
		(width 0.1016)
		(layer "B.Cu")
		(net "T6_NODE3_EN")
	)
	(segment
		(start 109.02696 -183.137556)
		(end 109.0295 -183.137556)
		(width 0.1016)
		(layer "B.Cu")
		(net "T6_NODE3_EN")
	)
	(segment
		(start 110.924848 -180.567584)
		(end 110.91545 -180.567584)
		(width 0.1016)
		(layer "B.Cu")
		(net "T6_NODE3_EN")
	)
	(segment
		(start 113.52276 -179.479702)
		(end 112.01273 -179.479702)
		(width 0.1016)
		(layer "B.Cu")
		(net "T6_NODE3_EN")
	)
	(segment
		(start 112.01273 -179.479702)
		(end 110.924848 -180.567584)
		(width 0.1016)
		(layer "B.Cu")
		(net "T6_NODE3_EN")
	)
	(segment
		(start 109.02442 -183.13273)
		(end 109.17428 -182.98287)
		(width 0.1016)
		(layer "B.Cu")
		(net "T6_NODE3_EN")
	)
	(segment
		(start 110.789212 -180.633624)
		(end 110.84941 -180.633624)
		(width 0.1016)
		(layer "B.Cu")
		(net "T6_NODE3_EN")
	)
	(segment
		(start 108.950252 -180.44414)
		(end 109.217968 -180.176424)
		(width 0.1016)
		(layer "B.Cu")
		(net "T6_NODE3_EN")
	)
	(segment
		(start 109.17428 -182.98287)
		(end 109.17428 -181.419246)
		(width 0.1016)
		(layer "B.Cu")
		(net "T6_NODE3_EN")
	)
	(via
		(at 65.82918 -179.105052)
		(size 0.508)
		(drill 0.254)
		(layers "F.Cu" "B.Cu")
		(net "T1_NODE2_EN")
	)
	(via
		(at 68.43014 -179.324762)
		(size 0.508)
		(drill 0.254)
		(layers "F.Cu" "B.Cu")
		(net "T1_NODE2_EN")
	)
	(segment
		(start 74.208386 -174.587408)
		(end 73.30186 -174.587408)
		(width 0.1016)
		(layer "B.Cu")
		(net "T1_NODE2_EN")
	)
	(segment
		(start 65.28054 -183.314594)
		(end 65.28054 -179.653692)
		(width 0.1016)
		(layer "B.Cu")
		(net "T1_NODE2_EN")
	)
	(segment
		(start 68.60159 -179.324762)
		(end 68.43014 -179.324762)
		(width 0.1016)
		(layer "B.Cu")
		(net "T1_NODE2_EN")
	)
	(segment
		(start 73.30186 -174.587408)
		(end 71.18604 -176.703228)
		(width 0.1016)
		(layer "B.Cu")
		(net "T1_NODE2_EN")
	)
	(segment
		(start 79.23149 -171.914058)
		(end 79.09814 -172.047408)
		(width 0.1016)
		(layer "B.Cu")
		(net "T1_NODE2_EN")
	)
	(segment
		(start 65.16878 -183.426354)
		(end 65.28054 -183.314594)
		(width 0.1016)
		(layer "B.Cu")
		(net "T1_NODE2_EN")
	)
	(segment
		(start 76.748386 -172.047408)
		(end 74.208386 -174.587408)
		(width 0.1016)
		(layer "B.Cu")
		(net "T1_NODE2_EN")
	)
	(segment
		(start 65.38976 -184.805574)
		(end 65.16878 -184.584594)
		(width 0.1016)
		(layer "B.Cu")
		(net "T1_NODE2_EN")
	)
	(segment
		(start 81.89976 -172.419518)
		(end 80.612234 -172.419518)
		(width 0.1016)
		(layer "B.Cu")
		(net "T1_NODE2_EN")
	)
	(segment
		(start 65.28054 -179.653692)
		(end 65.82918 -179.105052)
		(width 0.1016)
		(layer "B.Cu")
		(net "T1_NODE2_EN")
	)
	(segment
		(start 65.16878 -184.584594)
		(end 65.16878 -183.426354)
		(width 0.1016)
		(layer "B.Cu")
		(net "T1_NODE2_EN")
	)
	(segment
		(start 80.612234 -172.419518)
		(end 79.68234 -171.489624)
		(width 0.1016)
		(layer "B.Cu")
		(net "T1_NODE2_EN")
	)
	(segment
		(start 79.23149 -171.489624)
		(end 79.23149 -171.914058)
		(width 0.1016)
		(layer "B.Cu")
		(net "T1_NODE2_EN")
	)
	(segment
		(start 71.18604 -176.740312)
		(end 68.60159 -179.324762)
		(width 0.1016)
		(layer "B.Cu")
		(net "T1_NODE2_EN")
	)
	(segment
		(start 71.18604 -176.703228)
		(end 71.18604 -176.740312)
		(width 0.1016)
		(layer "B.Cu")
		(net "T1_NODE2_EN")
	)
	(segment
		(start 79.68234 -171.489624)
		(end 79.23149 -171.489624)
		(width 0.1016)
		(layer "B.Cu")
		(net "T1_NODE2_EN")
	)
	(segment
		(start 79.09814 -172.047408)
		(end 76.748386 -172.047408)
		(width 0.1016)
		(layer "B.Cu")
		(net "T1_NODE2_EN")
	)
	(segment
		(start 68.43014 -179.324762)
		(end 68.21043 -179.105052)
		(width 0.1143)
		(layer "In2.Cu")
		(net "T1_NODE2_EN")
	)
	(segment
		(start 68.21043 -179.105052)
		(end 65.82918 -179.105052)
		(width 0.1143)
		(layer "In2.Cu")
		(net "T1_NODE2_EN")
	)
	(segment
		(start 95.69958 -186.664346)
		(end 95.55734 -186.806586)
		(width 0.1016)
		(layer "F.Cu")
		(net "T5_NODE4_EN")
	)
	(segment
		(start 95.69958 -186.664092)
		(end 95.69958 -186.664346)
		(width 0.1016)
		(layer "F.Cu")
		(net "T5_NODE4_EN")
	)
	(segment
		(start 95.55734 -186.806586)
		(end 94.611444 -186.806586)
		(width 0.1016)
		(layer "F.Cu")
		(net "T5_NODE4_EN")
	)
	(via
		(at 104.66832 -182.634636)
		(size 0.508)
		(drill 0.254)
		(layers "F.Cu" "B.Cu")
		(net "T5_NODE4_EN")
	)
	(via
		(at 95.69958 -186.664092)
		(size 0.508)
		(drill 0.254)
		(layers "F.Cu" "B.Cu")
		(net "T5_NODE4_EN")
	)
	(segment
		(start 104.66832 -182.634636)
		(end 106.6673 -180.635656)
		(width 0.1016)
		(layer "B.Cu")
		(net "T5_NODE4_EN")
	)
	(segment
		(start 111.313214 -177.657252)
		(end 112.540288 -177.657252)
		(width 0.1016)
		(layer "B.Cu")
		(net "T5_NODE4_EN")
	)
	(segment
		(start 110.362746 -178.072288)
		(end 110.84941 -177.585624)
		(width 0.1016)
		(layer "B.Cu")
		(net "T5_NODE4_EN")
	)
	(segment
		(start 107.343448 -178.725576)
		(end 108.520484 -178.725576)
		(width 0.1016)
		(layer "B.Cu")
		(net "T5_NODE4_EN")
	)
	(segment
		(start 111.241586 -177.585624)
		(end 111.313214 -177.657252)
		(width 0.1016)
		(layer "B.Cu")
		(net "T5_NODE4_EN")
	)
	(segment
		(start 106.6673 -179.401724)
		(end 107.343448 -178.725576)
		(width 0.1016)
		(layer "B.Cu")
		(net "T5_NODE4_EN")
	)
	(segment
		(start 109.173772 -178.072288)
		(end 110.362746 -178.072288)
		(width 0.1016)
		(layer "B.Cu")
		(net "T5_NODE4_EN")
	)
	(segment
		(start 110.84941 -177.585624)
		(end 111.241586 -177.585624)
		(width 0.1016)
		(layer "B.Cu")
		(net "T5_NODE4_EN")
	)
	(segment
		(start 106.6673 -180.635656)
		(end 106.6673 -179.401724)
		(width 0.1016)
		(layer "B.Cu")
		(net "T5_NODE4_EN")
	)
	(segment
		(start 112.540288 -177.657252)
		(end 112.667796 -177.529744)
		(width 0.1016)
		(layer "B.Cu")
		(net "T5_NODE4_EN")
	)
	(segment
		(start 112.667796 -177.529744)
		(end 113.52276 -177.529744)
		(width 0.1016)
		(layer "B.Cu")
		(net "T5_NODE4_EN")
	)
	(segment
		(start 108.520484 -178.725576)
		(end 109.173772 -178.072288)
		(width 0.1016)
		(layer "B.Cu")
		(net "T5_NODE4_EN")
	)
	(segment
		(start 101.118924 -182.520082)
		(end 101.33584 -182.303166)
		(width 0.1143)
		(layer "In2.Cu")
		(net "T5_NODE4_EN")
	)
	(segment
		(start 95.642938 -186.664092)
		(end 94.07779 -185.098944)
		(width 0.1143)
		(layer "In2.Cu")
		(net "T5_NODE4_EN")
	)
	(segment
		(start 94.07779 -185.098944)
		(end 94.07779 -182.776622)
		(width 0.1143)
		(layer "In2.Cu")
		(net "T5_NODE4_EN")
	)
	(segment
		(start 94.07779 -182.776622)
		(end 94.33433 -182.520082)
		(width 0.1143)
		(layer "In2.Cu")
		(net "T5_NODE4_EN")
	)
	(segment
		(start 95.69958 -186.664092)
		(end 95.642938 -186.664092)
		(width 0.1143)
		(layer "In2.Cu")
		(net "T5_NODE4_EN")
	)
	(segment
		(start 94.33433 -182.520082)
		(end 101.118924 -182.520082)
		(width 0.1143)
		(layer "In2.Cu")
		(net "T5_NODE4_EN")
	)
	(segment
		(start 104.33685 -182.303166)
		(end 104.66832 -182.634636)
		(width 0.1143)
		(layer "In2.Cu")
		(net "T5_NODE4_EN")
	)
	(segment
		(start 101.33584 -182.303166)
		(end 104.33685 -182.303166)
		(width 0.1143)
		(layer "In2.Cu")
		(net "T5_NODE4_EN")
	)
	(segment
		(start 68.81876 -184.805574)
		(end 68.81876 -183.40832)
		(width 0.1016)
		(layer "F.Cu")
		(net "T2_NODE1_EN")
	)
	(via
		(at 68.81876 -183.40832)
		(size 0.508)
		(drill 0.254)
		(layers "F.Cu" "B.Cu")
		(net "T2_NODE1_EN")
	)
	(via
		(at 80.310736 -174.65802)
		(size 0.508)
		(drill 0.254)
		(layers "F.Cu" "B.Cu")
		(net "T2_NODE1_EN")
	)
	(segment
		(start 75.303634 -176.586134)
		(end 73.354692 -178.535076)
		(width 0.1016)
		(layer "B.Cu")
		(net "T2_NODE1_EN")
	)
	(segment
		(start 73.354692 -179.168806)
		(end 72.50811 -180.015388)
		(width 0.1016)
		(layer "B.Cu")
		(net "T2_NODE1_EN")
	)
	(segment
		(start 79.23149 -174.537624)
		(end 79.23149 -174.742602)
		(width 0.1016)
		(layer "B.Cu")
		(net "T2_NODE1_EN")
	)
	(segment
		(start 78.979268 -174.994824)
		(end 77.55382 -174.994824)
		(width 0.1016)
		(layer "B.Cu")
		(net "T2_NODE1_EN")
	)
	(segment
		(start 77.55382 -174.994824)
		(end 75.96251 -176.586134)
		(width 0.1016)
		(layer "B.Cu")
		(net "T2_NODE1_EN")
	)
	(segment
		(start 72.50811 -180.015388)
		(end 72.211692 -180.015388)
		(width 0.1016)
		(layer "B.Cu")
		(net "T2_NODE1_EN")
	)
	(segment
		(start 79.729584 -174.65802)
		(end 79.609188 -174.537624)
		(width 0.1016)
		(layer "B.Cu")
		(net "T2_NODE1_EN")
	)
	(segment
		(start 79.609188 -174.537624)
		(end 79.23149 -174.537624)
		(width 0.1016)
		(layer "B.Cu")
		(net "T2_NODE1_EN")
	)
	(segment
		(start 80.599026 -174.36973)
		(end 80.310736 -174.65802)
		(width 0.1016)
		(layer "B.Cu")
		(net "T2_NODE1_EN")
	)
	(segment
		(start 79.23149 -174.742602)
		(end 78.979268 -174.994824)
		(width 0.1016)
		(layer "B.Cu")
		(net "T2_NODE1_EN")
	)
	(segment
		(start 81.89976 -174.36973)
		(end 80.599026 -174.36973)
		(width 0.1016)
		(layer "B.Cu")
		(net "T2_NODE1_EN")
	)
	(segment
		(start 73.354692 -178.535076)
		(end 73.354692 -179.168806)
		(width 0.1016)
		(layer "B.Cu")
		(net "T2_NODE1_EN")
	)
	(segment
		(start 72.211692 -180.015388)
		(end 68.81876 -183.40832)
		(width 0.1016)
		(layer "B.Cu")
		(net "T2_NODE1_EN")
	)
	(segment
		(start 75.96251 -176.586134)
		(end 75.303634 -176.586134)
		(width 0.1016)
		(layer "B.Cu")
		(net "T2_NODE1_EN")
	)
	(segment
		(start 80.310736 -174.65802)
		(end 79.729584 -174.65802)
		(width 0.1016)
		(layer "B.Cu")
		(net "T2_NODE1_EN")
	)
	(via
		(at 84.05876 -182.65775)
		(size 0.6604)
		(drill 0.3302)
		(layers "F.Cu" "B.Cu")
		(net "T3_NODE1_EN")
	)
	(segment
		(start 88.80602 -176.969674)
		(end 87.74176 -176.969674)
		(width 0.1016)
		(layer "B.Cu")
		(net "T3_NODE1_EN")
	)
	(segment
		(start 90.150696 -178.829208)
		(end 90.41257 -178.567334)
		(width 0.1016)
		(layer "B.Cu")
		(net "T3_NODE1_EN")
	)
	(segment
		(start 79.60614 -185.198004)
		(end 81.611216 -185.198004)
		(width 0.1016)
		(layer "B.Cu")
		(net "T3_NODE1_EN")
	)
	(segment
		(start 90.41257 -178.567334)
		(end 90.41257 -178.086512)
		(width 0.1016)
		(layer "B.Cu")
		(net "T3_NODE1_EN")
	)
	(segment
		(start 90.41257 -178.086512)
		(end 89.922858 -178.086512)
		(width 0.1016)
		(layer "B.Cu")
		(net "T3_NODE1_EN")
	)
	(segment
		(start 84.05876 -181.874414)
		(end 87.103966 -178.829208)
		(width 0.1016)
		(layer "B.Cu")
		(net "T3_NODE1_EN")
	)
	(segment
		(start 84.05876 -182.75046)
		(end 84.05876 -182.65775)
		(width 0.1016)
		(layer "B.Cu")
		(net "T3_NODE1_EN")
	)
	(segment
		(start 87.103966 -178.829208)
		(end 90.150696 -178.829208)
		(width 0.1016)
		(layer "B.Cu")
		(net "T3_NODE1_EN")
	)
	(segment
		(start 89.922858 -178.086512)
		(end 88.80602 -176.969674)
		(width 0.1016)
		(layer "B.Cu")
		(net "T3_NODE1_EN")
	)
	(segment
		(start 84.05876 -182.65775)
		(end 84.05876 -181.874414)
		(width 0.1016)
		(layer "B.Cu")
		(net "T3_NODE1_EN")
	)
	(segment
		(start 81.611216 -185.198004)
		(end 84.05876 -182.75046)
		(width 0.1016)
		(layer "B.Cu")
		(net "T3_NODE1_EN")
	)
	(via
		(at 152.860502 -181.757066)
		(size 0.508)
		(drill 0.254)
		(layers "F.Cu" "B.Cu")
		(net "T11_NODE4_EN")
	)
	(via
		(at 153.47188 -178.758596)
		(size 0.508)
		(drill 0.254)
		(layers "F.Cu" "B.Cu")
		(net "T11_NODE4_EN")
	)
	(segment
		(start 150.98776 -175.146716)
		(end 151.558498 -175.146716)
		(width 0.1016)
		(layer "B.Cu")
		(net "T11_NODE4_EN")
	)
	(segment
		(start 151.62276 -184.551574)
		(end 152.860502 -183.313832)
		(width 0.1016)
		(layer "B.Cu")
		(net "T11_NODE4_EN")
	)
	(segment
		(start 152.433782 -176.569624)
		(end 153.66111 -176.569624)
		(width 0.1016)
		(layer "B.Cu")
		(net "T11_NODE4_EN")
	)
	(segment
		(start 152.04186 -176.177702)
		(end 152.433782 -176.569624)
		(width 0.1016)
		(layer "B.Cu")
		(net "T11_NODE4_EN")
	)
	(segment
		(start 153.66111 -177.391822)
		(end 153.47188 -177.581052)
		(width 0.1016)
		(layer "B.Cu")
		(net "T11_NODE4_EN")
	)
	(segment
		(start 153.66111 -176.569624)
		(end 153.66111 -177.391822)
		(width 0.1016)
		(layer "B.Cu")
		(net "T11_NODE4_EN")
	)
	(segment
		(start 152.860502 -183.313832)
		(end 152.860502 -181.757066)
		(width 0.1016)
		(layer "B.Cu")
		(net "T11_NODE4_EN")
	)
	(segment
		(start 153.47188 -177.581052)
		(end 153.47188 -178.758596)
		(width 0.1016)
		(layer "B.Cu")
		(net "T11_NODE4_EN")
	)
	(segment
		(start 151.558498 -175.146716)
		(end 152.04186 -175.630078)
		(width 0.1016)
		(layer "B.Cu")
		(net "T11_NODE4_EN")
	)
	(segment
		(start 152.04186 -175.630078)
		(end 152.04186 -176.177702)
		(width 0.1016)
		(layer "B.Cu")
		(net "T11_NODE4_EN")
	)
	(segment
		(start 153.47188 -181.145688)
		(end 152.860502 -181.757066)
		(width 0.1143)
		(layer "In2.Cu")
		(net "T11_NODE4_EN")
	)
	(segment
		(start 153.47188 -178.758596)
		(end 153.47188 -181.145688)
		(width 0.1143)
		(layer "In2.Cu")
		(net "T11_NODE4_EN")
	)
	(segment
		(start 139.93876 -184.805574)
		(end 139.93876 -183.466232)
		(width 0.1016)
		(layer "F.Cu")
		(net "T10_NODE2_EN")
	)
	(segment
		(start 139.93876 -183.466232)
		(end 139.83589 -183.363362)
		(width 0.1016)
		(layer "F.Cu")
		(net "T10_NODE2_EN")
	)
	(via
		(at 139.83589 -183.363362)
		(size 0.508)
		(drill 0.254)
		(layers "F.Cu" "B.Cu")
		(net "T10_NODE2_EN")
	)
	(via
		(at 143.148558 -175.840136)
		(size 0.508)
		(drill 0.254)
		(layers "F.Cu" "B.Cu")
		(net "T10_NODE2_EN")
	)
	(segment
		(start 142.47241 -176.061624)
		(end 142.92707 -176.061624)
		(width 0.1016)
		(layer "B.Cu")
		(net "T10_NODE2_EN")
	)
	(segment
		(start 143.596106 -175.840136)
		(end 143.148558 -175.840136)
		(width 0.1016)
		(layer "B.Cu")
		(net "T10_NODE2_EN")
	)
	(segment
		(start 142.92707 -176.061624)
		(end 143.148558 -175.840136)
		(width 0.1016)
		(layer "B.Cu")
		(net "T10_NODE2_EN")
	)
	(segment
		(start 144.289526 -175.146716)
		(end 143.596106 -175.840136)
		(width 0.1016)
		(layer "B.Cu")
		(net "T10_NODE2_EN")
	)
	(segment
		(start 145.14576 -175.146716)
		(end 144.289526 -175.146716)
		(width 0.1016)
		(layer "B.Cu")
		(net "T10_NODE2_EN")
	)
	(segment
		(start 143.990822 -176.250346)
		(end 143.990822 -177.885344)
		(width 0.1143)
		(layer "In2.Cu")
		(net "T10_NODE2_EN")
	)
	(segment
		(start 141.077188 -182.833264)
		(end 140.54709 -183.363362)
		(width 0.1143)
		(layer "In2.Cu")
		(net "T10_NODE2_EN")
	)
	(segment
		(start 143.88846 -179.746656)
		(end 143.963898 -179.822094)
		(width 0.1143)
		(layer "In2.Cu")
		(net "T10_NODE2_EN")
	)
	(segment
		(start 140.54709 -183.363362)
		(end 139.83589 -183.363362)
		(width 0.1143)
		(layer "In2.Cu")
		(net "T10_NODE2_EN")
	)
	(segment
		(start 143.990822 -177.885344)
		(end 143.88846 -177.987706)
		(width 0.1143)
		(layer "In2.Cu")
		(net "T10_NODE2_EN")
	)
	(segment
		(start 143.963898 -179.822094)
		(end 143.963898 -180.997098)
		(width 0.1143)
		(layer "In2.Cu")
		(net "T10_NODE2_EN")
	)
	(segment
		(start 143.148558 -175.840136)
		(end 143.580612 -175.840136)
		(width 0.1143)
		(layer "In2.Cu")
		(net "T10_NODE2_EN")
	)
	(segment
		(start 143.59128 -181.80177)
		(end 142.559786 -182.833264)
		(width 0.1143)
		(layer "In2.Cu")
		(net "T10_NODE2_EN")
	)
	(segment
		(start 143.88846 -177.987706)
		(end 143.88846 -179.746656)
		(width 0.1143)
		(layer "In2.Cu")
		(net "T10_NODE2_EN")
	)
	(segment
		(start 143.59128 -181.369716)
		(end 143.59128 -181.80177)
		(width 0.1143)
		(layer "In2.Cu")
		(net "T10_NODE2_EN")
	)
	(segment
		(start 142.559786 -182.833264)
		(end 141.077188 -182.833264)
		(width 0.1143)
		(layer "In2.Cu")
		(net "T10_NODE2_EN")
	)
	(segment
		(start 143.580612 -175.840136)
		(end 143.990822 -176.250346)
		(width 0.1143)
		(layer "In2.Cu")
		(net "T10_NODE2_EN")
	)
	(segment
		(start 143.963898 -180.997098)
		(end 143.59128 -181.369716)
		(width 0.1143)
		(layer "In2.Cu")
		(net "T10_NODE2_EN")
	)
	(via
		(at 80.52308 -199.767444)
		(size 0.6604)
		(drill 0.3302)
		(layers "F.Cu" "B.Cu")
		(net "T3_NODE1_EN_R")
	)
	(segment
		(start 79.23276 -188.526674)
		(end 79.355442 -188.526674)
		(width 0.1016)
		(layer "B.Cu")
		(net "T3_NODE1_EN_R")
	)
	(segment
		(start 80.52308 -197.706742)
		(end 80.52308 -199.767444)
		(width 0.1016)
		(layer "B.Cu")
		(net "T3_NODE1_EN_R")
	)
	(segment
		(start 80.15478 -197.338442)
		(end 80.52308 -197.706742)
		(width 0.1016)
		(layer "B.Cu")
		(net "T3_NODE1_EN_R")
	)
	(segment
		(start 79.7687 -188.113416)
		(end 79.7687 -186.60999)
		(width 0.1016)
		(layer "B.Cu")
		(net "T3_NODE1_EN_R")
	)
	(segment
		(start 79.23276 -188.526674)
		(end 79.23276 -189.22365)
		(width 0.1016)
		(layer "B.Cu")
		(net "T3_NODE1_EN_R")
	)
	(segment
		(start 79.7687 -186.60999)
		(end 79.60614 -186.44743)
		(width 0.1016)
		(layer "B.Cu")
		(net "T3_NODE1_EN_R")
	)
	(segment
		(start 79.23276 -189.22365)
		(end 80.15478 -190.14567)
		(width 0.1016)
		(layer "B.Cu")
		(net "T3_NODE1_EN_R")
	)
	(segment
		(start 80.01508 -200.692512)
		(end 80.01508 -205.199488)
		(width 0.1016)
		(layer "B.Cu")
		(net "T3_NODE1_EN_R")
	)
	(segment
		(start 80.52308 -200.184512)
		(end 80.01508 -200.692512)
		(width 0.1016)
		(layer "B.Cu")
		(net "T3_NODE1_EN_R")
	)
	(segment
		(start 79.355442 -188.526674)
		(end 79.7687 -188.113416)
		(width 0.1016)
		(layer "B.Cu")
		(net "T3_NODE1_EN_R")
	)
	(segment
		(start 80.15478 -190.14567)
		(end 80.15478 -197.338442)
		(width 0.1016)
		(layer "B.Cu")
		(net "T3_NODE1_EN_R")
	)
	(segment
		(start 80.52308 -199.767444)
		(end 80.52308 -200.184512)
		(width 0.1016)
		(layer "B.Cu")
		(net "T3_NODE1_EN_R")
	)
	(segment
		(start 79.60614 -186.44743)
		(end 79.60614 -185.998104)
		(width 0.1016)
		(layer "B.Cu")
		(net "T3_NODE1_EN_R")
	)
	(segment
		(start 94.634812 -183.799988)
		(end 95.776796 -183.799988)
		(width 0.1016)
		(layer "F.Cu")
		(net "T5_NODE3_EN_R")
	)
	(segment
		(start 95.776796 -183.799988)
		(end 95.97136 -183.994552)
		(width 0.1016)
		(layer "F.Cu")
		(net "T5_NODE3_EN_R")
	)
	(via
		(at 94.83598 -199.117712)
		(size 0.6604)
		(drill 0.3302)
		(layers "F.Cu" "B.Cu")
		(net "T5_NODE3_EN_R")
	)
	(via
		(at 95.97136 -183.994552)
		(size 0.508)
		(drill 0.254)
		(layers "F.Cu" "B.Cu")
		(net "T5_NODE3_EN_R")
	)
	(segment
		(start 96.2406 -187.120022)
		(end 96.1009 -187.259722)
		(width 0.1016)
		(layer "B.Cu")
		(net "T5_NODE3_EN_R")
	)
	(segment
		(start 95.01505 -199.296782)
		(end 95.01505 -205.199488)
		(width 0.1016)
		(layer "B.Cu")
		(net "T5_NODE3_EN_R")
	)
	(segment
		(start 95.97136 -183.994552)
		(end 95.422974 -183.994552)
		(width 0.1016)
		(layer "B.Cu")
		(net "T5_NODE3_EN_R")
	)
	(segment
		(start 96.2406 -184.263792)
		(end 96.2406 -187.120022)
		(width 0.1016)
		(layer "B.Cu")
		(net "T5_NODE3_EN_R")
	)
	(segment
		(start 96.1009 -187.259722)
		(end 96.1009 -189.911228)
		(width 0.1016)
		(layer "B.Cu")
		(net "T5_NODE3_EN_R")
	)
	(segment
		(start 94.634812 -184.782714)
		(end 94.634812 -184.815988)
		(width 0.1016)
		(layer "B.Cu")
		(net "T5_NODE3_EN_R")
	)
	(segment
		(start 94.83598 -191.176148)
		(end 94.83598 -199.117712)
		(width 0.1016)
		(layer "B.Cu")
		(net "T5_NODE3_EN_R")
	)
	(segment
		(start 95.422974 -183.994552)
		(end 94.634812 -184.782714)
		(width 0.1016)
		(layer "B.Cu")
		(net "T5_NODE3_EN_R")
	)
	(segment
		(start 94.83598 -199.117712)
		(end 95.01505 -199.296782)
		(width 0.1016)
		(layer "B.Cu")
		(net "T5_NODE3_EN_R")
	)
	(segment
		(start 95.97136 -183.994552)
		(end 96.2406 -184.263792)
		(width 0.1016)
		(layer "B.Cu")
		(net "T5_NODE3_EN_R")
	)
	(segment
		(start 96.1009 -189.911228)
		(end 94.83598 -191.176148)
		(width 0.1016)
		(layer "B.Cu")
		(net "T5_NODE3_EN_R")
	)
	(segment
		(start 83.220814 -183.001158)
		(end 82.944462 -183.27751)
		(width 0.1016)
		(layer "F.Cu")
		(net "T4_NODE3_EN")
	)
	(segment
		(start 82.69224 -181.201314)
		(end 83.220814 -181.729888)
		(width 0.1016)
		(layer "F.Cu")
		(net "T4_NODE3_EN")
	)
	(segment
		(start 80.2767 -184.805574)
		(end 80.24876 -184.805574)
		(width 0.1016)
		(layer "F.Cu")
		(net "T4_NODE3_EN")
	)
	(segment
		(start 81.804764 -183.27751)
		(end 80.2767 -184.805574)
		(width 0.1016)
		(layer "F.Cu")
		(net "T4_NODE3_EN")
	)
	(segment
		(start 83.220814 -181.729888)
		(end 83.220814 -183.001158)
		(width 0.1016)
		(layer "F.Cu")
		(net "T4_NODE3_EN")
	)
	(segment
		(start 82.944462 -183.27751)
		(end 81.804764 -183.27751)
		(width 0.1016)
		(layer "F.Cu")
		(net "T4_NODE3_EN")
	)
	(via
		(at 82.69224 -181.201314)
		(size 0.508)
		(drill 0.254)
		(layers "F.Cu" "B.Cu")
		(net "T4_NODE3_EN")
	)
	(segment
		(start 87.74176 -173.069504)
		(end 89.11082 -173.069504)
		(width 0.1016)
		(layer "B.Cu")
		(net "T4_NODE3_EN")
	)
	(segment
		(start 87.74176 -173.069504)
		(end 87.74176 -173.068742)
		(width 0.1016)
		(layer "B.Cu")
		(net "T4_NODE3_EN")
	)
	(segment
		(start 87.74176 -173.068742)
		(end 86.188804 -173.068742)
		(width 0.1016)
		(layer "B.Cu")
		(net "T4_NODE3_EN")
	)
	(segment
		(start 86.188804 -173.068742)
		(end 83.52536 -175.732186)
		(width 0.1016)
		(layer "B.Cu")
		(net "T4_NODE3_EN")
	)
	(segment
		(start 83.52536 -175.732186)
		(end 83.52536 -178.570128)
		(width 0.1016)
		(layer "B.Cu")
		(net "T4_NODE3_EN")
	)
	(segment
		(start 90.189812 -171.990512)
		(end 90.41257 -171.990512)
		(width 0.1016)
		(layer "B.Cu")
		(net "T4_NODE3_EN")
	)
	(segment
		(start 89.11082 -173.069504)
		(end 90.189812 -171.990512)
		(width 0.1016)
		(layer "B.Cu")
		(net "T4_NODE3_EN")
	)
	(segment
		(start 82.78368 -179.311808)
		(end 82.78368 -181.109874)
		(width 0.1016)
		(layer "B.Cu")
		(net "T4_NODE3_EN")
	)
	(segment
		(start 83.52536 -178.570128)
		(end 82.78368 -179.311808)
		(width 0.1016)
		(layer "B.Cu")
		(net "T4_NODE3_EN")
	)
	(segment
		(start 82.78368 -181.109874)
		(end 82.69224 -181.201314)
		(width 0.1016)
		(layer "B.Cu")
		(net "T4_NODE3_EN")
	)
	(via
		(at 148.415248 -180.521864)
		(size 0.508)
		(drill 0.254)
		(layers "F.Cu" "B.Cu")
		(net "T11_NODE2_EN")
	)
	(via
		(at 153.961084 -181.13883)
		(size 0.508)
		(drill 0.254)
		(layers "F.Cu" "B.Cu")
		(net "T11_NODE2_EN")
	)
	(segment
		(start 148.85924 -180.077872)
		(end 148.415248 -180.521864)
		(width 0.1016)
		(layer "B.Cu")
		(net "T11_NODE2_EN")
	)
	(segment
		(start 148.247354 -178.253898)
		(end 148.247354 -178.384454)
		(width 0.1016)
		(layer "B.Cu")
		(net "T11_NODE2_EN")
	)
	(segment
		(start 150.054564 -176.446688)
		(end 148.247354 -178.253898)
		(width 0.1016)
		(layer "B.Cu")
		(net "T11_NODE2_EN")
	)
	(segment
		(start 153.90876 -184.551574)
		(end 153.90876 -184.165748)
		(width 0.1016)
		(layer "B.Cu")
		(net "T11_NODE2_EN")
	)
	(segment
		(start 148.247354 -178.384454)
		(end 148.85924 -178.99634)
		(width 0.1016)
		(layer "B.Cu")
		(net "T11_NODE2_EN")
	)
	(segment
		(start 150.98776 -176.446688)
		(end 150.054564 -176.446688)
		(width 0.1016)
		(layer "B.Cu")
		(net "T11_NODE2_EN")
	)
	(segment
		(start 148.85924 -178.99634)
		(end 148.85924 -180.077872)
		(width 0.1016)
		(layer "B.Cu")
		(net "T11_NODE2_EN")
	)
	(segment
		(start 153.6065 -181.493414)
		(end 153.961084 -181.13883)
		(width 0.1016)
		(layer "B.Cu")
		(net "T11_NODE2_EN")
	)
	(segment
		(start 153.6065 -183.863488)
		(end 153.6065 -181.493414)
		(width 0.1016)
		(layer "B.Cu")
		(net "T11_NODE2_EN")
	)
	(segment
		(start 153.90876 -184.165748)
		(end 153.6065 -183.863488)
		(width 0.1016)
		(layer "B.Cu")
		(net "T11_NODE2_EN")
	)
	(segment
		(start 151.60371 -179.580032)
		(end 151.24049 -179.580032)
		(width 0.1143)
		(layer "In6.Cu")
		(net "T11_NODE2_EN")
	)
	(segment
		(start 148.690076 -180.247036)
		(end 148.415248 -180.521864)
		(width 0.1143)
		(layer "In6.Cu")
		(net "T11_NODE2_EN")
	)
	(segment
		(start 152.270714 -180.247036)
		(end 151.60371 -179.580032)
		(width 0.1143)
		(layer "In6.Cu")
		(net "T11_NODE2_EN")
	)
	(segment
		(start 150.573486 -180.247036)
		(end 148.690076 -180.247036)
		(width 0.1143)
		(layer "In6.Cu")
		(net "T11_NODE2_EN")
	)
	(segment
		(start 153.961084 -181.13883)
		(end 153.06929 -180.247036)
		(width 0.1143)
		(layer "In6.Cu")
		(net "T11_NODE2_EN")
	)
	(segment
		(start 151.24049 -179.580032)
		(end 150.573486 -180.247036)
		(width 0.1143)
		(layer "In6.Cu")
		(net "T11_NODE2_EN")
	)
	(segment
		(start 153.06929 -180.247036)
		(end 152.270714 -180.247036)
		(width 0.1143)
		(layer "In6.Cu")
		(net "T11_NODE2_EN")
	)
	(via
		(at 76.81976 -199.321674)
		(size 0.6604)
		(drill 0.3302)
		(layers "F.Cu" "B.Cu")
		(net "T3_NODE4_EN_R")
	)
	(segment
		(start 76.41844 -185.40349)
		(end 76.5683 -185.25363)
		(width 0.1016)
		(layer "B.Cu")
		(net "T3_NODE4_EN_R")
	)
	(segment
		(start 76.41844 -187.353194)
		(end 76.41844 -185.40349)
		(width 0.1016)
		(layer "B.Cu")
		(net "T3_NODE4_EN_R")
	)
	(segment
		(start 77.015086 -199.674226)
		(end 77.015086 -205.199488)
		(width 0.1016)
		(layer "B.Cu")
		(net "T3_NODE4_EN_R")
	)
	(segment
		(start 76.48956 -187.424314)
		(end 76.41844 -187.353194)
		(width 0.1016)
		(layer "B.Cu")
		(net "T3_NODE4_EN_R")
	)
	(segment
		(start 76.48956 -188.094874)
		(end 76.48956 -187.424314)
		(width 0.1016)
		(layer "B.Cu")
		(net "T3_NODE4_EN_R")
	)
	(segment
		(start 76.81976 -199.321674)
		(end 76.81976 -189.288674)
		(width 0.1016)
		(layer "B.Cu")
		(net "T3_NODE4_EN_R")
	)
	(segment
		(start 76.81976 -189.288674)
		(end 76.05776 -188.526674)
		(width 0.1016)
		(layer "B.Cu")
		(net "T3_NODE4_EN_R")
	)
	(segment
		(start 76.05776 -188.526674)
		(end 76.48956 -188.094874)
		(width 0.1016)
		(layer "B.Cu")
		(net "T3_NODE4_EN_R")
	)
	(segment
		(start 76.81976 -199.321674)
		(end 76.81976 -199.4789)
		(width 0.1016)
		(layer "B.Cu")
		(net "T3_NODE4_EN_R")
	)
	(segment
		(start 76.81976 -199.4789)
		(end 77.015086 -199.674226)
		(width 0.1016)
		(layer "B.Cu")
		(net "T3_NODE4_EN_R")
	)
	(via
		(at 66.04 -199.449182)
		(size 0.6604)
		(drill 0.3302)
		(layers "F.Cu" "B.Cu")
		(net "T1_NODE1_EN_R")
	)
	(segment
		(start 66.04 -199.449182)
		(end 66.04 -200.002648)
		(width 0.1016)
		(layer "B.Cu")
		(net "T1_NODE1_EN_R")
	)
	(segment
		(start 65.01511 -201.027538)
		(end 65.01511 -205.199488)
		(width 0.1016)
		(layer "B.Cu")
		(net "T1_NODE1_EN_R")
	)
	(segment
		(start 66.04 -189.502034)
		(end 66.77406 -188.767974)
		(width 0.1016)
		(layer "B.Cu")
		(net "T1_NODE1_EN_R")
	)
	(segment
		(start 66.04 -200.002648)
		(end 65.01511 -201.027538)
		(width 0.1016)
		(layer "B.Cu")
		(net "T1_NODE1_EN_R")
	)
	(segment
		(start 66.53276 -185.605674)
		(end 66.53276 -186.00039)
		(width 0.1016)
		(layer "B.Cu")
		(net "T1_NODE1_EN_R")
	)
	(segment
		(start 66.04 -199.449182)
		(end 66.04 -189.502034)
		(width 0.1016)
		(layer "B.Cu")
		(net "T1_NODE1_EN_R")
	)
	(segment
		(start 65.94348 -187.937394)
		(end 66.53276 -188.526674)
		(width 0.1016)
		(layer "B.Cu")
		(net "T1_NODE1_EN_R")
	)
	(segment
		(start 65.94348 -186.58967)
		(end 65.94348 -187.937394)
		(width 0.1016)
		(layer "B.Cu")
		(net "T1_NODE1_EN_R")
	)
	(segment
		(start 66.77406 -188.767974)
		(end 66.53276 -188.526674)
		(width 0.1016)
		(layer "B.Cu")
		(net "T1_NODE1_EN_R")
	)
	(segment
		(start 66.53276 -186.00039)
		(end 65.94348 -186.58967)
		(width 0.1016)
		(layer "B.Cu")
		(net "T1_NODE1_EN_R")
	)
	(segment
		(start 153.016458 -178.914044)
		(end 153.016458 -172.85335)
		(width 0.1016)
		(layer "F.Cu")
		(net "T12_NODE4_EN")
	)
	(segment
		(start 157.184344 -182.901336)
		(end 154.570684 -180.287676)
		(width 0.1016)
		(layer "F.Cu")
		(net "T12_NODE4_EN")
	)
	(segment
		(start 154.570684 -180.287676)
		(end 154.39009 -180.287676)
		(width 0.1016)
		(layer "F.Cu")
		(net "T12_NODE4_EN")
	)
	(segment
		(start 158.685484 -182.901336)
		(end 157.184344 -182.901336)
		(width 0.1016)
		(layer "F.Cu")
		(net "T12_NODE4_EN")
	)
	(segment
		(start 159.382968 -183.30545)
		(end 159.089598 -183.30545)
		(width 0.1016)
		(layer "F.Cu")
		(net "T12_NODE4_EN")
	)
	(segment
		(start 159.55264 -183.475122)
		(end 159.382968 -183.30545)
		(width 0.1016)
		(layer "F.Cu")
		(net "T12_NODE4_EN")
	)
	(segment
		(start 159.089598 -183.30545)
		(end 158.685484 -182.901336)
		(width 0.1016)
		(layer "F.Cu")
		(net "T12_NODE4_EN")
	)
	(segment
		(start 152.91308 -172.749972)
		(end 152.91308 -172.505624)
		(width 0.1016)
		(layer "F.Cu")
		(net "T12_NODE4_EN")
	)
	(segment
		(start 153.016458 -172.85335)
		(end 152.91308 -172.749972)
		(width 0.1016)
		(layer "F.Cu")
		(net "T12_NODE4_EN")
	)
	(segment
		(start 154.39009 -180.287676)
		(end 153.016458 -178.914044)
		(width 0.1016)
		(layer "F.Cu")
		(net "T12_NODE4_EN")
	)
	(via
		(at 152.91308 -172.505624)
		(size 0.508)
		(drill 0.254)
		(layers "F.Cu" "B.Cu")
		(net "T12_NODE4_EN")
	)
	(via
		(at 159.55264 -183.475122)
		(size 0.508)
		(drill 0.254)
		(layers "F.Cu" "B.Cu")
		(net "T12_NODE4_EN")
	)
	(segment
		(start 152.872186 -172.546518)
		(end 152.91308 -172.505624)
		(width 0.1016)
		(layer "B.Cu")
		(net "T12_NODE4_EN")
	)
	(segment
		(start 159.55264 -183.768492)
		(end 159.55264 -183.475122)
		(width 0.1016)
		(layer "B.Cu")
		(net "T12_NODE4_EN")
	)
	(segment
		(start 159.62376 -184.549288)
		(end 159.62376 -183.839612)
		(width 0.1016)
		(layer "B.Cu")
		(net "T12_NODE4_EN")
	)
	(segment
		(start 159.62376 -183.839612)
		(end 159.55264 -183.768492)
		(width 0.1016)
		(layer "B.Cu")
		(net "T12_NODE4_EN")
	)
	(segment
		(start 150.98776 -172.546518)
		(end 152.872186 -172.546518)
		(width 0.1016)
		(layer "B.Cu")
		(net "T12_NODE4_EN")
	)
	(segment
		(start 152.91308 -172.505624)
		(end 153.66111 -172.505624)
		(width 0.1016)
		(layer "B.Cu")
		(net "T12_NODE4_EN")
	)
	(via
		(at 78.34122 -182.548022)
		(size 0.6604)
		(drill 0.3302)
		(layers "F.Cu" "B.Cu")
		(net "T3_NODE4_EN")
	)
	(segment
		(start 77.25918 -182.548022)
		(end 78.34122 -182.548022)
		(width 0.1016)
		(layer "B.Cu")
		(net "T3_NODE4_EN")
	)
	(segment
		(start 84.94268 -177.15611)
		(end 84.94268 -178.091592)
		(width 0.1016)
		(layer "B.Cu")
		(net "T3_NODE4_EN")
	)
	(segment
		(start 84.94014 -177.15357)
		(end 84.94268 -177.15611)
		(width 0.1016)
		(layer "B.Cu")
		(net "T3_NODE4_EN")
	)
	(segment
		(start 79.809086 -182.447184)
		(end 79.553816 -182.702454)
		(width 0.1016)
		(layer "B.Cu")
		(net "T3_NODE4_EN")
	)
	(segment
		(start 82.78495 -181.82717)
		(end 82.0674 -181.82717)
		(width 0.1016)
		(layer "B.Cu")
		(net "T3_NODE4_EN")
	)
	(segment
		(start 76.5683 -183.238902)
		(end 77.25918 -182.548022)
		(width 0.1016)
		(layer "B.Cu")
		(net "T3_NODE4_EN")
	)
	(segment
		(start 84.94014 -176.080166)
		(end 84.94014 -177.15357)
		(width 0.1016)
		(layer "B.Cu")
		(net "T3_NODE4_EN")
	)
	(segment
		(start 76.5683 -184.45353)
		(end 76.5683 -183.238902)
		(width 0.1016)
		(layer "B.Cu")
		(net "T3_NODE4_EN")
	)
	(segment
		(start 85.627718 -175.392588)
		(end 84.94014 -176.080166)
		(width 0.1016)
		(layer "B.Cu")
		(net "T3_NODE4_EN")
	)
	(segment
		(start 79.553816 -182.702454)
		(end 79.06512 -182.702454)
		(width 0.1016)
		(layer "B.Cu")
		(net "T3_NODE4_EN")
	)
	(segment
		(start 83.2358 -181.37632)
		(end 82.78495 -181.82717)
		(width 0.1016)
		(layer "B.Cu")
		(net "T3_NODE4_EN")
	)
	(segment
		(start 89.83853 -175.462184)
		(end 89.324688 -175.462184)
		(width 0.1016)
		(layer "B.Cu")
		(net "T3_NODE4_EN")
	)
	(segment
		(start 86.532466 -175.392588)
		(end 85.627718 -175.392588)
		(width 0.1016)
		(layer "B.Cu")
		(net "T3_NODE4_EN")
	)
	(segment
		(start 90.262202 -175.038512)
		(end 89.83853 -175.462184)
		(width 0.1016)
		(layer "B.Cu")
		(net "T3_NODE4_EN")
	)
	(segment
		(start 88.88222 -175.019716)
		(end 87.74176 -175.019716)
		(width 0.1016)
		(layer "B.Cu")
		(net "T3_NODE4_EN")
	)
	(segment
		(start 89.324688 -175.462184)
		(end 88.88222 -175.019716)
		(width 0.1016)
		(layer "B.Cu")
		(net "T3_NODE4_EN")
	)
	(segment
		(start 80.947514 -182.447184)
		(end 79.809086 -182.447184)
		(width 0.1016)
		(layer "B.Cu")
		(net "T3_NODE4_EN")
	)
	(segment
		(start 87.74176 -175.019716)
		(end 86.905338 -175.019716)
		(width 0.1016)
		(layer "B.Cu")
		(net "T3_NODE4_EN")
	)
	(segment
		(start 90.41257 -175.038512)
		(end 90.262202 -175.038512)
		(width 0.1016)
		(layer "B.Cu")
		(net "T3_NODE4_EN")
	)
	(segment
		(start 83.2358 -179.798472)
		(end 83.2358 -181.37632)
		(width 0.1016)
		(layer "B.Cu")
		(net "T3_NODE4_EN")
	)
	(segment
		(start 79.06512 -182.702454)
		(end 78.910688 -182.548022)
		(width 0.1016)
		(layer "B.Cu")
		(net "T3_NODE4_EN")
	)
	(segment
		(start 82.0674 -181.82717)
		(end 81.420208 -182.474362)
		(width 0.1016)
		(layer "B.Cu")
		(net "T3_NODE4_EN")
	)
	(segment
		(start 81.420208 -182.474362)
		(end 80.974692 -182.474362)
		(width 0.1016)
		(layer "B.Cu")
		(net "T3_NODE4_EN")
	)
	(segment
		(start 86.905338 -175.019716)
		(end 86.532466 -175.392588)
		(width 0.1016)
		(layer "B.Cu")
		(net "T3_NODE4_EN")
	)
	(segment
		(start 78.910688 -182.548022)
		(end 78.34122 -182.548022)
		(width 0.1016)
		(layer "B.Cu")
		(net "T3_NODE4_EN")
	)
	(segment
		(start 80.974692 -182.474362)
		(end 80.947514 -182.447184)
		(width 0.1016)
		(layer "B.Cu")
		(net "T3_NODE4_EN")
	)
	(segment
		(start 84.94268 -178.091592)
		(end 83.2358 -179.798472)
		(width 0.1016)
		(layer "B.Cu")
		(net "T3_NODE4_EN")
	)
	(via
		(at 138.413236 -183.08828)
		(size 0.508)
		(drill 0.254)
		(layers "F.Cu" "B.Cu")
		(net "T9_NODE3_EN")
	)
	(via
		(at 143.150844 -173.262798)
		(size 0.508)
		(drill 0.254)
		(layers "F.Cu" "B.Cu")
		(net "T9_NODE3_EN")
	)
	(segment
		(start 137.65276 -184.551574)
		(end 137.65276 -183.848756)
		(width 0.1016)
		(layer "B.Cu")
		(net "T9_NODE3_EN")
	)
	(segment
		(start 142.47241 -173.013624)
		(end 142.90167 -173.013624)
		(width 0.1016)
		(layer "B.Cu")
		(net "T9_NODE3_EN")
	)
	(segment
		(start 143.975582 -173.262798)
		(end 143.150844 -173.262798)
		(width 0.1016)
		(layer "B.Cu")
		(net "T9_NODE3_EN")
	)
	(segment
		(start 142.90167 -173.013624)
		(end 143.150844 -173.262798)
		(width 0.1016)
		(layer "B.Cu")
		(net "T9_NODE3_EN")
	)
	(segment
		(start 144.041876 -173.196504)
		(end 143.975582 -173.262798)
		(width 0.1016)
		(layer "B.Cu")
		(net "T9_NODE3_EN")
	)
	(segment
		(start 145.14576 -173.196504)
		(end 144.041876 -173.196504)
		(width 0.1016)
		(layer "B.Cu")
		(net "T9_NODE3_EN")
	)
	(segment
		(start 137.65276 -183.848756)
		(end 138.413236 -183.08828)
		(width 0.1016)
		(layer "B.Cu")
		(net "T9_NODE3_EN")
	)
	(segment
		(start 138.915902 -183.08828)
		(end 141.793468 -180.210714)
		(width 0.1143)
		(layer "In7.Cu")
		(net "T9_NODE3_EN")
	)
	(segment
		(start 143.654272 -173.373796)
		(end 143.261842 -173.373796)
		(width 0.1143)
		(layer "In7.Cu")
		(net "T9_NODE3_EN")
	)
	(segment
		(start 141.793468 -180.210714)
		(end 141.793468 -178.820318)
		(width 0.1143)
		(layer "In7.Cu")
		(net "T9_NODE3_EN")
	)
	(segment
		(start 143.990822 -173.710346)
		(end 143.654272 -173.373796)
		(width 0.1143)
		(layer "In7.Cu")
		(net "T9_NODE3_EN")
	)
	(segment
		(start 143.261842 -173.373796)
		(end 143.150844 -173.262798)
		(width 0.1143)
		(layer "In7.Cu")
		(net "T9_NODE3_EN")
	)
	(segment
		(start 138.413236 -183.08828)
		(end 138.915902 -183.08828)
		(width 0.1143)
		(layer "In7.Cu")
		(net "T9_NODE3_EN")
	)
	(segment
		(start 141.793468 -178.820318)
		(end 143.990822 -176.622964)
		(width 0.1143)
		(layer "In7.Cu")
		(net "T9_NODE3_EN")
	)
	(segment
		(start 143.990822 -176.622964)
		(end 143.990822 -173.710346)
		(width 0.1143)
		(layer "In7.Cu")
		(net "T9_NODE3_EN")
	)
	(segment
		(start 86.84133 -181.376066)
		(end 85.94979 -181.376066)
		(width 0.1016)
		(layer "F.Cu")
		(net "T4_NODE1_EN")
	)
	(segment
		(start 85.16493 -182.160926)
		(end 83.813396 -183.51246)
		(width 0.1016)
		(layer "F.Cu")
		(net "T4_NODE1_EN")
	)
	(segment
		(start 87.35822 -180.004466)
		(end 87.35822 -180.758846)
		(width 0.1016)
		(layer "F.Cu")
		(net "T4_NODE1_EN")
	)
	(segment
		(start 87.11692 -181.000146)
		(end 87.11692 -181.100476)
		(width 0.1016)
		(layer "F.Cu")
		(net "T4_NODE1_EN")
	)
	(segment
		(start 86.127844 -178.77409)
		(end 87.35822 -180.004466)
		(width 0.1016)
		(layer "F.Cu")
		(net "T4_NODE1_EN")
	)
	(segment
		(start 87.35822 -180.758846)
		(end 87.11692 -181.000146)
		(width 0.1016)
		(layer "F.Cu")
		(net "T4_NODE1_EN")
	)
	(segment
		(start 84.51088 -177.33518)
		(end 85.94979 -178.77409)
		(width 0.1016)
		(layer "F.Cu")
		(net "T4_NODE1_EN")
	)
	(segment
		(start 83.813396 -183.51246)
		(end 83.48472 -183.51246)
		(width 0.1016)
		(layer "F.Cu")
		(net "T4_NODE1_EN")
	)
	(segment
		(start 87.11692 -181.100476)
		(end 86.84133 -181.376066)
		(width 0.1016)
		(layer "F.Cu")
		(net "T4_NODE1_EN")
	)
	(segment
		(start 85.94979 -178.77409)
		(end 86.127844 -178.77409)
		(width 0.1016)
		(layer "F.Cu")
		(net "T4_NODE1_EN")
	)
	(segment
		(start 85.94979 -181.376066)
		(end 85.16493 -182.160926)
		(width 0.1016)
		(layer "F.Cu")
		(net "T4_NODE1_EN")
	)
	(segment
		(start 83.48472 -183.51246)
		(end 82.53476 -184.46242)
		(width 0.1016)
		(layer "F.Cu")
		(net "T4_NODE1_EN")
	)
	(segment
		(start 82.53476 -184.46242)
		(end 82.53476 -184.805574)
		(width 0.1016)
		(layer "F.Cu")
		(net "T4_NODE1_EN")
	)
	(via
		(at 85.16493 -182.160926)
		(size 0.762)
		(drill 0.381)
		(layers "F.Cu" "B.Cu")
		(net "T4_NODE1_EN")
	)
	(via
		(at 84.51088 -177.33518)
		(size 0.508)
		(drill 0.254)
		(layers "F.Cu" "B.Cu")
		(net "T4_NODE1_EN")
	)
	(segment
		(start 84.51088 -176.150016)
		(end 85.656928 -175.003968)
		(width 0.1016)
		(layer "B.Cu")
		(net "T4_NODE1_EN")
	)
	(segment
		(start 84.51088 -177.33518)
		(end 84.51088 -176.150016)
		(width 0.1016)
		(layer "B.Cu")
		(net "T4_NODE1_EN")
	)
	(segment
		(start 87.166958 -174.36973)
		(end 87.74176 -174.36973)
		(width 0.1016)
		(layer "B.Cu")
		(net "T4_NODE1_EN")
	)
	(segment
		(start 86.53272 -175.003968)
		(end 87.166958 -174.36973)
		(width 0.1016)
		(layer "B.Cu")
		(net "T4_NODE1_EN")
	)
	(segment
		(start 85.656928 -175.003968)
		(end 86.53272 -175.003968)
		(width 0.1016)
		(layer "B.Cu")
		(net "T4_NODE1_EN")
	)
	(segment
		(start 89.792302 -174.022512)
		(end 89.445084 -174.36973)
		(width 0.1016)
		(layer "B.Cu")
		(net "T4_NODE1_EN")
	)
	(segment
		(start 90.41257 -174.022512)
		(end 89.792302 -174.022512)
		(width 0.1016)
		(layer "B.Cu")
		(net "T4_NODE1_EN")
	)
	(segment
		(start 89.445084 -174.36973)
		(end 87.74176 -174.36973)
		(width 0.1016)
		(layer "B.Cu")
		(net "T4_NODE1_EN")
	)
	(segment
		(start 67.67576 -184.490106)
		(end 68.38696 -183.778906)
		(width 0.1016)
		(layer "F.Cu")
		(net "T2_NODE2_EN")
	)
	(segment
		(start 68.668138 -182.948072)
		(end 74.161904 -182.948072)
		(width 0.1016)
		(layer "F.Cu")
		(net "T2_NODE2_EN")
	)
	(segment
		(start 74.161904 -182.948072)
		(end 74.4982 -182.611776)
		(width 0.1016)
		(layer "F.Cu")
		(net "T2_NODE2_EN")
	)
	(segment
		(start 68.38696 -183.22925)
		(end 68.668138 -182.948072)
		(width 0.1016)
		(layer "F.Cu")
		(net "T2_NODE2_EN")
	)
	(segment
		(start 67.67576 -184.805574)
		(end 67.67576 -184.490106)
		(width 0.1016)
		(layer "F.Cu")
		(net "T2_NODE2_EN")
	)
	(segment
		(start 68.38696 -183.778906)
		(end 68.38696 -183.22925)
		(width 0.1016)
		(layer "F.Cu")
		(net "T2_NODE2_EN")
	)
	(via
		(at 79.911956 -175.454818)
		(size 0.508)
		(drill 0.254)
		(layers "F.Cu" "B.Cu")
		(net "T2_NODE2_EN")
	)
	(via
		(at 74.4982 -182.611776)
		(size 0.508)
		(drill 0.254)
		(layers "F.Cu" "B.Cu")
		(net "T2_NODE2_EN")
	)
	(segment
		(start 80.234028 -175.454818)
		(end 79.911956 -175.454818)
		(width 0.1016)
		(layer "B.Cu")
		(net "T2_NODE2_EN")
	)
	(segment
		(start 79.23149 -175.553624)
		(end 79.81315 -175.553624)
		(width 0.1016)
		(layer "B.Cu")
		(net "T2_NODE2_EN")
	)
	(segment
		(start 80.66913 -175.019716)
		(end 80.234028 -175.454818)
		(width 0.1016)
		(layer "B.Cu")
		(net "T2_NODE2_EN")
	)
	(segment
		(start 79.81315 -175.553624)
		(end 79.911956 -175.454818)
		(width 0.1016)
		(layer "B.Cu")
		(net "T2_NODE2_EN")
	)
	(segment
		(start 81.89976 -175.019716)
		(end 80.66913 -175.019716)
		(width 0.1016)
		(layer "B.Cu")
		(net "T2_NODE2_EN")
	)
	(segment
		(start 75.313032 -181.304692)
		(end 74.647298 -181.970426)
		(width 0.1143)
		(layer "In7.Cu")
		(net "T2_NODE2_EN")
	)
	(segment
		(start 78.62824 -178.308254)
		(end 75.631802 -181.304692)
		(width 0.1143)
		(layer "In7.Cu")
		(net "T2_NODE2_EN")
	)
	(segment
		(start 74.647298 -182.462678)
		(end 74.4982 -182.611776)
		(width 0.1143)
		(layer "In7.Cu")
		(net "T2_NODE2_EN")
	)
	(segment
		(start 75.631802 -181.304692)
		(end 75.313032 -181.304692)
		(width 0.1143)
		(layer "In7.Cu")
		(net "T2_NODE2_EN")
	)
	(segment
		(start 79.911956 -175.454818)
		(end 78.62824 -176.738534)
		(width 0.1143)
		(layer "In7.Cu")
		(net "T2_NODE2_EN")
	)
	(segment
		(start 74.647298 -181.970426)
		(end 74.647298 -182.462678)
		(width 0.1143)
		(layer "In7.Cu")
		(net "T2_NODE2_EN")
	)
	(segment
		(start 78.62824 -176.738534)
		(end 78.62824 -178.308254)
		(width 0.1143)
		(layer "In7.Cu")
		(net "T2_NODE2_EN")
	)
	(segment
		(start 124.6886 -179.36083)
		(end 124.6886 -179.361084)
		(width 0.1016)
		(layer "F.Cu")
		(net "T7_NODE4_EN")
	)
	(segment
		(start 124.79782 -179.470304)
		(end 125.335538 -179.470304)
		(width 0.1016)
		(layer "F.Cu")
		(net "T7_NODE4_EN")
	)
	(segment
		(start 124.6886 -179.361084)
		(end 124.79782 -179.470304)
		(width 0.1016)
		(layer "F.Cu")
		(net "T7_NODE4_EN")
	)
	(segment
		(start 125.335538 -179.470304)
		(end 125.335538 -179.471828)
		(width 0.1016)
		(layer "F.Cu")
		(net "T7_NODE4_EN")
	)
	(via
		(at 124.6886 -179.36083)
		(size 0.508)
		(drill 0.254)
		(layers "F.Cu" "B.Cu")
		(net "T7_NODE4_EN")
	)
	(segment
		(start 119.36476 -178.829716)
		(end 118.160546 -178.829716)
		(width 0.1016)
		(layer "B.Cu")
		(net "T7_NODE4_EN")
	)
	(segment
		(start 118.160546 -178.829716)
		(end 116.616988 -180.373274)
		(width 0.1016)
		(layer "B.Cu")
		(net "T7_NODE4_EN")
	)
	(segment
		(start 117.2591 -182.356252)
		(end 117.2591 -183.990234)
		(width 0.1016)
		(layer "B.Cu")
		(net "T7_NODE4_EN")
	)
	(segment
		(start 117.2591 -183.990234)
		(end 116.44376 -184.805574)
		(width 0.1016)
		(layer "B.Cu")
		(net "T7_NODE4_EN")
	)
	(segment
		(start 116.616988 -180.373274)
		(end 116.616988 -181.71414)
		(width 0.1016)
		(layer "B.Cu")
		(net "T7_NODE4_EN")
	)
	(segment
		(start 122.150886 -178.829716)
		(end 119.36476 -178.829716)
		(width 0.1016)
		(layer "B.Cu")
		(net "T7_NODE4_EN")
	)
	(segment
		(start 116.616988 -181.71414)
		(end 117.2591 -182.356252)
		(width 0.1016)
		(layer "B.Cu")
		(net "T7_NODE4_EN")
	)
	(segment
		(start 124.6886 -179.36083)
		(end 122.682 -179.36083)
		(width 0.1016)
		(layer "B.Cu")
		(net "T7_NODE4_EN")
	)
	(segment
		(start 122.682 -179.36083)
		(end 122.150886 -178.829716)
		(width 0.1016)
		(layer "B.Cu")
		(net "T7_NODE4_EN")
	)
	(via
		(at 106.058208 -196.309996)
		(size 0.6604)
		(drill 0.3302)
		(layers "F.Cu" "B.Cu")
		(net "T5_NODE1_EN_R")
	)
	(segment
		(start 106.28376 -193.737738)
		(end 106.28376 -188.526674)
		(width 0.1016)
		(layer "B.Cu")
		(net "T5_NODE1_EN_R")
	)
	(segment
		(start 105.80878 -186.638184)
		(end 105.80878 -188.051694)
		(width 0.1016)
		(layer "B.Cu")
		(net "T5_NODE1_EN_R")
	)
	(segment
		(start 106.058208 -193.96329)
		(end 106.28376 -193.737738)
		(width 0.1016)
		(layer "B.Cu")
		(net "T5_NODE1_EN_R")
	)
	(segment
		(start 106.28376 -186.163204)
		(end 105.80878 -186.638184)
		(width 0.1016)
		(layer "B.Cu")
		(net "T5_NODE1_EN_R")
	)
	(segment
		(start 105.015538 -199.64273)
		(end 105.781856 -198.876412)
		(width 0.1016)
		(layer "B.Cu")
		(net "T5_NODE1_EN_R")
	)
	(segment
		(start 105.015538 -205.199488)
		(end 105.015538 -199.64273)
		(width 0.1016)
		(layer "B.Cu")
		(net "T5_NODE1_EN_R")
	)
	(segment
		(start 106.28376 -185.605674)
		(end 106.28376 -186.163204)
		(width 0.1016)
		(layer "B.Cu")
		(net "T5_NODE1_EN_R")
	)
	(segment
		(start 105.80878 -188.051694)
		(end 106.28376 -188.526674)
		(width 0.1016)
		(layer "B.Cu")
		(net "T5_NODE1_EN_R")
	)
	(segment
		(start 105.781856 -196.586348)
		(end 106.058208 -196.309996)
		(width 0.1016)
		(layer "B.Cu")
		(net "T5_NODE1_EN_R")
	)
	(segment
		(start 105.781856 -198.876412)
		(end 105.781856 -196.586348)
		(width 0.1016)
		(layer "B.Cu")
		(net "T5_NODE1_EN_R")
	)
	(segment
		(start 106.058208 -196.309996)
		(end 106.058208 -193.96329)
		(width 0.1016)
		(layer "B.Cu")
		(net "T5_NODE1_EN_R")
	)
	(segment
		(start 66.678302 -184.804812)
		(end 66.53276 -184.804812)
		(width 0.1016)
		(layer "F.Cu")
		(net "T2_NODE3_EN")
	)
	(segment
		(start 73.4441 -182.511192)
		(end 73.311766 -182.643526)
		(width 0.1016)
		(layer "F.Cu")
		(net "T2_NODE3_EN")
	)
	(segment
		(start 73.311766 -182.643526)
		(end 69.771006 -182.643526)
		(width 0.1016)
		(layer "F.Cu")
		(net "T2_NODE3_EN")
	)
	(segment
		(start 69.06768 -181.9402)
		(end 68.70827 -181.9402)
		(width 0.1016)
		(layer "F.Cu")
		(net "T2_NODE3_EN")
	)
	(segment
		(start 68.11518 -182.53329)
		(end 68.11518 -183.367934)
		(width 0.1016)
		(layer "F.Cu")
		(net "T2_NODE3_EN")
	)
	(segment
		(start 69.771006 -182.643526)
		(end 69.06768 -181.9402)
		(width 0.1016)
		(layer "F.Cu")
		(net "T2_NODE3_EN")
	)
	(segment
		(start 68.11518 -183.367934)
		(end 66.678302 -184.804812)
		(width 0.1016)
		(layer "F.Cu")
		(net "T2_NODE3_EN")
	)
	(segment
		(start 68.70827 -181.9402)
		(end 68.11518 -182.53329)
		(width 0.1016)
		(layer "F.Cu")
		(net "T2_NODE3_EN")
	)
	(segment
		(start 66.53276 -184.804812)
		(end 66.53276 -184.805574)
		(width 0.1016)
		(layer "F.Cu")
		(net "T2_NODE3_EN")
	)
	(via
		(at 80.30591 -176.124616)
		(size 0.508)
		(drill 0.254)
		(layers "F.Cu" "B.Cu")
		(net "T2_NODE3_EN")
	)
	(via
		(at 73.4441 -182.511192)
		(size 0.508)
		(drill 0.254)
		(layers "F.Cu" "B.Cu")
		(net "T2_NODE3_EN")
	)
	(segment
		(start 79.23149 -176.569624)
		(end 79.860902 -176.569624)
		(width 0.1016)
		(layer "B.Cu")
		(net "T2_NODE3_EN")
	)
	(segment
		(start 81.89976 -175.669702)
		(end 81.351628 -175.669702)
		(width 0.1016)
		(layer "B.Cu")
		(net "T2_NODE3_EN")
	)
	(segment
		(start 80.896714 -176.124616)
		(end 80.30591 -176.124616)
		(width 0.1016)
		(layer "B.Cu")
		(net "T2_NODE3_EN")
	)
	(segment
		(start 81.351628 -175.669702)
		(end 80.896714 -176.124616)
		(width 0.1016)
		(layer "B.Cu")
		(net "T2_NODE3_EN")
	)
	(segment
		(start 79.860902 -176.569624)
		(end 80.30591 -176.124616)
		(width 0.1016)
		(layer "B.Cu")
		(net "T2_NODE3_EN")
	)
	(segment
		(start 75.36561 -183.049926)
		(end 73.982834 -183.049926)
		(width 0.1143)
		(layer "In7.Cu")
		(net "T2_NODE3_EN")
	)
	(segment
		(start 78.94574 -177.484786)
		(end 78.94574 -178.60137)
		(width 0.1143)
		(layer "In7.Cu")
		(net "T2_NODE3_EN")
	)
	(segment
		(start 76.696824 -181.718712)
		(end 75.36561 -183.049926)
		(width 0.1143)
		(layer "In7.Cu")
		(net "T2_NODE3_EN")
	)
	(segment
		(start 73.982834 -183.049926)
		(end 73.4441 -182.511192)
		(width 0.1143)
		(layer "In7.Cu")
		(net "T2_NODE3_EN")
	)
	(segment
		(start 76.696824 -180.850286)
		(end 76.696824 -181.718712)
		(width 0.1143)
		(layer "In7.Cu")
		(net "T2_NODE3_EN")
	)
	(segment
		(start 80.30591 -176.124616)
		(end 78.94574 -177.484786)
		(width 0.1143)
		(layer "In7.Cu")
		(net "T2_NODE3_EN")
	)
	(segment
		(start 78.94574 -178.60137)
		(end 76.696824 -180.850286)
		(width 0.1143)
		(layer "In7.Cu")
		(net "T2_NODE3_EN")
	)
	(segment
		(start 152.04948 -174.64151)
		(end 151.84628 -174.84471)
		(width 0.1016)
		(layer "F.Cu")
		(net "T12_NODE3_EN")
	)
	(segment
		(start 151.84628 -174.84471)
		(end 151.84628 -180.21427)
		(width 0.1016)
		(layer "F.Cu")
		(net "T12_NODE3_EN")
	)
	(segment
		(start 152.089866 -180.457856)
		(end 152.089866 -181.981602)
		(width 0.1016)
		(layer "F.Cu")
		(net "T12_NODE3_EN")
	)
	(segment
		(start 151.84628 -180.21427)
		(end 152.089866 -180.457856)
		(width 0.1016)
		(layer "F.Cu")
		(net "T12_NODE3_EN")
	)
	(segment
		(start 152.76576 -182.657496)
		(end 152.76576 -184.805574)
		(width 0.1016)
		(layer "F.Cu")
		(net "T12_NODE3_EN")
	)
	(segment
		(start 152.089866 -181.981602)
		(end 152.76576 -182.657496)
		(width 0.1016)
		(layer "F.Cu")
		(net "T12_NODE3_EN")
	)
	(segment
		(start 152.584658 -173.196504)
		(end 152.04948 -173.731682)
		(width 0.1016)
		(layer "F.Cu")
		(net "T12_NODE3_EN")
	)
	(segment
		(start 152.04948 -173.731682)
		(end 152.04948 -174.64151)
		(width 0.1016)
		(layer "F.Cu")
		(net "T12_NODE3_EN")
	)
	(via
		(at 152.584658 -173.196504)
		(size 0.508)
		(drill 0.254)
		(layers "F.Cu" "B.Cu")
		(net "T12_NODE3_EN")
	)
	(segment
		(start 152.926034 -173.521624)
		(end 152.600914 -173.196504)
		(width 0.1016)
		(layer "B.Cu")
		(net "T12_NODE3_EN")
	)
	(segment
		(start 153.66111 -173.521624)
		(end 152.926034 -173.521624)
		(width 0.1016)
		(layer "B.Cu")
		(net "T12_NODE3_EN")
	)
	(segment
		(start 150.98776 -173.196504)
		(end 152.584658 -173.196504)
		(width 0.1016)
		(layer "B.Cu")
		(net "T12_NODE3_EN")
	)
	(segment
		(start 152.600914 -173.196504)
		(end 152.584658 -173.196504)
		(width 0.1016)
		(layer "B.Cu")
		(net "T12_NODE3_EN")
	)
	(via
		(at 111.934752 -175.117252)
		(size 0.508)
		(drill 0.254)
		(layers "F.Cu" "B.Cu")
		(net "T5_NODE1_EN")
	)
	(via
		(at 107.11942 -182.219092)
		(size 0.508)
		(drill 0.254)
		(layers "F.Cu" "B.Cu")
		(net "T5_NODE1_EN")
	)
	(segment
		(start 106.28376 -182.66664)
		(end 106.28376 -184.805574)
		(width 0.1016)
		(layer "B.Cu")
		(net "T5_NODE1_EN")
	)
	(segment
		(start 111.355124 -174.537624)
		(end 111.934752 -175.117252)
		(width 0.1016)
		(layer "B.Cu")
		(net "T5_NODE1_EN")
	)
	(segment
		(start 107.11942 -182.219092)
		(end 106.731308 -182.219092)
		(width 0.1016)
		(layer "B.Cu")
		(net "T5_NODE1_EN")
	)
	(segment
		(start 112.397032 -175.579532)
		(end 111.934752 -175.117252)
		(width 0.1016)
		(layer "B.Cu")
		(net "T5_NODE1_EN")
	)
	(segment
		(start 110.84941 -174.537624)
		(end 111.355124 -174.537624)
		(width 0.1016)
		(layer "B.Cu")
		(net "T5_NODE1_EN")
	)
	(segment
		(start 106.731308 -182.219092)
		(end 106.28376 -182.66664)
		(width 0.1016)
		(layer "B.Cu")
		(net "T5_NODE1_EN")
	)
	(segment
		(start 113.52276 -175.579532)
		(end 112.397032 -175.579532)
		(width 0.1016)
		(layer "B.Cu")
		(net "T5_NODE1_EN")
	)
	(segment
		(start 112.372902 -177.270156)
		(end 112.372902 -175.555402)
		(width 0.1143)
		(layer "In7.Cu")
		(net "T5_NODE1_EN")
	)
	(segment
		(start 107.11942 -182.219092)
		(end 109.183932 -180.15458)
		(width 0.1143)
		(layer "In7.Cu")
		(net "T5_NODE1_EN")
	)
	(segment
		(start 112.372902 -175.555402)
		(end 111.934752 -175.117252)
		(width 0.1143)
		(layer "In7.Cu")
		(net "T5_NODE1_EN")
	)
	(segment
		(start 109.183932 -180.15458)
		(end 109.488478 -180.15458)
		(width 0.1143)
		(layer "In7.Cu")
		(net "T5_NODE1_EN")
	)
	(segment
		(start 109.488478 -180.15458)
		(end 112.372902 -177.270156)
		(width 0.1143)
		(layer "In7.Cu")
		(net "T5_NODE1_EN")
	)
	(via
		(at 79.99222 -184.031382)
		(size 0.508)
		(drill 0.254)
		(layers "F.Cu" "B.Cu")
		(net "T3_NODE2_EN")
	)
	(via
		(at 83.92414 -181.07533)
		(size 0.508)
		(drill 0.254)
		(layers "F.Cu" "B.Cu")
		(net "T3_NODE2_EN")
	)
	(segment
		(start 86.960456 -176.319688)
		(end 87.74176 -176.319688)
		(width 0.1016)
		(layer "B.Cu")
		(net "T3_NODE2_EN")
	)
	(segment
		(start 88.97366 -176.319688)
		(end 89.724484 -177.070512)
		(width 0.1016)
		(layer "B.Cu")
		(net "T3_NODE2_EN")
	)
	(segment
		(start 79.130652 -184.031382)
		(end 79.99222 -184.031382)
		(width 0.1016)
		(layer "B.Cu")
		(net "T3_NODE2_EN")
	)
	(segment
		(start 83.92414 -181.07533)
		(end 86.78164 -178.21783)
		(width 0.1016)
		(layer "B.Cu")
		(net "T3_NODE2_EN")
	)
	(segment
		(start 89.724484 -177.070512)
		(end 90.41257 -177.070512)
		(width 0.1016)
		(layer "B.Cu")
		(net "T3_NODE2_EN")
	)
	(segment
		(start 86.78164 -178.21783)
		(end 86.78164 -176.498504)
		(width 0.1016)
		(layer "B.Cu")
		(net "T3_NODE2_EN")
	)
	(segment
		(start 78.62062 -184.541414)
		(end 79.130652 -184.031382)
		(width 0.1016)
		(layer "B.Cu")
		(net "T3_NODE2_EN")
	)
	(segment
		(start 78.62062 -184.859168)
		(end 78.62062 -184.541414)
		(width 0.1016)
		(layer "B.Cu")
		(net "T3_NODE2_EN")
	)
	(segment
		(start 86.78164 -176.498504)
		(end 86.960456 -176.319688)
		(width 0.1016)
		(layer "B.Cu")
		(net "T3_NODE2_EN")
	)
	(segment
		(start 87.74176 -176.319688)
		(end 88.97366 -176.319688)
		(width 0.1016)
		(layer "B.Cu")
		(net "T3_NODE2_EN")
	)
	(segment
		(start 83.92414 -181.07533)
		(end 82.755486 -182.243984)
		(width 0.1143)
		(layer "In7.Cu")
		(net "T3_NODE2_EN")
	)
	(segment
		(start 82.441034 -182.243984)
		(end 80.653636 -184.031382)
		(width 0.1143)
		(layer "In7.Cu")
		(net "T3_NODE2_EN")
	)
	(segment
		(start 82.755486 -182.243984)
		(end 82.441034 -182.243984)
		(width 0.1143)
		(layer "In7.Cu")
		(net "T3_NODE2_EN")
	)
	(segment
		(start 80.653636 -184.031382)
		(end 79.99222 -184.031382)
		(width 0.1143)
		(layer "In7.Cu")
		(net "T3_NODE2_EN")
	)
	(segment
		(start 93.18244 -187.948824)
		(end 93.18244 -187.45581)
		(width 0.1016)
		(layer "F.Cu")
		(net "T5_NODE4_EN_R")
	)
	(segment
		(start 93.811344 -186.826906)
		(end 93.811344 -186.806586)
		(width 0.1016)
		(layer "F.Cu")
		(net "T5_NODE4_EN_R")
	)
	(segment
		(start 93.18244 -187.45581)
		(end 93.811344 -186.826906)
		(width 0.1016)
		(layer "F.Cu")
		(net "T5_NODE4_EN_R")
	)
	(via
		(at 94.01302 -195.60667)
		(size 0.6604)
		(drill 0.3302)
		(layers "F.Cu" "B.Cu")
		(net "T5_NODE4_EN_R")
	)
	(via
		(at 93.18244 -187.948824)
		(size 0.508)
		(drill 0.254)
		(layers "F.Cu" "B.Cu")
		(net "T5_NODE4_EN_R")
	)
	(segment
		(start 94.01302 -195.60667)
		(end 94.01302 -200.214992)
		(width 0.1016)
		(layer "B.Cu")
		(net "T5_NODE4_EN_R")
	)
	(segment
		(start 93.07322 -188.058044)
		(end 93.07322 -194.66687)
		(width 0.1016)
		(layer "B.Cu")
		(net "T5_NODE4_EN_R")
	)
	(segment
		(start 93.07322 -194.66687)
		(end 94.01302 -195.60667)
		(width 0.1016)
		(layer "B.Cu")
		(net "T5_NODE4_EN_R")
	)
	(segment
		(start 93.3069 -187.822586)
		(end 93.811344 -187.822586)
		(width 0.1016)
		(layer "B.Cu")
		(net "T5_NODE4_EN_R")
	)
	(segment
		(start 93.18244 -187.948824)
		(end 93.07322 -188.058044)
		(width 0.1016)
		(layer "B.Cu")
		(net "T5_NODE4_EN_R")
	)
	(segment
		(start 94.01302 -200.214992)
		(end 94.015052 -200.217024)
		(width 0.1016)
		(layer "B.Cu")
		(net "T5_NODE4_EN_R")
	)
	(segment
		(start 93.18244 -187.947046)
		(end 93.3069 -187.822586)
		(width 0.1016)
		(layer "B.Cu")
		(net "T5_NODE4_EN_R")
	)
	(segment
		(start 93.18244 -187.948824)
		(end 93.18244 -187.947046)
		(width 0.1016)
		(layer "B.Cu")
		(net "T5_NODE4_EN_R")
	)
	(segment
		(start 94.015052 -200.217024)
		(end 94.015052 -205.199488)
		(width 0.1016)
		(layer "B.Cu")
		(net "T5_NODE4_EN_R")
	)
	(via
		(at 65.1891 -195.742052)
		(size 0.6604)
		(drill 0.3302)
		(layers "F.Cu" "B.Cu")
		(net "T1_NODE2_EN_R")
	)
	(segment
		(start 64.015112 -205.199488)
		(end 64.015112 -201.7014)
		(width 0.1016)
		(layer "B.Cu")
		(net "T1_NODE2_EN_R")
	)
	(segment
		(start 65.0621 -188.477652)
		(end 65.340738 -188.477652)
		(width 0.1016)
		(layer "B.Cu")
		(net "T1_NODE2_EN_R")
	)
	(segment
		(start 65.55486 -188.691774)
		(end 65.38976 -188.526674)
		(width 0.1016)
		(layer "B.Cu")
		(net "T1_NODE2_EN_R")
	)
	(segment
		(start 64.67602 -201.040492)
		(end 64.67602 -196.255132)
		(width 0.1016)
		(layer "B.Cu")
		(net "T1_NODE2_EN_R")
	)
	(segment
		(start 65.38976 -186.251088)
		(end 64.84874 -186.792108)
		(width 0.1016)
		(layer "B.Cu")
		(net "T1_NODE2_EN_R")
	)
	(segment
		(start 65.340738 -188.477652)
		(end 65.38976 -188.526674)
		(width 0.1016)
		(layer "B.Cu")
		(net "T1_NODE2_EN_R")
	)
	(segment
		(start 64.015112 -201.7014)
		(end 64.67602 -201.040492)
		(width 0.1016)
		(layer "B.Cu")
		(net "T1_NODE2_EN_R")
	)
	(segment
		(start 65.1891 -195.742052)
		(end 65.1891 -189.057534)
		(width 0.1016)
		(layer "B.Cu")
		(net "T1_NODE2_EN_R")
	)
	(segment
		(start 65.38976 -185.605674)
		(end 65.38976 -186.251088)
		(width 0.1016)
		(layer "B.Cu")
		(net "T1_NODE2_EN_R")
	)
	(segment
		(start 65.1891 -189.057534)
		(end 65.55486 -188.691774)
		(width 0.1016)
		(layer "B.Cu")
		(net "T1_NODE2_EN_R")
	)
	(segment
		(start 64.84874 -186.792108)
		(end 64.84874 -188.264292)
		(width 0.1016)
		(layer "B.Cu")
		(net "T1_NODE2_EN_R")
	)
	(segment
		(start 64.84874 -188.264292)
		(end 65.0621 -188.477652)
		(width 0.1016)
		(layer "B.Cu")
		(net "T1_NODE2_EN_R")
	)
	(segment
		(start 64.67602 -196.255132)
		(end 65.1891 -195.742052)
		(width 0.1016)
		(layer "B.Cu")
		(net "T1_NODE2_EN_R")
	)
	(via
		(at 79.10576 -196.608446)
		(size 0.6604)
		(drill 0.3302)
		(layers "F.Cu" "B.Cu")
		(net "T3_NODE2_EN_R")
	)
	(segment
		(start 78.62062 -186.276488)
		(end 78.67396 -186.329828)
		(width 0.1016)
		(layer "B.Cu")
		(net "T3_NODE2_EN_R")
	)
	(segment
		(start 79.10576 -198.728584)
		(end 79.446882 -199.069706)
		(width 0.1016)
		(layer "B.Cu")
		(net "T3_NODE2_EN_R")
	)
	(segment
		(start 78.67396 -187.917074)
		(end 78.66634 -187.924694)
		(width 0.1016)
		(layer "B.Cu")
		(net "T3_NODE2_EN_R")
	)
	(segment
		(start 78.400402 -188.526674)
		(end 78.21676 -188.526674)
		(width 0.1016)
		(layer "B.Cu")
		(net "T3_NODE2_EN_R")
	)
	(segment
		(start 78.21676 -188.526674)
		(end 78.21676 -189.12713)
		(width 0.1016)
		(layer "B.Cu")
		(net "T3_NODE2_EN_R")
	)
	(segment
		(start 78.66634 -188.260736)
		(end 78.400402 -188.526674)
		(width 0.1016)
		(layer "B.Cu")
		(net "T3_NODE2_EN_R")
	)
	(segment
		(start 79.446882 -199.069706)
		(end 79.446882 -201.314304)
		(width 0.1016)
		(layer "B.Cu")
		(net "T3_NODE2_EN_R")
	)
	(segment
		(start 79.446882 -201.314304)
		(end 79.015082 -201.746104)
		(width 0.1016)
		(layer "B.Cu")
		(net "T3_NODE2_EN_R")
	)
	(segment
		(start 79.015082 -201.746104)
		(end 79.015082 -205.199488)
		(width 0.1016)
		(layer "B.Cu")
		(net "T3_NODE2_EN_R")
	)
	(segment
		(start 79.10576 -190.01613)
		(end 79.10576 -196.608446)
		(width 0.1016)
		(layer "B.Cu")
		(net "T3_NODE2_EN_R")
	)
	(segment
		(start 78.21676 -189.12713)
		(end 79.10576 -190.01613)
		(width 0.1016)
		(layer "B.Cu")
		(net "T3_NODE2_EN_R")
	)
	(segment
		(start 78.62062 -185.659268)
		(end 78.62062 -186.276488)
		(width 0.1016)
		(layer "B.Cu")
		(net "T3_NODE2_EN_R")
	)
	(segment
		(start 79.10576 -196.608446)
		(end 79.10576 -198.728584)
		(width 0.1016)
		(layer "B.Cu")
		(net "T3_NODE2_EN_R")
	)
	(segment
		(start 78.66634 -187.924694)
		(end 78.66634 -188.260736)
		(width 0.1016)
		(layer "B.Cu")
		(net "T3_NODE2_EN_R")
	)
	(segment
		(start 78.67396 -186.329828)
		(end 78.67396 -187.917074)
		(width 0.1016)
		(layer "B.Cu")
		(net "T3_NODE2_EN_R")
	)
	(segment
		(start 81.34604 -182.128922)
		(end 81.18348 -181.966362)
		(width 0.1016)
		(layer "F.Cu")
		(net "T4_NODE4_EN")
	)
	(segment
		(start 79.10576 -183.949594)
		(end 79.611982 -183.443372)
		(width 0.1016)
		(layer "F.Cu")
		(net "T4_NODE4_EN")
	)
	(segment
		(start 79.10576 -184.805574)
		(end 79.10576 -183.949594)
		(width 0.1016)
		(layer "F.Cu")
		(net "T4_NODE4_EN")
	)
	(segment
		(start 81.34604 -182.96255)
		(end 81.34604 -182.128922)
		(width 0.1016)
		(layer "F.Cu")
		(net "T4_NODE4_EN")
	)
	(segment
		(start 80.865218 -183.443372)
		(end 81.34604 -182.96255)
		(width 0.1016)
		(layer "F.Cu")
		(net "T4_NODE4_EN")
	)
	(segment
		(start 79.611982 -183.443372)
		(end 80.865218 -183.443372)
		(width 0.1016)
		(layer "F.Cu")
		(net "T4_NODE4_EN")
	)
	(via
		(at 81.18348 -181.966362)
		(size 0.508)
		(drill 0.254)
		(layers "F.Cu" "B.Cu")
		(net "T4_NODE4_EN")
	)
	(segment
		(start 81.18348 -181.966362)
		(end 81.31048 -181.839362)
		(width 0.1016)
		(layer "B.Cu")
		(net "T4_NODE4_EN")
	)
	(segment
		(start 90.41257 -171.185078)
		(end 90.41257 -170.974512)
		(width 0.1016)
		(layer "B.Cu")
		(net "T4_NODE4_EN")
	)
	(segment
		(start 81.31048 -181.839362)
		(end 81.31048 -180.378862)
		(width 0.1016)
		(layer "B.Cu")
		(net "T4_NODE4_EN")
	)
	(segment
		(start 89.17813 -172.419518)
		(end 90.41257 -171.185078)
		(width 0.1016)
		(layer "B.Cu")
		(net "T4_NODE4_EN")
	)
	(segment
		(start 81.31048 -180.378862)
		(end 83.27136 -178.417982)
		(width 0.1016)
		(layer "B.Cu")
		(net "T4_NODE4_EN")
	)
	(segment
		(start 83.27136 -175.626776)
		(end 86.478618 -172.419518)
		(width 0.1016)
		(layer "B.Cu")
		(net "T4_NODE4_EN")
	)
	(segment
		(start 83.27136 -178.417982)
		(end 83.27136 -175.626776)
		(width 0.1016)
		(layer "B.Cu")
		(net "T4_NODE4_EN")
	)
	(segment
		(start 86.478618 -172.419518)
		(end 87.74176 -172.419518)
		(width 0.1016)
		(layer "B.Cu")
		(net "T4_NODE4_EN")
	)
	(segment
		(start 87.74176 -172.419518)
		(end 89.17813 -172.419518)
		(width 0.1016)
		(layer "B.Cu")
		(net "T4_NODE4_EN")
	)
	(segment
		(start 124.766324 -181.503828)
		(end 124.68606 -181.584092)
		(width 0.1016)
		(layer "F.Cu")
		(net "T7_NODE2_EN")
	)
	(segment
		(start 125.335538 -181.503828)
		(end 124.766324 -181.503828)
		(width 0.1016)
		(layer "F.Cu")
		(net "T7_NODE2_EN")
	)
	(via
		(at 124.68606 -181.584092)
		(size 0.508)
		(drill 0.254)
		(layers "F.Cu" "B.Cu")
		(net "T7_NODE2_EN")
	)
	(segment
		(start 119.36476 -180.129688)
		(end 118.648988 -180.129688)
		(width 0.1016)
		(layer "B.Cu")
		(net "T7_NODE2_EN")
	)
	(segment
		(start 123.243594 -181.58333)
		(end 121.789952 -180.129688)
		(width 0.1016)
		(layer "B.Cu")
		(net "T7_NODE2_EN")
	)
	(segment
		(start 121.789952 -180.129688)
		(end 119.36476 -180.129688)
		(width 0.1016)
		(layer "B.Cu")
		(net "T7_NODE2_EN")
	)
	(segment
		(start 117.85092 -184.180734)
		(end 118.47576 -184.805574)
		(width 0.1016)
		(layer "B.Cu")
		(net "T7_NODE2_EN")
	)
	(segment
		(start 118.648988 -180.129688)
		(end 117.85092 -180.927756)
		(width 0.1016)
		(layer "B.Cu")
		(net "T7_NODE2_EN")
	)
	(segment
		(start 124.68606 -181.584092)
		(end 124.68606 -181.58333)
		(width 0.1016)
		(layer "B.Cu")
		(net "T7_NODE2_EN")
	)
	(segment
		(start 124.68606 -181.58333)
		(end 123.243594 -181.58333)
		(width 0.1016)
		(layer "B.Cu")
		(net "T7_NODE2_EN")
	)
	(segment
		(start 117.85092 -180.927756)
		(end 117.85092 -184.180734)
		(width 0.1016)
		(layer "B.Cu")
		(net "T7_NODE2_EN")
	)
	(via
		(at 63.18758 -184.056274)
		(size 0.508)
		(drill 0.254)
		(layers "F.Cu" "B.Cu")
		(net "T1_NODE4_EN")
	)
	(via
		(at 67.2084 -183.663844)
		(size 0.508)
		(drill 0.254)
		(layers "F.Cu" "B.Cu")
		(net "T1_NODE4_EN")
	)
	(segment
		(start 67.2084 -183.663844)
		(end 67.2084 -182.721758)
		(width 0.1016)
		(layer "B.Cu")
		(net "T1_NODE4_EN")
	)
	(segment
		(start 75.565 -175.801274)
		(end 77.38745 -173.978824)
		(width 0.1016)
		(layer "B.Cu")
		(net "T1_NODE4_EN")
	)
	(segment
		(start 80.534002 -173.719744)
		(end 80.335882 -173.521624)
		(width 0.1016)
		(layer "B.Cu")
		(net "T1_NODE4_EN")
	)
	(segment
		(start 63.10376 -184.805574)
		(end 63.10376 -184.140094)
		(width 0.1016)
		(layer "B.Cu")
		(net "T1_NODE4_EN")
	)
	(segment
		(start 70.9168 -179.601622)
		(end 74.717148 -175.801274)
		(width 0.1016)
		(layer "B.Cu")
		(net "T1_NODE4_EN")
	)
	(segment
		(start 70.328536 -179.601622)
		(end 70.9168 -179.601622)
		(width 0.1016)
		(layer "B.Cu")
		(net "T1_NODE4_EN")
	)
	(segment
		(start 74.717148 -175.801274)
		(end 75.565 -175.801274)
		(width 0.1016)
		(layer "B.Cu")
		(net "T1_NODE4_EN")
	)
	(segment
		(start 80.335882 -173.521624)
		(end 79.23149 -173.521624)
		(width 0.1016)
		(layer "B.Cu")
		(net "T1_NODE4_EN")
	)
	(segment
		(start 63.10376 -184.140094)
		(end 63.18758 -184.056274)
		(width 0.1016)
		(layer "B.Cu")
		(net "T1_NODE4_EN")
	)
	(segment
		(start 77.38745 -173.978824)
		(end 79.078328 -173.978824)
		(width 0.1016)
		(layer "B.Cu")
		(net "T1_NODE4_EN")
	)
	(segment
		(start 67.2084 -182.721758)
		(end 70.328536 -179.601622)
		(width 0.1016)
		(layer "B.Cu")
		(net "T1_NODE4_EN")
	)
	(segment
		(start 81.89976 -173.719744)
		(end 80.534002 -173.719744)
		(width 0.1016)
		(layer "B.Cu")
		(net "T1_NODE4_EN")
	)
	(segment
		(start 79.078328 -173.978824)
		(end 79.23149 -173.825662)
		(width 0.1016)
		(layer "B.Cu")
		(net "T1_NODE4_EN")
	)
	(segment
		(start 79.23149 -173.825662)
		(end 79.23149 -173.521624)
		(width 0.1016)
		(layer "B.Cu")
		(net "T1_NODE4_EN")
	)
	(segment
		(start 66.409062 -182.864506)
		(end 64.379348 -182.864506)
		(width 0.1143)
		(layer "In2.Cu")
		(net "T1_NODE4_EN")
	)
	(segment
		(start 67.2084 -183.663844)
		(end 66.409062 -182.864506)
		(width 0.1143)
		(layer "In2.Cu")
		(net "T1_NODE4_EN")
	)
	(segment
		(start 64.379348 -182.864506)
		(end 63.18758 -184.056274)
		(width 0.1143)
		(layer "In2.Cu")
		(net "T1_NODE4_EN")
	)
	(segment
		(start 154.392884 -180.803804)
		(end 152.64638 -179.0573)
		(width 0.1016)
		(layer "F.Cu")
		(net "T12_NODE1_EN")
	)
	(segment
		(start 152.64638 -175.812704)
		(end 152.57526 -175.741584)
		(width 0.1016)
		(layer "F.Cu")
		(net "T12_NODE1_EN")
	)
	(segment
		(start 154.16276 -183.916574)
		(end 154.16276 -181.54904)
		(width 0.1016)
		(layer "F.Cu")
		(net "T12_NODE1_EN")
	)
	(segment
		(start 152.64638 -179.0573)
		(end 152.64638 -175.812704)
		(width 0.1016)
		(layer "F.Cu")
		(net "T12_NODE1_EN")
	)
	(segment
		(start 155.05176 -184.805574)
		(end 154.16276 -183.916574)
		(width 0.1016)
		(layer "F.Cu")
		(net "T12_NODE1_EN")
	)
	(segment
		(start 154.392884 -181.318916)
		(end 154.392884 -180.803804)
		(width 0.1016)
		(layer "F.Cu")
		(net "T12_NODE1_EN")
	)
	(segment
		(start 154.16276 -181.54904)
		(end 154.392884 -181.318916)
		(width 0.1016)
		(layer "F.Cu")
		(net "T12_NODE1_EN")
	)
	(via
		(at 152.57526 -175.741584)
		(size 0.508)
		(drill 0.254)
		(layers "F.Cu" "B.Cu")
		(net "T12_NODE1_EN")
	)
	(segment
		(start 150.98776 -174.49673)
		(end 151.736044 -174.49673)
		(width 0.1016)
		(layer "B.Cu")
		(net "T12_NODE1_EN")
	)
	(segment
		(start 152.321514 -175.0822)
		(end 152.321514 -175.487838)
		(width 0.1016)
		(layer "B.Cu")
		(net "T12_NODE1_EN")
	)
	(segment
		(start 153.186892 -175.741584)
		(end 152.57526 -175.741584)
		(width 0.1016)
		(layer "B.Cu")
		(net "T12_NODE1_EN")
	)
	(segment
		(start 151.736044 -174.49673)
		(end 152.321514 -175.0822)
		(width 0.1016)
		(layer "B.Cu")
		(net "T12_NODE1_EN")
	)
	(segment
		(start 152.321514 -175.487838)
		(end 152.57526 -175.741584)
		(width 0.1016)
		(layer "B.Cu")
		(net "T12_NODE1_EN")
	)
	(segment
		(start 153.66111 -175.553624)
		(end 153.374852 -175.553624)
		(width 0.1016)
		(layer "B.Cu")
		(net "T12_NODE1_EN")
	)
	(segment
		(start 153.374852 -175.553624)
		(end 153.186892 -175.741584)
		(width 0.1016)
		(layer "B.Cu")
		(net "T12_NODE1_EN")
	)
	(via
		(at 152.871424 -180.715666)
		(size 0.508)
		(drill 0.254)
		(layers "F.Cu" "B.Cu")
		(net "T11_NODE3_EN")
	)
	(via
		(at 146.416268 -179.194968)
		(size 0.508)
		(drill 0.254)
		(layers "F.Cu" "B.Cu")
		(net "T11_NODE3_EN")
	)
	(segment
		(start 146.416268 -178.675792)
		(end 146.416268 -179.194968)
		(width 0.1016)
		(layer "B.Cu")
		(net "T11_NODE3_EN")
	)
	(segment
		(start 152.76576 -184.551574)
		(end 152.76576 -183.956198)
		(width 0.1016)
		(layer "B.Cu")
		(net "T11_NODE3_EN")
	)
	(segment
		(start 150.38578 -175.796702)
		(end 150.317962 -175.86452)
		(width 0.1016)
		(layer "B.Cu")
		(net "T11_NODE3_EN")
	)
	(segment
		(start 150.98776 -175.796702)
		(end 150.38578 -175.796702)
		(width 0.1016)
		(layer "B.Cu")
		(net "T11_NODE3_EN")
	)
	(segment
		(start 148.874988 -175.86452)
		(end 147.104354 -177.635154)
		(width 0.1016)
		(layer "B.Cu")
		(net "T11_NODE3_EN")
	)
	(segment
		(start 153.351738 -183.37022)
		(end 153.351738 -181.19598)
		(width 0.1016)
		(layer "B.Cu")
		(net "T11_NODE3_EN")
	)
	(segment
		(start 147.104354 -178.384454)
		(end 146.707606 -178.384454)
		(width 0.1016)
		(layer "B.Cu")
		(net "T11_NODE3_EN")
	)
	(segment
		(start 147.104354 -177.635154)
		(end 147.104354 -178.384454)
		(width 0.1016)
		(layer "B.Cu")
		(net "T11_NODE3_EN")
	)
	(segment
		(start 150.317962 -175.86452)
		(end 148.874988 -175.86452)
		(width 0.1016)
		(layer "B.Cu")
		(net "T11_NODE3_EN")
	)
	(segment
		(start 153.351738 -181.19598)
		(end 152.871424 -180.715666)
		(width 0.1016)
		(layer "B.Cu")
		(net "T11_NODE3_EN")
	)
	(segment
		(start 146.707606 -178.384454)
		(end 146.416268 -178.675792)
		(width 0.1016)
		(layer "B.Cu")
		(net "T11_NODE3_EN")
	)
	(segment
		(start 152.76576 -183.956198)
		(end 153.351738 -183.37022)
		(width 0.1016)
		(layer "B.Cu")
		(net "T11_NODE3_EN")
	)
	(segment
		(start 147.64893 -180.960014)
		(end 146.416268 -179.727352)
		(width 0.1143)
		(layer "In6.Cu")
		(net "T11_NODE3_EN")
	)
	(segment
		(start 146.416268 -179.727352)
		(end 146.416268 -179.194968)
		(width 0.1143)
		(layer "In6.Cu")
		(net "T11_NODE3_EN")
	)
	(segment
		(start 149.668484 -180.715666)
		(end 149.424136 -180.960014)
		(width 0.1143)
		(layer "In6.Cu")
		(net "T11_NODE3_EN")
	)
	(segment
		(start 149.424136 -180.960014)
		(end 147.64893 -180.960014)
		(width 0.1143)
		(layer "In6.Cu")
		(net "T11_NODE3_EN")
	)
	(segment
		(start 152.871424 -180.715666)
		(end 149.668484 -180.715666)
		(width 0.1143)
		(layer "In6.Cu")
		(net "T11_NODE3_EN")
	)
	(segment
		(start 81.39176 -184.50179)
		(end 81.77022 -184.12333)
		(width 0.1016)
		(layer "F.Cu")
		(net "T4_NODE2_EN")
	)
	(segment
		(start 81.39176 -184.805574)
		(end 81.39176 -184.50179)
		(width 0.1016)
		(layer "F.Cu")
		(net "T4_NODE2_EN")
	)
	(via
		(at 81.77022 -184.12333)
		(size 0.508)
		(drill 0.254)
		(layers "F.Cu" "B.Cu")
		(net "T4_NODE2_EN")
	)
	(via
		(at 84.20608 -178.217068)
		(size 0.508)
		(drill 0.254)
		(layers "F.Cu" "B.Cu")
		(net "T4_NODE2_EN")
	)
	(segment
		(start 89.985596 -173.006512)
		(end 90.41257 -173.006512)
		(width 0.1016)
		(layer "B.Cu")
		(net "T4_NODE2_EN")
	)
	(segment
		(start 89.334086 -173.658022)
		(end 89.985596 -173.006512)
		(width 0.1016)
		(layer "B.Cu")
		(net "T4_NODE2_EN")
	)
	(segment
		(start 84.07908 -175.537876)
		(end 85.897212 -173.719744)
		(width 0.1016)
		(layer "B.Cu")
		(net "T4_NODE2_EN")
	)
	(segment
		(start 87.74176 -173.719744)
		(end 88.60028 -173.719744)
		(width 0.1016)
		(layer "B.Cu")
		(net "T4_NODE2_EN")
	)
	(segment
		(start 88.662002 -173.658022)
		(end 89.334086 -173.658022)
		(width 0.1016)
		(layer "B.Cu")
		(net "T4_NODE2_EN")
	)
	(segment
		(start 84.20608 -178.217068)
		(end 84.07908 -178.090068)
		(width 0.1016)
		(layer "B.Cu")
		(net "T4_NODE2_EN")
	)
	(segment
		(start 88.60028 -173.719744)
		(end 88.662002 -173.658022)
		(width 0.1016)
		(layer "B.Cu")
		(net "T4_NODE2_EN")
	)
	(segment
		(start 84.07908 -178.090068)
		(end 84.07908 -175.537876)
		(width 0.1016)
		(layer "B.Cu")
		(net "T4_NODE2_EN")
	)
	(segment
		(start 85.897212 -173.719744)
		(end 87.74176 -173.719744)
		(width 0.1016)
		(layer "B.Cu")
		(net "T4_NODE2_EN")
	)
	(segment
		(start 82.052922 -184.406032)
		(end 81.77022 -184.12333)
		(width 0.1143)
		(layer "In7.Cu")
		(net "T4_NODE2_EN")
	)
	(segment
		(start 84.73059 -180.323236)
		(end 84.73059 -183.572912)
		(width 0.1143)
		(layer "In7.Cu")
		(net "T4_NODE2_EN")
	)
	(segment
		(start 84.73059 -183.572912)
		(end 83.89747 -184.406032)
		(width 0.1143)
		(layer "In7.Cu")
		(net "T4_NODE2_EN")
	)
	(segment
		(start 83.89747 -184.406032)
		(end 82.052922 -184.406032)
		(width 0.1143)
		(layer "In7.Cu")
		(net "T4_NODE2_EN")
	)
	(segment
		(start 84.20608 -178.217068)
		(end 84.20608 -179.798726)
		(width 0.1143)
		(layer "In7.Cu")
		(net "T4_NODE2_EN")
	)
	(segment
		(start 84.20608 -179.798726)
		(end 84.73059 -180.323236)
		(width 0.1143)
		(layer "In7.Cu")
		(net "T4_NODE2_EN")
	)
	(via
		(at 62.20714 -199.588628)
		(size 0.6604)
		(drill 0.3302)
		(layers "F.Cu" "B.Cu")
		(net "T1_NODE4_EN_R")
	)
	(segment
		(start 62.015116 -199.780652)
		(end 62.20714 -199.588628)
		(width 0.1016)
		(layer "B.Cu")
		(net "T1_NODE4_EN_R")
	)
	(segment
		(start 63.10376 -192.513458)
		(end 63.10376 -188.526674)
		(width 0.1016)
		(layer "B.Cu")
		(net "T1_NODE4_EN_R")
	)
	(segment
		(start 63.10376 -185.605674)
		(end 63.10376 -186.188604)
		(width 0.1016)
		(layer "B.Cu")
		(net "T1_NODE4_EN_R")
	)
	(segment
		(start 62.20714 -199.588628)
		(end 62.20714 -193.410078)
		(width 0.1016)
		(layer "B.Cu")
		(net "T1_NODE4_EN_R")
	)
	(segment
		(start 62.42558 -187.848494)
		(end 63.10376 -188.526674)
		(width 0.1016)
		(layer "B.Cu")
		(net "T1_NODE4_EN_R")
	)
	(segment
		(start 62.20714 -193.410078)
		(end 63.10376 -192.513458)
		(width 0.1016)
		(layer "B.Cu")
		(net "T1_NODE4_EN_R")
	)
	(segment
		(start 63.10376 -186.188604)
		(end 62.42558 -186.866784)
		(width 0.1016)
		(layer "B.Cu")
		(net "T1_NODE4_EN_R")
	)
	(segment
		(start 62.42558 -186.866784)
		(end 62.42558 -187.848494)
		(width 0.1016)
		(layer "B.Cu")
		(net "T1_NODE4_EN_R")
	)
	(segment
		(start 62.015116 -205.199488)
		(end 62.015116 -199.780652)
		(width 0.1016)
		(layer "B.Cu")
		(net "T1_NODE4_EN_R")
	)
	(segment
		(start 92.73286 -171.938442)
		(end 90.58656 -171.938442)
		(width 0.1016)
		(layer "F.Cu")
		(net "UART_T6_NODE1_TXD")
	)
	(segment
		(start 89.776046 -171.390818)
		(end 90.31986 -171.390818)
		(width 0.1016)
		(layer "F.Cu")
		(net "UART_T6_NODE1_TXD")
	)
	(segment
		(start 90.58656 -171.938442)
		(end 90.412062 -171.763944)
		(width 0.1016)
		(layer "F.Cu")
		(net "UART_T6_NODE1_TXD")
	)
	(segment
		(start 89.542112 -171.624752)
		(end 89.776046 -171.390818)
		(width 0.1016)
		(layer "F.Cu")
		(net "UART_T6_NODE1_TXD")
	)
	(segment
		(start 87.744808 -171.624752)
		(end 89.542112 -171.624752)
		(width 0.1016)
		(layer "F.Cu")
		(net "UART_T6_NODE1_TXD")
	)
	(segment
		(start 90.31986 -171.390818)
		(end 90.412062 -171.48302)
		(width 0.1016)
		(layer "F.Cu")
		(net "UART_T6_NODE1_TXD")
	)
	(segment
		(start 90.412062 -171.763944)
		(end 90.412062 -171.48302)
		(width 0.1016)
		(layer "F.Cu")
		(net "UART_T6_NODE1_TXD")
	)
	(via
		(at 92.73286 -171.938442)
		(size 0.508)
		(drill 0.254)
		(layers "F.Cu" "B.Cu")
		(net "UART_T6_NODE1_TXD")
	)
	(segment
		(start 152.66162 -201.562716)
		(end 152.015698 -202.208638)
		(width 0.1016)
		(layer "F.Cu")
		(net "T12_NODE4_EN_R")
	)
	(segment
		(start 152.015698 -202.208638)
		(end 152.015698 -205.199488)
		(width 0.1016)
		(layer "F.Cu")
		(net "T12_NODE4_EN_R")
	)
	(segment
		(start 152.66162 -192.158874)
		(end 152.66162 -201.562716)
		(width 0.1016)
		(layer "F.Cu")
		(net "T12_NODE4_EN_R")
	)
	(segment
		(start 153.400252 -191.420242)
		(end 152.66162 -192.158874)
		(width 0.1016)
		(layer "F.Cu")
		(net "T12_NODE4_EN_R")
	)
	(via
		(at 162.27806 -186.659266)
		(size 0.508)
		(drill 0.254)
		(layers "F.Cu" "B.Cu")
		(net "T12_NODE4_EN_R")
	)
	(via
		(at 153.400252 -191.420242)
		(size 0.508)
		(drill 0.254)
		(layers "F.Cu" "B.Cu")
		(net "T12_NODE4_EN_R")
	)
	(segment
		(start 162.10026 -186.539124)
		(end 162.220402 -186.659266)
		(width 0.1016)
		(layer "B.Cu")
		(net "T12_NODE4_EN_R")
	)
	(segment
		(start 162.220402 -186.659266)
		(end 162.27806 -186.659266)
		(width 0.1016)
		(layer "B.Cu")
		(net "T12_NODE4_EN_R")
	)
	(segment
		(start 161.392108 -185.830972)
		(end 161.598356 -186.03722)
		(width 0.1016)
		(layer "B.Cu")
		(net "T12_NODE4_EN_R")
	)
	(segment
		(start 159.62376 -185.349388)
		(end 159.62376 -185.35015)
		(width 0.1016)
		(layer "B.Cu")
		(net "T12_NODE4_EN_R")
	)
	(segment
		(start 162.10026 -186.44616)
		(end 162.10026 -186.539124)
		(width 0.1016)
		(layer "B.Cu")
		(net "T12_NODE4_EN_R")
	)
	(segment
		(start 158.48076 -185.351674)
		(end 158.483046 -185.349388)
		(width 0.1016)
		(layer "B.Cu")
		(net "T12_NODE4_EN_R")
	)
	(segment
		(start 160.104582 -185.830972)
		(end 161.392108 -185.830972)
		(width 0.1016)
		(layer "B.Cu")
		(net "T12_NODE4_EN_R")
	)
	(segment
		(start 158.483046 -185.349388)
		(end 159.62376 -185.349388)
		(width 0.1016)
		(layer "B.Cu")
		(net "T12_NODE4_EN_R")
	)
	(segment
		(start 161.598356 -186.03722)
		(end 161.69132 -186.03722)
		(width 0.1016)
		(layer "B.Cu")
		(net "T12_NODE4_EN_R")
	)
	(segment
		(start 159.62376 -185.35015)
		(end 160.104582 -185.830972)
		(width 0.1016)
		(layer "B.Cu")
		(net "T12_NODE4_EN_R")
	)
	(segment
		(start 161.69132 -186.03722)
		(end 162.10026 -186.44616)
		(width 0.1016)
		(layer "B.Cu")
		(net "T12_NODE4_EN_R")
	)
	(segment
		(start 162.103562 -187.499498)
		(end 162.27806 -187.325)
		(width 0.1143)
		(layer "In7.Cu")
		(net "T12_NODE4_EN_R")
	)
	(segment
		(start 153.400252 -191.420242)
		(end 154.235404 -190.58509)
		(width 0.1143)
		(layer "In7.Cu")
		(net "T12_NODE4_EN_R")
	)
	(segment
		(start 159.602424 -190.925958)
		(end 160.905952 -190.925958)
		(width 0.1143)
		(layer "In7.Cu")
		(net "T12_NODE4_EN_R")
	)
	(segment
		(start 160.905952 -190.925958)
		(end 162.21329 -189.61862)
		(width 0.1143)
		(layer "In7.Cu")
		(net "T12_NODE4_EN_R")
	)
	(segment
		(start 159.261556 -190.58509)
		(end 159.602424 -190.925958)
		(width 0.1143)
		(layer "In7.Cu")
		(net "T12_NODE4_EN_R")
	)
	(segment
		(start 162.103562 -187.864242)
		(end 162.103562 -187.499498)
		(width 0.1143)
		(layer "In7.Cu")
		(net "T12_NODE4_EN_R")
	)
	(segment
		(start 154.235404 -190.58509)
		(end 159.261556 -190.58509)
		(width 0.1143)
		(layer "In7.Cu")
		(net "T12_NODE4_EN_R")
	)
	(segment
		(start 162.21329 -189.61862)
		(end 162.21329 -187.97397)
		(width 0.1143)
		(layer "In7.Cu")
		(net "T12_NODE4_EN_R")
	)
	(segment
		(start 162.27806 -187.325)
		(end 162.27806 -186.659266)
		(width 0.1143)
		(layer "In7.Cu")
		(net "T12_NODE4_EN_R")
	)
	(segment
		(start 162.21329 -187.97397)
		(end 162.103562 -187.864242)
		(width 0.1143)
		(layer "In7.Cu")
		(net "T12_NODE4_EN_R")
	)
	(segment
		(start 92.43822 -174.530512)
		(end 90.92819 -174.530512)
		(width 0.1016)
		(layer "F.Cu")
		(net "UART_T6_NODE3_RXD")
	)
	(segment
		(start 89.13876 -187.726574)
		(end 89.318592 -187.726574)
		(width 0.1016)
		(layer "F.Cu")
		(net "UART_T6_NODE3_RXD")
	)
	(segment
		(start 88.689942 -174.12462)
		(end 87.744808 -174.12462)
		(width 0.1016)
		(layer "F.Cu")
		(net "UART_T6_NODE3_RXD")
	)
	(segment
		(start 92.65031 -174.742602)
		(end 92.43822 -174.530512)
		(width 0.1016)
		(layer "F.Cu")
		(net "UART_T6_NODE3_RXD")
	)
	(segment
		(start 90.001852 -174.353728)
		(end 88.91905 -174.353728)
		(width 0.1016)
		(layer "F.Cu")
		(net "UART_T6_NODE3_RXD")
	)
	(segment
		(start 90.182446 -174.534322)
		(end 90.001852 -174.353728)
		(width 0.1016)
		(layer "F.Cu")
		(net "UART_T6_NODE3_RXD")
	)
	(segment
		(start 89.39276 -185.779918)
		(end 89.93124 -186.318398)
		(width 0.1016)
		(layer "F.Cu")
		(net "UART_T6_NODE3_RXD")
	)
	(segment
		(start 89.93124 -187.113926)
		(end 89.93124 -186.63666)
		(width 0.1016)
		(layer "F.Cu")
		(net "UART_T6_NODE3_RXD")
	)
	(segment
		(start 89.318592 -187.726574)
		(end 89.93124 -187.113926)
		(width 0.1016)
		(layer "F.Cu")
		(net "UART_T6_NODE3_RXD")
	)
	(segment
		(start 90.92819 -174.530512)
		(end 90.92438 -174.534322)
		(width 0.1016)
		(layer "F.Cu")
		(net "UART_T6_NODE3_RXD")
	)
	(segment
		(start 88.91905 -174.353728)
		(end 88.689942 -174.12462)
		(width 0.1016)
		(layer "F.Cu")
		(net "UART_T6_NODE3_RXD")
	)
	(segment
		(start 90.92438 -174.534322)
		(end 90.182446 -174.534322)
		(width 0.1016)
		(layer "F.Cu")
		(net "UART_T6_NODE3_RXD")
	)
	(segment
		(start 89.93124 -186.318398)
		(end 89.93124 -186.63666)
		(width 0.1016)
		(layer "F.Cu")
		(net "UART_T6_NODE3_RXD")
	)
	(segment
		(start 89.39276 -185.605674)
		(end 89.39276 -185.779918)
		(width 0.1016)
		(layer "F.Cu")
		(net "UART_T6_NODE3_RXD")
	)
	(via
		(at 92.65031 -174.742602)
		(size 0.508)
		(drill 0.254)
		(layers "F.Cu" "B.Cu")
		(net "UART_T6_NODE3_RXD")
	)
	(via
		(at 89.93124 -186.63666)
		(size 0.508)
		(drill 0.254)
		(layers "F.Cu" "B.Cu")
		(net "UART_T6_NODE3_RXD")
	)
	(segment
		(start 89.93124 -186.63666)
		(end 90.195146 -186.372754)
		(width 0.1143)
		(layer "In7.Cu")
		(net "UART_T6_NODE3_RXD")
	)
	(segment
		(start 90.520774 -185.737754)
		(end 90.992198 -185.737754)
		(width 0.1143)
		(layer "In7.Cu")
		(net "UART_T6_NODE3_RXD")
	)
	(segment
		(start 92.89034 -186.228736)
		(end 93.2561 -186.228736)
		(width 0.1143)
		(layer "In7.Cu")
		(net "UART_T6_NODE3_RXD")
	)
	(segment
		(start 92.79128 -178.590702)
		(end 92.79128 -177.875438)
		(width 0.1143)
		(layer "In7.Cu")
		(net "UART_T6_NODE3_RXD")
	)
	(segment
		(start 92.888308 -186.226704)
		(end 92.89034 -186.228736)
		(width 0.1143)
		(layer "In7.Cu")
		(net "UART_T6_NODE3_RXD")
	)
	(segment
		(start 94.03588 -176.630838)
		(end 94.03588 -175.233076)
		(width 0.1143)
		(layer "In7.Cu")
		(net "UART_T6_NODE3_RXD")
	)
	(segment
		(start 94.03588 -175.233076)
		(end 93.545406 -174.742602)
		(width 0.1143)
		(layer "In7.Cu")
		(net "UART_T6_NODE3_RXD")
	)
	(segment
		(start 92.583 -178.798982)
		(end 92.79128 -178.590702)
		(width 0.1143)
		(layer "In7.Cu")
		(net "UART_T6_NODE3_RXD")
	)
	(segment
		(start 92.23248 -182.01132)
		(end 91.37904 -181.15788)
		(width 0.1143)
		(layer "In7.Cu")
		(net "UART_T6_NODE3_RXD")
	)
	(segment
		(start 90.992198 -185.737754)
		(end 91.481148 -186.226704)
		(width 0.1143)
		(layer "In7.Cu")
		(net "UART_T6_NODE3_RXD")
	)
	(segment
		(start 93.70822 -185.900568)
		(end 93.70822 -183.762396)
		(width 0.1143)
		(layer "In7.Cu")
		(net "UART_T6_NODE3_RXD")
	)
	(segment
		(start 93.258132 -186.226704)
		(end 93.382084 -186.226704)
		(width 0.1143)
		(layer "In7.Cu")
		(net "UART_T6_NODE3_RXD")
	)
	(segment
		(start 91.37904 -181.15788)
		(end 91.37904 -180.495194)
		(width 0.1143)
		(layer "In7.Cu")
		(net "UART_T6_NODE3_RXD")
	)
	(segment
		(start 91.37904 -180.495194)
		(end 92.583 -179.291234)
		(width 0.1143)
		(layer "In7.Cu")
		(net "UART_T6_NODE3_RXD")
	)
	(segment
		(start 90.195146 -186.372754)
		(end 90.195146 -186.063382)
		(width 0.1143)
		(layer "In7.Cu")
		(net "UART_T6_NODE3_RXD")
	)
	(segment
		(start 93.2561 -186.228736)
		(end 93.258132 -186.226704)
		(width 0.1143)
		(layer "In7.Cu")
		(net "UART_T6_NODE3_RXD")
	)
	(segment
		(start 90.195146 -186.063382)
		(end 90.520774 -185.737754)
		(width 0.1143)
		(layer "In7.Cu")
		(net "UART_T6_NODE3_RXD")
	)
	(segment
		(start 92.79128 -177.875438)
		(end 94.03588 -176.630838)
		(width 0.1143)
		(layer "In7.Cu")
		(net "UART_T6_NODE3_RXD")
	)
	(segment
		(start 92.583 -179.291234)
		(end 92.583 -178.798982)
		(width 0.1143)
		(layer "In7.Cu")
		(net "UART_T6_NODE3_RXD")
	)
	(segment
		(start 93.70822 -183.762396)
		(end 92.23248 -182.286656)
		(width 0.1143)
		(layer "In7.Cu")
		(net "UART_T6_NODE3_RXD")
	)
	(segment
		(start 93.545406 -174.742602)
		(end 92.65031 -174.742602)
		(width 0.1143)
		(layer "In7.Cu")
		(net "UART_T6_NODE3_RXD")
	)
	(segment
		(start 92.23248 -182.286656)
		(end 92.23248 -182.01132)
		(width 0.1143)
		(layer "In7.Cu")
		(net "UART_T6_NODE3_RXD")
	)
	(segment
		(start 91.481148 -186.226704)
		(end 92.888308 -186.226704)
		(width 0.1143)
		(layer "In7.Cu")
		(net "UART_T6_NODE3_RXD")
	)
	(segment
		(start 93.382084 -186.226704)
		(end 93.70822 -185.900568)
		(width 0.1143)
		(layer "In7.Cu")
		(net "UART_T6_NODE3_RXD")
	)
	(via
		(at 63.29426 -195.51904)
		(size 0.6604)
		(drill 0.3302)
		(layers "F.Cu" "B.Cu")
		(net "T1_NODE3_EN_R")
	)
	(segment
		(start 63.015114 -199.352154)
		(end 63.015114 -205.199488)
		(width 0.1016)
		(layer "B.Cu")
		(net "T1_NODE3_EN_R")
	)
	(segment
		(start 63.29426 -194.157346)
		(end 63.29426 -195.51904)
		(width 0.1016)
		(layer "B.Cu")
		(net "T1_NODE3_EN_R")
	)
	(segment
		(start 63.4746 -198.892668)
		(end 63.015114 -199.352154)
		(width 0.1016)
		(layer "B.Cu")
		(net "T1_NODE3_EN_R")
	)
	(segment
		(start 63.69812 -186.247278)
		(end 63.69812 -187.978034)
		(width 0.1016)
		(layer "B.Cu")
		(net "T1_NODE3_EN_R")
	)
	(segment
		(start 64.24676 -193.204846)
		(end 63.29426 -194.157346)
		(width 0.1016)
		(layer "B.Cu")
		(net "T1_NODE3_EN_R")
	)
	(segment
		(start 63.4746 -195.69938)
		(end 63.4746 -198.892668)
		(width 0.1016)
		(layer "B.Cu")
		(net "T1_NODE3_EN_R")
	)
	(segment
		(start 64.24676 -185.698638)
		(end 63.69812 -186.247278)
		(width 0.1016)
		(layer "B.Cu")
		(net "T1_NODE3_EN_R")
	)
	(segment
		(start 63.69812 -187.978034)
		(end 64.24676 -188.526674)
		(width 0.1016)
		(layer "B.Cu")
		(net "T1_NODE3_EN_R")
	)
	(segment
		(start 63.29426 -195.51904)
		(end 63.4746 -195.69938)
		(width 0.1016)
		(layer "B.Cu")
		(net "T1_NODE3_EN_R")
	)
	(segment
		(start 64.24676 -188.526674)
		(end 64.24676 -193.204846)
		(width 0.1016)
		(layer "B.Cu")
		(net "T1_NODE3_EN_R")
	)
	(segment
		(start 64.24676 -185.605674)
		(end 64.24676 -185.698638)
		(width 0.1016)
		(layer "B.Cu")
		(net "T1_NODE3_EN_R")
	)
	(segment
		(start 107.2388 -186.7789)
		(end 107.2388 -187.665614)
		(width 0.1016)
		(layer "F.Cu")
		(net "UART_T6_NODE1_RXD")
	)
	(segment
		(start 86.28761 -172.124624)
		(end 85.79612 -171.633134)
		(width 0.1016)
		(layer "F.Cu")
		(net "UART_T6_NODE1_RXD")
	)
	(segment
		(start 85.79612 -170.769026)
		(end 86.09838 -170.466766)
		(width 0.1016)
		(layer "F.Cu")
		(net "UART_T6_NODE1_RXD")
	)
	(segment
		(start 86.09838 -170.466766)
		(end 86.09838 -170.377104)
		(width 0.1016)
		(layer "F.Cu")
		(net "UART_T6_NODE1_RXD")
	)
	(segment
		(start 85.79612 -171.633134)
		(end 85.79612 -170.769026)
		(width 0.1016)
		(layer "F.Cu")
		(net "UART_T6_NODE1_RXD")
	)
	(segment
		(start 107.503976 -186.52617)
		(end 107.49153 -186.52617)
		(width 0.1016)
		(layer "F.Cu")
		(net "UART_T6_NODE1_RXD")
	)
	(segment
		(start 107.17276 -185.709306)
		(end 107.17276 -185.605674)
		(width 0.1016)
		(layer "F.Cu")
		(net "UART_T6_NODE1_RXD")
	)
	(segment
		(start 107.7468 -186.283346)
		(end 107.17276 -185.709306)
		(width 0.1016)
		(layer "F.Cu")
		(net "UART_T6_NODE1_RXD")
	)
	(segment
		(start 107.7468 -186.283346)
		(end 107.503976 -186.52617)
		(width 0.1016)
		(layer "F.Cu")
		(net "UART_T6_NODE1_RXD")
	)
	(segment
		(start 107.2388 -187.665614)
		(end 107.29976 -187.726574)
		(width 0.1016)
		(layer "F.Cu")
		(net "UART_T6_NODE1_RXD")
	)
	(segment
		(start 87.744808 -172.124624)
		(end 86.28761 -172.124624)
		(width 0.1016)
		(layer "F.Cu")
		(net "UART_T6_NODE1_RXD")
	)
	(segment
		(start 107.49153 -186.52617)
		(end 107.2388 -186.7789)
		(width 0.1016)
		(layer "F.Cu")
		(net "UART_T6_NODE1_RXD")
	)
	(via
		(at 86.09838 -170.377104)
		(size 0.508)
		(drill 0.254)
		(layers "F.Cu" "B.Cu")
		(net "UART_T6_NODE1_RXD")
	)
	(via
		(at 103.88854 -184.441338)
		(size 0.508)
		(drill 0.254)
		(layers "F.Cu" "B.Cu")
		(net "UART_T6_NODE1_RXD")
	)
	(via
		(at 107.7468 -186.283346)
		(size 0.508)
		(drill 0.254)
		(layers "F.Cu" "B.Cu")
		(net "UART_T6_NODE1_RXD")
	)
	(segment
		(start 86.78164 -167.768016)
		(end 86.78164 -168.129966)
		(width 0.1143)
		(layer "In7.Cu")
		(net "UART_T6_NODE1_RXD")
	)
	(segment
		(start 101.80701 -177.860452)
		(end 101.46284 -177.516282)
		(width 0.1143)
		(layer "In7.Cu")
		(net "UART_T6_NODE1_RXD")
	)
	(segment
		(start 93.125036 -166.21125)
		(end 92.8878 -165.974014)
		(width 0.1143)
		(layer "In7.Cu")
		(net "UART_T6_NODE1_RXD")
	)
	(segment
		(start 86.08187 -167.068246)
		(end 86.78164 -167.768016)
		(width 0.1143)
		(layer "In7.Cu")
		(net "UART_T6_NODE1_RXD")
	)
	(segment
		(start 103.938832 -184.49163)
		(end 103.88854 -184.441338)
		(width 0.1143)
		(layer "In7.Cu")
		(net "UART_T6_NODE1_RXD")
	)
	(segment
		(start 92.52331 -165.974014)
		(end 92.168218 -166.329106)
		(width 0.1143)
		(layer "In7.Cu")
		(net "UART_T6_NODE1_RXD")
	)
	(segment
		(start 101.80701 -181.50967)
		(end 101.80701 -177.860452)
		(width 0.1143)
		(layer "In7.Cu")
		(net "UART_T6_NODE1_RXD")
	)
	(segment
		(start 99.10572 -175.831754)
		(end 99.77628 -175.16094)
		(width 0.1143)
		(layer "In7.Cu")
		(net "UART_T6_NODE1_RXD")
	)
	(segment
		(start 92.8878 -165.974014)
		(end 92.52331 -165.974014)
		(width 0.1143)
		(layer "In7.Cu")
		(net "UART_T6_NODE1_RXD")
	)
	(segment
		(start 86.14283 -168.739058)
		(end 86.14283 -170.332654)
		(width 0.1143)
		(layer "In7.Cu")
		(net "UART_T6_NODE1_RXD")
	)
	(segment
		(start 103.866442 -184.41924)
		(end 103.866442 -183.569102)
		(width 0.1143)
		(layer "In7.Cu")
		(net "UART_T6_NODE1_RXD")
	)
	(segment
		(start 86.494112 -168.387776)
		(end 86.14283 -168.739058)
		(width 0.1143)
		(layer "In7.Cu")
		(net "UART_T6_NODE1_RXD")
	)
	(segment
		(start 99.77628 -173.615858)
		(end 99.59594 -173.435518)
		(width 0.1143)
		(layer "In7.Cu")
		(net "UART_T6_NODE1_RXD")
	)
	(segment
		(start 106.14533 -185.84799)
		(end 104.78897 -184.49163)
		(width 0.1143)
		(layer "In7.Cu")
		(net "UART_T6_NODE1_RXD")
	)
	(segment
		(start 94.47657 -168.435528)
		(end 94.47657 -166.490142)
		(width 0.1143)
		(layer "In7.Cu")
		(net "UART_T6_NODE1_RXD")
	)
	(segment
		(start 103.866442 -183.569102)
		(end 101.80701 -181.50967)
		(width 0.1143)
		(layer "In7.Cu")
		(net "UART_T6_NODE1_RXD")
	)
	(segment
		(start 107.7468 -186.283346)
		(end 107.510834 -186.283346)
		(width 0.1143)
		(layer "In7.Cu")
		(net "UART_T6_NODE1_RXD")
	)
	(segment
		(start 99.467924 -177.516282)
		(end 99.10572 -177.154078)
		(width 0.1143)
		(layer "In7.Cu")
		(net "UART_T6_NODE1_RXD")
	)
	(segment
		(start 86.14283 -170.332654)
		(end 86.09838 -170.377104)
		(width 0.1143)
		(layer "In7.Cu")
		(net "UART_T6_NODE1_RXD")
	)
	(segment
		(start 103.88854 -184.441338)
		(end 103.866442 -184.41924)
		(width 0.1143)
		(layer "In7.Cu")
		(net "UART_T6_NODE1_RXD")
	)
	(segment
		(start 95.979488 -169.938446)
		(end 94.47657 -168.435528)
		(width 0.1143)
		(layer "In7.Cu")
		(net "UART_T6_NODE1_RXD")
	)
	(segment
		(start 86.78164 -168.129966)
		(end 86.52383 -168.387776)
		(width 0.1143)
		(layer "In7.Cu")
		(net "UART_T6_NODE1_RXD")
	)
	(segment
		(start 94.197678 -166.21125)
		(end 93.125036 -166.21125)
		(width 0.1143)
		(layer "In7.Cu")
		(net "UART_T6_NODE1_RXD")
	)
	(segment
		(start 99.77628 -175.16094)
		(end 99.77628 -173.615858)
		(width 0.1143)
		(layer "In7.Cu")
		(net "UART_T6_NODE1_RXD")
	)
	(segment
		(start 99.59594 -173.435518)
		(end 99.59594 -172.920406)
		(width 0.1143)
		(layer "In7.Cu")
		(net "UART_T6_NODE1_RXD")
	)
	(segment
		(start 89.710768 -165.64229)
		(end 86.651592 -165.64229)
		(width 0.1143)
		(layer "In7.Cu")
		(net "UART_T6_NODE1_RXD")
	)
	(segment
		(start 90.397584 -166.329106)
		(end 89.710768 -165.64229)
		(width 0.1143)
		(layer "In7.Cu")
		(net "UART_T6_NODE1_RXD")
	)
	(segment
		(start 107.075478 -185.84799)
		(end 106.14533 -185.84799)
		(width 0.1143)
		(layer "In7.Cu")
		(net "UART_T6_NODE1_RXD")
	)
	(segment
		(start 94.47657 -166.490142)
		(end 94.197678 -166.21125)
		(width 0.1143)
		(layer "In7.Cu")
		(net "UART_T6_NODE1_RXD")
	)
	(segment
		(start 86.651592 -165.64229)
		(end 86.08187 -166.212012)
		(width 0.1143)
		(layer "In7.Cu")
		(net "UART_T6_NODE1_RXD")
	)
	(segment
		(start 99.59594 -172.920406)
		(end 96.61398 -169.938446)
		(width 0.1143)
		(layer "In7.Cu")
		(net "UART_T6_NODE1_RXD")
	)
	(segment
		(start 107.510834 -186.283346)
		(end 107.075478 -185.84799)
		(width 0.1143)
		(layer "In7.Cu")
		(net "UART_T6_NODE1_RXD")
	)
	(segment
		(start 104.78897 -184.49163)
		(end 103.938832 -184.49163)
		(width 0.1143)
		(layer "In7.Cu")
		(net "UART_T6_NODE1_RXD")
	)
	(segment
		(start 99.10572 -177.154078)
		(end 99.10572 -175.831754)
		(width 0.1143)
		(layer "In7.Cu")
		(net "UART_T6_NODE1_RXD")
	)
	(segment
		(start 86.52383 -168.387776)
		(end 86.494112 -168.387776)
		(width 0.1143)
		(layer "In7.Cu")
		(net "UART_T6_NODE1_RXD")
	)
	(segment
		(start 92.168218 -166.329106)
		(end 90.397584 -166.329106)
		(width 0.1143)
		(layer "In7.Cu")
		(net "UART_T6_NODE1_RXD")
	)
	(segment
		(start 86.08187 -166.212012)
		(end 86.08187 -167.068246)
		(width 0.1143)
		(layer "In7.Cu")
		(net "UART_T6_NODE1_RXD")
	)
	(segment
		(start 101.46284 -177.516282)
		(end 99.467924 -177.516282)
		(width 0.1143)
		(layer "In7.Cu")
		(net "UART_T6_NODE1_RXD")
	)
	(segment
		(start 96.61398 -169.938446)
		(end 95.979488 -169.938446)
		(width 0.1143)
		(layer "In7.Cu")
		(net "UART_T6_NODE1_RXD")
	)
	(segment
		(start 138.79576 -184.805574)
		(end 138.79576 -183.95823)
		(width 0.1016)
		(layer "F.Cu")
		(net "T10_NODE3_EN")
	)
	(segment
		(start 138.79576 -183.95823)
		(end 138.827764 -183.926226)
		(width 0.1016)
		(layer "F.Cu")
		(net "T10_NODE3_EN")
	)
	(via
		(at 143.552672 -176.431956)
		(size 0.508)
		(drill 0.254)
		(layers "F.Cu" "B.Cu")
		(net "T10_NODE3_EN")
	)
	(via
		(at 138.827764 -183.926226)
		(size 0.508)
		(drill 0.254)
		(layers "F.Cu" "B.Cu")
		(net "T10_NODE3_EN")
	)
	(segment
		(start 142.907004 -177.077624)
		(end 143.552672 -176.431956)
		(width 0.1016)
		(layer "B.Cu")
		(net "T10_NODE3_EN")
	)
	(segment
		(start 144.187926 -175.796702)
		(end 143.552672 -176.431956)
		(width 0.1016)
		(layer "B.Cu")
		(net "T10_NODE3_EN")
	)
	(segment
		(start 142.47241 -177.077624)
		(end 142.907004 -177.077624)
		(width 0.1016)
		(layer "B.Cu")
		(net "T10_NODE3_EN")
	)
	(segment
		(start 145.14576 -175.796702)
		(end 144.187926 -175.796702)
		(width 0.1016)
		(layer "B.Cu")
		(net "T10_NODE3_EN")
	)
	(segment
		(start 143.087598 -180.798724)
		(end 143.32331 -181.034436)
		(width 0.1143)
		(layer "In2.Cu")
		(net "T10_NODE3_EN")
	)
	(segment
		(start 143.32331 -181.398926)
		(end 142.781274 -181.940962)
		(width 0.1143)
		(layer "In2.Cu")
		(net "T10_NODE3_EN")
	)
	(segment
		(start 141.515846 -181.940962)
		(end 140.563346 -182.893462)
		(width 0.1143)
		(layer "In2.Cu")
		(net "T10_NODE3_EN")
	)
	(segment
		(start 139.68603 -182.893462)
		(end 138.827764 -183.751728)
		(width 0.1143)
		(layer "In2.Cu")
		(net "T10_NODE3_EN")
	)
	(segment
		(start 143.087598 -176.89703)
		(end 143.087598 -180.798724)
		(width 0.1143)
		(layer "In2.Cu")
		(net "T10_NODE3_EN")
	)
	(segment
		(start 138.827764 -183.751728)
		(end 138.827764 -183.926226)
		(width 0.1143)
		(layer "In2.Cu")
		(net "T10_NODE3_EN")
	)
	(segment
		(start 143.32331 -181.034436)
		(end 143.32331 -181.398926)
		(width 0.1143)
		(layer "In2.Cu")
		(net "T10_NODE3_EN")
	)
	(segment
		(start 143.552672 -176.431956)
		(end 143.087598 -176.89703)
		(width 0.1143)
		(layer "In2.Cu")
		(net "T10_NODE3_EN")
	)
	(segment
		(start 140.563346 -182.893462)
		(end 139.68603 -182.893462)
		(width 0.1143)
		(layer "In2.Cu")
		(net "T10_NODE3_EN")
	)
	(segment
		(start 142.781274 -181.940962)
		(end 141.515846 -181.940962)
		(width 0.1143)
		(layer "In2.Cu")
		(net "T10_NODE3_EN")
	)
	(segment
		(start 87.10676 -185.753248)
		(end 87.78494 -186.431428)
		(width 0.1016)
		(layer "F.Cu")
		(net "UART_T6_NODE4_RXD")
	)
	(segment
		(start 87.10676 -187.726574)
		(end 87.10676 -187.109608)
		(width 0.1016)
		(layer "F.Cu")
		(net "UART_T6_NODE4_RXD")
	)
	(segment
		(start 92.469462 -176.003712)
		(end 88.55075 -176.003712)
		(width 0.1016)
		(layer "F.Cu")
		(net "UART_T6_NODE4_RXD")
	)
	(segment
		(start 87.10676 -185.605674)
		(end 87.10676 -185.753248)
		(width 0.1016)
		(layer "F.Cu")
		(net "UART_T6_NODE4_RXD")
	)
	(segment
		(start 88.55075 -176.003712)
		(end 88.429846 -176.124616)
		(width 0.1016)
		(layer "F.Cu")
		(net "UART_T6_NODE4_RXD")
	)
	(segment
		(start 92.48521 -176.01946)
		(end 92.469462 -176.003712)
		(width 0.1016)
		(layer "F.Cu")
		(net "UART_T6_NODE4_RXD")
	)
	(segment
		(start 87.10676 -187.109608)
		(end 87.78494 -186.431428)
		(width 0.1016)
		(layer "F.Cu")
		(net "UART_T6_NODE4_RXD")
	)
	(segment
		(start 88.429846 -176.124616)
		(end 87.744808 -176.124616)
		(width 0.1016)
		(layer "F.Cu")
		(net "UART_T6_NODE4_RXD")
	)
	(via
		(at 92.48521 -176.01946)
		(size 0.508)
		(drill 0.254)
		(layers "F.Cu" "B.Cu")
		(net "UART_T6_NODE4_RXD")
	)
	(via
		(at 87.78494 -186.431428)
		(size 0.508)
		(drill 0.254)
		(layers "F.Cu" "B.Cu")
		(net "UART_T6_NODE4_RXD")
	)
	(segment
		(start 91.299792 -183.57596)
		(end 91.975686 -183.57596)
		(width 0.1143)
		(layer "In7.Cu")
		(net "UART_T6_NODE4_RXD")
	)
	(segment
		(start 93.08465 -184.684924)
		(end 93.08465 -185.048144)
		(width 0.1143)
		(layer "In7.Cu")
		(net "UART_T6_NODE4_RXD")
	)
	(segment
		(start 93.08465 -185.048144)
		(end 92.82811 -185.304684)
		(width 0.1143)
		(layer "In7.Cu")
		(net "UART_T6_NODE4_RXD")
	)
	(segment
		(start 90.45067 -182.726838)
		(end 91.299792 -183.57596)
		(width 0.1143)
		(layer "In7.Cu")
		(net "UART_T6_NODE4_RXD")
	)
	(segment
		(start 92.82811 -185.304684)
		(end 91.801188 -185.304684)
		(width 0.1143)
		(layer "In7.Cu")
		(net "UART_T6_NODE4_RXD")
	)
	(segment
		(start 91.975686 -183.57596)
		(end 93.08465 -184.684924)
		(width 0.1143)
		(layer "In7.Cu")
		(net "UART_T6_NODE4_RXD")
	)
	(segment
		(start 89.564464 -184.651904)
		(end 87.78494 -186.431428)
		(width 0.1143)
		(layer "In7.Cu")
		(net "UART_T6_NODE4_RXD")
	)
	(segment
		(start 91.801188 -185.304684)
		(end 91.148408 -184.651904)
		(width 0.1143)
		(layer "In7.Cu")
		(net "UART_T6_NODE4_RXD")
	)
	(segment
		(start 91.79941 -176.01946)
		(end 90.50528 -177.31359)
		(width 0.1143)
		(layer "In7.Cu")
		(net "UART_T6_NODE4_RXD")
	)
	(segment
		(start 90.50528 -182.208678)
		(end 90.45067 -182.263288)
		(width 0.1143)
		(layer "In7.Cu")
		(net "UART_T6_NODE4_RXD")
	)
	(segment
		(start 90.50528 -177.31359)
		(end 90.50528 -182.208678)
		(width 0.1143)
		(layer "In7.Cu")
		(net "UART_T6_NODE4_RXD")
	)
	(segment
		(start 90.45067 -182.263288)
		(end 90.45067 -182.726838)
		(width 0.1143)
		(layer "In7.Cu")
		(net "UART_T6_NODE4_RXD")
	)
	(segment
		(start 92.48521 -176.01946)
		(end 91.79941 -176.01946)
		(width 0.1143)
		(layer "In7.Cu")
		(net "UART_T6_NODE4_RXD")
	)
	(segment
		(start 91.148408 -184.651904)
		(end 89.564464 -184.651904)
		(width 0.1143)
		(layer "In7.Cu")
		(net "UART_T6_NODE4_RXD")
	)
	(segment
		(start 110.940596 -182.720742)
		(end 110.559088 -182.339234)
		(width 0.1016)
		(layer "F.Cu")
		(net "T6_NODE1_EN")
	)
	(segment
		(start 111.74476 -184.805574)
		(end 111.74476 -183.966358)
		(width 0.1016)
		(layer "F.Cu")
		(net "T6_NODE1_EN")
	)
	(segment
		(start 111.9886 -183.232552)
		(end 111.47679 -182.720742)
		(width 0.1016)
		(layer "F.Cu")
		(net "T6_NODE1_EN")
	)
	(segment
		(start 111.74476 -183.966358)
		(end 111.9886 -183.722518)
		(width 0.1016)
		(layer "F.Cu")
		(net "T6_NODE1_EN")
	)
	(segment
		(start 111.47679 -182.720742)
		(end 110.940596 -182.720742)
		(width 0.1016)
		(layer "F.Cu")
		(net "T6_NODE1_EN")
	)
	(segment
		(start 110.559088 -182.339234)
		(end 108.49102 -182.339234)
		(width 0.1016)
		(layer "F.Cu")
		(net "T6_NODE1_EN")
	)
	(segment
		(start 111.9886 -183.722518)
		(end 111.9886 -183.232552)
		(width 0.1016)
		(layer "F.Cu")
		(net "T6_NODE1_EN")
	)
	(via
		(at 111.93526 -178.406044)
		(size 0.508)
		(drill 0.254)
		(layers "F.Cu" "B.Cu")
		(net "T6_NODE1_EN")
	)
	(via
		(at 108.49102 -182.339234)
		(size 0.508)
		(drill 0.254)
		(layers "F.Cu" "B.Cu")
		(net "T6_NODE1_EN")
	)
	(segment
		(start 113.52276 -178.17973)
		(end 112.161574 -178.17973)
		(width 0.1016)
		(layer "B.Cu")
		(net "T6_NODE1_EN")
	)
	(segment
		(start 111.73968 -178.601624)
		(end 110.84941 -178.601624)
		(width 0.1016)
		(layer "B.Cu")
		(net "T6_NODE1_EN")
	)
	(segment
		(start 112.161574 -178.17973)
		(end 111.93526 -178.406044)
		(width 0.1016)
		(layer "B.Cu")
		(net "T6_NODE1_EN")
	)
	(segment
		(start 111.93526 -178.406044)
		(end 111.73968 -178.601624)
		(width 0.1016)
		(layer "B.Cu")
		(net "T6_NODE1_EN")
	)
	(segment
		(start 109.845602 -180.495702)
		(end 109.845602 -180.815234)
		(width 0.1143)
		(layer "In7.Cu")
		(net "T6_NODE1_EN")
	)
	(segment
		(start 109.845602 -180.815234)
		(end 108.49102 -182.169816)
		(width 0.1143)
		(layer "In7.Cu")
		(net "T6_NODE1_EN")
	)
	(segment
		(start 108.49102 -182.169816)
		(end 108.49102 -182.339234)
		(width 0.1143)
		(layer "In7.Cu")
		(net "T6_NODE1_EN")
	)
	(segment
		(start 111.93526 -178.406044)
		(end 109.845602 -180.495702)
		(width 0.1143)
		(layer "In7.Cu")
		(net "T6_NODE1_EN")
	)
	(segment
		(start 90.412062 -172.499782)
		(end 90.412062 -172.714158)
		(width 0.1016)
		(layer "F.Cu")
		(net "UART_T6_NODE2_TXD")
	)
	(segment
		(start 90.801444 -173.10354)
		(end 90.801444 -173.424088)
		(width 0.1016)
		(layer "F.Cu")
		(net "UART_T6_NODE2_TXD")
	)
	(segment
		(start 89.099898 -172.624496)
		(end 90.146124 -173.670722)
		(width 0.1016)
		(layer "F.Cu")
		(net "UART_T6_NODE2_TXD")
	)
	(segment
		(start 90.412062 -172.714158)
		(end 90.801444 -173.10354)
		(width 0.1016)
		(layer "F.Cu")
		(net "UART_T6_NODE2_TXD")
	)
	(segment
		(start 90.801444 -173.424088)
		(end 90.55481 -173.670722)
		(width 0.1016)
		(layer "F.Cu")
		(net "UART_T6_NODE2_TXD")
	)
	(segment
		(start 87.744808 -172.624496)
		(end 89.099898 -172.624496)
		(width 0.1016)
		(layer "F.Cu")
		(net "UART_T6_NODE2_TXD")
	)
	(segment
		(start 90.146124 -173.670722)
		(end 90.55481 -173.670722)
		(width 0.1016)
		(layer "F.Cu")
		(net "UART_T6_NODE2_TXD")
	)
	(via
		(at 90.55481 -173.670722)
		(size 0.762)
		(drill 0.381)
		(layers "F.Cu" "B.Cu")
		(net "UART_T6_NODE2_TXD")
	)
	(segment
		(start 125.44298 -177.740818)
		(end 123.47956 -179.704238)
		(width 0.1016)
		(layer "F.Cu")
		(net "T8_NODE1_EN")
	)
	(segment
		(start 123.47956 -184.348374)
		(end 123.93676 -184.805574)
		(width 0.1016)
		(layer "F.Cu")
		(net "T8_NODE1_EN")
	)
	(segment
		(start 126.3269 -177.740818)
		(end 125.44298 -177.740818)
		(width 0.1016)
		(layer "F.Cu")
		(net "T8_NODE1_EN")
	)
	(segment
		(start 123.47956 -179.704238)
		(end 123.47956 -184.348374)
		(width 0.1016)
		(layer "F.Cu")
		(net "T8_NODE1_EN")
	)
	(via
		(at 126.3269 -177.740818)
		(size 0.508)
		(drill 0.254)
		(layers "F.Cu" "B.Cu")
		(net "T8_NODE1_EN")
	)
	(segment
		(start 123.60021 -176.931828)
		(end 123.30811 -177.223928)
		(width 0.1016)
		(layer "B.Cu")
		(net "T8_NODE1_EN")
	)
	(segment
		(start 123.30811 -177.223928)
		(end 123.30811 -177.458624)
		(width 0.1016)
		(layer "B.Cu")
		(net "T8_NODE1_EN")
	)
	(segment
		(start 122.587004 -178.17973)
		(end 119.36476 -178.17973)
		(width 0.1016)
		(layer "B.Cu")
		(net "T8_NODE1_EN")
	)
	(segment
		(start 125.51791 -176.931828)
		(end 123.60021 -176.931828)
		(width 0.1016)
		(layer "B.Cu")
		(net "T8_NODE1_EN")
	)
	(segment
		(start 126.3269 -177.740818)
		(end 125.51791 -176.931828)
		(width 0.1016)
		(layer "B.Cu")
		(net "T8_NODE1_EN")
	)
	(segment
		(start 123.30811 -177.458624)
		(end 122.587004 -178.17973)
		(width 0.1016)
		(layer "B.Cu")
		(net "T8_NODE1_EN")
	)
	(segment
		(start 94.611444 -189.851538)
		(end 94.611444 -188.838586)
		(width 0.1016)
		(layer "F.Cu")
		(net "UART_T6_NODE2_RXD")
	)
	(segment
		(start 89.318592 -174.018956)
		(end 88.424258 -173.124622)
		(width 0.1016)
		(layer "F.Cu")
		(net "UART_T6_NODE2_RXD")
	)
	(segment
		(start 90.31097 -174.229522)
		(end 90.100404 -174.018956)
		(width 0.1016)
		(layer "F.Cu")
		(net "UART_T6_NODE2_RXD")
	)
	(segment
		(start 91.551506 -173.475142)
		(end 90.797126 -174.229522)
		(width 0.1016)
		(layer "F.Cu")
		(net "UART_T6_NODE2_RXD")
	)
	(segment
		(start 94.867984 -190.108078)
		(end 94.611444 -189.851538)
		(width 0.1016)
		(layer "F.Cu")
		(net "UART_T6_NODE2_RXD")
	)
	(segment
		(start 92.3544 -173.475142)
		(end 91.551506 -173.475142)
		(width 0.1016)
		(layer "F.Cu")
		(net "UART_T6_NODE2_RXD")
	)
	(segment
		(start 90.100404 -174.018956)
		(end 89.318592 -174.018956)
		(width 0.1016)
		(layer "F.Cu")
		(net "UART_T6_NODE2_RXD")
	)
	(segment
		(start 88.424258 -173.124622)
		(end 87.744808 -173.124622)
		(width 0.1016)
		(layer "F.Cu")
		(net "UART_T6_NODE2_RXD")
	)
	(segment
		(start 90.797126 -174.229522)
		(end 90.31097 -174.229522)
		(width 0.1016)
		(layer "F.Cu")
		(net "UART_T6_NODE2_RXD")
	)
	(segment
		(start 94.869 -190.108078)
		(end 94.867984 -190.108078)
		(width 0.1016)
		(layer "F.Cu")
		(net "UART_T6_NODE2_RXD")
	)
	(segment
		(start 92.620846 -173.741588)
		(end 92.3544 -173.475142)
		(width 0.1016)
		(layer "F.Cu")
		(net "UART_T6_NODE2_RXD")
	)
	(via
		(at 94.869 -190.108078)
		(size 0.508)
		(drill 0.254)
		(layers "F.Cu" "B.Cu")
		(net "UART_T6_NODE2_RXD")
	)
	(via
		(at 92.620846 -173.741588)
		(size 0.508)
		(drill 0.254)
		(layers "F.Cu" "B.Cu")
		(net "UART_T6_NODE2_RXD")
	)
	(segment
		(start 94.869 -190.108078)
		(end 94.867984 -190.108078)
		(width 0.1016)
		(layer "B.Cu")
		(net "UART_T6_NODE2_RXD")
	)
	(segment
		(start 94.611444 -189.851538)
		(end 94.611444 -188.838586)
		(width 0.1016)
		(layer "B.Cu")
		(net "UART_T6_NODE2_RXD")
	)
	(segment
		(start 94.867984 -190.108078)
		(end 94.611444 -189.851538)
		(width 0.1016)
		(layer "B.Cu")
		(net "UART_T6_NODE2_RXD")
	)
	(segment
		(start 93.15831 -178.674776)
		(end 92.90177 -178.931316)
		(width 0.1143)
		(layer "In7.Cu")
		(net "UART_T6_NODE2_RXD")
	)
	(segment
		(start 93.172534 -174.374556)
		(end 93.626432 -174.374556)
		(width 0.1143)
		(layer "In7.Cu")
		(net "UART_T6_NODE2_RXD")
	)
	(segment
		(start 92.620846 -173.741588)
		(end 92.620846 -173.822868)
		(width 0.1143)
		(layer "In7.Cu")
		(net "UART_T6_NODE2_RXD")
	)
	(segment
		(start 93.626432 -174.374556)
		(end 94.35338 -175.101504)
		(width 0.1143)
		(layer "In7.Cu")
		(net "UART_T6_NODE2_RXD")
	)
	(segment
		(start 94.05366 -189.223904)
		(end 94.869 -190.039244)
		(width 0.1143)
		(layer "In7.Cu")
		(net "UART_T6_NODE2_RXD")
	)
	(segment
		(start 92.55125 -180.071776)
		(end 92.54998 -180.073046)
		(width 0.1143)
		(layer "In7.Cu")
		(net "UART_T6_NODE2_RXD")
	)
	(segment
		(start 92.620846 -173.822868)
		(end 93.172534 -174.374556)
		(width 0.1143)
		(layer "In7.Cu")
		(net "UART_T6_NODE2_RXD")
	)
	(segment
		(start 92.55125 -179.77358)
		(end 92.55125 -180.071776)
		(width 0.1143)
		(layer "In7.Cu")
		(net "UART_T6_NODE2_RXD")
	)
	(segment
		(start 94.35338 -177.8508)
		(end 93.529404 -178.674776)
		(width 0.1143)
		(layer "In7.Cu")
		(net "UART_T6_NODE2_RXD")
	)
	(segment
		(start 92.54998 -182.155084)
		(end 94.05366 -183.658764)
		(width 0.1143)
		(layer "In7.Cu")
		(net "UART_T6_NODE2_RXD")
	)
	(segment
		(start 94.35338 -175.101504)
		(end 94.35338 -177.8508)
		(width 0.1143)
		(layer "In7.Cu")
		(net "UART_T6_NODE2_RXD")
	)
	(segment
		(start 92.90177 -179.422806)
		(end 92.55125 -179.77358)
		(width 0.1143)
		(layer "In7.Cu")
		(net "UART_T6_NODE2_RXD")
	)
	(segment
		(start 94.869 -190.039244)
		(end 94.869 -190.108078)
		(width 0.1143)
		(layer "In7.Cu")
		(net "UART_T6_NODE2_RXD")
	)
	(segment
		(start 93.529404 -178.674776)
		(end 93.15831 -178.674776)
		(width 0.1143)
		(layer "In7.Cu")
		(net "UART_T6_NODE2_RXD")
	)
	(segment
		(start 92.54998 -180.073046)
		(end 92.54998 -182.155084)
		(width 0.1143)
		(layer "In7.Cu")
		(net "UART_T6_NODE2_RXD")
	)
	(segment
		(start 92.90177 -178.931316)
		(end 92.90177 -179.422806)
		(width 0.1143)
		(layer "In7.Cu")
		(net "UART_T6_NODE2_RXD")
	)
	(segment
		(start 94.05366 -183.658764)
		(end 94.05366 -189.223904)
		(width 0.1143)
		(layer "In7.Cu")
		(net "UART_T6_NODE2_RXD")
	)
	(segment
		(start 124.165868 -182.519828)
		(end 123.99772 -182.687976)
		(width 0.1016)
		(layer "F.Cu")
		(net "T7_NODE1_EN")
	)
	(segment
		(start 125.335538 -182.519828)
		(end 124.165868 -182.519828)
		(width 0.1016)
		(layer "F.Cu")
		(net "T7_NODE1_EN")
	)
	(via
		(at 123.99772 -182.687976)
		(size 0.508)
		(drill 0.254)
		(layers "F.Cu" "B.Cu")
		(net "T7_NODE1_EN")
	)
	(segment
		(start 123.99772 -182.687976)
		(end 123.674124 -182.687976)
		(width 0.1016)
		(layer "B.Cu")
		(net "T7_NODE1_EN")
	)
	(segment
		(start 119.36476 -182.350664)
		(end 119.05996 -182.655464)
		(width 0.1016)
		(layer "B.Cu")
		(net "T7_NODE1_EN")
	)
	(segment
		(start 119.05996 -182.655464)
		(end 119.05996 -184.373774)
		(width 0.1016)
		(layer "B.Cu")
		(net "T7_NODE1_EN")
	)
	(segment
		(start 121.765822 -180.779674)
		(end 119.36476 -180.779674)
		(width 0.1016)
		(layer "B.Cu")
		(net "T7_NODE1_EN")
	)
	(segment
		(start 119.36476 -180.779674)
		(end 119.36476 -182.350664)
		(width 0.1016)
		(layer "B.Cu")
		(net "T7_NODE1_EN")
	)
	(segment
		(start 123.674124 -182.687976)
		(end 121.765822 -180.779674)
		(width 0.1016)
		(layer "B.Cu")
		(net "T7_NODE1_EN")
	)
	(segment
		(start 119.05996 -184.373774)
		(end 119.49176 -184.805574)
		(width 0.1016)
		(layer "B.Cu")
		(net "T7_NODE1_EN")
	)
	(segment
		(start 87.172038 -183.117744)
		(end 88.24976 -184.195466)
		(width 0.1016)
		(layer "F.Cu")
		(net "UART_T6_NODE3_TXD")
	)
	(segment
		(start 86.92642 -183.117744)
		(end 87.172038 -183.117744)
		(width 0.1016)
		(layer "F.Cu")
		(net "UART_T6_NODE3_TXD")
	)
	(segment
		(start 85.800692 -174.21606)
		(end 86.392004 -173.624748)
		(width 0.1016)
		(layer "F.Cu")
		(net "UART_T6_NODE3_TXD")
	)
	(segment
		(start 86.392004 -173.624748)
		(end 87.744808 -173.624748)
		(width 0.1016)
		(layer "F.Cu")
		(net "UART_T6_NODE3_TXD")
	)
	(segment
		(start 85.800692 -174.427134)
		(end 85.800692 -174.21606)
		(width 0.1016)
		(layer "F.Cu")
		(net "UART_T6_NODE3_TXD")
	)
	(segment
		(start 88.24976 -184.195466)
		(end 88.24976 -184.805574)
		(width 0.1016)
		(layer "F.Cu")
		(net "UART_T6_NODE3_TXD")
	)
	(via
		(at 86.92642 -183.117744)
		(size 0.508)
		(drill 0.254)
		(layers "F.Cu" "B.Cu")
		(net "UART_T6_NODE3_TXD")
	)
	(via
		(at 85.800692 -174.427134)
		(size 0.508)
		(drill 0.254)
		(layers "F.Cu" "B.Cu")
		(net "UART_T6_NODE3_TXD")
	)
	(segment
		(start 85.800692 -174.427134)
		(end 87.76208 -176.388522)
		(width 0.1143)
		(layer "In7.Cu")
		(net "UART_T6_NODE3_TXD")
	)
	(segment
		(start 87.76208 -176.388522)
		(end 87.76208 -180.757576)
		(width 0.1143)
		(layer "In7.Cu")
		(net "UART_T6_NODE3_TXD")
	)
	(segment
		(start 87.757 -182.287164)
		(end 86.92642 -183.117744)
		(width 0.1143)
		(layer "In7.Cu")
		(net "UART_T6_NODE3_TXD")
	)
	(segment
		(start 88.01354 -181.372256)
		(end 87.757 -181.628796)
		(width 0.1143)
		(layer "In7.Cu")
		(net "UART_T6_NODE3_TXD")
	)
	(segment
		(start 87.757 -181.628796)
		(end 87.757 -182.287164)
		(width 0.1143)
		(layer "In7.Cu")
		(net "UART_T6_NODE3_TXD")
	)
	(segment
		(start 87.76208 -180.757576)
		(end 88.01354 -181.009036)
		(width 0.1143)
		(layer "In7.Cu")
		(net "UART_T6_NODE3_TXD")
	)
	(segment
		(start 88.01354 -181.009036)
		(end 88.01354 -181.372256)
		(width 0.1143)
		(layer "In7.Cu")
		(net "UART_T6_NODE3_TXD")
	)
	(segment
		(start 85.96376 -184.805574)
		(end 85.96884 -184.800494)
		(width 0.1016)
		(layer "F.Cu")
		(net "UART_T6_NODE4_TXD")
	)
	(segment
		(start 87.744808 -175.626014)
		(end 87.744808 -175.624744)
		(width 0.1016)
		(layer "F.Cu")
		(net "UART_T6_NODE4_TXD")
	)
	(segment
		(start 85.96884 -184.800494)
		(end 85.96884 -184.04459)
		(width 0.1016)
		(layer "F.Cu")
		(net "UART_T6_NODE4_TXD")
	)
	(segment
		(start 86.005162 -175.626014)
		(end 87.744808 -175.626014)
		(width 0.1016)
		(layer "F.Cu")
		(net "UART_T6_NODE4_TXD")
	)
	(segment
		(start 85.37194 -176.259236)
		(end 86.005162 -175.626014)
		(width 0.1016)
		(layer "F.Cu")
		(net "UART_T6_NODE4_TXD")
	)
	(via
		(at 85.37194 -176.259236)
		(size 0.508)
		(drill 0.254)
		(layers "F.Cu" "B.Cu")
		(net "UART_T6_NODE4_TXD")
	)
	(via
		(at 85.96884 -184.04459)
		(size 0.508)
		(drill 0.254)
		(layers "F.Cu" "B.Cu")
		(net "UART_T6_NODE4_TXD")
	)
	(segment
		(start 85.96884 -183.18861)
		(end 86.90737 -182.25008)
		(width 0.1143)
		(layer "In7.Cu")
		(net "UART_T6_NODE4_TXD")
	)
	(segment
		(start 85.37194 -177.275236)
		(end 85.37194 -176.259236)
		(width 0.1143)
		(layer "In7.Cu")
		(net "UART_T6_NODE4_TXD")
	)
	(segment
		(start 85.41766 -180.320696)
		(end 85.41766 -177.320956)
		(width 0.1143)
		(layer "In7.Cu")
		(net "UART_T6_NODE4_TXD")
	)
	(segment
		(start 86.90737 -181.810406)
		(end 85.41766 -180.320696)
		(width 0.1143)
		(layer "In7.Cu")
		(net "UART_T6_NODE4_TXD")
	)
	(segment
		(start 85.96884 -184.04459)
		(end 85.96884 -183.18861)
		(width 0.1143)
		(layer "In7.Cu")
		(net "UART_T6_NODE4_TXD")
	)
	(segment
		(start 86.90737 -182.25008)
		(end 86.90737 -181.810406)
		(width 0.1143)
		(layer "In7.Cu")
		(net "UART_T6_NODE4_TXD")
	)
	(segment
		(start 85.41766 -177.320956)
		(end 85.37194 -177.275236)
		(width 0.1143)
		(layer "In7.Cu")
		(net "UART_T6_NODE4_TXD")
	)
	(segment
		(start 89.71026 -169.882312)
		(end 89.45245 -169.624502)
		(width 0.1016)
		(layer "F.Cu")
		(net "UART_T5_NODE3_TXD")
	)
	(segment
		(start 87.744808 -169.622724)
		(end 87.744808 -169.624502)
		(width 0.1016)
		(layer "F.Cu")
		(net "UART_T5_NODE3_TXD")
	)
	(segment
		(start 89.45245 -169.624502)
		(end 87.746586 -169.624502)
		(width 0.1016)
		(layer "F.Cu")
		(net "UART_T5_NODE3_TXD")
	)
	(segment
		(start 91.858592 -169.882312)
		(end 89.71026 -169.882312)
		(width 0.1016)
		(layer "F.Cu")
		(net "UART_T5_NODE3_TXD")
	)
	(segment
		(start 87.746586 -169.624502)
		(end 87.744808 -169.622724)
		(width 0.1016)
		(layer "F.Cu")
		(net "UART_T5_NODE3_TXD")
	)
	(segment
		(start 91.88704 -169.853864)
		(end 91.858592 -169.882312)
		(width 0.1016)
		(layer "F.Cu")
		(net "UART_T5_NODE3_TXD")
	)
	(via
		(at 92.6465 -184.866534)
		(size 0.508)
		(drill 0.254)
		(layers "F.Cu" "B.Cu")
		(net "UART_T5_NODE3_TXD")
	)
	(via
		(at 91.88704 -169.853864)
		(size 0.508)
		(drill 0.254)
		(layers "F.Cu" "B.Cu")
		(net "UART_T5_NODE3_TXD")
	)
	(segment
		(start 92.574364 -184.794398)
		(end 92.6465 -184.866534)
		(width 0.1016)
		(layer "B.Cu")
		(net "UART_T5_NODE3_TXD")
	)
	(segment
		(start 91.502484 -184.794398)
		(end 92.574364 -184.794398)
		(width 0.1016)
		(layer "B.Cu")
		(net "UART_T5_NODE3_TXD")
	)
	(segment
		(start 90.18778 -182.077106)
		(end 90.13317 -182.131716)
		(width 0.1143)
		(layer "In7.Cu")
		(net "UART_T5_NODE3_TXD")
	)
	(segment
		(start 90.13317 -182.873142)
		(end 92.126562 -184.866534)
		(width 0.1143)
		(layer "In7.Cu")
		(net "UART_T5_NODE3_TXD")
	)
	(segment
		(start 90.18778 -176.93767)
		(end 90.18778 -182.077106)
		(width 0.1143)
		(layer "In7.Cu")
		(net "UART_T5_NODE3_TXD")
	)
	(segment
		(start 91.88704 -169.853864)
		(end 91.28252 -170.458384)
		(width 0.1143)
		(layer "In7.Cu")
		(net "UART_T5_NODE3_TXD")
	)
	(segment
		(start 91.28252 -172.322744)
		(end 90.89136 -172.713904)
		(width 0.1143)
		(layer "In7.Cu")
		(net "UART_T5_NODE3_TXD")
	)
	(segment
		(start 90.89136 -176.23409)
		(end 90.18778 -176.93767)
		(width 0.1143)
		(layer "In7.Cu")
		(net "UART_T5_NODE3_TXD")
	)
	(segment
		(start 90.13317 -182.131716)
		(end 90.13317 -182.873142)
		(width 0.1143)
		(layer "In7.Cu")
		(net "UART_T5_NODE3_TXD")
	)
	(segment
		(start 91.28252 -170.458384)
		(end 91.28252 -172.322744)
		(width 0.1143)
		(layer "In7.Cu")
		(net "UART_T5_NODE3_TXD")
	)
	(segment
		(start 92.126562 -184.866534)
		(end 92.6465 -184.866534)
		(width 0.1143)
		(layer "In7.Cu")
		(net "UART_T5_NODE3_TXD")
	)
	(segment
		(start 90.89136 -172.713904)
		(end 90.89136 -176.23409)
		(width 0.1143)
		(layer "In7.Cu")
		(net "UART_T5_NODE3_TXD")
	)
	(segment
		(start 91.502484 -186.826398)
		(end 92.280994 -186.826398)
		(width 0.1016)
		(layer "F.Cu")
		(net "UART_T5_NODE3_RXD")
	)
	(segment
		(start 89.276936 -170.124628)
		(end 87.744808 -170.124628)
		(width 0.1016)
		(layer "F.Cu")
		(net "UART_T5_NODE3_RXD")
	)
	(segment
		(start 92.280994 -186.826398)
		(end 92.31884 -186.788552)
		(width 0.1016)
		(layer "F.Cu")
		(net "UART_T5_NODE3_RXD")
	)
	(segment
		(start 89.33688 -170.184572)
		(end 89.276936 -170.124628)
		(width 0.1016)
		(layer "F.Cu")
		(net "UART_T5_NODE3_RXD")
	)
	(via
		(at 85.92058 -186.280298)
		(size 0.508)
		(drill 0.254)
		(layers "F.Cu" "B.Cu")
		(net "UART_T5_NODE3_RXD")
	)
	(via
		(at 92.31884 -186.788552)
		(size 0.508)
		(drill 0.254)
		(layers "F.Cu" "B.Cu")
		(net "UART_T5_NODE3_RXD")
	)
	(via
		(at 89.33688 -170.184572)
		(size 0.508)
		(drill 0.254)
		(layers "F.Cu" "B.Cu")
		(net "UART_T5_NODE3_RXD")
	)
	(segment
		(start 85.92058 -186.280298)
		(end 86.456774 -185.744104)
		(width 0.1016)
		(layer "B.Cu")
		(net "UART_T5_NODE3_RXD")
	)
	(segment
		(start 91.502484 -186.826398)
		(end 92.280994 -186.826398)
		(width 0.1016)
		(layer "B.Cu")
		(net "UART_T5_NODE3_RXD")
	)
	(segment
		(start 91.502484 -186.315858)
		(end 91.502484 -186.826398)
		(width 0.1016)
		(layer "B.Cu")
		(net "UART_T5_NODE3_RXD")
	)
	(segment
		(start 86.456774 -185.744104)
		(end 90.93073 -185.744104)
		(width 0.1016)
		(layer "B.Cu")
		(net "UART_T5_NODE3_RXD")
	)
	(segment
		(start 92.280994 -186.826398)
		(end 92.31884 -186.788552)
		(width 0.1016)
		(layer "B.Cu")
		(net "UART_T5_NODE3_RXD")
	)
	(segment
		(start 90.93073 -185.744104)
		(end 91.502484 -186.315858)
		(width 0.1016)
		(layer "B.Cu")
		(net "UART_T5_NODE3_RXD")
	)
	(segment
		(start 88.0745 -182.656734)
		(end 85.92058 -184.810654)
		(width 0.1143)
		(layer "In7.Cu")
		(net "UART_T5_NODE3_RXD")
	)
	(segment
		(start 88.0745 -181.760368)
		(end 88.0745 -182.656734)
		(width 0.1143)
		(layer "In7.Cu")
		(net "UART_T5_NODE3_RXD")
	)
	(segment
		(start 88.33104 -180.877464)
		(end 88.33104 -181.503828)
		(width 0.1143)
		(layer "In7.Cu")
		(net "UART_T5_NODE3_RXD")
	)
	(segment
		(start 89.33688 -170.184572)
		(end 88.914478 -170.606974)
		(width 0.1143)
		(layer "In7.Cu")
		(net "UART_T5_NODE3_RXD")
	)
	(segment
		(start 85.92058 -184.810654)
		(end 85.92058 -186.280298)
		(width 0.1143)
		(layer "In7.Cu")
		(net "UART_T5_NODE3_RXD")
	)
	(segment
		(start 88.28659 -180.833014)
		(end 88.33104 -180.877464)
		(width 0.1143)
		(layer "In7.Cu")
		(net "UART_T5_NODE3_RXD")
	)
	(segment
		(start 88.28659 -172.41647)
		(end 88.28659 -180.833014)
		(width 0.1143)
		(layer "In7.Cu")
		(net "UART_T5_NODE3_RXD")
	)
	(segment
		(start 88.914478 -170.606974)
		(end 88.914478 -171.788582)
		(width 0.1143)
		(layer "In7.Cu")
		(net "UART_T5_NODE3_RXD")
	)
	(segment
		(start 88.33104 -181.503828)
		(end 88.0745 -181.760368)
		(width 0.1143)
		(layer "In7.Cu")
		(net "UART_T5_NODE3_RXD")
	)
	(segment
		(start 88.914478 -171.788582)
		(end 88.28659 -172.41647)
		(width 0.1143)
		(layer "In7.Cu")
		(net "UART_T5_NODE3_RXD")
	)
	(segment
		(start 92.75064 -170.922188)
		(end 92.729304 -170.943524)
		(width 0.1016)
		(layer "F.Cu")
		(net "UART_T5_NODE4_TXD")
	)
	(segment
		(start 92.729304 -170.943524)
		(end 89.051638 -170.943524)
		(width 0.1016)
		(layer "F.Cu")
		(net "UART_T5_NODE4_TXD")
	)
	(segment
		(start 89.051638 -170.943524)
		(end 88.732614 -170.6245)
		(width 0.1016)
		(layer "F.Cu")
		(net "UART_T5_NODE4_TXD")
	)
	(segment
		(start 88.732614 -170.6245)
		(end 87.744808 -170.6245)
		(width 0.1016)
		(layer "F.Cu")
		(net "UART_T5_NODE4_TXD")
	)
	(via
		(at 92.75064 -170.922188)
		(size 0.508)
		(drill 0.254)
		(layers "F.Cu" "B.Cu")
		(net "UART_T5_NODE4_TXD")
	)
	(via
		(at 90.88882 -182.545228)
		(size 0.508)
		(drill 0.254)
		(layers "F.Cu" "B.Cu")
		(net "UART_T5_NODE4_TXD")
	)
	(segment
		(start 90.91168 -183.05018)
		(end 91.502484 -183.640984)
		(width 0.1016)
		(layer "B.Cu")
		(net "UART_T5_NODE4_TXD")
	)
	(segment
		(start 91.502484 -183.640984)
		(end 91.502484 -183.778398)
		(width 0.1016)
		(layer "B.Cu")
		(net "UART_T5_NODE4_TXD")
	)
	(segment
		(start 90.91168 -182.568088)
		(end 90.91168 -183.05018)
		(width 0.1016)
		(layer "B.Cu")
		(net "UART_T5_NODE4_TXD")
	)
	(segment
		(start 90.88882 -182.545228)
		(end 90.91168 -182.568088)
		(width 0.1016)
		(layer "B.Cu")
		(net "UART_T5_NODE4_TXD")
	)
	(segment
		(start 92.75064 -171.300902)
		(end 92.29344 -171.758102)
		(width 0.1143)
		(layer "In7.Cu")
		(net "UART_T5_NODE4_TXD")
	)
	(segment
		(start 92.92336 -175.83785)
		(end 92.92336 -176.20107)
		(width 0.1143)
		(layer "In7.Cu")
		(net "UART_T5_NODE4_TXD")
	)
	(segment
		(start 91.851734 -177.000662)
		(end 90.88882 -177.963576)
		(width 0.1143)
		(layer "In7.Cu")
		(net "UART_T5_NODE4_TXD")
	)
	(segment
		(start 92.123768 -177.000662)
		(end 91.851734 -177.000662)
		(width 0.1143)
		(layer "In7.Cu")
		(net "UART_T5_NODE4_TXD")
	)
	(segment
		(start 92.29344 -171.761658)
		(end 91.20886 -172.846238)
		(width 0.1143)
		(layer "In7.Cu")
		(net "UART_T5_NODE4_TXD")
	)
	(segment
		(start 91.20886 -175.034702)
		(end 91.755468 -175.58131)
		(width 0.1143)
		(layer "In7.Cu")
		(net "UART_T5_NODE4_TXD")
	)
	(segment
		(start 92.75064 -170.922188)
		(end 92.75064 -171.300902)
		(width 0.1143)
		(layer "In7.Cu")
		(net "UART_T5_NODE4_TXD")
	)
	(segment
		(start 91.20886 -172.846238)
		(end 91.20886 -175.034702)
		(width 0.1143)
		(layer "In7.Cu")
		(net "UART_T5_NODE4_TXD")
	)
	(segment
		(start 90.88882 -177.963576)
		(end 90.88882 -182.545228)
		(width 0.1143)
		(layer "In7.Cu")
		(net "UART_T5_NODE4_TXD")
	)
	(segment
		(start 92.29344 -171.758102)
		(end 92.29344 -171.761658)
		(width 0.1143)
		(layer "In7.Cu")
		(net "UART_T5_NODE4_TXD")
	)
	(segment
		(start 92.92336 -176.20107)
		(end 92.123768 -177.000662)
		(width 0.1143)
		(layer "In7.Cu")
		(net "UART_T5_NODE4_TXD")
	)
	(segment
		(start 91.755468 -175.58131)
		(end 92.66682 -175.58131)
		(width 0.1143)
		(layer "In7.Cu")
		(net "UART_T5_NODE4_TXD")
	)
	(segment
		(start 92.66682 -175.58131)
		(end 92.92336 -175.83785)
		(width 0.1143)
		(layer "In7.Cu")
		(net "UART_T5_NODE4_TXD")
	)
	(segment
		(start 92.66174 -183.151272)
		(end 92.66174 -183.979058)
		(width 0.1016)
		(layer "F.Cu")
		(net "UART_T5_NODE4_RXD")
	)
	(segment
		(start 91.577668 -182.0672)
		(end 92.66174 -183.151272)
		(width 0.1016)
		(layer "F.Cu")
		(net "UART_T5_NODE4_RXD")
	)
	(segment
		(start 86.49462 -171.378626)
		(end 86.49462 -171.617132)
		(width 0.1016)
		(layer "F.Cu")
		(net "UART_T5_NODE4_RXD")
	)
	(segment
		(start 87.744808 -171.124626)
		(end 86.74862 -171.124626)
		(width 0.1016)
		(layer "F.Cu")
		(net "UART_T5_NODE4_RXD")
	)
	(segment
		(start 86.74862 -171.124626)
		(end 86.49462 -171.378626)
		(width 0.1016)
		(layer "F.Cu")
		(net "UART_T5_NODE4_RXD")
	)
	(segment
		(start 94.361254 -184.231788)
		(end 94.611444 -184.481978)
		(width 0.1016)
		(layer "F.Cu")
		(net "UART_T5_NODE4_RXD")
	)
	(segment
		(start 92.91447 -184.231788)
		(end 94.361254 -184.231788)
		(width 0.1016)
		(layer "F.Cu")
		(net "UART_T5_NODE4_RXD")
	)
	(segment
		(start 94.611444 -184.774586)
		(end 95.461836 -184.774586)
		(width 0.1016)
		(layer "F.Cu")
		(net "UART_T5_NODE4_RXD")
	)
	(segment
		(start 92.66174 -183.979058)
		(end 92.91447 -184.231788)
		(width 0.1016)
		(layer "F.Cu")
		(net "UART_T5_NODE4_RXD")
	)
	(segment
		(start 86.1822 -182.0672)
		(end 91.577668 -182.0672)
		(width 0.1016)
		(layer "F.Cu")
		(net "UART_T5_NODE4_RXD")
	)
	(segment
		(start 94.611444 -184.481978)
		(end 94.611444 -184.774586)
		(width 0.1016)
		(layer "F.Cu")
		(net "UART_T5_NODE4_RXD")
	)
	(via
		(at 95.461836 -184.774586)
		(size 0.508)
		(drill 0.254)
		(layers "F.Cu" "B.Cu")
		(net "UART_T5_NODE4_RXD")
	)
	(via
		(at 86.49462 -171.617132)
		(size 0.508)
		(drill 0.254)
		(layers "F.Cu" "B.Cu")
		(net "UART_T5_NODE4_RXD")
	)
	(via
		(at 86.1822 -182.0672)
		(size 0.508)
		(drill 0.254)
		(layers "F.Cu" "B.Cu")
		(net "UART_T5_NODE4_RXD")
	)
	(segment
		(start 94.611444 -185.790586)
		(end 94.611444 -185.624978)
		(width 0.1016)
		(layer "B.Cu")
		(net "UART_T5_NODE4_RXD")
	)
	(segment
		(start 94.611444 -185.624978)
		(end 95.461836 -184.774586)
		(width 0.1016)
		(layer "B.Cu")
		(net "UART_T5_NODE4_RXD")
	)
	(segment
		(start 86.49462 -172.262546)
		(end 86.49462 -171.617132)
		(width 0.1143)
		(layer "In7.Cu")
		(net "UART_T5_NODE4_RXD")
	)
	(segment
		(start 86.1822 -182.0672)
		(end 85.10016 -180.98516)
		(width 0.1143)
		(layer "In7.Cu")
		(net "UART_T5_NODE4_RXD")
	)
	(segment
		(start 85.10016 -180.98516)
		(end 85.10016 -180.170582)
		(width 0.1143)
		(layer "In7.Cu")
		(net "UART_T5_NODE4_RXD")
	)
	(segment
		(start 84.94903 -176.457356)
		(end 84.93379 -176.442116)
		(width 0.1143)
		(layer "In7.Cu")
		(net "UART_T5_NODE4_RXD")
	)
	(segment
		(start 85.10016 -180.170582)
		(end 84.94903 -180.019452)
		(width 0.1143)
		(layer "In7.Cu")
		(net "UART_T5_NODE4_RXD")
	)
	(segment
		(start 84.93379 -173.823376)
		(end 86.49462 -172.262546)
		(width 0.1143)
		(layer "In7.Cu")
		(net "UART_T5_NODE4_RXD")
	)
	(segment
		(start 84.94903 -180.019452)
		(end 84.94903 -176.457356)
		(width 0.1143)
		(layer "In7.Cu")
		(net "UART_T5_NODE4_RXD")
	)
	(segment
		(start 84.93379 -176.442116)
		(end 84.93379 -173.823376)
		(width 0.1143)
		(layer "In7.Cu")
		(net "UART_T5_NODE4_RXD")
	)
	(segment
		(start 89.231216 -168.624504)
		(end 89.33942 -168.5163)
		(width 0.1016)
		(layer "F.Cu")
		(net "UART_T5_NODE2_TXD")
	)
	(segment
		(start 87.744808 -168.624504)
		(end 89.231216 -168.624504)
		(width 0.1016)
		(layer "F.Cu")
		(net "UART_T5_NODE2_TXD")
	)
	(segment
		(start 90.41257 -168.434512)
		(end 89.421208 -168.434512)
		(width 0.1016)
		(layer "F.Cu")
		(net "UART_T5_NODE2_TXD")
	)
	(segment
		(start 89.421208 -168.434512)
		(end 89.33942 -168.5163)
		(width 0.1016)
		(layer "F.Cu")
		(net "UART_T5_NODE2_TXD")
	)
	(via
		(at 89.33942 -168.5163)
		(size 0.508)
		(drill 0.254)
		(layers "F.Cu" "B.Cu")
		(net "UART_T5_NODE2_TXD")
	)
	(segment
		(start 90.83294 -189.983364)
		(end 90.702384 -189.852808)
		(width 0.1016)
		(layer "F.Cu")
		(net "UART_T5_NODE1_RXD")
	)
	(segment
		(start 87.744808 -166.624508)
		(end 86.750906 -166.624508)
		(width 0.1016)
		(layer "F.Cu")
		(net "UART_T5_NODE1_RXD")
	)
	(segment
		(start 90.83294 -190.068708)
		(end 90.83294 -189.983364)
		(width 0.1016)
		(layer "F.Cu")
		(net "UART_T5_NODE1_RXD")
	)
	(segment
		(start 86.750906 -166.624508)
		(end 86.52002 -166.393622)
		(width 0.1016)
		(layer "F.Cu")
		(net "UART_T5_NODE1_RXD")
	)
	(segment
		(start 90.702384 -189.852808)
		(end 90.702384 -188.858398)
		(width 0.1016)
		(layer "F.Cu")
		(net "UART_T5_NODE1_RXD")
	)
	(via
		(at 86.52002 -166.393622)
		(size 0.508)
		(drill 0.254)
		(layers "F.Cu" "B.Cu")
		(net "UART_T5_NODE1_RXD")
	)
	(via
		(at 90.83294 -190.068708)
		(size 0.508)
		(drill 0.254)
		(layers "F.Cu" "B.Cu")
		(net "UART_T5_NODE1_RXD")
	)
	(segment
		(start 90.83294 -189.983364)
		(end 90.702384 -189.852808)
		(width 0.1016)
		(layer "B.Cu")
		(net "UART_T5_NODE1_RXD")
	)
	(segment
		(start 90.83294 -190.068708)
		(end 90.83294 -189.983364)
		(width 0.1016)
		(layer "B.Cu")
		(net "UART_T5_NODE1_RXD")
	)
	(segment
		(start 90.702384 -189.852808)
		(end 90.702384 -188.858398)
		(width 0.1016)
		(layer "B.Cu")
		(net "UART_T5_NODE1_RXD")
	)
	(segment
		(start 87.644224 -166.393622)
		(end 86.52002 -166.393622)
		(width 0.1143)
		(layer "In7.Cu")
		(net "UART_T5_NODE1_RXD")
	)
	(segment
		(start 87.74557 -184.225184)
		(end 87.74557 -183.628284)
		(width 0.1143)
		(layer "In7.Cu")
		(net "UART_T5_NODE1_RXD")
	)
	(segment
		(start 90.83294 -190.350648)
		(end 90.449146 -190.734442)
		(width 0.1143)
		(layer "In7.Cu")
		(net "UART_T5_NODE1_RXD")
	)
	(segment
		(start 89.784174 -190.734442)
		(end 86.35873 -187.308998)
		(width 0.1143)
		(layer "In7.Cu")
		(net "UART_T5_NODE1_RXD")
	)
	(segment
		(start 90.329258 -170.824652)
		(end 90.329258 -168.886378)
		(width 0.1143)
		(layer "In7.Cu")
		(net "UART_T5_NODE1_RXD")
	)
	(segment
		(start 88.60409 -180.701442)
		(end 88.60409 -172.54982)
		(width 0.1143)
		(layer "In7.Cu")
		(net "UART_T5_NODE1_RXD")
	)
	(segment
		(start 87.74557 -183.628284)
		(end 88.392 -182.981854)
		(width 0.1143)
		(layer "In7.Cu")
		(net "UART_T5_NODE1_RXD")
	)
	(segment
		(start 86.35873 -187.308998)
		(end 86.35873 -185.612024)
		(width 0.1143)
		(layer "In7.Cu")
		(net "UART_T5_NODE1_RXD")
	)
	(segment
		(start 88.392 -182.981854)
		(end 88.392 -181.89194)
		(width 0.1143)
		(layer "In7.Cu")
		(net "UART_T5_NODE1_RXD")
	)
	(segment
		(start 90.329258 -168.886378)
		(end 89.52103 -168.07815)
		(width 0.1143)
		(layer "In7.Cu")
		(net "UART_T5_NODE1_RXD")
	)
	(segment
		(start 88.60409 -172.54982)
		(end 90.329258 -170.824652)
		(width 0.1143)
		(layer "In7.Cu")
		(net "UART_T5_NODE1_RXD")
	)
	(segment
		(start 90.83294 -190.068708)
		(end 90.83294 -190.350648)
		(width 0.1143)
		(layer "In7.Cu")
		(net "UART_T5_NODE1_RXD")
	)
	(segment
		(start 88.392 -181.89194)
		(end 88.64854 -181.6354)
		(width 0.1143)
		(layer "In7.Cu")
		(net "UART_T5_NODE1_RXD")
	)
	(segment
		(start 88.64854 -180.745892)
		(end 88.60409 -180.701442)
		(width 0.1143)
		(layer "In7.Cu")
		(net "UART_T5_NODE1_RXD")
	)
	(segment
		(start 90.449146 -190.734442)
		(end 89.784174 -190.734442)
		(width 0.1143)
		(layer "In7.Cu")
		(net "UART_T5_NODE1_RXD")
	)
	(segment
		(start 88.64854 -181.6354)
		(end 88.64854 -180.745892)
		(width 0.1143)
		(layer "In7.Cu")
		(net "UART_T5_NODE1_RXD")
	)
	(segment
		(start 89.328752 -168.07815)
		(end 87.644224 -166.393622)
		(width 0.1143)
		(layer "In7.Cu")
		(net "UART_T5_NODE1_RXD")
	)
	(segment
		(start 86.35873 -185.612024)
		(end 87.74557 -184.225184)
		(width 0.1143)
		(layer "In7.Cu")
		(net "UART_T5_NODE1_RXD")
	)
	(segment
		(start 89.52103 -168.07815)
		(end 89.328752 -168.07815)
		(width 0.1143)
		(layer "In7.Cu")
		(net "UART_T5_NODE1_RXD")
	)
	(segment
		(start 87.744808 -165.256972)
		(end 87.744808 -166.124636)
		(width 0.1016)
		(layer "F.Cu")
		(net "UART_T5_NODE1_TXD")
	)
	(segment
		(start 87.893906 -165.107874)
		(end 87.744808 -165.256972)
		(width 0.1016)
		(layer "F.Cu")
		(net "UART_T5_NODE1_TXD")
	)
	(segment
		(start 87.53602 -163.171632)
		(end 87.53602 -164.282374)
		(width 0.1016)
		(layer "F.Cu")
		(net "UART_T5_NODE1_TXD")
	)
	(segment
		(start 88.51392 -162.193732)
		(end 87.53602 -163.171632)
		(width 0.1016)
		(layer "F.Cu")
		(net "UART_T5_NODE1_TXD")
	)
	(segment
		(start 87.893906 -164.64026)
		(end 87.893906 -165.107874)
		(width 0.1016)
		(layer "F.Cu")
		(net "UART_T5_NODE1_TXD")
	)
	(segment
		(start 87.53602 -164.282374)
		(end 87.893906 -164.64026)
		(width 0.1016)
		(layer "F.Cu")
		(net "UART_T5_NODE1_TXD")
	)
	(via
		(at 88.51392 -162.193732)
		(size 0.508)
		(drill 0.254)
		(layers "F.Cu" "B.Cu")
		(net "UART_T5_NODE1_TXD")
	)
	(segment
		(start 88.8746 -161.831528)
		(end 90.41257 -161.831528)
		(width 0.1016)
		(layer "B.Cu")
		(net "UART_T5_NODE1_TXD")
	)
	(segment
		(start 88.51392 -162.193732)
		(end 88.51392 -162.192208)
		(width 0.1016)
		(layer "B.Cu")
		(net "UART_T5_NODE1_TXD")
	)
	(segment
		(start 88.51392 -162.192208)
		(end 88.8746 -161.831528)
		(width 0.1016)
		(layer "B.Cu")
		(net "UART_T5_NODE1_TXD")
	)
	(segment
		(start 90.41257 -161.831528)
		(end 90.41257 -161.830512)
		(width 0.1016)
		(layer "B.Cu")
		(net "UART_T5_NODE1_TXD")
	)
	(segment
		(start 92.80652 -169.918888)
		(end 92.283534 -169.395902)
		(width 0.1016)
		(layer "F.Cu")
		(net "UART_T5_NODE2_RXD")
	)
	(segment
		(start 88.57742 -169.2529)
		(end 88.57742 -169.25163)
		(width 0.1016)
		(layer "F.Cu")
		(net "UART_T5_NODE2_RXD")
	)
	(segment
		(start 94.611444 -185.790586)
		(end 95.389192 -185.790586)
		(width 0.1016)
		(layer "F.Cu")
		(net "UART_T5_NODE2_RXD")
	)
	(segment
		(start 92.283534 -169.395902)
		(end 90.447368 -169.395902)
		(width 0.1016)
		(layer "F.Cu")
		(net "UART_T5_NODE2_RXD")
	)
	(segment
		(start 90.070178 -169.018712)
		(end 89.712038 -169.018712)
		(width 0.1016)
		(layer "F.Cu")
		(net "UART_T5_NODE2_RXD")
	)
	(segment
		(start 88.45042 -169.12463)
		(end 87.744808 -169.12463)
		(width 0.1016)
		(layer "F.Cu")
		(net "UART_T5_NODE2_RXD")
	)
	(segment
		(start 89.47785 -169.2529)
		(end 88.57742 -169.2529)
		(width 0.1016)
		(layer "F.Cu")
		(net "UART_T5_NODE2_RXD")
	)
	(segment
		(start 89.712038 -169.018712)
		(end 89.47785 -169.2529)
		(width 0.1016)
		(layer "F.Cu")
		(net "UART_T5_NODE2_RXD")
	)
	(segment
		(start 90.447368 -169.395902)
		(end 90.070178 -169.018712)
		(width 0.1016)
		(layer "F.Cu")
		(net "UART_T5_NODE2_RXD")
	)
	(segment
		(start 88.57742 -169.25163)
		(end 88.45042 -169.12463)
		(width 0.1016)
		(layer "F.Cu")
		(net "UART_T5_NODE2_RXD")
	)
	(via
		(at 92.80652 -169.918888)
		(size 0.508)
		(drill 0.254)
		(layers "F.Cu" "B.Cu")
		(net "UART_T5_NODE2_RXD")
	)
	(via
		(at 95.389192 -185.790586)
		(size 0.508)
		(drill 0.254)
		(layers "F.Cu" "B.Cu")
		(net "UART_T5_NODE2_RXD")
	)
	(segment
		(start 94.611444 -186.806586)
		(end 94.692978 -186.806586)
		(width 0.1016)
		(layer "B.Cu")
		(net "UART_T5_NODE2_RXD")
	)
	(segment
		(start 95.389192 -186.110372)
		(end 95.389192 -185.790586)
		(width 0.1016)
		(layer "B.Cu")
		(net "UART_T5_NODE2_RXD")
	)
	(segment
		(start 94.692978 -186.806586)
		(end 95.389192 -186.110372)
		(width 0.1016)
		(layer "B.Cu")
		(net "UART_T5_NODE2_RXD")
	)
	(segment
		(start 93.70568 -170.283378)
		(end 93.17101 -170.283378)
		(width 0.1143)
		(layer "In7.Cu")
		(net "UART_T5_NODE2_RXD")
	)
	(segment
		(start 93.17101 -170.283378)
		(end 92.80652 -169.918888)
		(width 0.1143)
		(layer "In7.Cu")
		(net "UART_T5_NODE2_RXD")
	)
	(segment
		(start 93.82506 -181.167024)
		(end 93.82506 -180.112924)
		(width 0.1143)
		(layer "In7.Cu")
		(net "UART_T5_NODE2_RXD")
	)
	(segment
		(start 94.97314 -185.374534)
		(end 94.97314 -182.315104)
		(width 0.1143)
		(layer "In7.Cu")
		(net "UART_T5_NODE2_RXD")
	)
	(segment
		(start 94.98838 -171.92371)
		(end 93.96222 -170.89755)
		(width 0.1143)
		(layer "In7.Cu")
		(net "UART_T5_NODE2_RXD")
	)
	(segment
		(start 94.98838 -178.949604)
		(end 94.98838 -171.92371)
		(width 0.1143)
		(layer "In7.Cu")
		(net "UART_T5_NODE2_RXD")
	)
	(segment
		(start 93.96222 -170.539918)
		(end 93.70568 -170.283378)
		(width 0.1143)
		(layer "In7.Cu")
		(net "UART_T5_NODE2_RXD")
	)
	(segment
		(start 93.96222 -170.89755)
		(end 93.96222 -170.539918)
		(width 0.1143)
		(layer "In7.Cu")
		(net "UART_T5_NODE2_RXD")
	)
	(segment
		(start 94.97314 -182.315104)
		(end 93.82506 -181.167024)
		(width 0.1143)
		(layer "In7.Cu")
		(net "UART_T5_NODE2_RXD")
	)
	(segment
		(start 93.82506 -180.112924)
		(end 94.98838 -178.949604)
		(width 0.1143)
		(layer "In7.Cu")
		(net "UART_T5_NODE2_RXD")
	)
	(segment
		(start 95.389192 -185.790586)
		(end 94.97314 -185.374534)
		(width 0.1143)
		(layer "In7.Cu")
		(net "UART_T5_NODE2_RXD")
	)
	(segment
		(start 170.170602 -9.855962)
		(end 170.176698 -9.862058)
		(width 0.1016)
		(layer "F.Cu")
		(net "JTAG_CPLD3_TDO")
	)
	(segment
		(start 131.430522 -181.182772)
		(end 131.08305 -180.8353)
		(width 0.1016)
		(layer "F.Cu")
		(net "JTAG_CPLD3_TDO")
	)
	(segment
		(start 131.08305 -180.8353)
		(end 131.08305 -180.062124)
		(width 0.1016)
		(layer "F.Cu")
		(net "JTAG_CPLD3_TDO")
	)
	(segment
		(start 131.525772 -179.619402)
		(end 131.525772 -178.858672)
		(width 0.1016)
		(layer "F.Cu")
		(net "JTAG_CPLD3_TDO")
	)
	(segment
		(start 170.176698 -9.862058)
		(end 170.176698 -12.074144)
		(width 0.1016)
		(layer "F.Cu")
		(net "JTAG_CPLD3_TDO")
	)
	(segment
		(start 131.430522 -182.120794)
		(end 131.430522 -181.182772)
		(width 0.1016)
		(layer "F.Cu")
		(net "JTAG_CPLD3_TDO")
	)
	(segment
		(start 131.08305 -180.062124)
		(end 131.525772 -179.619402)
		(width 0.1016)
		(layer "F.Cu")
		(net "JTAG_CPLD3_TDO")
	)
	(via
		(at 131.430522 -182.120794)
		(size 0.508)
		(drill 0.254)
		(layers "F.Cu" "B.Cu")
		(net "JTAG_CPLD3_TDO")
	)
	(via
		(at 167.02278 -185.525156)
		(size 0.508)
		(drill 0.254)
		(layers "F.Cu" "B.Cu")
		(net "JTAG_CPLD3_TDO")
	)
	(via
		(at 190.6778 -82.237834)
		(size 0.508)
		(drill 0.254)
		(layers "F.Cu" "B.Cu")
		(net "JTAG_CPLD3_TDO")
	)
	(segment
		(start 167.200326 -185.525156)
		(end 169.545 -183.180482)
		(width 0.1143)
		(layer "In2.Cu")
		(net "JTAG_CPLD3_TDO")
	)
	(segment
		(start 169.545 -183.180482)
		(end 169.545 -176.2506)
		(width 0.1143)
		(layer "In2.Cu")
		(net "JTAG_CPLD3_TDO")
	)
	(segment
		(start 170.7896 -173.397418)
		(end 173.59884 -170.588178)
		(width 0.1143)
		(layer "In2.Cu")
		(net "JTAG_CPLD3_TDO")
	)
	(segment
		(start 197.1548 -154.333702)
		(end 197.1548 -91.3892)
		(width 0.1143)
		(layer "In2.Cu")
		(net "JTAG_CPLD3_TDO")
	)
	(segment
		(start 167.02278 -185.525156)
		(end 167.200326 -185.525156)
		(width 0.1143)
		(layer "In2.Cu")
		(net "JTAG_CPLD3_TDO")
	)
	(segment
		(start 173.59884 -170.588178)
		(end 173.59884 -169.009314)
		(width 0.1143)
		(layer "In2.Cu")
		(net "JTAG_CPLD3_TDO")
	)
	(segment
		(start 170.7896 -175.006)
		(end 170.7896 -173.397418)
		(width 0.1143)
		(layer "In2.Cu")
		(net "JTAG_CPLD3_TDO")
	)
	(segment
		(start 173.59884 -169.009314)
		(end 175.547528 -167.060626)
		(width 0.1143)
		(layer "In2.Cu")
		(net "JTAG_CPLD3_TDO")
	)
	(segment
		(start 191.897 -87.0204)
		(end 190.6778 -85.8012)
		(width 0.1143)
		(layer "In2.Cu")
		(net "JTAG_CPLD3_TDO")
	)
	(segment
		(start 192.786 -87.0204)
		(end 191.897 -87.0204)
		(width 0.1143)
		(layer "In2.Cu")
		(net "JTAG_CPLD3_TDO")
	)
	(segment
		(start 175.547528 -167.060626)
		(end 184.427876 -167.060626)
		(width 0.1143)
		(layer "In2.Cu")
		(net "JTAG_CPLD3_TDO")
	)
	(segment
		(start 197.1548 -91.3892)
		(end 192.786 -87.0204)
		(width 0.1143)
		(layer "In2.Cu")
		(net "JTAG_CPLD3_TDO")
	)
	(segment
		(start 169.545 -176.2506)
		(end 170.7896 -175.006)
		(width 0.1143)
		(layer "In2.Cu")
		(net "JTAG_CPLD3_TDO")
	)
	(segment
		(start 190.6778 -85.8012)
		(end 190.6778 -82.237834)
		(width 0.1143)
		(layer "In2.Cu")
		(net "JTAG_CPLD3_TDO")
	)
	(segment
		(start 184.427876 -167.060626)
		(end 197.1548 -154.333702)
		(width 0.1143)
		(layer "In2.Cu")
		(net "JTAG_CPLD3_TDO")
	)
	(segment
		(start 161.5948 -185.928)
		(end 160.02 -185.928)
		(width 0.1143)
		(layer "In6.Cu")
		(net "JTAG_CPLD3_TDO")
	)
	(segment
		(start 167.02278 -185.525156)
		(end 161.997644 -185.525156)
		(width 0.1143)
		(layer "In6.Cu")
		(net "JTAG_CPLD3_TDO")
	)
	(segment
		(start 170.20794 -35.345878)
		(end 170.20794 -43.842686)
		(width 0.1143)
		(layer "In6.Cu")
		(net "JTAG_CPLD3_TDO")
	)
	(segment
		(start 188.608208 -82.614008)
		(end 190.301626 -82.614008)
		(width 0.1143)
		(layer "In6.Cu")
		(net "JTAG_CPLD3_TDO")
	)
	(segment
		(start 145.2626 -186.5376)
		(end 144.9324 -186.5376)
		(width 0.1143)
		(layer "In6.Cu")
		(net "JTAG_CPLD3_TDO")
	)
	(segment
		(start 145.8722 -185.928)
		(end 145.2626 -186.5376)
		(width 0.1143)
		(layer "In6.Cu")
		(net "JTAG_CPLD3_TDO")
	)
	(segment
		(start 147.5232 -186.182)
		(end 147.2692 -185.928)
		(width 0.1143)
		(layer "In6.Cu")
		(net "JTAG_CPLD3_TDO")
	)
	(segment
		(start 170.20794 -43.842686)
		(end 174.12081 -47.755556)
		(width 0.1143)
		(layer "In6.Cu")
		(net "JTAG_CPLD3_TDO")
	)
	(segment
		(start 159.766 -186.182)
		(end 147.5232 -186.182)
		(width 0.1143)
		(layer "In6.Cu")
		(net "JTAG_CPLD3_TDO")
	)
	(segment
		(start 135.59409 -185.928)
		(end 132.736844 -183.070754)
		(width 0.1143)
		(layer "In6.Cu")
		(net "JTAG_CPLD3_TDO")
	)
	(segment
		(start 174.12081 -47.755556)
		(end 174.12081 -68.12661)
		(width 0.1143)
		(layer "In6.Cu")
		(net "JTAG_CPLD3_TDO")
	)
	(segment
		(start 174.12081 -68.12661)
		(end 188.608208 -82.614008)
		(width 0.1143)
		(layer "In6.Cu")
		(net "JTAG_CPLD3_TDO")
	)
	(segment
		(start 132.380482 -183.070754)
		(end 131.430522 -182.120794)
		(width 0.1143)
		(layer "In6.Cu")
		(net "JTAG_CPLD3_TDO")
	)
	(segment
		(start 144.3228 -185.928)
		(end 135.59409 -185.928)
		(width 0.1143)
		(layer "In6.Cu")
		(net "JTAG_CPLD3_TDO")
	)
	(segment
		(start 170.170602 -9.855962)
		(end 169.164 -10.862564)
		(width 0.1143)
		(layer "In6.Cu")
		(net "JTAG_CPLD3_TDO")
	)
	(segment
		(start 147.2692 -185.928)
		(end 145.8722 -185.928)
		(width 0.1143)
		(layer "In6.Cu")
		(net "JTAG_CPLD3_TDO")
	)
	(segment
		(start 144.9324 -186.5376)
		(end 144.3228 -185.928)
		(width 0.1143)
		(layer "In6.Cu")
		(net "JTAG_CPLD3_TDO")
	)
	(segment
		(start 169.164 -34.301938)
		(end 170.20794 -35.345878)
		(width 0.1143)
		(layer "In6.Cu")
		(net "JTAG_CPLD3_TDO")
	)
	(segment
		(start 190.301626 -82.614008)
		(end 190.6778 -82.237834)
		(width 0.1143)
		(layer "In6.Cu")
		(net "JTAG_CPLD3_TDO")
	)
	(segment
		(start 132.736844 -183.070754)
		(end 132.380482 -183.070754)
		(width 0.1143)
		(layer "In6.Cu")
		(net "JTAG_CPLD3_TDO")
	)
	(segment
		(start 160.02 -185.928)
		(end 159.766 -186.182)
		(width 0.1143)
		(layer "In6.Cu")
		(net "JTAG_CPLD3_TDO")
	)
	(segment
		(start 161.997644 -185.525156)
		(end 161.5948 -185.928)
		(width 0.1143)
		(layer "In6.Cu")
		(net "JTAG_CPLD3_TDO")
	)
	(segment
		(start 169.164 -10.862564)
		(end 169.164 -34.301938)
		(width 0.1143)
		(layer "In6.Cu")
		(net "JTAG_CPLD3_TDO")
	)
	(segment
		(start 84.107274 -166.70528)
		(end 84.107274 -166.704264)
		(width 0.1016)
		(layer "F.Cu")
		(net "UART_T4_NODE2_TXD")
	)
	(segment
		(start 74.53376 -184.18048)
		(end 74.54392 -184.17032)
		(width 0.1016)
		(layer "F.Cu")
		(net "UART_T4_NODE2_TXD")
	)
	(segment
		(start 84.107274 -166.704264)
		(end 83.49488 -165.287706)
		(width 0.1016)
		(layer "F.Cu")
		(net "UART_T4_NODE2_TXD")
	)
	(segment
		(start 84.37626 -167.610282)
		(end 84.107274 -166.70528)
		(width 0.1016)
		(layer "F.Cu")
		(net "UART_T4_NODE2_TXD")
	)
	(segment
		(start 83.49488 -165.287706)
		(end 83.49488 -164.374576)
		(width 0.1016)
		(layer "F.Cu")
		(net "UART_T4_NODE2_TXD")
	)
	(segment
		(start 74.53376 -184.805574)
		(end 74.53376 -184.18048)
		(width 0.1016)
		(layer "F.Cu")
		(net "UART_T4_NODE2_TXD")
	)
	(via
		(at 84.37626 -167.610282)
		(size 0.508)
		(drill 0.254)
		(layers "F.Cu" "B.Cu")
		(net "UART_T4_NODE2_TXD")
	)
	(via
		(at 74.54392 -184.17032)
		(size 0.508)
		(drill 0.254)
		(layers "F.Cu" "B.Cu")
		(net "UART_T4_NODE2_TXD")
	)
	(segment
		(start 84.054696 -168.817798)
		(end 83.618324 -169.666412)
		(width 0.1143)
		(layer "In2.Cu")
		(net "UART_T4_NODE2_TXD")
	)
	(segment
		(start 83.618324 -169.666412)
		(end 83.36661 -169.918126)
		(width 0.1143)
		(layer "In2.Cu")
		(net "UART_T4_NODE2_TXD")
	)
	(segment
		(start 74.686922 -177.271426)
		(end 74.056494 -178.549554)
		(width 0.1143)
		(layer "In2.Cu")
		(net "UART_T4_NODE2_TXD")
	)
	(segment
		(start 74.05878 -182.412132)
		(end 74.05878 -182.818532)
		(width 0.1143)
		(layer "In2.Cu")
		(net "UART_T4_NODE2_TXD")
	)
	(segment
		(start 76.299568 -175.65878)
		(end 74.686922 -177.271426)
		(width 0.1143)
		(layer "In2.Cu")
		(net "UART_T4_NODE2_TXD")
	)
	(segment
		(start 84.37626 -167.610282)
		(end 84.37626 -167.988234)
		(width 0.1143)
		(layer "In2.Cu")
		(net "UART_T4_NODE2_TXD")
	)
	(segment
		(start 77.476858 -175.053752)
		(end 76.299568 -175.65878)
		(width 0.1143)
		(layer "In2.Cu")
		(net "UART_T4_NODE2_TXD")
	)
	(segment
		(start 74.432922 -180.798978)
		(end 74.432922 -181.42712)
		(width 0.1143)
		(layer "In2.Cu")
		(net "UART_T4_NODE2_TXD")
	)
	(segment
		(start 84.37626 -167.988234)
		(end 84.054696 -168.817798)
		(width 0.1143)
		(layer "In2.Cu")
		(net "UART_T4_NODE2_TXD")
	)
	(segment
		(start 82.888836 -170.221402)
		(end 79.881476 -172.996098)
		(width 0.1143)
		(layer "In2.Cu")
		(net "UART_T4_NODE2_TXD")
	)
	(segment
		(start 74.056494 -178.549554)
		(end 74.056494 -178.87315)
		(width 0.1143)
		(layer "In2.Cu")
		(net "UART_T4_NODE2_TXD")
	)
	(segment
		(start 74.432922 -181.42712)
		(end 74.05878 -182.412132)
		(width 0.1143)
		(layer "In2.Cu")
		(net "UART_T4_NODE2_TXD")
	)
	(segment
		(start 74.056494 -178.87315)
		(end 74.432922 -180.798978)
		(width 0.1143)
		(layer "In2.Cu")
		(net "UART_T4_NODE2_TXD")
	)
	(segment
		(start 74.05878 -182.818532)
		(end 74.54392 -184.17032)
		(width 0.1143)
		(layer "In2.Cu")
		(net "UART_T4_NODE2_TXD")
	)
	(segment
		(start 79.881476 -172.996098)
		(end 77.823822 -175.053752)
		(width 0.1143)
		(layer "In2.Cu")
		(net "UART_T4_NODE2_TXD")
	)
	(segment
		(start 83.36661 -169.918126)
		(end 82.888836 -170.221402)
		(width 0.1143)
		(layer "In2.Cu")
		(net "UART_T4_NODE2_TXD")
	)
	(segment
		(start 77.823822 -175.053752)
		(end 77.476858 -175.053752)
		(width 0.1143)
		(layer "In2.Cu")
		(net "UART_T4_NODE2_TXD")
	)
	(segment
		(start 113.64976 -176.9364)
		(end 113.64976 -177.0126)
		(width 0.1016)
		(layer "F.Cu")
		(net "N31348569")
	)
	(segment
		(start 113.64976 -178.613562)
		(end 113.64976 -177.0126)
		(width 0.1016)
		(layer "F.Cu")
		(net "N31348569")
	)
	(segment
		(start 114.759486 -175.826674)
		(end 113.64976 -176.9364)
		(width 0.1016)
		(layer "F.Cu")
		(net "N31348569")
	)
	(segment
		(start 114.79276 -175.826674)
		(end 114.759486 -175.826674)
		(width 0.1016)
		(layer "F.Cu")
		(net "N31348569")
	)
	(via
		(at 113.64976 -177.0126)
		(size 0.762)
		(drill 0.381)
		(layers "F.Cu" "B.Cu")
		(net "N31348569")
	)
	(segment
		(start 72.6059 -184.268364)
		(end 72.6059 -183.463692)
		(width 0.1016)
		(layer "F.Cu")
		(net "UART_T4_NODE3_TXD")
	)
	(segment
		(start 84.494878 -166.508684)
		(end 84.517738 -166.531544)
		(width 0.1016)
		(layer "F.Cu")
		(net "UART_T4_NODE3_TXD")
	)
	(segment
		(start 84.494878 -164.374576)
		(end 84.494878 -166.508684)
		(width 0.1016)
		(layer "F.Cu")
		(net "UART_T4_NODE3_TXD")
	)
	(segment
		(start 72.24776 -184.805574)
		(end 72.6059 -184.268364)
		(width 0.1016)
		(layer "F.Cu")
		(net "UART_T4_NODE3_TXD")
	)
	(segment
		(start 72.6059 -183.463692)
		(end 72.61352 -183.456072)
		(width 0.1016)
		(layer "F.Cu")
		(net "UART_T4_NODE3_TXD")
	)
	(via
		(at 72.61352 -183.456072)
		(size 0.508)
		(drill 0.254)
		(layers "F.Cu" "B.Cu")
		(net "UART_T4_NODE3_TXD")
	)
	(via
		(at 84.517738 -166.531544)
		(size 0.508)
		(drill 0.254)
		(layers "F.Cu" "B.Cu")
		(net "UART_T4_NODE3_TXD")
	)
	(segment
		(start 72.765158 -182.34533)
		(end 73.63079 -178.599592)
		(width 0.1143)
		(layer "In2.Cu")
		(net "UART_T4_NODE3_TXD")
	)
	(segment
		(start 73.63079 -178.599592)
		(end 74.287634 -177.198528)
		(width 0.1143)
		(layer "In2.Cu")
		(net "UART_T4_NODE3_TXD")
	)
	(segment
		(start 77.81417 -174.088044)
		(end 79.842868 -172.059346)
		(width 0.1143)
		(layer "In2.Cu")
		(net "UART_T4_NODE3_TXD")
	)
	(segment
		(start 74.287634 -177.198528)
		(end 77.398118 -174.088044)
		(width 0.1143)
		(layer "In2.Cu")
		(net "UART_T4_NODE3_TXD")
	)
	(segment
		(start 77.398118 -174.088044)
		(end 77.81417 -174.088044)
		(width 0.1143)
		(layer "In2.Cu")
		(net "UART_T4_NODE3_TXD")
	)
	(segment
		(start 81.395316 -169.468546)
		(end 83.124802 -167.73906)
		(width 0.1143)
		(layer "In2.Cu")
		(net "UART_T4_NODE3_TXD")
	)
	(segment
		(start 72.61352 -183.456072)
		(end 72.765158 -182.34533)
		(width 0.1143)
		(layer "In2.Cu")
		(net "UART_T4_NODE3_TXD")
	)
	(segment
		(start 83.124802 -167.73906)
		(end 84.094066 -167.184324)
		(width 0.1143)
		(layer "In2.Cu")
		(net "UART_T4_NODE3_TXD")
	)
	(segment
		(start 79.84236 -172.059346)
		(end 81.395316 -169.468546)
		(width 0.1143)
		(layer "In2.Cu")
		(net "UART_T4_NODE3_TXD")
	)
	(segment
		(start 84.094066 -167.184324)
		(end 84.517738 -166.531544)
		(width 0.1143)
		(layer "In2.Cu")
		(net "UART_T4_NODE3_TXD")
	)
	(segment
		(start 79.842868 -172.059346)
		(end 79.84236 -172.059346)
		(width 0.1143)
		(layer "In2.Cu")
		(net "UART_T4_NODE3_TXD")
	)
	(segment
		(start 84.99475 -163.730686)
		(end 84.99475 -164.374576)
		(width 0.1016)
		(layer "F.Cu")
		(net "UART_T4_NODE3_RXD")
	)
	(segment
		(start 73.39076 -185.605674)
		(end 73.39076 -186.498484)
		(width 0.1016)
		(layer "F.Cu")
		(net "UART_T4_NODE3_RXD")
	)
	(segment
		(start 73.36028 -187.696094)
		(end 73.39076 -187.726574)
		(width 0.1016)
		(layer "F.Cu")
		(net "UART_T4_NODE3_RXD")
	)
	(segment
		(start 84.50834 -163.244276)
		(end 84.99475 -163.730686)
		(width 0.1016)
		(layer "F.Cu")
		(net "UART_T4_NODE3_RXD")
	)
	(segment
		(start 73.36028 -186.747404)
		(end 73.36028 -187.696094)
		(width 0.1016)
		(layer "F.Cu")
		(net "UART_T4_NODE3_RXD")
	)
	(segment
		(start 73.25106 -186.638184)
		(end 73.36028 -186.747404)
		(width 0.1016)
		(layer "F.Cu")
		(net "UART_T4_NODE3_RXD")
	)
	(segment
		(start 73.39076 -186.498484)
		(end 73.25106 -186.638184)
		(width 0.1016)
		(layer "F.Cu")
		(net "UART_T4_NODE3_RXD")
	)
	(via
		(at 84.50834 -163.244276)
		(size 0.508)
		(drill 0.254)
		(layers "F.Cu" "B.Cu")
		(net "UART_T4_NODE3_RXD")
	)
	(via
		(at 73.25106 -186.638184)
		(size 0.508)
		(drill 0.254)
		(layers "F.Cu" "B.Cu")
		(net "UART_T4_NODE3_RXD")
	)
	(segment
		(start 81.3816 -176.44364)
		(end 81.3816 -166.387272)
		(width 0.1143)
		(layer "In7.Cu")
		(net "UART_T4_NODE3_RXD")
	)
	(segment
		(start 79.498698 -181.639972)
		(end 80.03794 -181.10073)
		(width 0.1143)
		(layer "In7.Cu")
		(net "UART_T4_NODE3_RXD")
	)
	(segment
		(start 78.80604 -182.317644)
		(end 78.80604 -182.090314)
		(width 0.1143)
		(layer "In7.Cu")
		(net "UART_T4_NODE3_RXD")
	)
	(segment
		(start 84.50834 -163.260532)
		(end 84.50834 -163.244276)
		(width 0.1143)
		(layer "In7.Cu")
		(net "UART_T4_NODE3_RXD")
	)
	(segment
		(start 79.256382 -181.639972)
		(end 79.498698 -181.639972)
		(width 0.1143)
		(layer "In7.Cu")
		(net "UART_T4_NODE3_RXD")
	)
	(segment
		(start 80.42148 -179.98567)
		(end 80.42148 -177.40376)
		(width 0.1143)
		(layer "In7.Cu")
		(net "UART_T4_NODE3_RXD")
	)
	(segment
		(start 81.3816 -166.387272)
		(end 84.50834 -163.260532)
		(width 0.1143)
		(layer "In7.Cu")
		(net "UART_T4_NODE3_RXD")
	)
	(segment
		(start 75.661266 -184.698132)
		(end 76.425552 -184.698132)
		(width 0.1143)
		(layer "In7.Cu")
		(net "UART_T4_NODE3_RXD")
	)
	(segment
		(start 78.80604 -182.090314)
		(end 79.256382 -181.639972)
		(width 0.1143)
		(layer "In7.Cu")
		(net "UART_T4_NODE3_RXD")
	)
	(segment
		(start 80.03794 -180.36921)
		(end 80.42148 -179.98567)
		(width 0.1143)
		(layer "In7.Cu")
		(net "UART_T4_NODE3_RXD")
	)
	(segment
		(start 73.480422 -186.408822)
		(end 73.950576 -186.408822)
		(width 0.1143)
		(layer "In7.Cu")
		(net "UART_T4_NODE3_RXD")
	)
	(segment
		(start 80.03794 -181.10073)
		(end 80.03794 -180.36921)
		(width 0.1143)
		(layer "In7.Cu")
		(net "UART_T4_NODE3_RXD")
	)
	(segment
		(start 76.425552 -184.698132)
		(end 78.80604 -182.317644)
		(width 0.1143)
		(layer "In7.Cu")
		(net "UART_T4_NODE3_RXD")
	)
	(segment
		(start 80.42148 -177.40376)
		(end 81.3816 -176.44364)
		(width 0.1143)
		(layer "In7.Cu")
		(net "UART_T4_NODE3_RXD")
	)
	(segment
		(start 73.950576 -186.408822)
		(end 75.661266 -184.698132)
		(width 0.1143)
		(layer "In7.Cu")
		(net "UART_T4_NODE3_RXD")
	)
	(segment
		(start 73.25106 -186.638184)
		(end 73.480422 -186.408822)
		(width 0.1143)
		(layer "In7.Cu")
		(net "UART_T4_NODE3_RXD")
	)
	(segment
		(start 82.494882 -162.97783)
		(end 82.8929 -162.579812)
		(width 0.1016)
		(layer "F.Cu")
		(net "UART_T4_NODE1_TXD")
	)
	(segment
		(start 82.8929 -162.579812)
		(end 82.8929 -162.297872)
		(width 0.1016)
		(layer "F.Cu")
		(net "UART_T4_NODE1_TXD")
	)
	(segment
		(start 82.537046 -162.297872)
		(end 82.379312 -162.455606)
		(width 0.1016)
		(layer "F.Cu")
		(net "UART_T4_NODE1_TXD")
	)
	(segment
		(start 82.8929 -162.297872)
		(end 82.537046 -162.297872)
		(width 0.1016)
		(layer "F.Cu")
		(net "UART_T4_NODE1_TXD")
	)
	(segment
		(start 82.379312 -162.455606)
		(end 82.190082 -162.455606)
		(width 0.1016)
		(layer "F.Cu")
		(net "UART_T4_NODE1_TXD")
	)
	(segment
		(start 82.494882 -164.374576)
		(end 82.494882 -162.97783)
		(width 0.1016)
		(layer "F.Cu")
		(net "UART_T4_NODE1_TXD")
	)
	(via
		(at 82.8929 -162.297872)
		(size 0.508)
		(drill 0.254)
		(layers "F.Cu" "B.Cu")
		(net "UART_T4_NODE1_TXD")
	)
	(segment
		(start 83.55965 -162.865816)
		(end 83.50123 -162.807396)
		(width 0.1016)
		(layer "F.Cu")
		(net "UART_T4_NODE1_RXD")
	)
	(segment
		(start 77.851 -186.57951)
		(end 78.06944 -186.36107)
		(width 0.1016)
		(layer "F.Cu")
		(net "UART_T4_NODE1_RXD")
	)
	(segment
		(start 82.994754 -163.544758)
		(end 82.994754 -164.374576)
		(width 0.1016)
		(layer "F.Cu")
		(net "UART_T4_NODE1_RXD")
	)
	(segment
		(start 78.02372 -185.666634)
		(end 77.96276 -185.605674)
		(width 0.1016)
		(layer "F.Cu")
		(net "UART_T4_NODE1_RXD")
	)
	(segment
		(start 78.06944 -186.36107)
		(end 78.02372 -186.31535)
		(width 0.1016)
		(layer "F.Cu")
		(net "UART_T4_NODE1_RXD")
	)
	(segment
		(start 84.23656 -162.776408)
		(end 84.147152 -162.865816)
		(width 0.1016)
		(layer "F.Cu")
		(net "UART_T4_NODE1_RXD")
	)
	(segment
		(start 83.13928 -162.807396)
		(end 82.888328 -163.058348)
		(width 0.1016)
		(layer "F.Cu")
		(net "UART_T4_NODE1_RXD")
	)
	(segment
		(start 85.338158 -162.776408)
		(end 84.23656 -162.776408)
		(width 0.1016)
		(layer "F.Cu")
		(net "UART_T4_NODE1_RXD")
	)
	(segment
		(start 77.78496 -187.548774)
		(end 77.78496 -186.87669)
		(width 0.1016)
		(layer "F.Cu")
		(net "UART_T4_NODE1_RXD")
	)
	(segment
		(start 83.50123 -162.807396)
		(end 83.13928 -162.807396)
		(width 0.1016)
		(layer "F.Cu")
		(net "UART_T4_NODE1_RXD")
	)
	(segment
		(start 77.78496 -186.87669)
		(end 77.851 -186.81065)
		(width 0.1016)
		(layer "F.Cu")
		(net "UART_T4_NODE1_RXD")
	)
	(segment
		(start 77.851 -186.81065)
		(end 77.851 -186.57951)
		(width 0.1016)
		(layer "F.Cu")
		(net "UART_T4_NODE1_RXD")
	)
	(segment
		(start 84.147152 -162.865816)
		(end 83.55965 -162.865816)
		(width 0.1016)
		(layer "F.Cu")
		(net "UART_T4_NODE1_RXD")
	)
	(segment
		(start 77.96276 -187.726574)
		(end 77.78496 -187.548774)
		(width 0.1016)
		(layer "F.Cu")
		(net "UART_T4_NODE1_RXD")
	)
	(segment
		(start 85.61578 -162.498786)
		(end 85.338158 -162.776408)
		(width 0.1016)
		(layer "F.Cu")
		(net "UART_T4_NODE1_RXD")
	)
	(segment
		(start 82.888328 -163.438332)
		(end 82.994754 -163.544758)
		(width 0.1016)
		(layer "F.Cu")
		(net "UART_T4_NODE1_RXD")
	)
	(segment
		(start 78.02372 -186.31535)
		(end 78.02372 -185.666634)
		(width 0.1016)
		(layer "F.Cu")
		(net "UART_T4_NODE1_RXD")
	)
	(segment
		(start 82.888328 -163.058348)
		(end 82.888328 -163.438332)
		(width 0.1016)
		(layer "F.Cu")
		(net "UART_T4_NODE1_RXD")
	)
	(segment
		(start 78.04912 -186.36107)
		(end 78.06944 -186.36107)
		(width 0.1016)
		(layer "F.Cu")
		(net "UART_T4_NODE1_RXD")
	)
	(via
		(at 78.04912 -186.36107)
		(size 0.508)
		(drill 0.254)
		(layers "F.Cu" "B.Cu")
		(net "UART_T4_NODE1_RXD")
	)
	(via
		(at 85.61578 -162.498786)
		(size 0.508)
		(drill 0.254)
		(layers "F.Cu" "B.Cu")
		(net "UART_T4_NODE1_RXD")
	)
	(segment
		(start 79.783178 -183.320436)
		(end 79.40929 -183.694324)
		(width 0.1143)
		(layer "In7.Cu")
		(net "UART_T4_NODE1_RXD")
	)
	(segment
		(start 79.40929 -183.694324)
		(end 79.40929 -184.764426)
		(width 0.1143)
		(layer "In7.Cu")
		(net "UART_T4_NODE1_RXD")
	)
	(segment
		(start 82.2071 -181.956964)
		(end 80.843628 -183.320436)
		(width 0.1143)
		(layer "In7.Cu")
		(net "UART_T4_NODE1_RXD")
	)
	(segment
		(start 84.18957 -168.506902)
		(end 84.18957 -169.105072)
		(width 0.1143)
		(layer "In7.Cu")
		(net "UART_T4_NODE1_RXD")
	)
	(segment
		(start 85.05698 -166.743888)
		(end 84.80679 -166.994078)
		(width 0.1143)
		(layer "In7.Cu")
		(net "UART_T4_NODE1_RXD")
	)
	(segment
		(start 83.08213 -172.49013)
		(end 83.08213 -179.354734)
		(width 0.1143)
		(layer "In7.Cu")
		(net "UART_T4_NODE1_RXD")
	)
	(segment
		(start 85.61578 -162.498786)
		(end 85.61578 -164.1094)
		(width 0.1143)
		(layer "In7.Cu")
		(net "UART_T4_NODE1_RXD")
	)
	(segment
		(start 84.81441 -167.882062)
		(end 84.18957 -168.506902)
		(width 0.1143)
		(layer "In7.Cu")
		(net "UART_T4_NODE1_RXD")
	)
	(segment
		(start 78.04912 -186.124596)
		(end 78.04912 -186.36107)
		(width 0.1143)
		(layer "In7.Cu")
		(net "UART_T4_NODE1_RXD")
	)
	(segment
		(start 82.336386 -170.958256)
		(end 82.336386 -171.744386)
		(width 0.1143)
		(layer "In7.Cu")
		(net "UART_T4_NODE1_RXD")
	)
	(segment
		(start 85.05698 -164.6682)
		(end 85.05698 -166.743888)
		(width 0.1143)
		(layer "In7.Cu")
		(net "UART_T4_NODE1_RXD")
	)
	(segment
		(start 84.18957 -169.105072)
		(end 82.336386 -170.958256)
		(width 0.1143)
		(layer "In7.Cu")
		(net "UART_T4_NODE1_RXD")
	)
	(segment
		(start 84.80679 -166.994078)
		(end 84.80679 -167.359838)
		(width 0.1143)
		(layer "In7.Cu")
		(net "UART_T4_NODE1_RXD")
	)
	(segment
		(start 83.08213 -179.354734)
		(end 82.2071 -180.229764)
		(width 0.1143)
		(layer "In7.Cu")
		(net "UART_T4_NODE1_RXD")
	)
	(segment
		(start 82.2071 -180.229764)
		(end 82.2071 -181.956964)
		(width 0.1143)
		(layer "In7.Cu")
		(net "UART_T4_NODE1_RXD")
	)
	(segment
		(start 80.843628 -183.320436)
		(end 79.783178 -183.320436)
		(width 0.1143)
		(layer "In7.Cu")
		(net "UART_T4_NODE1_RXD")
	)
	(segment
		(start 84.81441 -167.367458)
		(end 84.81441 -167.882062)
		(width 0.1143)
		(layer "In7.Cu")
		(net "UART_T4_NODE1_RXD")
	)
	(segment
		(start 85.61578 -164.1094)
		(end 85.05698 -164.6682)
		(width 0.1143)
		(layer "In7.Cu")
		(net "UART_T4_NODE1_RXD")
	)
	(segment
		(start 84.80679 -167.359838)
		(end 84.81441 -167.367458)
		(width 0.1143)
		(layer "In7.Cu")
		(net "UART_T4_NODE1_RXD")
	)
	(segment
		(start 82.336386 -171.744386)
		(end 83.08213 -172.49013)
		(width 0.1143)
		(layer "In7.Cu")
		(net "UART_T4_NODE1_RXD")
	)
	(segment
		(start 79.40929 -184.764426)
		(end 78.04912 -186.124596)
		(width 0.1143)
		(layer "In7.Cu")
		(net "UART_T4_NODE1_RXD")
	)
	(segment
		(start 75.84186 -186.351926)
		(end 76.16444 -186.674506)
		(width 0.1016)
		(layer "F.Cu")
		(net "UART_T4_NODE2_RXD")
	)
	(segment
		(start 83.994752 -163.563046)
		(end 83.994752 -164.374576)
		(width 0.1016)
		(layer "F.Cu")
		(net "UART_T4_NODE2_RXD")
	)
	(segment
		(start 75.67676 -185.605674)
		(end 75.67676 -186.186826)
		(width 0.1016)
		(layer "F.Cu")
		(net "UART_T4_NODE2_RXD")
	)
	(segment
		(start 76.16444 -187.247276)
		(end 75.91171 -187.500006)
		(width 0.1016)
		(layer "F.Cu")
		(net "UART_T4_NODE2_RXD")
	)
	(segment
		(start 83.670902 -163.239196)
		(end 83.994752 -163.563046)
		(width 0.1016)
		(layer "F.Cu")
		(net "UART_T4_NODE2_RXD")
	)
	(segment
		(start 75.67676 -186.186826)
		(end 75.84186 -186.351926)
		(width 0.1016)
		(layer "F.Cu")
		(net "UART_T4_NODE2_RXD")
	)
	(segment
		(start 75.91171 -187.500006)
		(end 75.903328 -187.500006)
		(width 0.1016)
		(layer "F.Cu")
		(net "UART_T4_NODE2_RXD")
	)
	(segment
		(start 75.903328 -187.500006)
		(end 75.67676 -187.726574)
		(width 0.1016)
		(layer "F.Cu")
		(net "UART_T4_NODE2_RXD")
	)
	(segment
		(start 83.320128 -163.239196)
		(end 83.670902 -163.239196)
		(width 0.1016)
		(layer "F.Cu")
		(net "UART_T4_NODE2_RXD")
	)
	(segment
		(start 76.16444 -186.674506)
		(end 76.16444 -187.247276)
		(width 0.1016)
		(layer "F.Cu")
		(net "UART_T4_NODE2_RXD")
	)
	(via
		(at 75.84186 -186.351926)
		(size 0.508)
		(drill 0.254)
		(layers "F.Cu" "B.Cu")
		(net "UART_T4_NODE2_RXD")
	)
	(via
		(at 83.320128 -163.239196)
		(size 0.508)
		(drill 0.254)
		(layers "F.Cu" "B.Cu")
		(net "UART_T4_NODE2_RXD")
	)
	(segment
		(start 84.94649 -163.062412)
		(end 84.654136 -162.770058)
		(width 0.1143)
		(layer "In7.Cu")
		(net "UART_T4_NODE2_RXD")
	)
	(segment
		(start 80.35544 -181.650894)
		(end 80.35544 -180.697632)
		(width 0.1143)
		(layer "In7.Cu")
		(net "UART_T4_NODE2_RXD")
	)
	(segment
		(start 84.654136 -162.770058)
		(end 84.221574 -162.770058)
		(width 0.1143)
		(layer "In7.Cu")
		(net "UART_T4_NODE2_RXD")
	)
	(segment
		(start 84.221574 -162.770058)
		(end 83.752436 -163.239196)
		(width 0.1143)
		(layer "In7.Cu")
		(net "UART_T4_NODE2_RXD")
	)
	(segment
		(start 79.722472 -182.284116)
		(end 80.35544 -181.650894)
		(width 0.1143)
		(layer "In7.Cu")
		(net "UART_T4_NODE2_RXD")
	)
	(segment
		(start 76.74737 -185.446416)
		(end 77.329792 -185.446416)
		(width 0.1143)
		(layer "In7.Cu")
		(net "UART_T4_NODE2_RXD")
	)
	(segment
		(start 81.6991 -166.674546)
		(end 84.94649 -163.427156)
		(width 0.1143)
		(layer "In7.Cu")
		(net "UART_T4_NODE2_RXD")
	)
	(segment
		(start 80.35544 -180.697632)
		(end 80.79994 -180.253132)
		(width 0.1143)
		(layer "In7.Cu")
		(net "UART_T4_NODE2_RXD")
	)
	(segment
		(start 79.722472 -182.481474)
		(end 79.722472 -182.284116)
		(width 0.1143)
		(layer "In7.Cu")
		(net "UART_T4_NODE2_RXD")
	)
	(segment
		(start 84.94649 -163.427156)
		(end 84.94649 -163.062412)
		(width 0.1143)
		(layer "In7.Cu")
		(net "UART_T4_NODE2_RXD")
	)
	(segment
		(start 83.752436 -163.239196)
		(end 83.320128 -163.239196)
		(width 0.1143)
		(layer "In7.Cu")
		(net "UART_T4_NODE2_RXD")
	)
	(segment
		(start 80.79994 -180.253132)
		(end 80.79994 -177.721006)
		(width 0.1143)
		(layer "In7.Cu")
		(net "UART_T4_NODE2_RXD")
	)
	(segment
		(start 78.63586 -183.568086)
		(end 79.722472 -182.481474)
		(width 0.1143)
		(layer "In7.Cu")
		(net "UART_T4_NODE2_RXD")
	)
	(segment
		(start 77.329792 -185.446416)
		(end 78.63586 -184.140348)
		(width 0.1143)
		(layer "In7.Cu")
		(net "UART_T4_NODE2_RXD")
	)
	(segment
		(start 78.63586 -184.140348)
		(end 78.63586 -183.568086)
		(width 0.1143)
		(layer "In7.Cu")
		(net "UART_T4_NODE2_RXD")
	)
	(segment
		(start 81.6991 -176.821846)
		(end 81.6991 -166.674546)
		(width 0.1143)
		(layer "In7.Cu")
		(net "UART_T4_NODE2_RXD")
	)
	(segment
		(start 80.79994 -177.721006)
		(end 81.6991 -176.821846)
		(width 0.1143)
		(layer "In7.Cu")
		(net "UART_T4_NODE2_RXD")
	)
	(segment
		(start 75.84186 -186.351926)
		(end 76.74737 -185.446416)
		(width 0.1143)
		(layer "In7.Cu")
		(net "UART_T4_NODE2_RXD")
	)
	(segment
		(start 85.49386 -165.33622)
		(end 85.494876 -165.33622)
		(width 0.1016)
		(layer "F.Cu")
		(net "UART_T4_NODE4_TXD")
	)
	(segment
		(start 85.24494 -166.80434)
		(end 85.49386 -166.55542)
		(width 0.1016)
		(layer "F.Cu")
		(net "UART_T4_NODE4_TXD")
	)
	(segment
		(start 69.96176 -184.805574)
		(end 69.96176 -183.535574)
		(width 0.1016)
		(layer "F.Cu")
		(net "UART_T4_NODE4_TXD")
	)
	(segment
		(start 85.49386 -166.55542)
		(end 85.49386 -165.33622)
		(width 0.1016)
		(layer "F.Cu")
		(net "UART_T4_NODE4_TXD")
	)
	(segment
		(start 69.96176 -183.535574)
		(end 70.07352 -183.423814)
		(width 0.1016)
		(layer "F.Cu")
		(net "UART_T4_NODE4_TXD")
	)
	(segment
		(start 85.24494 -167.176958)
		(end 85.24494 -166.80434)
		(width 0.1016)
		(layer "F.Cu")
		(net "UART_T4_NODE4_TXD")
	)
	(segment
		(start 85.494876 -165.33622)
		(end 85.494876 -164.374576)
		(width 0.1016)
		(layer "F.Cu")
		(net "UART_T4_NODE4_TXD")
	)
	(via
		(at 70.07352 -183.423814)
		(size 0.508)
		(drill 0.254)
		(layers "F.Cu" "B.Cu")
		(net "UART_T4_NODE4_TXD")
	)
	(via
		(at 85.24494 -167.176958)
		(size 0.508)
		(drill 0.254)
		(layers "F.Cu" "B.Cu")
		(net "UART_T4_NODE4_TXD")
	)
	(segment
		(start 75.256898 -174.427642)
		(end 71.38162 -178.30292)
		(width 0.1143)
		(layer "In2.Cu")
		(net "UART_T4_NODE4_TXD")
	)
	(segment
		(start 76.032614 -174.427642)
		(end 75.256898 -174.427642)
		(width 0.1143)
		(layer "In2.Cu")
		(net "UART_T4_NODE4_TXD")
	)
	(segment
		(start 71.38162 -182.12308)
		(end 70.080886 -183.423814)
		(width 0.1143)
		(layer "In2.Cu")
		(net "UART_T4_NODE4_TXD")
	)
	(segment
		(start 85.24494 -167.176958)
		(end 85.24494 -166.638986)
		(width 0.1143)
		(layer "In2.Cu")
		(net "UART_T4_NODE4_TXD")
	)
	(segment
		(start 78.265782 -172.952156)
		(end 77.5081 -172.952156)
		(width 0.1143)
		(layer "In2.Cu")
		(net "UART_T4_NODE4_TXD")
	)
	(segment
		(start 79.33182 -170.57624)
		(end 79.33182 -171.886118)
		(width 0.1143)
		(layer "In2.Cu")
		(net "UART_T4_NODE4_TXD")
	)
	(segment
		(start 70.080886 -183.423814)
		(end 70.07352 -183.423814)
		(width 0.1143)
		(layer "In2.Cu")
		(net "UART_T4_NODE4_TXD")
	)
	(segment
		(start 77.5081 -172.952156)
		(end 76.032614 -174.427642)
		(width 0.1143)
		(layer "In2.Cu")
		(net "UART_T4_NODE4_TXD")
	)
	(segment
		(start 85.24494 -166.638986)
		(end 84.699348 -166.093394)
		(width 0.1143)
		(layer "In2.Cu")
		(net "UART_T4_NODE4_TXD")
	)
	(segment
		(start 84.699348 -166.093394)
		(end 83.706462 -166.093394)
		(width 0.1143)
		(layer "In2.Cu")
		(net "UART_T4_NODE4_TXD")
	)
	(segment
		(start 83.06562 -166.734236)
		(end 83.06562 -166.84244)
		(width 0.1143)
		(layer "In2.Cu")
		(net "UART_T4_NODE4_TXD")
	)
	(segment
		(start 83.06562 -166.84244)
		(end 79.33182 -170.57624)
		(width 0.1143)
		(layer "In2.Cu")
		(net "UART_T4_NODE4_TXD")
	)
	(segment
		(start 71.38162 -178.30292)
		(end 71.38162 -182.12308)
		(width 0.1143)
		(layer "In2.Cu")
		(net "UART_T4_NODE4_TXD")
	)
	(segment
		(start 83.706462 -166.093394)
		(end 83.06562 -166.734236)
		(width 0.1143)
		(layer "In2.Cu")
		(net "UART_T4_NODE4_TXD")
	)
	(segment
		(start 79.33182 -171.886118)
		(end 78.265782 -172.952156)
		(width 0.1143)
		(layer "In2.Cu")
		(net "UART_T4_NODE4_TXD")
	)
	(segment
		(start 115.93576 -176.51603)
		(end 115.30076 -177.15103)
		(width 0.1016)
		(layer "F.Cu")
		(net "N31341801")
	)
	(segment
		(start 115.93576 -175.826674)
		(end 115.93576 -176.51603)
		(width 0.1016)
		(layer "F.Cu")
		(net "N31341801")
	)
	(segment
		(start 115.30076 -178.613562)
		(end 115.30076 -177.15103)
		(width 0.1016)
		(layer "F.Cu")
		(net "N31341801")
	)
	(via
		(at 115.30076 -177.15103)
		(size 0.762)
		(drill 0.381)
		(layers "F.Cu" "B.Cu")
		(net "N31341801")
	)
	(segment
		(start 71.10476 -186.57189)
		(end 71.10476 -185.605674)
		(width 0.1016)
		(layer "F.Cu")
		(net "UART_T4_NODE4_RXD")
	)
	(segment
		(start 71.10476 -187.726574)
		(end 71.10476 -186.70905)
		(width 0.1016)
		(layer "F.Cu")
		(net "UART_T4_NODE4_RXD")
	)
	(segment
		(start 71.10476 -186.70905)
		(end 71.17334 -186.64047)
		(width 0.1016)
		(layer "F.Cu")
		(net "UART_T4_NODE4_RXD")
	)
	(segment
		(start 71.17334 -186.64047)
		(end 71.10476 -186.57189)
		(width 0.1016)
		(layer "F.Cu")
		(net "UART_T4_NODE4_RXD")
	)
	(segment
		(start 86.529926 -163.786058)
		(end 85.994748 -164.321236)
		(width 0.1016)
		(layer "F.Cu")
		(net "UART_T4_NODE4_RXD")
	)
	(segment
		(start 85.994748 -164.321236)
		(end 85.994748 -164.374576)
		(width 0.1016)
		(layer "F.Cu")
		(net "UART_T4_NODE4_RXD")
	)
	(via
		(at 86.529926 -163.786058)
		(size 0.508)
		(drill 0.254)
		(layers "F.Cu" "B.Cu")
		(net "UART_T4_NODE4_RXD")
	)
	(via
		(at 71.17334 -186.64047)
		(size 0.508)
		(drill 0.254)
		(layers "F.Cu" "B.Cu")
		(net "UART_T4_NODE4_RXD")
	)
	(segment
		(start 72.147938 -185.665872)
		(end 73.744582 -185.665872)
		(width 0.1143)
		(layer "In7.Cu")
		(net "UART_T4_NODE4_RXD")
	)
	(segment
		(start 73.744582 -185.665872)
		(end 75.23734 -184.173114)
		(width 0.1143)
		(layer "In7.Cu")
		(net "UART_T4_NODE4_RXD")
	)
	(segment
		(start 75.23734 -183.811418)
		(end 77.147674 -181.901084)
		(width 0.1143)
		(layer "In7.Cu")
		(net "UART_T4_NODE4_RXD")
	)
	(segment
		(start 75.23734 -184.173114)
		(end 75.23734 -183.811418)
		(width 0.1143)
		(layer "In7.Cu")
		(net "UART_T4_NODE4_RXD")
	)
	(segment
		(start 86.0552 -162.318446)
		(end 86.0552 -162.602164)
		(width 0.1143)
		(layer "In7.Cu")
		(net "UART_T4_NODE4_RXD")
	)
	(segment
		(start 77.568552 -180.921152)
		(end 79.625444 -178.86426)
		(width 0.1143)
		(layer "In7.Cu")
		(net "UART_T4_NODE4_RXD")
	)
	(segment
		(start 79.74203 -178.86426)
		(end 80.10398 -178.50231)
		(width 0.1143)
		(layer "In7.Cu")
		(net "UART_T4_NODE4_RXD")
	)
	(segment
		(start 86.0552 -162.602164)
		(end 86.43366 -162.980624)
		(width 0.1143)
		(layer "In7.Cu")
		(net "UART_T4_NODE4_RXD")
	)
	(segment
		(start 77.573124 -181.290976)
		(end 77.568552 -181.286404)
		(width 0.1143)
		(layer "In7.Cu")
		(net "UART_T4_NODE4_RXD")
	)
	(segment
		(start 81.0641 -164.873686)
		(end 83.49234 -162.445446)
		(width 0.1143)
		(layer "In7.Cu")
		(net "UART_T4_NODE4_RXD")
	)
	(segment
		(start 86.43366 -162.980624)
		(end 86.43366 -163.689792)
		(width 0.1143)
		(layer "In7.Cu")
		(net "UART_T4_NODE4_RXD")
	)
	(segment
		(start 81.0641 -176.198022)
		(end 81.0641 -164.873686)
		(width 0.1143)
		(layer "In7.Cu")
		(net "UART_T4_NODE4_RXD")
	)
	(segment
		(start 71.17334 -186.64047)
		(end 72.147938 -185.665872)
		(width 0.1143)
		(layer "In7.Cu")
		(net "UART_T4_NODE4_RXD")
	)
	(segment
		(start 80.10398 -178.50231)
		(end 80.10398 -177.158142)
		(width 0.1143)
		(layer "In7.Cu")
		(net "UART_T4_NODE4_RXD")
	)
	(segment
		(start 77.568552 -181.286404)
		(end 77.568552 -180.921152)
		(width 0.1143)
		(layer "In7.Cu")
		(net "UART_T4_NODE4_RXD")
	)
	(segment
		(start 85.73262 -161.995866)
		(end 86.0552 -162.318446)
		(width 0.1143)
		(layer "In7.Cu")
		(net "UART_T4_NODE4_RXD")
	)
	(segment
		(start 83.75015 -161.995866)
		(end 85.73262 -161.995866)
		(width 0.1143)
		(layer "In7.Cu")
		(net "UART_T4_NODE4_RXD")
	)
	(segment
		(start 77.316584 -181.901084)
		(end 77.573124 -181.644544)
		(width 0.1143)
		(layer "In7.Cu")
		(net "UART_T4_NODE4_RXD")
	)
	(segment
		(start 77.147674 -181.901084)
		(end 77.316584 -181.901084)
		(width 0.1143)
		(layer "In7.Cu")
		(net "UART_T4_NODE4_RXD")
	)
	(segment
		(start 83.49234 -162.445446)
		(end 83.49234 -162.253676)
		(width 0.1143)
		(layer "In7.Cu")
		(net "UART_T4_NODE4_RXD")
	)
	(segment
		(start 79.625444 -178.86426)
		(end 79.74203 -178.86426)
		(width 0.1143)
		(layer "In7.Cu")
		(net "UART_T4_NODE4_RXD")
	)
	(segment
		(start 83.49234 -162.253676)
		(end 83.75015 -161.995866)
		(width 0.1143)
		(layer "In7.Cu")
		(net "UART_T4_NODE4_RXD")
	)
	(segment
		(start 86.43366 -163.689792)
		(end 86.529926 -163.786058)
		(width 0.1143)
		(layer "In7.Cu")
		(net "UART_T4_NODE4_RXD")
	)
	(segment
		(start 77.573124 -181.644544)
		(end 77.573124 -181.290976)
		(width 0.1143)
		(layer "In7.Cu")
		(net "UART_T4_NODE4_RXD")
	)
	(segment
		(start 80.10398 -177.158142)
		(end 81.0641 -176.198022)
		(width 0.1143)
		(layer "In7.Cu")
		(net "UART_T4_NODE4_RXD")
	)
	(segment
		(start 135.37057 -26.969466)
		(end 135.37057 -27.601926)
		(width 0.1016)
		(layer "F.Cu")
		(net "UART_RTS_P6_N")
	)
	(segment
		(start 135.37057 -27.601926)
		(end 134.761732 -28.210764)
		(width 0.1016)
		(layer "F.Cu")
		(net "UART_RTS_P6_N")
	)
	(segment
		(start 3.240532 -144.871694)
		(end 4.114292 -143.997934)
		(width 0.1016)
		(layer "F.Cu")
		(net "UART_RTS_P6_N")
	)
	(segment
		(start 134.761732 -28.210764)
		(end 134.761732 -30.079696)
		(width 0.1016)
		(layer "F.Cu")
		(net "UART_RTS_P6_N")
	)
	(segment
		(start 3.240532 -148.392642)
		(end 3.240532 -144.871694)
		(width 0.1016)
		(layer "F.Cu")
		(net "UART_RTS_P6_N")
	)
	(segment
		(start 4.114292 -143.997934)
		(end 4.1148 -143.997934)
		(width 0.1016)
		(layer "F.Cu")
		(net "UART_RTS_P6_N")
	)
	(via
		(at 4.1148 -143.997934)
		(size 0.508)
		(drill 0.254)
		(layers "F.Cu" "B.Cu")
		(net "UART_RTS_P6_N")
	)
	(via
		(at 35.6489 -20.662138)
		(size 0.508)
		(drill 0.254)
		(layers "F.Cu" "B.Cu")
		(net "UART_RTS_P6_N")
	)
	(via
		(at 135.37057 -27.601926)
		(size 0.508)
		(drill 0.254)
		(layers "F.Cu" "B.Cu")
		(net "UART_RTS_P6_N")
	)
	(segment
		(start 35.6489 -20.662138)
		(end 35.6489 -21.281136)
		(width 0.1143)
		(layer "In2.Cu")
		(net "UART_RTS_P6_N")
	)
	(segment
		(start 4.064 -143.947134)
		(end 4.1148 -143.997934)
		(width 0.1143)
		(layer "In2.Cu")
		(net "UART_RTS_P6_N")
	)
	(segment
		(start 21.03882 -50.816256)
		(end 21.03882 -54.649624)
		(width 0.1143)
		(layer "In2.Cu")
		(net "UART_RTS_P6_N")
	)
	(segment
		(start 35.6489 -21.281136)
		(end 34.08426 -23.650702)
		(width 0.1143)
		(layer "In2.Cu")
		(net "UART_RTS_P6_N")
	)
	(segment
		(start 4.064 -102.401878)
		(end 4.064 -143.947134)
		(width 0.1143)
		(layer "In2.Cu")
		(net "UART_RTS_P6_N")
	)
	(segment
		(start 20.07616 -55.612284)
		(end 20.07616 -57.076848)
		(width 0.1143)
		(layer "In2.Cu")
		(net "UART_RTS_P6_N")
	)
	(segment
		(start 21.724112 -44.571158)
		(end 21.724112 -50.130964)
		(width 0.1143)
		(layer "In2.Cu")
		(net "UART_RTS_P6_N")
	)
	(segment
		(start 34.08426 -23.650702)
		(end 34.08426 -26.412698)
		(width 0.1143)
		(layer "In2.Cu")
		(net "UART_RTS_P6_N")
	)
	(segment
		(start 22.42058 -43.87469)
		(end 21.724112 -44.571158)
		(width 0.1143)
		(layer "In2.Cu")
		(net "UART_RTS_P6_N")
	)
	(segment
		(start 18.95094 -58.203084)
		(end 18.95094 -67.782948)
		(width 0.1143)
		(layer "In2.Cu")
		(net "UART_RTS_P6_N")
	)
	(segment
		(start 16.3576 -85.885274)
		(end 16.3576 -90.108278)
		(width 0.1143)
		(layer "In2.Cu")
		(net "UART_RTS_P6_N")
	)
	(segment
		(start 20.45716 -81.785714)
		(end 16.3576 -85.885274)
		(width 0.1143)
		(layer "In2.Cu")
		(net "UART_RTS_P6_N")
	)
	(segment
		(start 20.07616 -57.076848)
		(end 18.95094 -58.203084)
		(width 0.1143)
		(layer "In2.Cu")
		(net "UART_RTS_P6_N")
	)
	(segment
		(start 25.781 -34.715958)
		(end 25.781 -38.491414)
		(width 0.1143)
		(layer "In2.Cu")
		(net "UART_RTS_P6_N")
	)
	(segment
		(start 34.08426 -26.412698)
		(end 25.781 -34.715958)
		(width 0.1143)
		(layer "In2.Cu")
		(net "UART_RTS_P6_N")
	)
	(segment
		(start 18.95094 -67.782948)
		(end 20.662392 -69.4944)
		(width 0.1143)
		(layer "In2.Cu")
		(net "UART_RTS_P6_N")
	)
	(segment
		(start 21.724112 -50.130964)
		(end 21.03882 -50.816256)
		(width 0.1143)
		(layer "In2.Cu")
		(net "UART_RTS_P6_N")
	)
	(segment
		(start 25.781 -38.491414)
		(end 22.42058 -41.851834)
		(width 0.1143)
		(layer "In2.Cu")
		(net "UART_RTS_P6_N")
	)
	(segment
		(start 22.42058 -41.851834)
		(end 22.42058 -43.87469)
		(width 0.1143)
		(layer "In2.Cu")
		(net "UART_RTS_P6_N")
	)
	(segment
		(start 21.03882 -54.649624)
		(end 20.07616 -55.612284)
		(width 0.1143)
		(layer "In2.Cu")
		(net "UART_RTS_P6_N")
	)
	(segment
		(start 20.662392 -72.05599)
		(end 20.45716 -72.261222)
		(width 0.1143)
		(layer "In2.Cu")
		(net "UART_RTS_P6_N")
	)
	(segment
		(start 20.662392 -69.4944)
		(end 20.662392 -72.05599)
		(width 0.1143)
		(layer "In2.Cu")
		(net "UART_RTS_P6_N")
	)
	(segment
		(start 20.45716 -72.261222)
		(end 20.45716 -81.785714)
		(width 0.1143)
		(layer "In2.Cu")
		(net "UART_RTS_P6_N")
	)
	(segment
		(start 16.3576 -90.108278)
		(end 4.064 -102.401878)
		(width 0.1143)
		(layer "In2.Cu")
		(net "UART_RTS_P6_N")
	)
	(segment
		(start 111.7981 -25.215342)
		(end 115.801648 -29.21889)
		(width 0.1143)
		(layer "In6.Cu")
		(net "UART_RTS_P6_N")
	)
	(segment
		(start 101.97338 -17.544796)
		(end 105.535222 -17.544796)
		(width 0.1143)
		(layer "In6.Cu")
		(net "UART_RTS_P6_N")
	)
	(segment
		(start 35.6489 -20.662138)
		(end 36.857686 -19.453352)
		(width 0.1143)
		(layer "In6.Cu")
		(net "UART_RTS_P6_N")
	)
	(segment
		(start 38.222682 -19.453352)
		(end 39.143432 -18.532602)
		(width 0.1143)
		(layer "In6.Cu")
		(net "UART_RTS_P6_N")
	)
	(segment
		(start 40.326564 -18.532602)
		(end 40.582342 -18.78838)
		(width 0.1143)
		(layer "In6.Cu")
		(net "UART_RTS_P6_N")
	)
	(segment
		(start 63.792354 -18.78838)
		(end 67.10426 -17.544796)
		(width 0.1143)
		(layer "In6.Cu")
		(net "UART_RTS_P6_N")
	)
	(segment
		(start 101.655372 -17.226788)
		(end 101.97338 -17.544796)
		(width 0.1143)
		(layer "In6.Cu")
		(net "UART_RTS_P6_N")
	)
	(segment
		(start 132.94741 -29.21889)
		(end 134.564374 -27.601926)
		(width 0.1143)
		(layer "In6.Cu")
		(net "UART_RTS_P6_N")
	)
	(segment
		(start 100.414582 -17.226788)
		(end 101.655372 -17.226788)
		(width 0.1143)
		(layer "In6.Cu")
		(net "UART_RTS_P6_N")
	)
	(segment
		(start 36.857686 -19.453352)
		(end 38.222682 -19.453352)
		(width 0.1143)
		(layer "In6.Cu")
		(net "UART_RTS_P6_N")
	)
	(segment
		(start 111.7981 -23.807674)
		(end 111.7981 -25.215342)
		(width 0.1143)
		(layer "In6.Cu")
		(net "UART_RTS_P6_N")
	)
	(segment
		(start 40.582342 -18.78838)
		(end 63.792354 -18.78838)
		(width 0.1143)
		(layer "In6.Cu")
		(net "UART_RTS_P6_N")
	)
	(segment
		(start 105.535222 -17.544796)
		(end 111.7981 -23.807674)
		(width 0.1143)
		(layer "In6.Cu")
		(net "UART_RTS_P6_N")
	)
	(segment
		(start 134.564374 -27.601926)
		(end 135.37057 -27.601926)
		(width 0.1143)
		(layer "In6.Cu")
		(net "UART_RTS_P6_N")
	)
	(segment
		(start 115.801648 -29.21889)
		(end 132.94741 -29.21889)
		(width 0.1143)
		(layer "In6.Cu")
		(net "UART_RTS_P6_N")
	)
	(segment
		(start 67.10426 -17.544796)
		(end 100.096574 -17.544796)
		(width 0.1143)
		(layer "In6.Cu")
		(net "UART_RTS_P6_N")
	)
	(segment
		(start 100.096574 -17.544796)
		(end 100.414582 -17.226788)
		(width 0.1143)
		(layer "In6.Cu")
		(net "UART_RTS_P6_N")
	)
	(segment
		(start 39.143432 -18.532602)
		(end 40.326564 -18.532602)
		(width 0.1143)
		(layer "In6.Cu")
		(net "UART_RTS_P6_N")
	)
	(segment
		(start 129.54 -44.069)
		(end 129.54 -45.054266)
		(width 0.1016)
		(layer "F.Cu")
		(net "UART_DTR_P6_N")
	)
	(segment
		(start 4.540504 -148.392642)
		(end 4.540504 -146.919188)
		(width 0.1016)
		(layer "F.Cu")
		(net "UART_DTR_P6_N")
	)
	(segment
		(start 129.261616 -45.33265)
		(end 129.261616 -47.199804)
		(width 0.1016)
		(layer "F.Cu")
		(net "UART_DTR_P6_N")
	)
	(segment
		(start 129.54 -45.054266)
		(end 129.261616 -45.33265)
		(width 0.1016)
		(layer "F.Cu")
		(net "UART_DTR_P6_N")
	)
	(via
		(at 4.540504 -146.919188)
		(size 0.508)
		(drill 0.254)
		(layers "F.Cu" "B.Cu")
		(net "UART_DTR_P6_N")
	)
	(via
		(at 129.54 -44.069)
		(size 0.508)
		(drill 0.254)
		(layers "F.Cu" "B.Cu")
		(net "UART_DTR_P6_N")
	)
	(segment
		(start 22.774402 -56.144414)
		(end 22.75078 -56.210454)
		(width 0.1143)
		(layer "In2.Cu")
		(net "UART_DTR_P6_N")
	)
	(segment
		(start 132.8674 -28.412186)
		(end 132.8674 -23.334218)
		(width 0.1143)
		(layer "In2.Cu")
		(net "UART_DTR_P6_N")
	)
	(segment
		(start 12.510516 -95.950278)
		(end 10.64768 -97.813114)
		(width 0.1143)
		(layer "In2.Cu")
		(net "UART_DTR_P6_N")
	)
	(segment
		(start 66.22034 -16.484854)
		(end 65.24498 -16.484854)
		(width 0.1143)
		(layer "In2.Cu")
		(net "UART_DTR_P6_N")
	)
	(segment
		(start 130.429 -34.29)
		(end 132.461 -32.258)
		(width 0.1143)
		(layer "In2.Cu")
		(net "UART_DTR_P6_N")
	)
	(segment
		(start 5.73278 -103.02494)
		(end 5.73278 -141.987524)
		(width 0.1143)
		(layer "In2.Cu")
		(net "UART_DTR_P6_N")
	)
	(segment
		(start 22.62632 -81.958434)
		(end 17.8816 -86.703154)
		(width 0.1143)
		(layer "In2.Cu")
		(net "UART_DTR_P6_N")
	)
	(segment
		(start 22.839172 -56.07939)
		(end 22.774402 -56.144414)
		(width 0.1143)
		(layer "In2.Cu")
		(net "UART_DTR_P6_N")
	)
	(segment
		(start 64.366648 -17.363186)
		(end 57.497218 -17.363186)
		(width 0.1143)
		(layer "In2.Cu")
		(net "UART_DTR_P6_N")
	)
	(segment
		(start 4.37769 -144.956784)
		(end 4.37769 -146.756374)
		(width 0.1143)
		(layer "In2.Cu")
		(net "UART_DTR_P6_N")
	)
	(segment
		(start 87.671148 -11.999722)
		(end 87.554308 -12.115546)
		(width 0.1143)
		(layer "In2.Cu")
		(net "UART_DTR_P6_N")
	)
	(segment
		(start 87.522304 -12.146534)
		(end 80.2894 -14.894814)
		(width 0.1143)
		(layer "In2.Cu")
		(net "UART_DTR_P6_N")
	)
	(segment
		(start 67.81038 -14.894814)
		(end 66.22034 -16.484854)
		(width 0.1143)
		(layer "In2.Cu")
		(net "UART_DTR_P6_N")
	)
	(segment
		(start 21.64334 -60.296552)
		(end 21.527516 -60.412376)
		(width 0.1143)
		(layer "In2.Cu")
		(net "UART_DTR_P6_N")
	)
	(segment
		(start 132.8674 -23.334218)
		(end 123.745244 -14.212062)
		(width 0.1143)
		(layer "In2.Cu")
		(net "UART_DTR_P6_N")
	)
	(segment
		(start 133.096 -29.337)
		(end 133.096 -28.640786)
		(width 0.1143)
		(layer "In2.Cu")
		(net "UART_DTR_P6_N")
	)
	(segment
		(start 90.73388 -12.170156)
		(end 90.3605 -11.796776)
		(width 0.1143)
		(layer "In2.Cu")
		(net "UART_DTR_P6_N")
	)
	(segment
		(start 132.461 -32.258)
		(end 132.461 -29.972)
		(width 0.1143)
		(layer "In2.Cu")
		(net "UART_DTR_P6_N")
	)
	(segment
		(start 37.40658 -21.022818)
		(end 35.55746 -23.821136)
		(width 0.1143)
		(layer "In2.Cu")
		(net "UART_DTR_P6_N")
	)
	(segment
		(start 80.2894 -14.894814)
		(end 67.81038 -14.894814)
		(width 0.1143)
		(layer "In2.Cu")
		(net "UART_DTR_P6_N")
	)
	(segment
		(start 22.2758 -65.064132)
		(end 22.2758 -66.005964)
		(width 0.1143)
		(layer "In2.Cu")
		(net "UART_DTR_P6_N")
	)
	(segment
		(start 107.352084 -12.20216)
		(end 107.32008 -12.170156)
		(width 0.1143)
		(layer "In2.Cu")
		(net "UART_DTR_P6_N")
	)
	(segment
		(start 17.8816 -86.703154)
		(end 17.8816 -91.95435)
		(width 0.1143)
		(layer "In2.Cu")
		(net "UART_DTR_P6_N")
	)
	(segment
		(start 13.885672 -95.950278)
		(end 12.510516 -95.950278)
		(width 0.1143)
		(layer "In2.Cu")
		(net "UART_DTR_P6_N")
	)
	(segment
		(start 112.246918 -13.46454)
		(end 107.352084 -12.20216)
		(width 0.1143)
		(layer "In2.Cu")
		(net "UART_DTR_P6_N")
	)
	(segment
		(start 22.75078 -56.210454)
		(end 22.6695 -56.249062)
		(width 0.1143)
		(layer "In2.Cu")
		(net "UART_DTR_P6_N")
	)
	(segment
		(start 132.461 -29.972)
		(end 133.096 -29.337)
		(width 0.1143)
		(layer "In2.Cu")
		(net "UART_DTR_P6_N")
	)
	(segment
		(start 21.64334 -57.275222)
		(end 21.64334 -60.296552)
		(width 0.1143)
		(layer "In2.Cu")
		(net "UART_DTR_P6_N")
	)
	(segment
		(start 5.73278 -141.987524)
		(end 5.62737 -142.092934)
		(width 0.1143)
		(layer "In2.Cu")
		(net "UART_DTR_P6_N")
	)
	(segment
		(start 53.64988 -19.411442)
		(end 40.649652 -19.411442)
		(width 0.1143)
		(layer "In2.Cu")
		(net "UART_DTR_P6_N")
	)
	(segment
		(start 123.745244 -14.212062)
		(end 119.278908 -14.212062)
		(width 0.1143)
		(layer "In2.Cu")
		(net "UART_DTR_P6_N")
	)
	(segment
		(start 24.00046 -52.688998)
		(end 23.779988 -53.31079)
		(width 0.1143)
		(layer "In2.Cu")
		(net "UART_DTR_P6_N")
	)
	(segment
		(start 87.553292 -12.116054)
		(end 87.522304 -12.146534)
		(width 0.1143)
		(layer "In2.Cu")
		(net "UART_DTR_P6_N")
	)
	(segment
		(start 27.36596 -35.481768)
		(end 27.36596 -38.979348)
		(width 0.1143)
		(layer "In2.Cu")
		(net "UART_DTR_P6_N")
	)
	(segment
		(start 22.62632 -66.356484)
		(end 22.62632 -81.958434)
		(width 0.1143)
		(layer "In2.Cu")
		(net "UART_DTR_P6_N")
	)
	(segment
		(start 27.36596 -38.979348)
		(end 24.00046 -42.344848)
		(width 0.1143)
		(layer "In2.Cu")
		(net "UART_DTR_P6_N")
	)
	(segment
		(start 129.54 -42.164)
		(end 130.429 -41.275)
		(width 0.1143)
		(layer "In2.Cu")
		(net "UART_DTR_P6_N")
	)
	(segment
		(start 10.64768 -98.11004)
		(end 5.73278 -103.02494)
		(width 0.1143)
		(layer "In2.Cu")
		(net "UART_DTR_P6_N")
	)
	(segment
		(start 35.55746 -23.821136)
		(end 35.55746 -27.290268)
		(width 0.1143)
		(layer "In2.Cu")
		(net "UART_DTR_P6_N")
	)
	(segment
		(start 21.527516 -64.315848)
		(end 22.2758 -65.064132)
		(width 0.1143)
		(layer "In2.Cu")
		(net "UART_DTR_P6_N")
	)
	(segment
		(start 24.00046 -42.344848)
		(end 24.00046 -52.688998)
		(width 0.1143)
		(layer "In2.Cu")
		(net "UART_DTR_P6_N")
	)
	(segment
		(start 55.849012 -17.858994)
		(end 53.64988 -19.411442)
		(width 0.1143)
		(layer "In2.Cu")
		(net "UART_DTR_P6_N")
	)
	(segment
		(start 118.531386 -13.46454)
		(end 112.246918 -13.46454)
		(width 0.1143)
		(layer "In2.Cu")
		(net "UART_DTR_P6_N")
	)
	(segment
		(start 17.8816 -91.95435)
		(end 13.885672 -95.950278)
		(width 0.1143)
		(layer "In2.Cu")
		(net "UART_DTR_P6_N")
	)
	(segment
		(start 35.55746 -27.290268)
		(end 27.36596 -35.481768)
		(width 0.1143)
		(layer "In2.Cu")
		(net "UART_DTR_P6_N")
	)
	(segment
		(start 40.10152 -19.958558)
		(end 38.47084 -19.958558)
		(width 0.1143)
		(layer "In2.Cu")
		(net "UART_DTR_P6_N")
	)
	(segment
		(start 129.54 -44.069)
		(end 129.54 -42.164)
		(width 0.1143)
		(layer "In2.Cu")
		(net "UART_DTR_P6_N")
	)
	(segment
		(start 4.37769 -146.756374)
		(end 4.540504 -146.919188)
		(width 0.1143)
		(layer "In2.Cu")
		(net "UART_DTR_P6_N")
	)
	(segment
		(start 133.096 -28.640786)
		(end 132.8674 -28.412186)
		(width 0.1143)
		(layer "In2.Cu")
		(net "UART_DTR_P6_N")
	)
	(segment
		(start 40.649652 -19.411442)
		(end 40.10152 -19.958558)
		(width 0.1143)
		(layer "In2.Cu")
		(net "UART_DTR_P6_N")
	)
	(segment
		(start 57.497218 -17.363186)
		(end 55.849012 -17.858994)
		(width 0.1143)
		(layer "In2.Cu")
		(net "UART_DTR_P6_N")
	)
	(segment
		(start 107.32008 -12.170156)
		(end 90.73388 -12.170156)
		(width 0.1143)
		(layer "In2.Cu")
		(net "UART_DTR_P6_N")
	)
	(segment
		(start 130.429 -41.275)
		(end 130.429 -34.29)
		(width 0.1143)
		(layer "In2.Cu")
		(net "UART_DTR_P6_N")
	)
	(segment
		(start 65.24498 -16.484854)
		(end 64.366648 -17.363186)
		(width 0.1143)
		(layer "In2.Cu")
		(net "UART_DTR_P6_N")
	)
	(segment
		(start 23.779988 -53.31079)
		(end 22.839172 -56.07939)
		(width 0.1143)
		(layer "In2.Cu")
		(net "UART_DTR_P6_N")
	)
	(segment
		(start 87.554308 -12.115546)
		(end 87.553292 -12.116054)
		(width 0.1143)
		(layer "In2.Cu")
		(net "UART_DTR_P6_N")
	)
	(segment
		(start 22.2758 -66.005964)
		(end 22.62632 -66.356484)
		(width 0.1143)
		(layer "In2.Cu")
		(net "UART_DTR_P6_N")
	)
	(segment
		(start 90.3605 -11.796776)
		(end 87.875364 -11.796776)
		(width 0.1143)
		(layer "In2.Cu")
		(net "UART_DTR_P6_N")
	)
	(segment
		(start 38.47084 -19.958558)
		(end 37.40658 -21.022818)
		(width 0.1143)
		(layer "In2.Cu")
		(net "UART_DTR_P6_N")
	)
	(segment
		(start 21.527516 -60.412376)
		(end 21.527516 -64.315848)
		(width 0.1143)
		(layer "In2.Cu")
		(net "UART_DTR_P6_N")
	)
	(segment
		(start 22.6695 -56.249062)
		(end 21.64334 -57.275222)
		(width 0.1143)
		(layer "In2.Cu")
		(net "UART_DTR_P6_N")
	)
	(segment
		(start 119.278908 -14.212062)
		(end 118.531386 -13.46454)
		(width 0.1143)
		(layer "In2.Cu")
		(net "UART_DTR_P6_N")
	)
	(segment
		(start 87.875364 -11.796776)
		(end 87.671148 -11.999722)
		(width 0.1143)
		(layer "In2.Cu")
		(net "UART_DTR_P6_N")
	)
	(segment
		(start 10.64768 -97.813114)
		(end 10.64768 -98.11004)
		(width 0.1143)
		(layer "In2.Cu")
		(net "UART_DTR_P6_N")
	)
	(segment
		(start 5.62737 -142.092934)
		(end 4.37769 -144.956784)
		(width 0.1143)
		(layer "In2.Cu")
		(net "UART_DTR_P6_N")
	)
	(segment
		(start 117.20576 -176.958244)
		(end 117.155976 -177.008028)
		(width 0.1016)
		(layer "F.Cu")
		(net "N31341803")
	)
	(segment
		(start 117.07876 -178.613562)
		(end 117.07876 -177.085244)
		(width 0.1016)
		(layer "F.Cu")
		(net "N31341803")
	)
	(segment
		(start 117.20576 -175.826674)
		(end 117.20576 -176.958244)
		(width 0.1016)
		(layer "F.Cu")
		(net "N31341803")
	)
	(segment
		(start 117.07876 -177.085244)
		(end 117.155976 -177.008028)
		(width 0.1016)
		(layer "F.Cu")
		(net "N31341803")
	)
	(via
		(at 117.155976 -177.008028)
		(size 0.762)
		(drill 0.381)
		(layers "F.Cu" "B.Cu")
		(net "N31341803")
	)
	(segment
		(start 131.73456 -31.886906)
		(end 131.27736 -31.886906)
		(width 0.1016)
		(layer "F.Cu")
		(net "UART_TX_P6")
	)
	(segment
		(start 130.76174 -31.371286)
		(end 130.76174 -30.079696)
		(width 0.1016)
		(layer "F.Cu")
		(net "UART_TX_P6")
	)
	(segment
		(start 3.890518 -146.228816)
		(end 4.81584 -145.303494)
		(width 0.1016)
		(layer "F.Cu")
		(net "UART_TX_P6")
	)
	(segment
		(start 131.27736 -31.886906)
		(end 130.76174 -31.371286)
		(width 0.1016)
		(layer "F.Cu")
		(net "UART_TX_P6")
	)
	(segment
		(start 3.890518 -148.392642)
		(end 3.890518 -146.228816)
		(width 0.1016)
		(layer "F.Cu")
		(net "UART_TX_P6")
	)
	(via
		(at 131.73456 -31.886906)
		(size 0.508)
		(drill 0.254)
		(layers "F.Cu" "B.Cu")
		(net "UART_TX_P6")
	)
	(via
		(at 4.81584 -145.303494)
		(size 0.508)
		(drill 0.254)
		(layers "F.Cu" "B.Cu")
		(net "UART_TX_P6")
	)
	(segment
		(start 119.192802 -14.57706)
		(end 118.512336 -13.896594)
		(width 0.1143)
		(layer "In2.Cu")
		(net "UART_TX_P6")
	)
	(segment
		(start 22.337776 -62.726062)
		(end 22.5933 -63.719456)
		(width 0.1143)
		(layer "In2.Cu")
		(net "UART_TX_P6")
	)
	(segment
		(start 10.96518 -97.944686)
		(end 10.96518 -98.272854)
		(width 0.1143)
		(layer "In2.Cu")
		(net "UART_TX_P6")
	)
	(segment
		(start 112.649 -13.896594)
		(end 107.187492 -12.487656)
		(width 0.1143)
		(layer "In2.Cu")
		(net "UART_TX_P6")
	)
	(segment
		(start 22.5933 -63.719456)
		(end 22.5933 -65.874392)
		(width 0.1143)
		(layer "In2.Cu")
		(net "UART_TX_P6")
	)
	(segment
		(start 131.5466 -27.751532)
		(end 131.5466 -26.931366)
		(width 0.1143)
		(layer "In2.Cu")
		(net "UART_TX_P6")
	)
	(segment
		(start 22.015196 -62.18301)
		(end 22.337776 -62.726062)
		(width 0.1143)
		(layer "In2.Cu")
		(net "UART_TX_P6")
	)
	(segment
		(start 122.756676 -14.57706)
		(end 119.192802 -14.57706)
		(width 0.1143)
		(layer "In2.Cu")
		(net "UART_TX_P6")
	)
	(segment
		(start 107.187492 -12.487656)
		(end 90.6018 -12.487656)
		(width 0.1143)
		(layer "In2.Cu")
		(net "UART_TX_P6")
	)
	(segment
		(start 65.378584 -16.802354)
		(end 64.39916 -17.781778)
		(width 0.1143)
		(layer "In2.Cu")
		(net "UART_TX_P6")
	)
	(segment
		(start 14.018006 -96.267778)
		(end 12.642088 -96.267778)
		(width 0.1143)
		(layer "In2.Cu")
		(net "UART_TX_P6")
	)
	(segment
		(start 88.00846 -12.114276)
		(end 87.700866 -12.41933)
		(width 0.1143)
		(layer "In2.Cu")
		(net "UART_TX_P6")
	)
	(segment
		(start 87.700866 -12.41933)
		(end 87.700358 -12.41933)
		(width 0.1143)
		(layer "In2.Cu")
		(net "UART_TX_P6")
	)
	(segment
		(start 38.363398 -20.668996)
		(end 37.357558 -21.674836)
		(width 0.1143)
		(layer "In2.Cu")
		(net "UART_TX_P6")
	)
	(segment
		(start 87.63635 -12.48283)
		(end 80.386428 -15.238476)
		(width 0.1143)
		(layer "In2.Cu")
		(net "UART_TX_P6")
	)
	(segment
		(start 4.81584 -145.033746)
		(end 4.81584 -145.303494)
		(width 0.1143)
		(layer "In2.Cu")
		(net "UART_TX_P6")
	)
	(segment
		(start 23.055072 -56.690768)
		(end 22.278848 -59.831732)
		(width 0.1143)
		(layer "In2.Cu")
		(net "UART_TX_P6")
	)
	(segment
		(start 90.6018 -12.487656)
		(end 90.22715 -12.114276)
		(width 0.1143)
		(layer "In2.Cu")
		(net "UART_TX_P6")
	)
	(segment
		(start 67.916298 -15.238476)
		(end 66.35242 -16.802354)
		(width 0.1143)
		(layer "In2.Cu")
		(net "UART_TX_P6")
	)
	(segment
		(start 24.31796 -42.649648)
		(end 24.31796 -52.963572)
		(width 0.1143)
		(layer "In2.Cu")
		(net "UART_TX_P6")
	)
	(segment
		(start 54.040786 -19.755612)
		(end 41.897808 -19.755612)
		(width 0.1143)
		(layer "In2.Cu")
		(net "UART_TX_P6")
	)
	(segment
		(start 6.05155 -103.186484)
		(end 6.05155 -142.074138)
		(width 0.1143)
		(layer "In2.Cu")
		(net "UART_TX_P6")
	)
	(segment
		(start 39.529766 -20.276058)
		(end 38.363398 -20.668996)
		(width 0.1143)
		(layer "In2.Cu")
		(net "UART_TX_P6")
	)
	(segment
		(start 64.39916 -17.781778)
		(end 57.550304 -17.781778)
		(width 0.1143)
		(layer "In2.Cu")
		(net "UART_TX_P6")
	)
	(segment
		(start 66.35242 -16.802354)
		(end 65.378584 -16.802354)
		(width 0.1143)
		(layer "In2.Cu")
		(net "UART_TX_P6")
	)
	(segment
		(start 27.686 -35.613086)
		(end 27.686 -39.281608)
		(width 0.1143)
		(layer "In2.Cu")
		(net "UART_TX_P6")
	)
	(segment
		(start 18.1991 -86.834726)
		(end 18.1991 -92.086684)
		(width 0.1143)
		(layer "In2.Cu")
		(net "UART_TX_P6")
	)
	(segment
		(start 22.5933 -65.874392)
		(end 23.0124 -66.293492)
		(width 0.1143)
		(layer "In2.Cu")
		(net "UART_TX_P6")
	)
	(segment
		(start 23.0124 -66.293492)
		(end 23.0124 -82.021426)
		(width 0.1143)
		(layer "In2.Cu")
		(net "UART_TX_P6")
	)
	(segment
		(start 6.05155 -142.074138)
		(end 4.81584 -145.033746)
		(width 0.1143)
		(layer "In2.Cu")
		(net "UART_TX_P6")
	)
	(segment
		(start 22.015196 -61.806074)
		(end 22.015196 -62.18301)
		(width 0.1143)
		(layer "In2.Cu")
		(net "UART_TX_P6")
	)
	(segment
		(start 80.386428 -15.238476)
		(end 67.916298 -15.238476)
		(width 0.1143)
		(layer "In2.Cu")
		(net "UART_TX_P6")
	)
	(segment
		(start 35.87496 -27.424126)
		(end 27.686 -35.613086)
		(width 0.1143)
		(layer "In2.Cu")
		(net "UART_TX_P6")
	)
	(segment
		(start 57.550304 -17.781778)
		(end 56.507126 -18.106644)
		(width 0.1143)
		(layer "In2.Cu")
		(net "UART_TX_P6")
	)
	(segment
		(start 87.696548 -12.42314)
		(end 87.63635 -12.48283)
		(width 0.1143)
		(layer "In2.Cu")
		(net "UART_TX_P6")
	)
	(segment
		(start 131.74472 -26.733246)
		(end 131.74472 -22.662896)
		(width 0.1143)
		(layer "In2.Cu")
		(net "UART_TX_P6")
	)
	(segment
		(start 40.201088 -20.276058)
		(end 39.529766 -20.276058)
		(width 0.1143)
		(layer "In2.Cu")
		(net "UART_TX_P6")
	)
	(segment
		(start 35.87496 -23.91664)
		(end 35.87496 -27.424126)
		(width 0.1143)
		(layer "In2.Cu")
		(net "UART_TX_P6")
	)
	(segment
		(start 27.686 -39.281608)
		(end 24.31796 -42.649648)
		(width 0.1143)
		(layer "In2.Cu")
		(net "UART_TX_P6")
	)
	(segment
		(start 90.22715 -12.114276)
		(end 88.00846 -12.114276)
		(width 0.1143)
		(layer "In2.Cu")
		(net "UART_TX_P6")
	)
	(segment
		(start 41.897808 -19.755612)
		(end 40.201088 -20.276058)
		(width 0.1143)
		(layer "In2.Cu")
		(net "UART_TX_P6")
	)
	(segment
		(start 131.73456 -31.886906)
		(end 131.73456 -27.939492)
		(width 0.1143)
		(layer "In2.Cu")
		(net "UART_TX_P6")
	)
	(segment
		(start 87.700358 -12.41933)
		(end 87.696548 -12.42314)
		(width 0.1143)
		(layer "In2.Cu")
		(net "UART_TX_P6")
	)
	(segment
		(start 10.96518 -98.272854)
		(end 6.05155 -103.186484)
		(width 0.1143)
		(layer "In2.Cu")
		(net "UART_TX_P6")
	)
	(segment
		(start 23.0124 -82.021426)
		(end 18.1991 -86.834726)
		(width 0.1143)
		(layer "In2.Cu")
		(net "UART_TX_P6")
	)
	(segment
		(start 18.1991 -92.086684)
		(end 14.018006 -96.267778)
		(width 0.1143)
		(layer "In2.Cu")
		(net "UART_TX_P6")
	)
	(segment
		(start 24.31796 -52.963572)
		(end 23.055072 -56.690768)
		(width 0.1143)
		(layer "In2.Cu")
		(net "UART_TX_P6")
	)
	(segment
		(start 131.5466 -26.931366)
		(end 131.74472 -26.733246)
		(width 0.1143)
		(layer "In2.Cu")
		(net "UART_TX_P6")
	)
	(segment
		(start 56.507126 -18.106644)
		(end 54.040786 -19.755612)
		(width 0.1143)
		(layer "In2.Cu")
		(net "UART_TX_P6")
	)
	(segment
		(start 131.73456 -27.939492)
		(end 131.5466 -27.751532)
		(width 0.1143)
		(layer "In2.Cu")
		(net "UART_TX_P6")
	)
	(segment
		(start 22.278848 -59.831732)
		(end 22.015196 -61.806074)
		(width 0.1143)
		(layer "In2.Cu")
		(net "UART_TX_P6")
	)
	(segment
		(start 12.642088 -96.267778)
		(end 10.96518 -97.944686)
		(width 0.1143)
		(layer "In2.Cu")
		(net "UART_TX_P6")
	)
	(segment
		(start 37.357558 -21.674836)
		(end 35.87496 -23.91664)
		(width 0.1143)
		(layer "In2.Cu")
		(net "UART_TX_P6")
	)
	(segment
		(start 131.74472 -22.662896)
		(end 124.055378 -14.973554)
		(width 0.1143)
		(layer "In2.Cu")
		(net "UART_TX_P6")
	)
	(segment
		(start 124.055378 -14.973554)
		(end 122.756676 -14.57706)
		(width 0.1143)
		(layer "In2.Cu")
		(net "UART_TX_P6")
	)
	(segment
		(start 118.512336 -13.896594)
		(end 112.649 -13.896594)
		(width 0.1143)
		(layer "In2.Cu")
		(net "UART_TX_P6")
	)
	(segment
		(start 2.347214 -162.229546)
		(end 2.608834 -162.491166)
		(width 0.1016)
		(layer "F.Cu")
		(net "UART_RTS_P5_N")
	)
	(segment
		(start 2.34696 -162.229546)
		(end 2.347214 -162.229546)
		(width 0.1016)
		(layer "F.Cu")
		(net "UART_RTS_P5_N")
	)
	(segment
		(start 126.73076 -45.654976)
		(end 126.73076 -45.728128)
		(width 0.1016)
		(layer "F.Cu")
		(net "UART_RTS_P5_N")
	)
	(segment
		(start 2.608834 -162.491166)
		(end 2.608834 -164.062156)
		(width 0.1016)
		(layer "F.Cu")
		(net "UART_RTS_P5_N")
	)
	(segment
		(start 126.761748 -45.759116)
		(end 126.761748 -47.199804)
		(width 0.1016)
		(layer "F.Cu")
		(net "UART_RTS_P5_N")
	)
	(segment
		(start 126.73076 -45.728128)
		(end 126.761748 -45.759116)
		(width 0.1016)
		(layer "F.Cu")
		(net "UART_RTS_P5_N")
	)
	(via
		(at 126.73076 -45.654976)
		(size 0.508)
		(drill 0.254)
		(layers "F.Cu" "B.Cu")
		(net "UART_RTS_P5_N")
	)
	(via
		(at 31.5341 -24.039322)
		(size 0.508)
		(drill 0.254)
		(layers "F.Cu" "B.Cu")
		(net "UART_RTS_P5_N")
	)
	(via
		(at 2.34696 -162.229546)
		(size 0.508)
		(drill 0.254)
		(layers "F.Cu" "B.Cu")
		(net "UART_RTS_P5_N")
	)
	(segment
		(start 15.29588 -58.315352)
		(end 15.451074 -57.662826)
		(width 0.1143)
		(layer "In2.Cu")
		(net "UART_RTS_P5_N")
	)
	(segment
		(start 11.24204 -91.993212)
		(end 11.24204 -91.271852)
		(width 0.1143)
		(layer "In2.Cu")
		(net "UART_RTS_P5_N")
	)
	(segment
		(start 14.01318 -80.882744)
		(end 14.071092 -80.823562)
		(width 0.1143)
		(layer "In2.Cu")
		(net "UART_RTS_P5_N")
	)
	(segment
		(start 29.925772 -26.98623)
		(end 31.5341 -24.039322)
		(width 0.1143)
		(layer "In2.Cu")
		(net "UART_RTS_P5_N")
	)
	(segment
		(start 3.03022 -97.10547)
		(end 6.129528 -97.10547)
		(width 0.1143)
		(layer "In2.Cu")
		(net "UART_RTS_P5_N")
	)
	(segment
		(start 15.236698 -73.398126)
		(end 15.29588 -73.020936)
		(width 0.1143)
		(layer "In2.Cu")
		(net "UART_RTS_P5_N")
	)
	(segment
		(start 16.544544 -52.619402)
		(end 16.61795 -52.253134)
		(width 0.1143)
		(layer "In2.Cu")
		(net "UART_RTS_P5_N")
	)
	(segment
		(start 13.71092 -88.802972)
		(end 13.71092 -83.132422)
		(width 0.1143)
		(layer "In2.Cu")
		(net "UART_RTS_P5_N")
	)
	(segment
		(start 16.39316 -52.959254)
		(end 16.544544 -52.619402)
		(width 0.1143)
		(layer "In2.Cu")
		(net "UART_RTS_P5_N")
	)
	(segment
		(start 15.29588 -73.020936)
		(end 15.29588 -58.315352)
		(width 0.1143)
		(layer "In2.Cu")
		(net "UART_RTS_P5_N")
	)
	(segment
		(start 17.902174 -44.939458)
		(end 18.843752 -42.054272)
		(width 0.1143)
		(layer "In2.Cu")
		(net "UART_RTS_P5_N")
	)
	(segment
		(start 2.34696 -162.229546)
		(end 2.34696 -161.81705)
		(width 0.1143)
		(layer "In2.Cu")
		(net "UART_RTS_P5_N")
	)
	(segment
		(start 14.353286 -79.027782)
		(end 15.236698 -73.398126)
		(width 0.1143)
		(layer "In2.Cu")
		(net "UART_RTS_P5_N")
	)
	(segment
		(start 6.129528 -97.10547)
		(end 11.24204 -91.993212)
		(width 0.1143)
		(layer "In2.Cu")
		(net "UART_RTS_P5_N")
	)
	(segment
		(start 11.24204 -91.271852)
		(end 13.71092 -88.802972)
		(width 0.1143)
		(layer "In2.Cu")
		(net "UART_RTS_P5_N")
	)
	(segment
		(start 16.61795 -52.253134)
		(end 17.902174 -45.292772)
		(width 0.1143)
		(layer "In2.Cu")
		(net "UART_RTS_P5_N")
	)
	(segment
		(start 23.39086 -33.521142)
		(end 29.925772 -26.98623)
		(width 0.1143)
		(layer "In2.Cu")
		(net "UART_RTS_P5_N")
	)
	(segment
		(start 18.843752 -42.054272)
		(end 23.39086 -37.507164)
		(width 0.1143)
		(layer "In2.Cu")
		(net "UART_RTS_P5_N")
	)
	(segment
		(start 2.34696 -161.81705)
		(end 1.60655 -161.07664)
		(width 0.1143)
		(layer "In2.Cu")
		(net "UART_RTS_P5_N")
	)
	(segment
		(start 23.39086 -37.507164)
		(end 23.39086 -33.521142)
		(width 0.1143)
		(layer "In2.Cu")
		(net "UART_RTS_P5_N")
	)
	(segment
		(start 15.451074 -57.662826)
		(end 16.39316 -52.959254)
		(width 0.1143)
		(layer "In2.Cu")
		(net "UART_RTS_P5_N")
	)
	(segment
		(start 17.902174 -45.292772)
		(end 17.902174 -44.939458)
		(width 0.1143)
		(layer "In2.Cu")
		(net "UART_RTS_P5_N")
	)
	(segment
		(start 1.60655 -161.07664)
		(end 1.60655 -100.934012)
		(width 0.1143)
		(layer "In2.Cu")
		(net "UART_RTS_P5_N")
	)
	(segment
		(start 14.01318 -81.206086)
		(end 14.01318 -80.882744)
		(width 0.1143)
		(layer "In2.Cu")
		(net "UART_RTS_P5_N")
	)
	(segment
		(start 13.71092 -83.132422)
		(end 14.01318 -81.206086)
		(width 0.1143)
		(layer "In2.Cu")
		(net "UART_RTS_P5_N")
	)
	(segment
		(start 1.60655 -100.934012)
		(end 2.180844 -97.954846)
		(width 0.1143)
		(layer "In2.Cu")
		(net "UART_RTS_P5_N")
	)
	(segment
		(start 2.180844 -97.954846)
		(end 3.03022 -97.10547)
		(width 0.1143)
		(layer "In2.Cu")
		(net "UART_RTS_P5_N")
	)
	(segment
		(start 14.071092 -80.823562)
		(end 14.353286 -79.027782)
		(width 0.1143)
		(layer "In2.Cu")
		(net "UART_RTS_P5_N")
	)
	(segment
		(start 124.403358 -44.033694)
		(end 123.985528 -44.033694)
		(width 0.1143)
		(layer "In6.Cu")
		(net "UART_RTS_P5_N")
	)
	(segment
		(start 126.73076 -45.654976)
		(end 126.657608 -45.654976)
		(width 0.1143)
		(layer "In6.Cu")
		(net "UART_RTS_P5_N")
	)
	(segment
		(start 121.54408 -41.592246)
		(end 121.54408 -39.78783)
		(width 0.1143)
		(layer "In6.Cu")
		(net "UART_RTS_P5_N")
	)
	(segment
		(start 36.520882 -23.040594)
		(end 35.82416 -23.738078)
		(width 0.1143)
		(layer "In6.Cu")
		(net "UART_RTS_P5_N")
	)
	(segment
		(start 34.697924 -24.039322)
		(end 31.5341 -24.039322)
		(width 0.1143)
		(layer "In6.Cu")
		(net "UART_RTS_P5_N")
	)
	(segment
		(start 104.563672 -21.172424)
		(end 41.275254 -21.172424)
		(width 0.1143)
		(layer "In6.Cu")
		(net "UART_RTS_P5_N")
	)
	(segment
		(start 121.54408 -39.78783)
		(end 120.376442 -38.625018)
		(width 0.1143)
		(layer "In6.Cu")
		(net "UART_RTS_P5_N")
	)
	(segment
		(start 126.657608 -45.654976)
		(end 126.0602 -45.057568)
		(width 0.1143)
		(layer "In6.Cu")
		(net "UART_RTS_P5_N")
	)
	(segment
		(start 125.427232 -45.057568)
		(end 124.403358 -44.033694)
		(width 0.1143)
		(layer "In6.Cu")
		(net "UART_RTS_P5_N")
	)
	(segment
		(start 111.17072 -31.664402)
		(end 111.17072 -30.548072)
		(width 0.1143)
		(layer "In6.Cu")
		(net "UART_RTS_P5_N")
	)
	(segment
		(start 120.376442 -38.625018)
		(end 113.295176 -33.787588)
		(width 0.1143)
		(layer "In6.Cu")
		(net "UART_RTS_P5_N")
	)
	(segment
		(start 113.295176 -33.787588)
		(end 111.17072 -31.664402)
		(width 0.1143)
		(layer "In6.Cu")
		(net "UART_RTS_P5_N")
	)
	(segment
		(start 35.82416 -23.738078)
		(end 34.697924 -24.039322)
		(width 0.1143)
		(layer "In6.Cu")
		(net "UART_RTS_P5_N")
	)
	(segment
		(start 126.0602 -45.057568)
		(end 125.427232 -45.057568)
		(width 0.1143)
		(layer "In6.Cu")
		(net "UART_RTS_P5_N")
	)
	(segment
		(start 123.985528 -44.033694)
		(end 121.54408 -41.592246)
		(width 0.1143)
		(layer "In6.Cu")
		(net "UART_RTS_P5_N")
	)
	(segment
		(start 39.407084 -23.040594)
		(end 36.520882 -23.040594)
		(width 0.1143)
		(layer "In6.Cu")
		(net "UART_RTS_P5_N")
	)
	(segment
		(start 108.15828 -26.588974)
		(end 108.15828 -24.767032)
		(width 0.1143)
		(layer "In6.Cu")
		(net "UART_RTS_P5_N")
	)
	(segment
		(start 41.275254 -21.172424)
		(end 39.407084 -23.040594)
		(width 0.1143)
		(layer "In6.Cu")
		(net "UART_RTS_P5_N")
	)
	(segment
		(start 111.17072 -30.548072)
		(end 108.15828 -26.588974)
		(width 0.1143)
		(layer "In6.Cu")
		(net "UART_RTS_P5_N")
	)
	(segment
		(start 108.15828 -24.767032)
		(end 104.563672 -21.172424)
		(width 0.1143)
		(layer "In6.Cu")
		(net "UART_RTS_P5_N")
	)
	(segment
		(start 125.261624 -31.065978)
		(end 125.090936 -31.236666)
		(width 0.1016)
		(layer "F.Cu")
		(net "UART_TX_P5")
	)
	(segment
		(start 124.52223 -31.236666)
		(end 123.70308 -30.417516)
		(width 0.1016)
		(layer "F.Cu")
		(net "UART_TX_P5")
	)
	(segment
		(start 3.25882 -161.843466)
		(end 2.3622 -160.946846)
		(width 0.1016)
		(layer "F.Cu")
		(net "UART_TX_P5")
	)
	(segment
		(start 3.25882 -164.062156)
		(end 3.25882 -161.843466)
		(width 0.1016)
		(layer "F.Cu")
		(net "UART_TX_P5")
	)
	(segment
		(start 125.261624 -30.079696)
		(end 125.261624 -31.065978)
		(width 0.1016)
		(layer "F.Cu")
		(net "UART_TX_P5")
	)
	(segment
		(start 2.3622 -160.946846)
		(end 2.3622 -160.393888)
		(width 0.1016)
		(layer "F.Cu")
		(net "UART_TX_P5")
	)
	(segment
		(start 125.090936 -31.236666)
		(end 124.52223 -31.236666)
		(width 0.1016)
		(layer "F.Cu")
		(net "UART_TX_P5")
	)
	(via
		(at 123.70308 -30.417516)
		(size 0.508)
		(drill 0.254)
		(layers "F.Cu" "B.Cu")
		(net "UART_TX_P5")
	)
	(via
		(at 2.3622 -160.393888)
		(size 0.508)
		(drill 0.254)
		(layers "F.Cu" "B.Cu")
		(net "UART_TX_P5")
	)
	(via
		(at 32.91332 -22.056598)
		(size 0.508)
		(drill 0.254)
		(layers "F.Cu" "B.Cu")
		(net "UART_TX_P5")
	)
	(segment
		(start 32.148272 -24.751792)
		(end 32.3342 -24.565864)
		(width 0.1143)
		(layer "In2.Cu")
		(net "UART_TX_P5")
	)
	(segment
		(start 5.06476 -97.99701)
		(end 6.13918 -97.99701)
		(width 0.1143)
		(layer "In2.Cu")
		(net "UART_TX_P5")
	)
	(segment
		(start 31.046674 -26.856944)
		(end 32.148272 -24.751792)
		(width 0.1143)
		(layer "In2.Cu")
		(net "UART_TX_P5")
	)
	(segment
		(start 6.13918 -97.99701)
		(end 11.877548 -92.258642)
		(width 0.1143)
		(layer "In2.Cu")
		(net "UART_TX_P5")
	)
	(segment
		(start 32.3342 -22.635718)
		(end 32.91332 -22.056598)
		(width 0.1143)
		(layer "In2.Cu")
		(net "UART_TX_P5")
	)
	(segment
		(start 16.6243 -56.180736)
		(end 17.565116 -51.893724)
		(width 0.1143)
		(layer "In2.Cu")
		(net "UART_TX_P5")
	)
	(segment
		(start 32.3342 -24.565864)
		(end 32.3342 -22.635718)
		(width 0.1143)
		(layer "In2.Cu")
		(net "UART_TX_P5")
	)
	(segment
		(start 18.6182 -49.534572)
		(end 18.6182 -47.533814)
		(width 0.1143)
		(layer "In2.Cu")
		(net "UART_TX_P5")
	)
	(segment
		(start 19.44878 -44.74591)
		(end 19.44878 -43.664124)
		(width 0.1143)
		(layer "In2.Cu")
		(net "UART_TX_P5")
	)
	(segment
		(start 2.32537 -100.562664)
		(end 2.770886 -98.265234)
		(width 0.1143)
		(layer "In2.Cu")
		(net "UART_TX_P5")
	)
	(segment
		(start 11.877548 -91.53779)
		(end 13.96238 -89.452958)
		(width 0.1143)
		(layer "In2.Cu")
		(net "UART_TX_P5")
	)
	(segment
		(start 24.10206 -33.801558)
		(end 31.046674 -26.856944)
		(width 0.1143)
		(layer "In2.Cu")
		(net "UART_TX_P5")
	)
	(segment
		(start 3.29565 -97.74047)
		(end 4.80822 -97.74047)
		(width 0.1143)
		(layer "In2.Cu")
		(net "UART_TX_P5")
	)
	(segment
		(start 14.64818 -88.76411)
		(end 14.64818 -81.143856)
		(width 0.1143)
		(layer "In2.Cu")
		(net "UART_TX_P5")
	)
	(segment
		(start 14.669262 -81.12252)
		(end 16.6243 -68.672456)
		(width 0.1143)
		(layer "In2.Cu")
		(net "UART_TX_P5")
	)
	(segment
		(start 4.80822 -97.74047)
		(end 5.06476 -97.99701)
		(width 0.1143)
		(layer "In2.Cu")
		(net "UART_TX_P5")
	)
	(segment
		(start 20.073366 -41.786048)
		(end 24.10206 -37.757354)
		(width 0.1143)
		(layer "In2.Cu")
		(net "UART_TX_P5")
	)
	(segment
		(start 2.3622 -160.393888)
		(end 2.32537 -160.357058)
		(width 0.1143)
		(layer "In2.Cu")
		(net "UART_TX_P5")
	)
	(segment
		(start 2.770886 -98.265234)
		(end 3.29565 -97.74047)
		(width 0.1143)
		(layer "In2.Cu")
		(net "UART_TX_P5")
	)
	(segment
		(start 19.44878 -43.664124)
		(end 20.073366 -41.786048)
		(width 0.1143)
		(layer "In2.Cu")
		(net "UART_TX_P5")
	)
	(segment
		(start 24.10206 -37.757354)
		(end 24.10206 -33.801558)
		(width 0.1143)
		(layer "In2.Cu")
		(net "UART_TX_P5")
	)
	(segment
		(start 14.64818 -81.143856)
		(end 14.669262 -81.12252)
		(width 0.1143)
		(layer "In2.Cu")
		(net "UART_TX_P5")
	)
	(segment
		(start 13.96238 -89.45245)
		(end 14.64818 -88.76411)
		(width 0.1143)
		(layer "In2.Cu")
		(net "UART_TX_P5")
	)
	(segment
		(start 16.6243 -68.672456)
		(end 16.6243 -56.180736)
		(width 0.1143)
		(layer "In2.Cu")
		(net "UART_TX_P5")
	)
	(segment
		(start 17.565116 -51.893724)
		(end 18.6182 -49.534572)
		(width 0.1143)
		(layer "In2.Cu")
		(net "UART_TX_P5")
	)
	(segment
		(start 11.877548 -92.258642)
		(end 11.877548 -91.53779)
		(width 0.1143)
		(layer "In2.Cu")
		(net "UART_TX_P5")
	)
	(segment
		(start 2.32537 -160.357058)
		(end 2.32537 -100.562664)
		(width 0.1143)
		(layer "In2.Cu")
		(net "UART_TX_P5")
	)
	(segment
		(start 13.96238 -89.452958)
		(end 13.96238 -89.45245)
		(width 0.1143)
		(layer "In2.Cu")
		(net "UART_TX_P5")
	)
	(segment
		(start 18.6182 -47.533814)
		(end 19.44878 -44.74591)
		(width 0.1143)
		(layer "In2.Cu")
		(net "UART_TX_P5")
	)
	(segment
		(start 101.22154 -18.11909)
		(end 101.93782 -17.965166)
		(width 0.1143)
		(layer "In6.Cu")
		(net "UART_TX_P5")
	)
	(segment
		(start 40.54094 -19.280632)
		(end 40.68953 -19.132042)
		(width 0.1143)
		(layer "In6.Cu")
		(net "UART_TX_P5")
	)
	(segment
		(start 40.75938 -19.11604)
		(end 63.82385 -19.11604)
		(width 0.1143)
		(layer "In6.Cu")
		(net "UART_TX_P5")
	)
	(segment
		(start 40.743378 -19.132042)
		(end 40.75938 -19.11604)
		(width 0.1143)
		(layer "In6.Cu")
		(net "UART_TX_P5")
	)
	(segment
		(start 122.21972 -29.833062)
		(end 123.70308 -30.417516)
		(width 0.1143)
		(layer "In6.Cu")
		(net "UART_TX_P5")
	)
	(segment
		(start 97.665794 -18.083276)
		(end 100.819966 -18.083276)
		(width 0.1143)
		(layer "In6.Cu")
		(net "UART_TX_P5")
	)
	(segment
		(start 35.68192 -21.12137)
		(end 40.54094 -19.280632)
		(width 0.1143)
		(layer "In6.Cu")
		(net "UART_TX_P5")
	)
	(segment
		(start 111.47806 -23.9395)
		(end 111.47806 -25.53589)
		(width 0.1143)
		(layer "In6.Cu")
		(net "UART_TX_P5")
	)
	(segment
		(start 115.775232 -29.833062)
		(end 122.21972 -29.833062)
		(width 0.1143)
		(layer "In6.Cu")
		(net "UART_TX_P5")
	)
	(segment
		(start 40.68953 -19.132042)
		(end 40.743378 -19.132042)
		(width 0.1143)
		(layer "In6.Cu")
		(net "UART_TX_P5")
	)
	(segment
		(start 33.848548 -21.12137)
		(end 35.68192 -21.12137)
		(width 0.1143)
		(layer "In6.Cu")
		(net "UART_TX_P5")
	)
	(segment
		(start 100.85578 -18.11909)
		(end 101.22154 -18.11909)
		(width 0.1143)
		(layer "In6.Cu")
		(net "UART_TX_P5")
	)
	(segment
		(start 105.767124 -18.228564)
		(end 111.47806 -23.9395)
		(width 0.1143)
		(layer "In6.Cu")
		(net "UART_TX_P5")
	)
	(segment
		(start 67.12204 -17.878044)
		(end 67.16395 -17.862296)
		(width 0.1143)
		(layer "In6.Cu")
		(net "UART_TX_P5")
	)
	(segment
		(start 111.47806 -25.53589)
		(end 115.775232 -29.833062)
		(width 0.1143)
		(layer "In6.Cu")
		(net "UART_TX_P5")
	)
	(segment
		(start 67.004184 -17.92224)
		(end 67.12204 -17.878044)
		(width 0.1143)
		(layer "In6.Cu")
		(net "UART_TX_P5")
	)
	(segment
		(start 32.91332 -22.056598)
		(end 33.848548 -21.12137)
		(width 0.1143)
		(layer "In6.Cu")
		(net "UART_TX_P5")
	)
	(segment
		(start 67.16395 -17.862296)
		(end 96.054672 -17.862296)
		(width 0.1143)
		(layer "In6.Cu")
		(net "UART_TX_P5")
	)
	(segment
		(start 101.93782 -17.965166)
		(end 102.825042 -17.91335)
		(width 0.1143)
		(layer "In6.Cu")
		(net "UART_TX_P5")
	)
	(segment
		(start 102.825042 -17.91335)
		(end 105.767124 -18.228564)
		(width 0.1143)
		(layer "In6.Cu")
		(net "UART_TX_P5")
	)
	(segment
		(start 63.82385 -19.11604)
		(end 67.004184 -17.92224)
		(width 0.1143)
		(layer "In6.Cu")
		(net "UART_TX_P5")
	)
	(segment
		(start 100.819966 -18.083276)
		(end 100.85578 -18.11909)
		(width 0.1143)
		(layer "In6.Cu")
		(net "UART_TX_P5")
	)
	(segment
		(start 96.054672 -17.862296)
		(end 97.665794 -18.083276)
		(width 0.1143)
		(layer "In6.Cu")
		(net "UART_TX_P5")
	)
	(segment
		(start 3.18008 -152.013666)
		(end 3.18008 -154.820112)
		(width 0.1016)
		(layer "F.Cu")
		(net "UART_RI_P5_N")
	)
	(segment
		(start 3.18008 -154.820112)
		(end 3.093212 -154.90698)
		(width 0.1016)
		(layer "F.Cu")
		(net "UART_RI_P5_N")
	)
	(segment
		(start 3.51028 -151.683466)
		(end 4.550156 -152.723342)
		(width 0.1016)
		(layer "F.Cu")
		(net "UART_RI_P5_N")
	)
	(segment
		(start 4.550156 -152.723342)
		(end 5.04698 -152.723342)
		(width 0.1016)
		(layer "F.Cu")
		(net "UART_RI_P5_N")
	)
	(segment
		(start 127.26162 -30.079696)
		(end 127.26162 -31.245048)
		(width 0.1016)
		(layer "F.Cu")
		(net "UART_RI_P5_N")
	)
	(segment
		(start 127.26162 -31.245048)
		(end 127.004572 -31.502096)
		(width 0.1016)
		(layer "F.Cu")
		(net "UART_RI_P5_N")
	)
	(segment
		(start 127.004572 -31.502096)
		(end 126.34722 -31.502096)
		(width 0.1016)
		(layer "F.Cu")
		(net "UART_RI_P5_N")
	)
	(segment
		(start 3.51028 -151.683466)
		(end 3.18008 -152.013666)
		(width 0.1016)
		(layer "F.Cu")
		(net "UART_RI_P5_N")
	)
	(segment
		(start 3.5433 -150.464266)
		(end 3.43154 -150.352506)
		(width 0.1016)
		(layer "F.Cu")
		(net "UART_RI_P5_N")
	)
	(segment
		(start 5.04698 -152.723342)
		(end 5.471668 -153.14803)
		(width 0.1016)
		(layer "F.Cu")
		(net "UART_RI_P5_N")
	)
	(segment
		(start 5.471668 -153.14803)
		(end 5.82549 -153.14803)
		(width 0.1016)
		(layer "F.Cu")
		(net "UART_RI_P5_N")
	)
	(segment
		(start 3.51028 -151.683466)
		(end 3.5433 -151.650446)
		(width 0.1016)
		(layer "F.Cu")
		(net "UART_RI_P5_N")
	)
	(segment
		(start 3.093212 -154.90698)
		(end 3.093212 -155.480766)
		(width 0.1016)
		(layer "F.Cu")
		(net "UART_RI_P5_N")
	)
	(segment
		(start 3.5433 -151.650446)
		(end 3.5433 -150.464266)
		(width 0.1016)
		(layer "F.Cu")
		(net "UART_RI_P5_N")
	)
	(via
		(at 126.34722 -31.502096)
		(size 0.508)
		(drill 0.254)
		(layers "F.Cu" "B.Cu")
		(net "UART_RI_P5_N")
	)
	(via
		(at 3.43154 -150.352506)
		(size 0.508)
		(drill 0.254)
		(layers "F.Cu" "B.Cu")
		(net "UART_RI_P5_N")
	)
	(via
		(at 33.6296 -22.390862)
		(size 0.508)
		(drill 0.254)
		(layers "F.Cu" "B.Cu")
		(net "UART_RI_P5_N")
	)
	(segment
		(start 19.939762 -52.329334)
		(end 20.11426 -51.570382)
		(width 0.1143)
		(layer "In2.Cu")
		(net "UART_RI_P5_N")
	)
	(segment
		(start 17.79778 -68.488052)
		(end 17.79778 -57.228994)
		(width 0.1143)
		(layer "In2.Cu")
		(net "UART_RI_P5_N")
	)
	(segment
		(start 17.55394 -75.004676)
		(end 17.556226 -74.99096)
		(width 0.1143)
		(layer "In2.Cu")
		(net "UART_RI_P5_N")
	)
	(segment
		(start 3.43154 -150.352506)
		(end 3.35788 -150.278846)
		(width 0.1143)
		(layer "In2.Cu")
		(net "UART_RI_P5_N")
	)
	(segment
		(start 3.35788 -150.278846)
		(end 3.35788 -102.209092)
		(width 0.1143)
		(layer "In2.Cu")
		(net "UART_RI_P5_N")
	)
	(segment
		(start 33.6296 -23.18639)
		(end 33.6296 -22.390862)
		(width 0.1143)
		(layer "In2.Cu")
		(net "UART_RI_P5_N")
	)
	(segment
		(start 3.35788 -102.209092)
		(end 15.71244 -89.854532)
		(width 0.1143)
		(layer "In2.Cu")
		(net "UART_RI_P5_N")
	)
	(segment
		(start 20.11426 -51.570382)
		(end 20.11426 -48.508412)
		(width 0.1143)
		(layer "In2.Cu")
		(net "UART_RI_P5_N")
	)
	(segment
		(start 17.55394 -77.71384)
		(end 17.55394 -75.004676)
		(width 0.1143)
		(layer "In2.Cu")
		(net "UART_RI_P5_N")
	)
	(segment
		(start 21.02104 -44.633896)
		(end 21.02104 -43.901106)
		(width 0.1143)
		(layer "In2.Cu")
		(net "UART_RI_P5_N")
	)
	(segment
		(start 20.11426 -48.508412)
		(end 20.32889 -47.58944)
		(width 0.1143)
		(layer "In2.Cu")
		(net "UART_RI_P5_N")
	)
	(segment
		(start 17.79778 -57.228994)
		(end 19.939762 -52.329334)
		(width 0.1143)
		(layer "In2.Cu")
		(net "UART_RI_P5_N")
	)
	(segment
		(start 21.02104 -43.901106)
		(end 21.709126 -41.66235)
		(width 0.1143)
		(layer "In2.Cu")
		(net "UART_RI_P5_N")
	)
	(segment
		(start 25.1079 -38.263576)
		(end 25.1079 -34.419286)
		(width 0.1143)
		(layer "In2.Cu")
		(net "UART_RI_P5_N")
	)
	(segment
		(start 25.1079 -34.419286)
		(end 32.446214 -27.080972)
		(width 0.1143)
		(layer "In2.Cu")
		(net "UART_RI_P5_N")
	)
	(segment
		(start 21.709126 -41.66235)
		(end 25.1079 -38.263576)
		(width 0.1143)
		(layer "In2.Cu")
		(net "UART_RI_P5_N")
	)
	(segment
		(start 33.40354 -25.27935)
		(end 33.40354 -23.529036)
		(width 0.1143)
		(layer "In2.Cu")
		(net "UART_RI_P5_N")
	)
	(segment
		(start 17.556226 -74.99096)
		(end 17.79778 -68.488052)
		(width 0.1143)
		(layer "In2.Cu")
		(net "UART_RI_P5_N")
	)
	(segment
		(start 20.32889 -47.58944)
		(end 21.02104 -44.633896)
		(width 0.1143)
		(layer "In2.Cu")
		(net "UART_RI_P5_N")
	)
	(segment
		(start 15.71244 -85.668358)
		(end 17.55394 -77.71384)
		(width 0.1143)
		(layer "In2.Cu")
		(net "UART_RI_P5_N")
	)
	(segment
		(start 15.71244 -89.854532)
		(end 15.71244 -85.668358)
		(width 0.1143)
		(layer "In2.Cu")
		(net "UART_RI_P5_N")
	)
	(segment
		(start 32.446214 -27.080972)
		(end 33.40354 -25.27935)
		(width 0.1143)
		(layer "In2.Cu")
		(net "UART_RI_P5_N")
	)
	(segment
		(start 33.40354 -23.529036)
		(end 33.6296 -23.18639)
		(width 0.1143)
		(layer "In2.Cu")
		(net "UART_RI_P5_N")
	)
	(segment
		(start 67.181476 -18.195544)
		(end 96.14662 -18.195544)
		(width 0.1143)
		(layer "In6.Cu")
		(net "UART_RI_P5_N")
	)
	(segment
		(start 111.14532 -24.076914)
		(end 111.14532 -25.802844)
		(width 0.1143)
		(layer "In6.Cu")
		(net "UART_RI_P5_N")
	)
	(segment
		(start 115.54587 -30.203394)
		(end 121.54408 -30.203394)
		(width 0.1143)
		(layer "In6.Cu")
		(net "UART_RI_P5_N")
	)
	(segment
		(start 33.6296 -22.286976)
		(end 34.251646 -21.66493)
		(width 0.1143)
		(layer "In6.Cu")
		(net "UART_RI_P5_N")
	)
	(segment
		(start 123.39574 -30.88513)
		(end 125.730254 -30.88513)
		(width 0.1143)
		(layer "In6.Cu")
		(net "UART_RI_P5_N")
	)
	(segment
		(start 111.14532 -25.802844)
		(end 115.54587 -30.203394)
		(width 0.1143)
		(layer "In6.Cu")
		(net "UART_RI_P5_N")
	)
	(segment
		(start 103.3526 -18.617184)
		(end 105.68559 -18.617184)
		(width 0.1143)
		(layer "In6.Cu")
		(net "UART_RI_P5_N")
	)
	(segment
		(start 102.969568 -19.000216)
		(end 103.3526 -18.617184)
		(width 0.1143)
		(layer "In6.Cu")
		(net "UART_RI_P5_N")
	)
	(segment
		(start 35.262058 -21.66493)
		(end 40.676322 -19.648932)
		(width 0.1143)
		(layer "In6.Cu")
		(net "UART_RI_P5_N")
	)
	(segment
		(start 125.730254 -30.88513)
		(end 126.34722 -31.502096)
		(width 0.1143)
		(layer "In6.Cu")
		(net "UART_RI_P5_N")
	)
	(segment
		(start 40.676322 -19.648932)
		(end 40.891714 -19.43354)
		(width 0.1143)
		(layer "In6.Cu")
		(net "UART_RI_P5_N")
	)
	(segment
		(start 96.14662 -18.195544)
		(end 99.389946 -18.640806)
		(width 0.1143)
		(layer "In6.Cu")
		(net "UART_RI_P5_N")
	)
	(segment
		(start 63.884302 -19.43354)
		(end 67.181476 -18.195544)
		(width 0.1143)
		(layer "In6.Cu")
		(net "UART_RI_P5_N")
	)
	(segment
		(start 40.891714 -19.43354)
		(end 63.884302 -19.43354)
		(width 0.1143)
		(layer "In6.Cu")
		(net "UART_RI_P5_N")
	)
	(segment
		(start 105.68559 -18.617184)
		(end 111.14532 -24.076914)
		(width 0.1143)
		(layer "In6.Cu")
		(net "UART_RI_P5_N")
	)
	(segment
		(start 33.6296 -22.390862)
		(end 33.6296 -22.286976)
		(width 0.1143)
		(layer "In6.Cu")
		(net "UART_RI_P5_N")
	)
	(segment
		(start 99.389946 -18.640806)
		(end 99.749356 -19.000216)
		(width 0.1143)
		(layer "In6.Cu")
		(net "UART_RI_P5_N")
	)
	(segment
		(start 99.749356 -19.000216)
		(end 102.969568 -19.000216)
		(width 0.1143)
		(layer "In6.Cu")
		(net "UART_RI_P5_N")
	)
	(segment
		(start 121.54408 -30.203394)
		(end 123.39574 -30.88513)
		(width 0.1143)
		(layer "In6.Cu")
		(net "UART_RI_P5_N")
	)
	(segment
		(start 34.251646 -21.66493)
		(end 35.262058 -21.66493)
		(width 0.1143)
		(layer "In6.Cu")
		(net "UART_RI_P5_N")
	)
	(segment
		(start 81.488788 -163.13785)
		(end 81.37144 -163.13785)
		(width 0.1016)
		(layer "F.Cu")
		(net "UART_T3_NODE4_RXD")
	)
	(segment
		(start 81.994756 -163.643818)
		(end 81.488788 -163.13785)
		(width 0.1016)
		(layer "F.Cu")
		(net "UART_T3_NODE4_RXD")
	)
	(segment
		(start 81.994756 -164.374576)
		(end 81.994756 -163.643818)
		(width 0.1016)
		(layer "F.Cu")
		(net "UART_T3_NODE4_RXD")
	)
	(via
		(at 81.37144 -163.13785)
		(size 0.508)
		(drill 0.254)
		(layers "F.Cu" "B.Cu")
		(net "UART_T3_NODE4_RXD")
	)
	(via
		(at 68.88734 -182.372)
		(size 0.508)
		(drill 0.254)
		(layers "F.Cu" "B.Cu")
		(net "UART_T3_NODE4_RXD")
	)
	(segment
		(start 68.23456 -185.389774)
		(end 68.81876 -184.805574)
		(width 0.1016)
		(layer "B.Cu")
		(net "UART_T3_NODE4_RXD")
	)
	(segment
		(start 68.23456 -187.314078)
		(end 68.23456 -185.389774)
		(width 0.1016)
		(layer "B.Cu")
		(net "UART_T3_NODE4_RXD")
	)
	(segment
		(start 68.81876 -184.348628)
		(end 68.81876 -184.805574)
		(width 0.1016)
		(layer "B.Cu")
		(net "UART_T3_NODE4_RXD")
	)
	(segment
		(start 68.647056 -187.726574)
		(end 68.23456 -187.314078)
		(width 0.1016)
		(layer "B.Cu")
		(net "UART_T3_NODE4_RXD")
	)
	(segment
		(start 68.81876 -187.726574)
		(end 68.647056 -187.726574)
		(width 0.1016)
		(layer "B.Cu")
		(net "UART_T3_NODE4_RXD")
	)
	(segment
		(start 68.88734 -182.372)
		(end 68.88734 -182.72887)
		(width 0.1016)
		(layer "B.Cu")
		(net "UART_T3_NODE4_RXD")
	)
	(segment
		(start 68.88734 -182.72887)
		(end 68.38696 -183.22925)
		(width 0.1016)
		(layer "B.Cu")
		(net "UART_T3_NODE4_RXD")
	)
	(segment
		(start 68.38696 -183.22925)
		(end 68.38696 -183.916828)
		(width 0.1016)
		(layer "B.Cu")
		(net "UART_T3_NODE4_RXD")
	)
	(segment
		(start 68.38696 -183.916828)
		(end 68.81876 -184.348628)
		(width 0.1016)
		(layer "B.Cu")
		(net "UART_T3_NODE4_RXD")
	)
	(segment
		(start 71.48322 -179.432712)
		(end 68.88734 -182.028592)
		(width 0.1143)
		(layer "In7.Cu")
		(net "UART_T3_NODE4_RXD")
	)
	(segment
		(start 74.877422 -171.803822)
		(end 74.877422 -174.361094)
		(width 0.1143)
		(layer "In7.Cu")
		(net "UART_T3_NODE4_RXD")
	)
	(segment
		(start 74.41438 -175.295306)
		(end 71.48322 -178.226466)
		(width 0.1143)
		(layer "In7.Cu")
		(net "UART_T3_NODE4_RXD")
	)
	(segment
		(start 74.877422 -174.361094)
		(end 74.41438 -174.824136)
		(width 0.1143)
		(layer "In7.Cu")
		(net "UART_T3_NODE4_RXD")
	)
	(segment
		(start 73.40346 -167.457882)
		(end 73.93686 -167.991282)
		(width 0.1143)
		(layer "In7.Cu")
		(net "UART_T3_NODE4_RXD")
	)
	(segment
		(start 73.93686 -170.86326)
		(end 74.877422 -171.803822)
		(width 0.1143)
		(layer "In7.Cu")
		(net "UART_T3_NODE4_RXD")
	)
	(segment
		(start 73.40346 -166.461186)
		(end 73.40346 -167.457882)
		(width 0.1143)
		(layer "In7.Cu")
		(net "UART_T3_NODE4_RXD")
	)
	(segment
		(start 74.97191 -164.892736)
		(end 73.40346 -166.461186)
		(width 0.1143)
		(layer "In7.Cu")
		(net "UART_T3_NODE4_RXD")
	)
	(segment
		(start 79.984092 -164.892736)
		(end 74.97191 -164.892736)
		(width 0.1143)
		(layer "In7.Cu")
		(net "UART_T3_NODE4_RXD")
	)
	(segment
		(start 81.37144 -163.486846)
		(end 79.984092 -164.892736)
		(width 0.1143)
		(layer "In7.Cu")
		(net "UART_T3_NODE4_RXD")
	)
	(segment
		(start 74.41438 -174.824136)
		(end 74.41438 -175.295306)
		(width 0.1143)
		(layer "In7.Cu")
		(net "UART_T3_NODE4_RXD")
	)
	(segment
		(start 73.93686 -167.991282)
		(end 73.93686 -170.86326)
		(width 0.1143)
		(layer "In7.Cu")
		(net "UART_T3_NODE4_RXD")
	)
	(segment
		(start 81.37144 -163.13785)
		(end 81.37144 -163.486846)
		(width 0.1143)
		(layer "In7.Cu")
		(net "UART_T3_NODE4_RXD")
	)
	(segment
		(start 71.48322 -178.226466)
		(end 71.48322 -179.432712)
		(width 0.1143)
		(layer "In7.Cu")
		(net "UART_T3_NODE4_RXD")
	)
	(segment
		(start 68.88734 -182.028592)
		(end 68.88734 -182.372)
		(width 0.1143)
		(layer "In7.Cu")
		(net "UART_T3_NODE4_RXD")
	)
	(segment
		(start 78.347316 -169.025824)
		(end 77.619606 -169.025824)
		(width 0.1016)
		(layer "F.Cu")
		(net "UART_T3_NODE4_TXD")
	)
	(segment
		(start 81.494884 -165.878256)
		(end 78.347316 -169.025824)
		(width 0.1016)
		(layer "F.Cu")
		(net "UART_T3_NODE4_TXD")
	)
	(segment
		(start 77.619606 -169.025824)
		(end 76.06538 -170.58005)
		(width 0.1016)
		(layer "F.Cu")
		(net "UART_T3_NODE4_TXD")
	)
	(segment
		(start 76.06538 -170.58005)
		(end 76.06538 -174.244)
		(width 0.1016)
		(layer "F.Cu")
		(net "UART_T3_NODE4_TXD")
	)
	(segment
		(start 81.494884 -164.374576)
		(end 81.494884 -165.878256)
		(width 0.1016)
		(layer "F.Cu")
		(net "UART_T3_NODE4_TXD")
	)
	(segment
		(start 76.06538 -174.244)
		(end 75.1713 -175.13808)
		(width 0.1016)
		(layer "F.Cu")
		(net "UART_T3_NODE4_TXD")
	)
	(via
		(at 72.32904 -179.583588)
		(size 0.508)
		(drill 0.254)
		(layers "F.Cu" "B.Cu")
		(net "UART_T3_NODE4_TXD")
	)
	(via
		(at 75.1713 -175.13808)
		(size 0.508)
		(drill 0.254)
		(layers "F.Cu" "B.Cu")
		(net "UART_T3_NODE4_TXD")
	)
	(segment
		(start 70.376796 -180.163978)
		(end 71.533766 -180.163978)
		(width 0.1016)
		(layer "B.Cu")
		(net "UART_T3_NODE4_TXD")
	)
	(segment
		(start 71.533766 -180.163978)
		(end 72.114156 -179.583588)
		(width 0.1016)
		(layer "B.Cu")
		(net "UART_T3_NODE4_TXD")
	)
	(segment
		(start 67.67576 -184.805574)
		(end 67.80022 -184.681114)
		(width 0.1016)
		(layer "B.Cu")
		(net "UART_T3_NODE4_TXD")
	)
	(segment
		(start 67.80022 -184.681114)
		(end 67.80022 -182.740554)
		(width 0.1016)
		(layer "B.Cu")
		(net "UART_T3_NODE4_TXD")
	)
	(segment
		(start 67.80022 -182.740554)
		(end 70.376796 -180.163978)
		(width 0.1016)
		(layer "B.Cu")
		(net "UART_T3_NODE4_TXD")
	)
	(segment
		(start 72.114156 -179.583588)
		(end 72.32904 -179.583588)
		(width 0.1016)
		(layer "B.Cu")
		(net "UART_T3_NODE4_TXD")
	)
	(segment
		(start 75.1713 -175.13808)
		(end 75.1713 -175.575722)
		(width 0.1143)
		(layer "In7.Cu")
		(net "UART_T3_NODE4_TXD")
	)
	(segment
		(start 75.1713 -175.575722)
		(end 72.408542 -178.33848)
		(width 0.1143)
		(layer "In7.Cu")
		(net "UART_T3_NODE4_TXD")
	)
	(segment
		(start 72.408542 -179.504086)
		(end 72.32904 -179.583588)
		(width 0.1143)
		(layer "In7.Cu")
		(net "UART_T3_NODE4_TXD")
	)
	(segment
		(start 72.408542 -178.33848)
		(end 72.408542 -179.504086)
		(width 0.1143)
		(layer "In7.Cu")
		(net "UART_T3_NODE4_TXD")
	)
	(segment
		(start 138.761724 -30.079696)
		(end 138.761724 -27.989022)
		(width 0.1016)
		(layer "F.Cu")
		(net "UART_RX_P6")
	)
	(segment
		(start 5.840476 -141.768068)
		(end 5.840476 -142.550642)
		(width 0.1016)
		(layer "F.Cu")
		(net "UART_RX_P6")
	)
	(segment
		(start 5.247386 -141.174978)
		(end 5.840476 -141.768068)
		(width 0.1016)
		(layer "F.Cu")
		(net "UART_RX_P6")
	)
	(segment
		(start 5.1689 -141.174978)
		(end 5.247386 -141.174978)
		(width 0.1016)
		(layer "F.Cu")
		(net "UART_RX_P6")
	)
	(via
		(at 138.761724 -27.989022)
		(size 0.508)
		(drill 0.254)
		(layers "F.Cu" "B.Cu")
		(net "UART_RX_P6")
	)
	(via
		(at 5.1689 -141.174978)
		(size 0.508)
		(drill 0.254)
		(layers "F.Cu" "B.Cu")
		(net "UART_RX_P6")
	)
	(segment
		(start 38.055042 -18.955258)
		(end 38.65499 -18.955258)
		(width 0.1143)
		(layer "In2.Cu")
		(net "UART_RX_P6")
	)
	(segment
		(start 135.87222 -25.82672)
		(end 137.686034 -27.640534)
		(width 0.1143)
		(layer "In2.Cu")
		(net "UART_RX_P6")
	)
	(segment
		(start 137.686034 -27.640534)
		(end 138.413236 -27.640534)
		(width 0.1143)
		(layer "In2.Cu")
		(net "UART_RX_P6")
	)
	(segment
		(start 36.59124 -20.43303)
		(end 36.610036 -20.400264)
		(width 0.1143)
		(layer "In2.Cu")
		(net "UART_RX_P6")
	)
	(segment
		(start 22.041612 -50.262536)
		(end 22.041612 -44.898056)
		(width 0.1143)
		(layer "In2.Cu")
		(net "UART_RX_P6")
	)
	(segment
		(start 87.45728 -10.793476)
		(end 90.92184 -10.793476)
		(width 0.1143)
		(layer "In2.Cu")
		(net "UART_RX_P6")
	)
	(segment
		(start 20.55622 -55.6768)
		(end 21.35632 -54.8767)
		(width 0.1143)
		(layer "In2.Cu")
		(net "UART_RX_P6")
	)
	(segment
		(start 26.16708 -38.555168)
		(end 26.16708 -34.829496)
		(width 0.1143)
		(layer "In2.Cu")
		(net "UART_RX_P6")
	)
	(segment
		(start 79.466186 -13.891514)
		(end 87.359998 -10.89152)
		(width 0.1143)
		(layer "In2.Cu")
		(net "UART_RX_P6")
	)
	(segment
		(start 63.88354 -15.210282)
		(end 66.071242 -15.210282)
		(width 0.1143)
		(layer "In2.Cu")
		(net "UART_RX_P6")
	)
	(segment
		(start 55.843932 -15.558008)
		(end 63.535814 -15.558008)
		(width 0.1143)
		(layer "In2.Cu")
		(net "UART_RX_P6")
	)
	(segment
		(start 90.92184 -10.793476)
		(end 91.29522 -11.166856)
		(width 0.1143)
		(layer "In2.Cu")
		(net "UART_RX_P6")
	)
	(segment
		(start 26.16708 -34.829496)
		(end 34.42208 -26.574496)
		(width 0.1143)
		(layer "In2.Cu")
		(net "UART_RX_P6")
	)
	(segment
		(start 34.42208 -26.574496)
		(end 34.42208 -23.71598)
		(width 0.1143)
		(layer "In2.Cu")
		(net "UART_RX_P6")
	)
	(segment
		(start 63.535814 -15.558008)
		(end 63.88354 -15.210282)
		(width 0.1143)
		(layer "In2.Cu")
		(net "UART_RX_P6")
	)
	(segment
		(start 112.11052 -11.166856)
		(end 113.24844 -12.304776)
		(width 0.1143)
		(layer "In2.Cu")
		(net "UART_RX_P6")
	)
	(segment
		(start 22.73808 -41.984168)
		(end 26.16708 -38.555168)
		(width 0.1143)
		(layer "In2.Cu")
		(net "UART_RX_P6")
	)
	(segment
		(start 66.071242 -15.210282)
		(end 67.39001 -13.891514)
		(width 0.1143)
		(layer "In2.Cu")
		(net "UART_RX_P6")
	)
	(segment
		(start 36.610036 -20.400264)
		(end 38.055042 -18.955258)
		(width 0.1143)
		(layer "In2.Cu")
		(net "UART_RX_P6")
	)
	(segment
		(start 4.3815 -140.387578)
		(end 4.3815 -102.660196)
		(width 0.1143)
		(layer "In2.Cu")
		(net "UART_RX_P6")
	)
	(segment
		(start 19.8374 -62.202568)
		(end 19.26844 -61.633608)
		(width 0.1143)
		(layer "In2.Cu")
		(net "UART_RX_P6")
	)
	(segment
		(start 12.120372 -94.921324)
		(end 13.491464 -94.921324)
		(width 0.1143)
		(layer "In2.Cu")
		(net "UART_RX_P6")
	)
	(segment
		(start 22.041612 -44.898056)
		(end 22.73808 -44.201588)
		(width 0.1143)
		(layer "In2.Cu")
		(net "UART_RX_P6")
	)
	(segment
		(start 118.867428 -12.304776)
		(end 119.771414 -13.208762)
		(width 0.1143)
		(layer "In2.Cu")
		(net "UART_RX_P6")
	)
	(segment
		(start 91.29522 -11.166856)
		(end 112.11052 -11.166856)
		(width 0.1143)
		(layer "In2.Cu")
		(net "UART_RX_P6")
	)
	(segment
		(start 87.359998 -10.89152)
		(end 87.45728 -10.793476)
		(width 0.1143)
		(layer "In2.Cu")
		(net "UART_RX_P6")
	)
	(segment
		(start 19.26844 -61.633608)
		(end 19.26844 -58.441336)
		(width 0.1143)
		(layer "In2.Cu")
		(net "UART_RX_P6")
	)
	(segment
		(start 119.771414 -13.208762)
		(end 124.2568 -13.208762)
		(width 0.1143)
		(layer "In2.Cu")
		(net "UART_RX_P6")
	)
	(segment
		(start 20.056856 -64.502284)
		(end 19.8374 -64.282828)
		(width 0.1143)
		(layer "In2.Cu")
		(net "UART_RX_P6")
	)
	(segment
		(start 53.214524 -18.187416)
		(end 55.843932 -15.558008)
		(width 0.1143)
		(layer "In2.Cu")
		(net "UART_RX_P6")
	)
	(segment
		(start 20.55622 -57.153556)
		(end 20.55622 -55.6768)
		(width 0.1143)
		(layer "In2.Cu")
		(net "UART_RX_P6")
	)
	(segment
		(start 36.29152 -20.885658)
		(end 36.59124 -20.43303)
		(width 0.1143)
		(layer "In2.Cu")
		(net "UART_RX_P6")
	)
	(segment
		(start 21.41855 -67.791838)
		(end 20.056856 -66.430144)
		(width 0.1143)
		(layer "In2.Cu")
		(net "UART_RX_P6")
	)
	(segment
		(start 4.3815 -102.660196)
		(end 12.120372 -94.921324)
		(width 0.1143)
		(layer "In2.Cu")
		(net "UART_RX_P6")
	)
	(segment
		(start 124.2568 -13.208762)
		(end 135.87222 -24.824182)
		(width 0.1143)
		(layer "In2.Cu")
		(net "UART_RX_P6")
	)
	(segment
		(start 22.73808 -44.201588)
		(end 22.73808 -41.984168)
		(width 0.1143)
		(layer "In2.Cu")
		(net "UART_RX_P6")
	)
	(segment
		(start 21.41855 -81.501488)
		(end 21.41855 -67.791838)
		(width 0.1143)
		(layer "In2.Cu")
		(net "UART_RX_P6")
	)
	(segment
		(start 67.39001 -13.891514)
		(end 79.466186 -13.891514)
		(width 0.1143)
		(layer "In2.Cu")
		(net "UART_RX_P6")
	)
	(segment
		(start 13.491464 -94.921324)
		(end 16.79702 -91.615768)
		(width 0.1143)
		(layer "In2.Cu")
		(net "UART_RX_P6")
	)
	(segment
		(start 16.79702 -86.123018)
		(end 21.41855 -81.501488)
		(width 0.1143)
		(layer "In2.Cu")
		(net "UART_RX_P6")
	)
	(segment
		(start 5.1689 -141.174978)
		(end 4.3815 -140.387578)
		(width 0.1143)
		(layer "In2.Cu")
		(net "UART_RX_P6")
	)
	(segment
		(start 138.413236 -27.640534)
		(end 138.761724 -27.989022)
		(width 0.1143)
		(layer "In2.Cu")
		(net "UART_RX_P6")
	)
	(segment
		(start 39.422832 -18.187416)
		(end 53.214524 -18.187416)
		(width 0.1143)
		(layer "In2.Cu")
		(net "UART_RX_P6")
	)
	(segment
		(start 34.42208 -23.71598)
		(end 36.29152 -20.885658)
		(width 0.1143)
		(layer "In2.Cu")
		(net "UART_RX_P6")
	)
	(segment
		(start 19.8374 -64.282828)
		(end 19.8374 -62.202568)
		(width 0.1143)
		(layer "In2.Cu")
		(net "UART_RX_P6")
	)
	(segment
		(start 21.35632 -54.8767)
		(end 21.35632 -50.948082)
		(width 0.1143)
		(layer "In2.Cu")
		(net "UART_RX_P6")
	)
	(segment
		(start 20.056856 -66.430144)
		(end 20.056856 -64.502284)
		(width 0.1143)
		(layer "In2.Cu")
		(net "UART_RX_P6")
	)
	(segment
		(start 19.26844 -58.441336)
		(end 20.55622 -57.153556)
		(width 0.1143)
		(layer "In2.Cu")
		(net "UART_RX_P6")
	)
	(segment
		(start 135.87222 -24.824182)
		(end 135.87222 -25.82672)
		(width 0.1143)
		(layer "In2.Cu")
		(net "UART_RX_P6")
	)
	(segment
		(start 38.65499 -18.955258)
		(end 39.422832 -18.187416)
		(width 0.1143)
		(layer "In2.Cu")
		(net "UART_RX_P6")
	)
	(segment
		(start 21.35632 -50.948082)
		(end 22.041612 -50.262536)
		(width 0.1143)
		(layer "In2.Cu")
		(net "UART_RX_P6")
	)
	(segment
		(start 113.24844 -12.304776)
		(end 118.867428 -12.304776)
		(width 0.1143)
		(layer "In2.Cu")
		(net "UART_RX_P6")
	)
	(segment
		(start 16.79702 -91.615768)
		(end 16.79702 -86.123018)
		(width 0.1143)
		(layer "In2.Cu")
		(net "UART_RX_P6")
	)
	(segment
		(start 76.49464 -165.603682)
		(end 76.54544 -165.654482)
		(width 0.1016)
		(layer "F.Cu")
		(net "UART_T3_NODE3_TXD")
	)
	(segment
		(start 76.49464 -164.374576)
		(end 76.49464 -165.603682)
		(width 0.1016)
		(layer "F.Cu")
		(net "UART_T3_NODE3_TXD")
	)
	(via
		(at 72.42302 -181.465982)
		(size 0.508)
		(drill 0.254)
		(layers "F.Cu" "B.Cu")
		(net "UART_T3_NODE3_TXD")
	)
	(via
		(at 76.54544 -165.654482)
		(size 0.508)
		(drill 0.254)
		(layers "F.Cu" "B.Cu")
		(net "UART_T3_NODE3_TXD")
	)
	(segment
		(start 70.41642 -183.79948)
		(end 70.58152 -183.63438)
		(width 0.1016)
		(layer "B.Cu")
		(net "UART_T3_NODE3_TXD")
	)
	(segment
		(start 70.58152 -183.307482)
		(end 72.42302 -181.465982)
		(width 0.1016)
		(layer "B.Cu")
		(net "UART_T3_NODE3_TXD")
	)
	(segment
		(start 69.96176 -184.805574)
		(end 70.41642 -184.350914)
		(width 0.1016)
		(layer "B.Cu")
		(net "UART_T3_NODE3_TXD")
	)
	(segment
		(start 70.58152 -183.63438)
		(end 70.58152 -183.307482)
		(width 0.1016)
		(layer "B.Cu")
		(net "UART_T3_NODE3_TXD")
	)
	(segment
		(start 70.41642 -184.350914)
		(end 70.41642 -183.79948)
		(width 0.1016)
		(layer "B.Cu")
		(net "UART_T3_NODE3_TXD")
	)
	(segment
		(start 76.46416 -167.710104)
		(end 75.82662 -168.347644)
		(width 0.1143)
		(layer "In7.Cu")
		(net "UART_T3_NODE3_TXD")
	)
	(segment
		(start 75.82662 -168.347644)
		(end 75.82662 -168.854374)
		(width 0.1143)
		(layer "In7.Cu")
		(net "UART_T3_NODE3_TXD")
	)
	(segment
		(start 75.82662 -168.854374)
		(end 76.76134 -169.789094)
		(width 0.1143)
		(layer "In7.Cu")
		(net "UART_T3_NODE3_TXD")
	)
	(segment
		(start 75.58532 -178.884326)
		(end 75.004676 -178.884326)
		(width 0.1143)
		(layer "In7.Cu")
		(net "UART_T3_NODE3_TXD")
	)
	(segment
		(start 76.46416 -167.357806)
		(end 76.46416 -167.710104)
		(width 0.1143)
		(layer "In7.Cu")
		(net "UART_T3_NODE3_TXD")
	)
	(segment
		(start 76.09332 -176.38776)
		(end 76.09332 -178.376326)
		(width 0.1143)
		(layer "In7.Cu")
		(net "UART_T3_NODE3_TXD")
	)
	(segment
		(start 76.76134 -169.789094)
		(end 76.76134 -175.71974)
		(width 0.1143)
		(layer "In7.Cu")
		(net "UART_T3_NODE3_TXD")
	)
	(segment
		(start 76.54544 -165.654482)
		(end 76.99756 -166.106602)
		(width 0.1143)
		(layer "In7.Cu")
		(net "UART_T3_NODE3_TXD")
	)
	(segment
		(start 76.09332 -178.376326)
		(end 75.58532 -178.884326)
		(width 0.1143)
		(layer "In7.Cu")
		(net "UART_T3_NODE3_TXD")
	)
	(segment
		(start 76.76134 -175.71974)
		(end 76.09332 -176.38776)
		(width 0.1143)
		(layer "In7.Cu")
		(net "UART_T3_NODE3_TXD")
	)
	(segment
		(start 76.99756 -166.106602)
		(end 76.99756 -166.824406)
		(width 0.1143)
		(layer "In7.Cu")
		(net "UART_T3_NODE3_TXD")
	)
	(segment
		(start 75.004676 -178.884326)
		(end 72.42302 -181.465982)
		(width 0.1143)
		(layer "In7.Cu")
		(net "UART_T3_NODE3_TXD")
	)
	(segment
		(start 76.99756 -166.824406)
		(end 76.46416 -167.357806)
		(width 0.1143)
		(layer "In7.Cu")
		(net "UART_T3_NODE3_TXD")
	)
	(segment
		(start 3.683 -154.48534)
		(end 3.929126 -154.731466)
		(width 0.1016)
		(layer "F.Cu")
		(net "UART_RX_P5")
	)
	(segment
		(start 123.62688 -40.38981)
		(end 122.451622 -40.38981)
		(width 0.1016)
		(layer "F.Cu")
		(net "UART_RX_P5")
	)
	(segment
		(start 5.06222 -154.731466)
		(end 5.34162 -155.010866)
		(width 0.1016)
		(layer "F.Cu")
		(net "UART_RX_P5")
	)
	(segment
		(start 124.00788 -40.00881)
		(end 123.62688 -40.38981)
		(width 0.1016)
		(layer "F.Cu")
		(net "UART_RX_P5")
	)
	(segment
		(start 3.683 -152.897078)
		(end 3.683 -154.48534)
		(width 0.1016)
		(layer "F.Cu")
		(net "UART_RX_P5")
	)
	(segment
		(start 3.929126 -154.731466)
		(end 5.06222 -154.731466)
		(width 0.1016)
		(layer "F.Cu")
		(net "UART_RX_P5")
	)
	(segment
		(start 5.208778 -157.33776)
		(end 5.208778 -158.220156)
		(width 0.1016)
		(layer "F.Cu")
		(net "UART_RX_P5")
	)
	(segment
		(start 5.34162 -157.204918)
		(end 5.208778 -157.33776)
		(width 0.1016)
		(layer "F.Cu")
		(net "UART_RX_P5")
	)
	(segment
		(start 5.34162 -155.010866)
		(end 5.34162 -157.204918)
		(width 0.1016)
		(layer "F.Cu")
		(net "UART_RX_P5")
	)
	(via
		(at 124.00788 -40.00881)
		(size 0.508)
		(drill 0.254)
		(layers "F.Cu" "B.Cu")
		(net "UART_RX_P5")
	)
	(via
		(at 34.36366 -22.266656)
		(size 0.508)
		(drill 0.254)
		(layers "F.Cu" "B.Cu")
		(net "UART_RX_P5")
	)
	(via
		(at 3.683 -152.897078)
		(size 0.508)
		(drill 0.254)
		(layers "F.Cu" "B.Cu")
		(net "UART_RX_P5")
	)
	(segment
		(start 16.02994 -89.986104)
		(end 3.67665 -102.339394)
		(width 0.1143)
		(layer "In2.Cu")
		(net "UART_RX_P5")
	)
	(segment
		(start 20.64512 -54.475888)
		(end 19.75866 -55.362348)
		(width 0.1143)
		(layer "In2.Cu")
		(net "UART_RX_P5")
	)
	(segment
		(start 34.36366 -22.650958)
		(end 33.72104 -23.62454)
		(width 0.1143)
		(layer "In2.Cu")
		(net "UART_RX_P5")
	)
	(segment
		(start 18.480786 -67.798188)
		(end 20.344892 -69.662294)
		(width 0.1143)
		(layer "In2.Cu")
		(net "UART_RX_P5")
	)
	(segment
		(start 25.4635 -38.35908)
		(end 22.10308 -41.7195)
		(width 0.1143)
		(layer "In2.Cu")
		(net "UART_RX_P5")
	)
	(segment
		(start 20.344892 -71.793608)
		(end 20.12442 -72.01408)
		(width 0.1143)
		(layer "In2.Cu")
		(net "UART_RX_P5")
	)
	(segment
		(start 3.88366 -144.387824)
		(end 3.88366 -151.676862)
		(width 0.1143)
		(layer "In2.Cu")
		(net "UART_RX_P5")
	)
	(segment
		(start 22.10308 -43.738038)
		(end 21.406612 -44.434506)
		(width 0.1143)
		(layer "In2.Cu")
		(net "UART_RX_P5")
	)
	(segment
		(start 20.12442 -81.66862)
		(end 16.02994 -85.7631)
		(width 0.1143)
		(layer "In2.Cu")
		(net "UART_RX_P5")
	)
	(segment
		(start 22.10308 -41.7195)
		(end 22.10308 -43.738038)
		(width 0.1143)
		(layer "In2.Cu")
		(net "UART_RX_P5")
	)
	(segment
		(start 33.72104 -23.62454)
		(end 33.72104 -26.29154)
		(width 0.1143)
		(layer "In2.Cu")
		(net "UART_RX_P5")
	)
	(segment
		(start 3.88366 -151.676862)
		(end 3.683 -152.897078)
		(width 0.1143)
		(layer "In2.Cu")
		(net "UART_RX_P5")
	)
	(segment
		(start 25.4635 -34.549334)
		(end 25.4635 -38.35908)
		(width 0.1143)
		(layer "In2.Cu")
		(net "UART_RX_P5")
	)
	(segment
		(start 3.67665 -144.180814)
		(end 3.88366 -144.387824)
		(width 0.1143)
		(layer "In2.Cu")
		(net "UART_RX_P5")
	)
	(segment
		(start 20.344892 -69.662294)
		(end 20.344892 -71.793608)
		(width 0.1143)
		(layer "In2.Cu")
		(net "UART_RX_P5")
	)
	(segment
		(start 16.02994 -85.7631)
		(end 16.02994 -89.986104)
		(width 0.1143)
		(layer "In2.Cu")
		(net "UART_RX_P5")
	)
	(segment
		(start 34.36366 -22.266656)
		(end 34.36366 -22.650958)
		(width 0.1143)
		(layer "In2.Cu")
		(net "UART_RX_P5")
	)
	(segment
		(start 20.64512 -50.760122)
		(end 20.64512 -54.475888)
		(width 0.1143)
		(layer "In2.Cu")
		(net "UART_RX_P5")
	)
	(segment
		(start 21.406612 -44.434506)
		(end 21.406612 -49.99863)
		(width 0.1143)
		(layer "In2.Cu")
		(net "UART_RX_P5")
	)
	(segment
		(start 33.72104 -26.29154)
		(end 33.71977 -26.293064)
		(width 0.1143)
		(layer "In2.Cu")
		(net "UART_RX_P5")
	)
	(segment
		(start 19.75866 -56.945276)
		(end 18.480786 -58.22315)
		(width 0.1143)
		(layer "In2.Cu")
		(net "UART_RX_P5")
	)
	(segment
		(start 19.75866 -55.362348)
		(end 19.75866 -56.945276)
		(width 0.1143)
		(layer "In2.Cu")
		(net "UART_RX_P5")
	)
	(segment
		(start 3.67665 -102.339394)
		(end 3.67665 -144.180814)
		(width 0.1143)
		(layer "In2.Cu")
		(net "UART_RX_P5")
	)
	(segment
		(start 21.406612 -49.99863)
		(end 20.64512 -50.760122)
		(width 0.1143)
		(layer "In2.Cu")
		(net "UART_RX_P5")
	)
	(segment
		(start 33.71977 -26.293064)
		(end 25.4635 -34.549334)
		(width 0.1143)
		(layer "In2.Cu")
		(net "UART_RX_P5")
	)
	(segment
		(start 20.12442 -72.01408)
		(end 20.12442 -81.66862)
		(width 0.1143)
		(layer "In2.Cu")
		(net "UART_RX_P5")
	)
	(segment
		(start 18.480786 -58.22315)
		(end 18.480786 -67.798188)
		(width 0.1143)
		(layer "In2.Cu")
		(net "UART_RX_P5")
	)
	(segment
		(start 40.74795 -19.962368)
		(end 39.47668 -21.233638)
		(width 0.1143)
		(layer "In6.Cu")
		(net "UART_RX_P5")
	)
	(segment
		(start 115.809522 -32.375856)
		(end 114.74958 -32.375856)
		(width 0.1143)
		(layer "In6.Cu")
		(net "UART_RX_P5")
	)
	(segment
		(start 114.00028 -31.626556)
		(end 114.00028 -29.35986)
		(width 0.1143)
		(layer "In6.Cu")
		(net "UART_RX_P5")
	)
	(segment
		(start 114.74958 -32.375856)
		(end 114.00028 -31.626556)
		(width 0.1143)
		(layer "In6.Cu")
		(net "UART_RX_P5")
	)
	(segment
		(start 123.442476 -40.00881)
		(end 115.809522 -32.375856)
		(width 0.1143)
		(layer "In6.Cu")
		(net "UART_RX_P5")
	)
	(segment
		(start 35.63747 -22.266656)
		(end 34.36366 -22.266656)
		(width 0.1143)
		(layer "In6.Cu")
		(net "UART_RX_P5")
	)
	(segment
		(start 105.401364 -19.962368)
		(end 40.74795 -19.962368)
		(width 0.1143)
		(layer "In6.Cu")
		(net "UART_RX_P5")
	)
	(segment
		(start 110.63732 -25.198324)
		(end 105.401364 -19.962368)
		(width 0.1143)
		(layer "In6.Cu")
		(net "UART_RX_P5")
	)
	(segment
		(start 114.00028 -29.35986)
		(end 110.63732 -25.9969)
		(width 0.1143)
		(layer "In6.Cu")
		(net "UART_RX_P5")
	)
	(segment
		(start 110.63732 -25.9969)
		(end 110.63732 -25.198324)
		(width 0.1143)
		(layer "In6.Cu")
		(net "UART_RX_P5")
	)
	(segment
		(start 36.1061 -21.798026)
		(end 35.63747 -22.266656)
		(width 0.1143)
		(layer "In6.Cu")
		(net "UART_RX_P5")
	)
	(segment
		(start 38.226238 -21.798026)
		(end 36.1061 -21.798026)
		(width 0.1143)
		(layer "In6.Cu")
		(net "UART_RX_P5")
	)
	(segment
		(start 124.00788 -40.00881)
		(end 123.442476 -40.00881)
		(width 0.1143)
		(layer "In6.Cu")
		(net "UART_RX_P5")
	)
	(segment
		(start 39.47668 -21.233638)
		(end 38.226238 -21.798026)
		(width 0.1143)
		(layer "In6.Cu")
		(net "UART_RX_P5")
	)
	(segment
		(start 76.90612 -167.539416)
		(end 76.904088 -167.539416)
		(width 0.1016)
		(layer "F.Cu")
		(net "UART_T3_NODE3_RXD")
	)
	(segment
		(start 76.994766 -164.374576)
		(end 76.994766 -165.233858)
		(width 0.1016)
		(layer "F.Cu")
		(net "UART_T3_NODE3_RXD")
	)
	(segment
		(start 76.994766 -165.233858)
		(end 76.97724 -165.251384)
		(width 0.1016)
		(layer "F.Cu")
		(net "UART_T3_NODE3_RXD")
	)
	(segment
		(start 76.97724 -167.468296)
		(end 76.90612 -167.539416)
		(width 0.1016)
		(layer "F.Cu")
		(net "UART_T3_NODE3_RXD")
	)
	(segment
		(start 76.97724 -165.251384)
		(end 76.97724 -167.468296)
		(width 0.1016)
		(layer "F.Cu")
		(net "UART_T3_NODE3_RXD")
	)
	(via
		(at 76.904088 -167.539416)
		(size 0.508)
		(drill 0.254)
		(layers "F.Cu" "B.Cu")
		(net "UART_T3_NODE3_RXD")
	)
	(via
		(at 71.58482 -183.434736)
		(size 0.508)
		(drill 0.254)
		(layers "F.Cu" "B.Cu")
		(net "UART_T3_NODE3_RXD")
	)
	(segment
		(start 70.97776 -187.647326)
		(end 70.52564 -187.195206)
		(width 0.1016)
		(layer "B.Cu")
		(net "UART_T3_NODE3_RXD")
	)
	(segment
		(start 71.66356 -184.970674)
		(end 71.10476 -185.529474)
		(width 0.1016)
		(layer "B.Cu")
		(net "UART_T3_NODE3_RXD")
	)
	(segment
		(start 71.58482 -183.434736)
		(end 71.58482 -183.617616)
		(width 0.1016)
		(layer "B.Cu")
		(net "UART_T3_NODE3_RXD")
	)
	(segment
		(start 70.97776 -187.726574)
		(end 70.97776 -187.647326)
		(width 0.1016)
		(layer "B.Cu")
		(net "UART_T3_NODE3_RXD")
	)
	(segment
		(start 71.58482 -183.617616)
		(end 71.66356 -183.696356)
		(width 0.1016)
		(layer "B.Cu")
		(net "UART_T3_NODE3_RXD")
	)
	(segment
		(start 71.66356 -183.696356)
		(end 71.66356 -184.970674)
		(width 0.1016)
		(layer "B.Cu")
		(net "UART_T3_NODE3_RXD")
	)
	(segment
		(start 70.52564 -186.108594)
		(end 71.10476 -185.529474)
		(width 0.1016)
		(layer "B.Cu")
		(net "UART_T3_NODE3_RXD")
	)
	(segment
		(start 70.52564 -187.195206)
		(end 70.52564 -186.108594)
		(width 0.1016)
		(layer "B.Cu")
		(net "UART_T3_NODE3_RXD")
	)
	(segment
		(start 76.904088 -167.658796)
		(end 76.904088 -167.539416)
		(width 0.1143)
		(layer "In7.Cu")
		(net "UART_T3_NODE3_RXD")
	)
	(segment
		(start 77.98054 -168.879774)
		(end 77.61478 -168.879774)
		(width 0.1143)
		(layer "In7.Cu")
		(net "UART_T3_NODE3_RXD")
	)
	(segment
		(start 75.412854 -180.936392)
		(end 78.25994 -178.089306)
		(width 0.1143)
		(layer "In7.Cu")
		(net "UART_T3_NODE3_RXD")
	)
	(segment
		(start 71.58482 -183.434736)
		(end 71.58482 -183.252364)
		(width 0.1143)
		(layer "In7.Cu")
		(net "UART_T3_NODE3_RXD")
	)
	(segment
		(start 75.02525 -180.936392)
		(end 75.412854 -180.936392)
		(width 0.1143)
		(layer "In7.Cu")
		(net "UART_T3_NODE3_RXD")
	)
	(segment
		(start 71.87057 -182.966614)
		(end 72.18172 -182.966614)
		(width 0.1143)
		(layer "In7.Cu")
		(net "UART_T3_NODE3_RXD")
	)
	(segment
		(start 77.360526 -168.62552)
		(end 77.360526 -168.115234)
		(width 0.1143)
		(layer "In7.Cu")
		(net "UART_T3_NODE3_RXD")
	)
	(segment
		(start 73.963784 -181.997858)
		(end 75.02525 -180.936392)
		(width 0.1143)
		(layer "In7.Cu")
		(net "UART_T3_NODE3_RXD")
	)
	(segment
		(start 71.58482 -183.252364)
		(end 71.87057 -182.966614)
		(width 0.1143)
		(layer "In7.Cu")
		(net "UART_T3_NODE3_RXD")
	)
	(segment
		(start 72.18172 -182.966614)
		(end 73.150476 -181.997858)
		(width 0.1143)
		(layer "In7.Cu")
		(net "UART_T3_NODE3_RXD")
	)
	(segment
		(start 73.150476 -181.997858)
		(end 73.963784 -181.997858)
		(width 0.1143)
		(layer "In7.Cu")
		(net "UART_T3_NODE3_RXD")
	)
	(segment
		(start 77.61478 -168.879774)
		(end 77.360526 -168.62552)
		(width 0.1143)
		(layer "In7.Cu")
		(net "UART_T3_NODE3_RXD")
	)
	(segment
		(start 78.25994 -178.089306)
		(end 78.25994 -169.159174)
		(width 0.1143)
		(layer "In7.Cu")
		(net "UART_T3_NODE3_RXD")
	)
	(segment
		(start 78.25994 -169.159174)
		(end 77.98054 -168.879774)
		(width 0.1143)
		(layer "In7.Cu")
		(net "UART_T3_NODE3_RXD")
	)
	(segment
		(start 77.360526 -168.115234)
		(end 76.904088 -167.658796)
		(width 0.1143)
		(layer "In7.Cu")
		(net "UART_T3_NODE3_RXD")
	)
	(segment
		(start 3.908806 -164.062156)
		(end 3.908806 -161.647124)
		(width 0.1016)
		(layer "F.Cu")
		(net "UART_DTR_P5_N")
	)
	(segment
		(start 127.26162 -45.95241)
		(end 127.26162 -47.199804)
		(width 0.1016)
		(layer "F.Cu")
		(net "UART_DTR_P5_N")
	)
	(segment
		(start 127.26416 -45.033438)
		(end 127.26416 -45.94987)
		(width 0.1016)
		(layer "F.Cu")
		(net "UART_DTR_P5_N")
	)
	(segment
		(start 3.507486 -161.245804)
		(end 3.506978 -161.245804)
		(width 0.1016)
		(layer "F.Cu")
		(net "UART_DTR_P5_N")
	)
	(segment
		(start 127.26416 -45.94987)
		(end 127.26162 -45.95241)
		(width 0.1016)
		(layer "F.Cu")
		(net "UART_DTR_P5_N")
	)
	(segment
		(start 3.908806 -161.647124)
		(end 3.507486 -161.245804)
		(width 0.1016)
		(layer "F.Cu")
		(net "UART_DTR_P5_N")
	)
	(via
		(at 31.87192 -23.155402)
		(size 0.508)
		(drill 0.254)
		(layers "F.Cu" "B.Cu")
		(net "UART_DTR_P5_N")
	)
	(via
		(at 3.506978 -161.245804)
		(size 0.508)
		(drill 0.254)
		(layers "F.Cu" "B.Cu")
		(net "UART_DTR_P5_N")
	)
	(via
		(at 127.26416 -45.033438)
		(size 0.508)
		(drill 0.254)
		(layers "F.Cu" "B.Cu")
		(net "UART_DTR_P5_N")
	)
	(segment
		(start 16.3068 -68.260214)
		(end 15.61338 -71.642732)
		(width 0.1143)
		(layer "In2.Cu")
		(net "UART_DTR_P5_N")
	)
	(segment
		(start 31.770574 -24.588216)
		(end 30.39618 -27.01544)
		(width 0.1143)
		(layer "In2.Cu")
		(net "UART_DTR_P5_N")
	)
	(segment
		(start 14.02842 -88.935052)
		(end 13.64234 -89.321386)
		(width 0.1143)
		(layer "In2.Cu")
		(net "UART_DTR_P5_N")
	)
	(segment
		(start 14.37005 -80.973422)
		(end 14.33068 -81.0133)
		(width 0.1143)
		(layer "In2.Cu")
		(net "UART_DTR_P5_N")
	)
	(segment
		(start 14.33068 -81.230978)
		(end 14.02842 -83.157314)
		(width 0.1143)
		(layer "In2.Cu")
		(net "UART_DTR_P5_N")
	)
	(segment
		(start 23.72868 -37.681154)
		(end 19.791934 -41.6179)
		(width 0.1143)
		(layer "In2.Cu")
		(net "UART_DTR_P5_N")
	)
	(segment
		(start 18.28038 -49.509426)
		(end 16.698468 -53.056282)
		(width 0.1143)
		(layer "In2.Cu")
		(net "UART_DTR_P5_N")
	)
	(segment
		(start 18.993358 -42.869104)
		(end 18.28038 -45.010832)
		(width 0.1143)
		(layer "In2.Cu")
		(net "UART_DTR_P5_N")
	)
	(segment
		(start 16.3068 -66.442844)
		(end 16.3068 -68.260214)
		(width 0.1143)
		(layer "In2.Cu")
		(net "UART_DTR_P5_N")
	)
	(segment
		(start 18.28038 -45.010832)
		(end 18.28038 -49.509426)
		(width 0.1143)
		(layer "In2.Cu")
		(net "UART_DTR_P5_N")
	)
	(segment
		(start 1.92405 -160.576768)
		(end 2.593086 -161.245804)
		(width 0.1143)
		(layer "In2.Cu")
		(net "UART_DTR_P5_N")
	)
	(segment
		(start 23.72868 -33.68294)
		(end 23.72868 -37.681154)
		(width 0.1143)
		(layer "In2.Cu")
		(net "UART_DTR_P5_N")
	)
	(segment
		(start 2.593086 -161.245804)
		(end 3.506978 -161.245804)
		(width 0.1143)
		(layer "In2.Cu")
		(net "UART_DTR_P5_N")
	)
	(segment
		(start 14.02842 -83.157314)
		(end 14.02842 -88.935052)
		(width 0.1143)
		(layer "In2.Cu")
		(net "UART_DTR_P5_N")
	)
	(segment
		(start 31.87192 -23.155402)
		(end 31.87192 -23.260812)
		(width 0.1143)
		(layer "In2.Cu")
		(net "UART_DTR_P5_N")
	)
	(segment
		(start 11.55954 -91.405964)
		(end 11.55954 -92.1258)
		(width 0.1143)
		(layer "In2.Cu")
		(net "UART_DTR_P5_N")
	)
	(segment
		(start 15.61338 -71.642732)
		(end 15.61338 -73.054718)
		(width 0.1143)
		(layer "In2.Cu")
		(net "UART_DTR_P5_N")
	)
	(segment
		(start 31.97225 -23.361142)
		(end 31.97225 -24.38654)
		(width 0.1143)
		(layer "In2.Cu")
		(net "UART_DTR_P5_N")
	)
	(segment
		(start 6.00583 -97.67951)
		(end 5.19684 -97.67951)
		(width 0.1143)
		(layer "In2.Cu")
		(net "UART_DTR_P5_N")
	)
	(segment
		(start 30.39618 -27.01544)
		(end 23.72868 -33.68294)
		(width 0.1143)
		(layer "In2.Cu")
		(net "UART_DTR_P5_N")
	)
	(segment
		(start 15.74546 -57.813194)
		(end 15.74546 -65.881504)
		(width 0.1143)
		(layer "In2.Cu")
		(net "UART_DTR_P5_N")
	)
	(segment
		(start 14.33068 -81.0133)
		(end 14.33068 -81.230978)
		(width 0.1143)
		(layer "In2.Cu")
		(net "UART_DTR_P5_N")
	)
	(segment
		(start 1.92405 -159.900366)
		(end 1.92405 -160.576768)
		(width 0.1143)
		(layer "In2.Cu")
		(net "UART_DTR_P5_N")
	)
	(segment
		(start 31.97225 -24.38654)
		(end 31.770574 -24.588216)
		(width 0.1143)
		(layer "In2.Cu")
		(net "UART_DTR_P5_N")
	)
	(segment
		(start 1.9558 -100.801424)
		(end 1.9558 -159.868616)
		(width 0.1143)
		(layer "In2.Cu")
		(net "UART_DTR_P5_N")
	)
	(segment
		(start 11.55954 -92.1258)
		(end 6.00583 -97.67951)
		(width 0.1143)
		(layer "In2.Cu")
		(net "UART_DTR_P5_N")
	)
	(segment
		(start 2.475484 -98.11004)
		(end 1.9558 -100.801424)
		(width 0.1143)
		(layer "In2.Cu")
		(net "UART_DTR_P5_N")
	)
	(segment
		(start 19.791934 -41.6179)
		(end 18.993358 -42.869104)
		(width 0.1143)
		(layer "In2.Cu")
		(net "UART_DTR_P5_N")
	)
	(segment
		(start 31.87192 -23.260812)
		(end 31.97225 -23.361142)
		(width 0.1143)
		(layer "In2.Cu")
		(net "UART_DTR_P5_N")
	)
	(segment
		(start 5.19684 -97.67951)
		(end 4.9403 -97.42297)
		(width 0.1143)
		(layer "In2.Cu")
		(net "UART_DTR_P5_N")
	)
	(segment
		(start 16.698468 -53.056282)
		(end 15.74546 -57.813194)
		(width 0.1143)
		(layer "In2.Cu")
		(net "UART_DTR_P5_N")
	)
	(segment
		(start 13.64234 -89.323164)
		(end 11.55954 -91.405964)
		(width 0.1143)
		(layer "In2.Cu")
		(net "UART_DTR_P5_N")
	)
	(segment
		(start 3.1623 -97.42297)
		(end 2.475484 -98.11004)
		(width 0.1143)
		(layer "In2.Cu")
		(net "UART_DTR_P5_N")
	)
	(segment
		(start 15.74546 -65.881504)
		(end 16.3068 -66.442844)
		(width 0.1143)
		(layer "In2.Cu")
		(net "UART_DTR_P5_N")
	)
	(segment
		(start 1.9558 -159.868616)
		(end 1.92405 -159.900366)
		(width 0.1143)
		(layer "In2.Cu")
		(net "UART_DTR_P5_N")
	)
	(segment
		(start 4.9403 -97.42297)
		(end 3.1623 -97.42297)
		(width 0.1143)
		(layer "In2.Cu")
		(net "UART_DTR_P5_N")
	)
	(segment
		(start 15.61338 -73.054718)
		(end 14.37005 -80.973422)
		(width 0.1143)
		(layer "In2.Cu")
		(net "UART_DTR_P5_N")
	)
	(segment
		(start 13.64234 -89.321386)
		(end 13.64234 -89.323164)
		(width 0.1143)
		(layer "In2.Cu")
		(net "UART_DTR_P5_N")
	)
	(segment
		(start 114.731292 -32.848042)
		(end 115.832636 -32.848042)
		(width 0.1143)
		(layer "In6.Cu")
		(net "UART_DTR_P5_N")
	)
	(segment
		(start 38.29558 -22.115526)
		(end 39.661084 -21.49983)
		(width 0.1143)
		(layer "In6.Cu")
		(net "UART_DTR_P5_N")
	)
	(segment
		(start 39.661084 -21.49983)
		(end 40.800528 -20.360386)
		(width 0.1143)
		(layer "In6.Cu")
		(net "UART_DTR_P5_N")
	)
	(segment
		(start 113.68278 -31.79953)
		(end 114.731292 -32.848042)
		(width 0.1143)
		(layer "In6.Cu")
		(net "UART_DTR_P5_N")
	)
	(segment
		(start 110.31982 -26.128472)
		(end 113.68278 -29.491432)
		(width 0.1143)
		(layer "In6.Cu")
		(net "UART_DTR_P5_N")
	)
	(segment
		(start 113.68278 -29.491432)
		(end 113.68278 -31.79953)
		(width 0.1143)
		(layer "In6.Cu")
		(net "UART_DTR_P5_N")
	)
	(segment
		(start 122.78868 -41.596564)
		(end 123.764548 -42.572432)
		(width 0.1143)
		(layer "In6.Cu")
		(net "UART_DTR_P5_N")
	)
	(segment
		(start 31.87192 -23.155402)
		(end 32.134302 -22.89302)
		(width 0.1143)
		(layer "In6.Cu")
		(net "UART_DTR_P5_N")
	)
	(segment
		(start 123.764548 -42.572432)
		(end 124.929138 -42.572432)
		(width 0.1143)
		(layer "In6.Cu")
		(net "UART_DTR_P5_N")
	)
	(segment
		(start 36.290758 -22.115526)
		(end 38.29558 -22.115526)
		(width 0.1143)
		(layer "In6.Cu")
		(net "UART_DTR_P5_N")
	)
	(segment
		(start 40.800528 -20.360386)
		(end 105.129584 -20.360386)
		(width 0.1143)
		(layer "In6.Cu")
		(net "UART_DTR_P5_N")
	)
	(segment
		(start 35.513264 -22.89302)
		(end 36.290758 -22.115526)
		(width 0.1143)
		(layer "In6.Cu")
		(net "UART_DTR_P5_N")
	)
	(segment
		(start 127.26416 -44.907454)
		(end 127.26416 -45.033438)
		(width 0.1143)
		(layer "In6.Cu")
		(net "UART_DTR_P5_N")
	)
	(segment
		(start 115.832636 -32.848042)
		(end 122.78868 -39.804086)
		(width 0.1143)
		(layer "In6.Cu")
		(net "UART_DTR_P5_N")
	)
	(segment
		(start 122.78868 -39.804086)
		(end 122.78868 -41.596564)
		(width 0.1143)
		(layer "In6.Cu")
		(net "UART_DTR_P5_N")
	)
	(segment
		(start 105.129584 -20.360386)
		(end 110.31982 -25.550622)
		(width 0.1143)
		(layer "In6.Cu")
		(net "UART_DTR_P5_N")
	)
	(segment
		(start 32.134302 -22.89302)
		(end 35.513264 -22.89302)
		(width 0.1143)
		(layer "In6.Cu")
		(net "UART_DTR_P5_N")
	)
	(segment
		(start 124.929138 -42.572432)
		(end 127.26416 -44.907454)
		(width 0.1143)
		(layer "In6.Cu")
		(net "UART_DTR_P5_N")
	)
	(segment
		(start 110.31982 -25.550622)
		(end 110.31982 -26.128472)
		(width 0.1143)
		(layer "In6.Cu")
		(net "UART_DTR_P5_N")
	)
	(via
		(at 80.310482 -163.726876)
		(size 0.6604)
		(drill 0.3302)
		(layers "F.Cu" "B.Cu")
		(net "CPLD_WDT2_R")
	)
	(segment
		(start 77.873098 -163.120832)
		(end 78.405482 -163.653216)
		(width 0.1016)
		(layer "B.Cu")
		(net "CPLD_WDT2_R")
	)
	(segment
		(start 80.81772 -164.234114)
		(end 80.81772 -164.876988)
		(width 0.1016)
		(layer "B.Cu")
		(net "CPLD_WDT2_R")
	)
	(segment
		(start 80.310482 -163.726876)
		(end 80.81772 -164.234114)
		(width 0.1016)
		(layer "B.Cu")
		(net "CPLD_WDT2_R")
	)
	(segment
		(start 80.81772 -164.876988)
		(end 80.944974 -165.004242)
		(width 0.1016)
		(layer "B.Cu")
		(net "CPLD_WDT2_R")
	)
	(segment
		(start 78.405482 -163.653216)
		(end 80.236822 -163.653216)
		(width 0.1016)
		(layer "B.Cu")
		(net "CPLD_WDT2_R")
	)
	(segment
		(start 80.944974 -165.004242)
		(end 81.906872 -165.004242)
		(width 0.1016)
		(layer "B.Cu")
		(net "CPLD_WDT2_R")
	)
	(segment
		(start 77.14615 -164.132768)
		(end 77.14615 -163.120832)
		(width 0.1016)
		(layer "B.Cu")
		(net "CPLD_WDT2_R")
	)
	(segment
		(start 80.236822 -163.653216)
		(end 80.310482 -163.726876)
		(width 0.1016)
		(layer "B.Cu")
		(net "CPLD_WDT2_R")
	)
	(segment
		(start 77.14615 -163.120832)
		(end 77.873098 -163.120832)
		(width 0.1016)
		(layer "B.Cu")
		(net "CPLD_WDT2_R")
	)
	(segment
		(start 75.994768 -168.302432)
		(end 76.42352 -168.731184)
		(width 0.1016)
		(layer "F.Cu")
		(net "UART_T3_NODE2_RXD")
	)
	(segment
		(start 75.994768 -164.374576)
		(end 75.994768 -168.302432)
		(width 0.1016)
		(layer "F.Cu")
		(net "UART_T3_NODE2_RXD")
	)
	(via
		(at 76.42352 -168.731184)
		(size 0.508)
		(drill 0.254)
		(layers "F.Cu" "B.Cu")
		(net "UART_T3_NODE2_RXD")
	)
	(via
		(at 73.42124 -183.437022)
		(size 0.508)
		(drill 0.254)
		(layers "F.Cu" "B.Cu")
		(net "UART_T3_NODE2_RXD")
	)
	(segment
		(start 73.42124 -183.437022)
		(end 73.273412 -183.58485)
		(width 0.1016)
		(layer "B.Cu")
		(net "UART_T3_NODE2_RXD")
	)
	(segment
		(start 73.00976 -187.726574)
		(end 73.00976 -187.341764)
		(width 0.1016)
		(layer "B.Cu")
		(net "UART_T3_NODE2_RXD")
	)
	(segment
		(start 72.6821 -184.920128)
		(end 73.31202 -185.550048)
		(width 0.1016)
		(layer "B.Cu")
		(net "UART_T3_NODE2_RXD")
	)
	(segment
		(start 73.252076 -183.58485)
		(end 72.6821 -184.154826)
		(width 0.1016)
		(layer "B.Cu")
		(net "UART_T3_NODE2_RXD")
	)
	(segment
		(start 72.74306 -186.119008)
		(end 73.31202 -185.550048)
		(width 0.1016)
		(layer "B.Cu")
		(net "UART_T3_NODE2_RXD")
	)
	(segment
		(start 73.273412 -183.58485)
		(end 73.252076 -183.58485)
		(width 0.1016)
		(layer "B.Cu")
		(net "UART_T3_NODE2_RXD")
	)
	(segment
		(start 72.74306 -187.075064)
		(end 72.74306 -186.119008)
		(width 0.1016)
		(layer "B.Cu")
		(net "UART_T3_NODE2_RXD")
	)
	(segment
		(start 72.6821 -184.154826)
		(end 72.6821 -184.920128)
		(width 0.1016)
		(layer "B.Cu")
		(net "UART_T3_NODE2_RXD")
	)
	(segment
		(start 73.00976 -187.341764)
		(end 72.74306 -187.075064)
		(width 0.1016)
		(layer "B.Cu")
		(net "UART_T3_NODE2_RXD")
	)
	(segment
		(start 77.18044 -178.469798)
		(end 77.18044 -169.759122)
		(width 0.1143)
		(layer "In7.Cu")
		(net "UART_T3_NODE2_RXD")
	)
	(segment
		(start 70.51294 -184.623964)
		(end 70.51294 -183.570626)
		(width 0.1143)
		(layer "In7.Cu")
		(net "UART_T3_NODE2_RXD")
	)
	(segment
		(start 73.42124 -183.437022)
		(end 72.91832 -183.939942)
		(width 0.1143)
		(layer "In7.Cu")
		(net "UART_T3_NODE2_RXD")
	)
	(segment
		(start 72.050148 -182.649114)
		(end 75.29195 -179.407312)
		(width 0.1143)
		(layer "In7.Cu")
		(net "UART_T3_NODE2_RXD")
	)
	(segment
		(start 76.42352 -169.002202)
		(end 76.42352 -168.731184)
		(width 0.1143)
		(layer "In7.Cu")
		(net "UART_T3_NODE2_RXD")
	)
	(segment
		(start 70.88632 -184.997344)
		(end 70.51294 -184.623964)
		(width 0.1143)
		(layer "In7.Cu")
		(net "UART_T3_NODE2_RXD")
	)
	(segment
		(start 72.91832 -183.939942)
		(end 72.91832 -184.628028)
		(width 0.1143)
		(layer "In7.Cu")
		(net "UART_T3_NODE2_RXD")
	)
	(segment
		(start 71.434452 -182.649114)
		(end 72.050148 -182.649114)
		(width 0.1143)
		(layer "In7.Cu")
		(net "UART_T3_NODE2_RXD")
	)
	(segment
		(start 77.18044 -169.759122)
		(end 76.42352 -169.002202)
		(width 0.1143)
		(layer "In7.Cu")
		(net "UART_T3_NODE2_RXD")
	)
	(segment
		(start 75.29195 -179.407312)
		(end 76.242926 -179.407312)
		(width 0.1143)
		(layer "In7.Cu")
		(net "UART_T3_NODE2_RXD")
	)
	(segment
		(start 72.91832 -184.628028)
		(end 72.549004 -184.997344)
		(width 0.1143)
		(layer "In7.Cu")
		(net "UART_T3_NODE2_RXD")
	)
	(segment
		(start 70.51294 -183.570626)
		(end 71.434452 -182.649114)
		(width 0.1143)
		(layer "In7.Cu")
		(net "UART_T3_NODE2_RXD")
	)
	(segment
		(start 76.242926 -179.407312)
		(end 77.18044 -178.469798)
		(width 0.1143)
		(layer "In7.Cu")
		(net "UART_T3_NODE2_RXD")
	)
	(segment
		(start 72.549004 -184.997344)
		(end 70.88632 -184.997344)
		(width 0.1143)
		(layer "In7.Cu")
		(net "UART_T3_NODE2_RXD")
	)
	(segment
		(start 120.38076 -177.562002)
		(end 119.829072 -177.010314)
		(width 0.1016)
		(layer "F.Cu")
		(net "N31328108")
	)
	(segment
		(start 119.49176 -175.826674)
		(end 119.49176 -176.673002)
		(width 0.1016)
		(layer "F.Cu")
		(net "N31328108")
	)
	(segment
		(start 120.38076 -178.613562)
		(end 120.38076 -177.562002)
		(width 0.1016)
		(layer "F.Cu")
		(net "N31328108")
	)
	(segment
		(start 119.49176 -176.673002)
		(end 119.829072 -177.010314)
		(width 0.1016)
		(layer "F.Cu")
		(net "N31328108")
	)
	(via
		(at 119.829072 -177.010314)
		(size 0.762)
		(drill 0.381)
		(layers "F.Cu" "B.Cu")
		(net "N31328108")
	)
	(segment
		(start 135.76173 -30.079696)
		(end 135.76173 -31.604966)
		(width 0.1016)
		(layer "F.Cu")
		(net "UART_RI_P6_N")
	)
	(segment
		(start 135.04037 -32.326326)
		(end 129.46634 -32.326326)
		(width 0.1016)
		(layer "F.Cu")
		(net "UART_RI_P6_N")
	)
	(segment
		(start 135.76173 -31.604966)
		(end 135.04037 -32.326326)
		(width 0.1016)
		(layer "F.Cu")
		(net "UART_RI_P6_N")
	)
	(via
		(at 129.46634 -32.326326)
		(size 0.508)
		(drill 0.254)
		(layers "F.Cu" "B.Cu")
		(net "UART_RI_P6_N")
	)
	(via
		(at 132.17398 -158.790132)
		(size 0.508)
		(drill 0.254)
		(layers "F.Cu" "B.Cu")
		(net "UART_RI_P6_N")
	)
	(segment
		(start 130.656838 -159.204914)
		(end 131.005072 -158.85668)
		(width 0.1016)
		(layer "B.Cu")
		(net "UART_RI_P6_N")
	)
	(segment
		(start 129.040128 -159.722566)
		(end 129.55778 -159.204914)
		(width 0.1016)
		(layer "B.Cu")
		(net "UART_RI_P6_N")
	)
	(segment
		(start 127.60706 -159.722566)
		(end 129.040128 -159.722566)
		(width 0.1016)
		(layer "B.Cu")
		(net "UART_RI_P6_N")
	)
	(segment
		(start 130.16611 -30.610048)
		(end 130.16611 -31.626556)
		(width 0.1016)
		(layer "B.Cu")
		(net "UART_RI_P6_N")
	)
	(segment
		(start 131.005072 -158.85668)
		(end 132.107432 -158.85668)
		(width 0.1016)
		(layer "B.Cu")
		(net "UART_RI_P6_N")
	)
	(segment
		(start 130.16611 -31.626556)
		(end 129.46634 -32.326326)
		(width 0.1016)
		(layer "B.Cu")
		(net "UART_RI_P6_N")
	)
	(segment
		(start 129.55778 -159.204914)
		(end 130.183382 -159.204914)
		(width 0.1016)
		(layer "B.Cu")
		(net "UART_RI_P6_N")
	)
	(segment
		(start 130.183382 -159.204914)
		(end 130.656838 -159.204914)
		(width 0.1016)
		(layer "B.Cu")
		(net "UART_RI_P6_N")
	)
	(segment
		(start 132.107432 -158.85668)
		(end 132.17398 -158.790132)
		(width 0.1016)
		(layer "B.Cu")
		(net "UART_RI_P6_N")
	)
	(segment
		(start 154.25674 -108.003594)
		(end 154.25674 -103.97236)
		(width 0.1143)
		(layer "In2.Cu")
		(net "UART_RI_P6_N")
	)
	(segment
		(start 129.46634 -40.141906)
		(end 129.46634 -32.326326)
		(width 0.1143)
		(layer "In2.Cu")
		(net "UART_RI_P6_N")
	)
	(segment
		(start 164.27831 -133.390386)
		(end 164.27831 -130.990848)
		(width 0.1143)
		(layer "In2.Cu")
		(net "UART_RI_P6_N")
	)
	(segment
		(start 158.640018 -133.7564)
		(end 163.912296 -133.7564)
		(width 0.1143)
		(layer "In2.Cu")
		(net "UART_RI_P6_N")
	)
	(segment
		(start 156.418534 -110.165388)
		(end 154.25674 -108.003594)
		(width 0.1143)
		(layer "In2.Cu")
		(net "UART_RI_P6_N")
	)
	(segment
		(start 150.6601 -144.34058)
		(end 150.95728 -144.0434)
		(width 0.1143)
		(layer "In2.Cu")
		(net "UART_RI_P6_N")
	)
	(segment
		(start 163.912296 -133.7564)
		(end 164.27831 -133.390386)
		(width 0.1143)
		(layer "In2.Cu")
		(net "UART_RI_P6_N")
	)
	(segment
		(start 159.291782 -110.165388)
		(end 156.418534 -110.165388)
		(width 0.1143)
		(layer "In2.Cu")
		(net "UART_RI_P6_N")
	)
	(segment
		(start 132.26796 -158.790132)
		(end 132.950712 -159.472884)
		(width 0.1143)
		(layer "In2.Cu")
		(net "UART_RI_P6_N")
	)
	(segment
		(start 150.33244 -149.839426)
		(end 150.33244 -145.191226)
		(width 0.1143)
		(layer "In2.Cu")
		(net "UART_RI_P6_N")
	)
	(segment
		(start 154.25674 -103.97236)
		(end 153.377392 -103.093012)
		(width 0.1143)
		(layer "In2.Cu")
		(net "UART_RI_P6_N")
	)
	(segment
		(start 163.6649 -114.538506)
		(end 159.291782 -110.165388)
		(width 0.1143)
		(layer "In2.Cu")
		(net "UART_RI_P6_N")
	)
	(segment
		(start 150.95728 -139.492736)
		(end 156.162248 -134.287768)
		(width 0.1143)
		(layer "In2.Cu")
		(net "UART_RI_P6_N")
	)
	(segment
		(start 150.95728 -144.0434)
		(end 150.95728 -139.492736)
		(width 0.1143)
		(layer "In2.Cu")
		(net "UART_RI_P6_N")
	)
	(segment
		(start 150.33244 -145.191226)
		(end 150.6601 -144.863566)
		(width 0.1143)
		(layer "In2.Cu")
		(net "UART_RI_P6_N")
	)
	(segment
		(start 132.17398 -158.790132)
		(end 132.26796 -158.790132)
		(width 0.1143)
		(layer "In2.Cu")
		(net "UART_RI_P6_N")
	)
	(segment
		(start 153.377392 -103.093012)
		(end 153.377392 -93.733874)
		(width 0.1143)
		(layer "In2.Cu")
		(net "UART_RI_P6_N")
	)
	(segment
		(start 156.162248 -134.287768)
		(end 158.10865 -134.287768)
		(width 0.1143)
		(layer "In2.Cu")
		(net "UART_RI_P6_N")
	)
	(segment
		(start 128.85547 -40.752776)
		(end 129.46634 -40.141906)
		(width 0.1143)
		(layer "In2.Cu")
		(net "UART_RI_P6_N")
	)
	(segment
		(start 134.89178 -75.248262)
		(end 134.89178 -74.479912)
		(width 0.1143)
		(layer "In2.Cu")
		(net "UART_RI_P6_N")
	)
	(segment
		(start 138.701526 -157.695646)
		(end 144.36852 -157.695646)
		(width 0.1143)
		(layer "In2.Cu")
		(net "UART_RI_P6_N")
	)
	(segment
		(start 164.27831 -130.990848)
		(end 163.6649 -130.377438)
		(width 0.1143)
		(layer "In2.Cu")
		(net "UART_RI_P6_N")
	)
	(segment
		(start 132.950712 -159.472884)
		(end 136.924288 -159.472884)
		(width 0.1143)
		(layer "In2.Cu")
		(net "UART_RI_P6_N")
	)
	(segment
		(start 136.924288 -159.472884)
		(end 138.701526 -157.695646)
		(width 0.1143)
		(layer "In2.Cu")
		(net "UART_RI_P6_N")
	)
	(segment
		(start 147.4216 -154.642566)
		(end 147.4216 -152.750266)
		(width 0.1143)
		(layer "In2.Cu")
		(net "UART_RI_P6_N")
	)
	(segment
		(start 127.61849 -66.22669)
		(end 127.61849 -52.091336)
		(width 0.1143)
		(layer "In2.Cu")
		(net "UART_RI_P6_N")
	)
	(segment
		(start 127.61849 -52.091336)
		(end 128.85547 -50.854356)
		(width 0.1143)
		(layer "In2.Cu")
		(net "UART_RI_P6_N")
	)
	(segment
		(start 128.85547 -50.854356)
		(end 128.85547 -40.752776)
		(width 0.1143)
		(layer "In2.Cu")
		(net "UART_RI_P6_N")
	)
	(segment
		(start 132.52958 -72.117712)
		(end 132.52958 -71.13778)
		(width 0.1143)
		(layer "In2.Cu")
		(net "UART_RI_P6_N")
	)
	(segment
		(start 134.89178 -74.479912)
		(end 132.52958 -72.117712)
		(width 0.1143)
		(layer "In2.Cu")
		(net "UART_RI_P6_N")
	)
	(segment
		(start 150.6601 -144.863566)
		(end 150.6601 -144.34058)
		(width 0.1143)
		(layer "In2.Cu")
		(net "UART_RI_P6_N")
	)
	(segment
		(start 158.10865 -134.287768)
		(end 158.640018 -133.7564)
		(width 0.1143)
		(layer "In2.Cu")
		(net "UART_RI_P6_N")
	)
	(segment
		(start 153.377392 -93.733874)
		(end 134.89178 -75.248262)
		(width 0.1143)
		(layer "In2.Cu")
		(net "UART_RI_P6_N")
	)
	(segment
		(start 163.6649 -130.377438)
		(end 163.6649 -114.538506)
		(width 0.1143)
		(layer "In2.Cu")
		(net "UART_RI_P6_N")
	)
	(segment
		(start 132.52958 -71.13778)
		(end 127.61849 -66.22669)
		(width 0.1143)
		(layer "In2.Cu")
		(net "UART_RI_P6_N")
	)
	(segment
		(start 147.4216 -152.750266)
		(end 150.33244 -149.839426)
		(width 0.1143)
		(layer "In2.Cu")
		(net "UART_RI_P6_N")
	)
	(segment
		(start 144.36852 -157.695646)
		(end 147.4216 -154.642566)
		(width 0.1143)
		(layer "In2.Cu")
		(net "UART_RI_P6_N")
	)
	(segment
		(start 118.34876 -176.862994)
		(end 118.537482 -177.051716)
		(width 0.1016)
		(layer "F.Cu")
		(net "N31328107")
	)
	(segment
		(start 118.72976 -178.613562)
		(end 118.72976 -177.243994)
		(width 0.1016)
		(layer "F.Cu")
		(net "N31328107")
	)
	(segment
		(start 118.34876 -175.826674)
		(end 118.34876 -176.862994)
		(width 0.1016)
		(layer "F.Cu")
		(net "N31328107")
	)
	(segment
		(start 118.72976 -177.243994)
		(end 118.537482 -177.051716)
		(width 0.1016)
		(layer "F.Cu")
		(net "N31328107")
	)
	(via
		(at 118.537482 -177.051716)
		(size 0.762)
		(drill 0.381)
		(layers "F.Cu" "B.Cu")
		(net "N31328107")
	)
	(segment
		(start 75.538076 -166.886382)
		(end 75.538076 -166.346124)
		(width 0.1016)
		(layer "F.Cu")
		(net "UART_T3_NODE2_TXD")
	)
	(segment
		(start 75.494642 -166.30269)
		(end 75.494642 -164.374576)
		(width 0.1016)
		(layer "F.Cu")
		(net "UART_T3_NODE2_TXD")
	)
	(segment
		(start 75.538076 -166.346124)
		(end 75.494642 -166.30269)
		(width 0.1016)
		(layer "F.Cu")
		(net "UART_T3_NODE2_TXD")
	)
	(via
		(at 75.538076 -166.886382)
		(size 0.508)
		(drill 0.254)
		(layers "F.Cu" "B.Cu")
		(net "UART_T3_NODE2_TXD")
	)
	(segment
		(start 75.299062 -166.647368)
		(end 75.538076 -166.886382)
		(width 0.1016)
		(layer "B.Cu")
		(net "UART_T3_NODE2_TXD")
	)
	(segment
		(start 75.299062 -165.696646)
		(end 75.299062 -166.647368)
		(width 0.1016)
		(layer "B.Cu")
		(net "UART_T3_NODE2_TXD")
	)
	(segment
		(start 120.63476 -176.440846)
		(end 121.211086 -177.017172)
		(width 0.1016)
		(layer "F.Cu")
		(net "N31328106")
	)
	(segment
		(start 122.03176 -177.837846)
		(end 121.211086 -177.017172)
		(width 0.1016)
		(layer "F.Cu")
		(net "N31328106")
	)
	(segment
		(start 120.63476 -175.826674)
		(end 120.63476 -176.440846)
		(width 0.1016)
		(layer "F.Cu")
		(net "N31328106")
	)
	(segment
		(start 122.03176 -178.613562)
		(end 122.03176 -177.837846)
		(width 0.1016)
		(layer "F.Cu")
		(net "N31328106")
	)
	(via
		(at 121.211086 -177.017172)
		(size 0.762)
		(drill 0.381)
		(layers "F.Cu" "B.Cu")
		(net "N31328106")
	)
	(segment
		(start 74.670666 -169.12463)
		(end 75.13828 -169.592244)
		(width 0.1016)
		(layer "F.Cu")
		(net "CPLD_WDT2")
	)
	(segment
		(start 75.13828 -169.592244)
		(end 75.13828 -172.6184)
		(width 0.1016)
		(layer "F.Cu")
		(net "CPLD_WDT2")
	)
	(segment
		(start 129.775712 -168.10863)
		(end 130.947414 -168.10863)
		(width 0.1016)
		(layer "F.Cu")
		(net "CPLD_WDT2")
	)
	(segment
		(start 75.13828 -172.6184)
		(end 74.41438 -173.3423)
		(width 0.1016)
		(layer "F.Cu")
		(net "CPLD_WDT2")
	)
	(segment
		(start 73.49871 -169.12463)
		(end 74.670666 -169.12463)
		(width 0.1016)
		(layer "F.Cu")
		(net "CPLD_WDT2")
	)
	(segment
		(start 72.244712 -169.12463)
		(end 73.49871 -169.12463)
		(width 0.1016)
		(layer "F.Cu")
		(net "CPLD_WDT2")
	)
	(via
		(at 95.7834 -177.093372)
		(size 0.508)
		(drill 0.254)
		(layers "F.Cu" "B.Cu")
		(net "CPLD_WDT2")
	)
	(via
		(at 101.438202 -166.011352)
		(size 0.508)
		(drill 0.254)
		(layers "F.Cu" "B.Cu")
		(net "CPLD_WDT2")
	)
	(via
		(at 73.49871 -169.12463)
		(size 0.508)
		(drill 0.254)
		(layers "F.Cu" "B.Cu")
		(net "CPLD_WDT2")
	)
	(via
		(at 74.41438 -173.3423)
		(size 0.508)
		(drill 0.254)
		(layers "F.Cu" "B.Cu")
		(net "CPLD_WDT2")
	)
	(via
		(at 130.947414 -168.10863)
		(size 0.508)
		(drill 0.254)
		(layers "F.Cu" "B.Cu")
		(net "CPLD_WDT2")
	)
	(segment
		(start 72.643238 -164.478462)
		(end 72.643238 -168.269158)
		(width 0.1016)
		(layer "B.Cu")
		(net "CPLD_WDT2")
	)
	(segment
		(start 97.062036 -181.672992)
		(end 97.620582 -181.672992)
		(width 0.1016)
		(layer "B.Cu")
		(net "CPLD_WDT2")
	)
	(segment
		(start 94.07144 -178.799998)
		(end 94.07144 -179.564792)
		(width 0.1016)
		(layer "B.Cu")
		(net "CPLD_WDT2")
	)
	(segment
		(start 94.21368 -181.458108)
		(end 94.21368 -181.699154)
		(width 0.1016)
		(layer "B.Cu")
		(net "CPLD_WDT2")
	)
	(segment
		(start 76.34605 -164.132768)
		(end 75.508104 -164.132768)
		(width 0.1016)
		(layer "B.Cu")
		(net "CPLD_WDT2")
	)
	(segment
		(start 72.643238 -168.269158)
		(end 73.49871 -169.12463)
		(width 0.1016)
		(layer "B.Cu")
		(net "CPLD_WDT2")
	)
	(segment
		(start 96.610424 -182.124604)
		(end 97.062036 -181.672992)
		(width 0.1016)
		(layer "B.Cu")
		(net "CPLD_WDT2")
	)
	(segment
		(start 95.7834 -177.093372)
		(end 95.778066 -177.093372)
		(width 0.1016)
		(layer "B.Cu")
		(net "CPLD_WDT2")
	)
	(segment
		(start 95.778066 -177.093372)
		(end 94.07144 -178.799998)
		(width 0.1016)
		(layer "B.Cu")
		(net "CPLD_WDT2")
	)
	(segment
		(start 75.404218 -164.028882)
		(end 73.092818 -164.028882)
		(width 0.1016)
		(layer "B.Cu")
		(net "CPLD_WDT2")
	)
	(segment
		(start 73.092818 -164.028882)
		(end 72.643238 -164.478462)
		(width 0.1016)
		(layer "B.Cu")
		(net "CPLD_WDT2")
	)
	(segment
		(start 94.21368 -181.699154)
		(end 94.63913 -182.124604)
		(width 0.1016)
		(layer "B.Cu")
		(net "CPLD_WDT2")
	)
	(segment
		(start 94.63913 -182.124604)
		(end 96.610424 -182.124604)
		(width 0.1016)
		(layer "B.Cu")
		(net "CPLD_WDT2")
	)
	(segment
		(start 94.07144 -179.564792)
		(end 93.76918 -179.867052)
		(width 0.1016)
		(layer "B.Cu")
		(net "CPLD_WDT2")
	)
	(segment
		(start 93.76918 -181.013608)
		(end 94.21368 -181.458108)
		(width 0.1016)
		(layer "B.Cu")
		(net "CPLD_WDT2")
	)
	(segment
		(start 75.508104 -164.132768)
		(end 75.404218 -164.028882)
		(width 0.1016)
		(layer "B.Cu")
		(net "CPLD_WDT2")
	)
	(segment
		(start 93.76918 -179.867052)
		(end 93.76918 -181.013608)
		(width 0.1016)
		(layer "B.Cu")
		(net "CPLD_WDT2")
	)
	(segment
		(start 95.628206 -176.938178)
		(end 95.7834 -177.093372)
		(width 0.1143)
		(layer "In6.Cu")
		(net "CPLD_WDT2")
	)
	(segment
		(start 84.9249 -174.971202)
		(end 85.20557 -175.251872)
		(width 0.1143)
		(layer "In6.Cu")
		(net "CPLD_WDT2")
	)
	(segment
		(start 76.705206 -171.051474)
		(end 78.59395 -171.051474)
		(width 0.1143)
		(layer "In6.Cu")
		(net "CPLD_WDT2")
	)
	(segment
		(start 82.513678 -174.971202)
		(end 84.9249 -174.971202)
		(width 0.1143)
		(layer "In6.Cu")
		(net "CPLD_WDT2")
	)
	(segment
		(start 78.59395 -171.051474)
		(end 82.513678 -174.971202)
		(width 0.1143)
		(layer "In6.Cu")
		(net "CPLD_WDT2")
	)
	(segment
		(start 85.20557 -175.251872)
		(end 88.35771 -175.251872)
		(width 0.1143)
		(layer "In6.Cu")
		(net "CPLD_WDT2")
	)
	(segment
		(start 74.41438 -173.3423)
		(end 76.705206 -171.051474)
		(width 0.1143)
		(layer "In6.Cu")
		(net "CPLD_WDT2")
	)
	(segment
		(start 90.1065 -177.000662)
		(end 92.088208 -177.000662)
		(width 0.1143)
		(layer "In6.Cu")
		(net "CPLD_WDT2")
	)
	(segment
		(start 92.088208 -177.000662)
		(end 92.150692 -176.938178)
		(width 0.1143)
		(layer "In6.Cu")
		(net "CPLD_WDT2")
	)
	(segment
		(start 92.150692 -176.938178)
		(end 95.628206 -176.938178)
		(width 0.1143)
		(layer "In6.Cu")
		(net "CPLD_WDT2")
	)
	(segment
		(start 88.35771 -175.251872)
		(end 90.1065 -177.000662)
		(width 0.1143)
		(layer "In6.Cu")
		(net "CPLD_WDT2")
	)
	(segment
		(start 100.83038 -165.40353)
		(end 101.438202 -166.011352)
		(width 0.1143)
		(layer "In7.Cu")
		(net "CPLD_WDT2")
	)
	(segment
		(start 73.011284 -166.332408)
		(end 74.992484 -164.351208)
		(width 0.1143)
		(layer "In7.Cu")
		(net "CPLD_WDT2")
	)
	(segment
		(start 79.72552 -164.351208)
		(end 80.70088 -163.375848)
		(width 0.1143)
		(layer "In7.Cu")
		(net "CPLD_WDT2")
	)
	(segment
		(start 107.74553 -165.72992)
		(end 110.76432 -165.72992)
		(width 0.1143)
		(layer "In7.Cu")
		(net "CPLD_WDT2")
	)
	(segment
		(start 88.12657 -163.57854)
		(end 89.04224 -163.57854)
		(width 0.1143)
		(layer "In7.Cu")
		(net "CPLD_WDT2")
	)
	(segment
		(start 89.18448 -163.4363)
		(end 95.522542 -163.4363)
		(width 0.1143)
		(layer "In7.Cu")
		(net "CPLD_WDT2")
	)
	(segment
		(start 111.125 -166.0906)
		(end 114.046 -166.0906)
		(width 0.1143)
		(layer "In7.Cu")
		(net "CPLD_WDT2")
	)
	(segment
		(start 110.76432 -165.72992)
		(end 111.125 -166.0906)
		(width 0.1143)
		(layer "In7.Cu")
		(net "CPLD_WDT2")
	)
	(segment
		(start 126.07036 -168.123362)
		(end 126.085092 -168.10863)
		(width 0.1143)
		(layer "In7.Cu")
		(net "CPLD_WDT2")
	)
	(segment
		(start 103.93172 -166.011352)
		(end 104.209596 -166.289228)
		(width 0.1143)
		(layer "In7.Cu")
		(net "CPLD_WDT2")
	)
	(segment
		(start 101.438202 -166.011352)
		(end 103.93172 -166.011352)
		(width 0.1143)
		(layer "In7.Cu")
		(net "CPLD_WDT2")
	)
	(segment
		(start 123.249436 -165.890448)
		(end 125.48235 -168.123362)
		(width 0.1143)
		(layer "In7.Cu")
		(net "CPLD_WDT2")
	)
	(segment
		(start 118.53418 -165.72992)
		(end 118.89613 -166.09187)
		(width 0.1143)
		(layer "In7.Cu")
		(net "CPLD_WDT2")
	)
	(segment
		(start 74.992484 -164.351208)
		(end 79.72552 -164.351208)
		(width 0.1143)
		(layer "In7.Cu")
		(net "CPLD_WDT2")
	)
	(segment
		(start 125.48235 -168.123362)
		(end 126.07036 -168.123362)
		(width 0.1143)
		(layer "In7.Cu")
		(net "CPLD_WDT2")
	)
	(segment
		(start 104.572816 -166.289228)
		(end 105.506266 -165.355778)
		(width 0.1143)
		(layer "In7.Cu")
		(net "CPLD_WDT2")
	)
	(segment
		(start 114.4016 -165.72992)
		(end 118.53418 -165.72992)
		(width 0.1143)
		(layer "In7.Cu")
		(net "CPLD_WDT2")
	)
	(segment
		(start 119.25935 -166.09187)
		(end 119.460772 -165.890448)
		(width 0.1143)
		(layer "In7.Cu")
		(net "CPLD_WDT2")
	)
	(segment
		(start 104.209596 -166.289228)
		(end 104.572816 -166.289228)
		(width 0.1143)
		(layer "In7.Cu")
		(net "CPLD_WDT2")
	)
	(segment
		(start 73.011284 -168.637204)
		(end 73.011284 -166.332408)
		(width 0.1143)
		(layer "In7.Cu")
		(net "CPLD_WDT2")
	)
	(segment
		(start 126.085092 -168.10863)
		(end 130.947414 -168.10863)
		(width 0.1143)
		(layer "In7.Cu")
		(net "CPLD_WDT2")
	)
	(segment
		(start 114.1476 -165.98392)
		(end 114.4016 -165.72992)
		(width 0.1143)
		(layer "In7.Cu")
		(net "CPLD_WDT2")
	)
	(segment
		(start 80.70088 -163.18865)
		(end 82.261964 -161.627566)
		(width 0.1143)
		(layer "In7.Cu")
		(net "CPLD_WDT2")
	)
	(segment
		(start 80.70088 -163.375848)
		(end 80.70088 -163.18865)
		(width 0.1143)
		(layer "In7.Cu")
		(net "CPLD_WDT2")
	)
	(segment
		(start 97.489772 -165.40353)
		(end 100.83038 -165.40353)
		(width 0.1143)
		(layer "In7.Cu")
		(net "CPLD_WDT2")
	)
	(segment
		(start 95.522542 -163.4363)
		(end 97.489772 -165.40353)
		(width 0.1143)
		(layer "In7.Cu")
		(net "CPLD_WDT2")
	)
	(segment
		(start 119.460772 -165.890448)
		(end 123.249436 -165.890448)
		(width 0.1143)
		(layer "In7.Cu")
		(net "CPLD_WDT2")
	)
	(segment
		(start 107.371388 -165.355778)
		(end 107.74553 -165.72992)
		(width 0.1143)
		(layer "In7.Cu")
		(net "CPLD_WDT2")
	)
	(segment
		(start 105.506266 -165.355778)
		(end 107.371388 -165.355778)
		(width 0.1143)
		(layer "In7.Cu")
		(net "CPLD_WDT2")
	)
	(segment
		(start 86.88578 -162.33775)
		(end 88.12657 -163.57854)
		(width 0.1143)
		(layer "In7.Cu")
		(net "CPLD_WDT2")
	)
	(segment
		(start 86.88578 -161.885376)
		(end 86.88578 -162.33775)
		(width 0.1143)
		(layer "In7.Cu")
		(net "CPLD_WDT2")
	)
	(segment
		(start 89.04224 -163.57854)
		(end 89.18448 -163.4363)
		(width 0.1143)
		(layer "In7.Cu")
		(net "CPLD_WDT2")
	)
	(segment
		(start 114.1476 -165.989)
		(end 114.1476 -165.98392)
		(width 0.1143)
		(layer "In7.Cu")
		(net "CPLD_WDT2")
	)
	(segment
		(start 73.49871 -169.12463)
		(end 73.011284 -168.637204)
		(width 0.1143)
		(layer "In7.Cu")
		(net "CPLD_WDT2")
	)
	(segment
		(start 86.62797 -161.627566)
		(end 86.88578 -161.885376)
		(width 0.1143)
		(layer "In7.Cu")
		(net "CPLD_WDT2")
	)
	(segment
		(start 82.261964 -161.627566)
		(end 86.62797 -161.627566)
		(width 0.1143)
		(layer "In7.Cu")
		(net "CPLD_WDT2")
	)
	(segment
		(start 118.89613 -166.09187)
		(end 119.25935 -166.09187)
		(width 0.1143)
		(layer "In7.Cu")
		(net "CPLD_WDT2")
	)
	(segment
		(start 114.046 -166.0906)
		(end 114.1476 -165.989)
		(width 0.1143)
		(layer "In7.Cu")
		(net "CPLD_WDT2")
	)
	(segment
		(start 111.696246 -130.247898)
		(end 111.696246 -130.572256)
		(width 0.254)
		(layer "F.Cu")
		(net "VR_PVCCP_NODE1_TONSET_R")
	)
	(segment
		(start 112.73663 -130.24739)
		(end 112.736122 -130.247898)
		(width 0.254)
		(layer "F.Cu")
		(net "VR_PVCCP_NODE1_TONSET_R")
	)
	(segment
		(start 112.736122 -130.247898)
		(end 111.696246 -130.247898)
		(width 0.254)
		(layer "F.Cu")
		(net "VR_PVCCP_NODE1_TONSET_R")
	)
	(segment
		(start 111.699548 -130.575558)
		(end 111.699548 -130.94716)
		(width 0.254)
		(layer "F.Cu")
		(net "VR_PVCCP_NODE1_TONSET_R")
	)
	(segment
		(start 111.696246 -130.572256)
		(end 111.699548 -130.575558)
		(width 0.254)
		(layer "F.Cu")
		(net "VR_PVCCP_NODE1_TONSET_R")
	)
	(segment
		(start 111.699548 -130.94716)
		(end 111.699548 -131.598924)
		(width 0.254)
		(layer "F.Cu")
		(net "VR_PVCCP_NODE1_TONSET_R")
	)
	(via
		(at 111.699548 -130.94716)
		(size 0.508)
		(drill 0.254)
		(layers "F.Cu" "B.Cu")
		(net "VR_PVCCP_NODE1_TONSET_R")
	)
	(segment
		(start 45.572426 -170.336972)
		(end 43.47972 -172.429678)
		(width 0.1016)
		(layer "F.Cu")
		(net "PSU_DC_OK_N")
	)
	(segment
		(start 63.868554 -177.15611)
		(end 64.399668 -177.687224)
		(width 0.1016)
		(layer "F.Cu")
		(net "PSU_DC_OK_N")
	)
	(segment
		(start 50.5206 -177.687224)
		(end 50.099722 -177.266346)
		(width 0.1016)
		(layer "F.Cu")
		(net "PSU_DC_OK_N")
	)
	(segment
		(start 47.60976 -177.687224)
		(end 47.615348 -177.681636)
		(width 0.1016)
		(layer "F.Cu")
		(net "PSU_DC_OK_N")
	)
	(segment
		(start 65.77076 -177.687224)
		(end 65.783714 -177.67427)
		(width 0.1016)
		(layer "F.Cu")
		(net "PSU_DC_OK_N")
	)
	(segment
		(start 47.615348 -177.681636)
		(end 47.615348 -176.247298)
		(width 0.1016)
		(layer "F.Cu")
		(net "PSU_DC_OK_N")
	)
	(segment
		(start 53.907944 -177.687224)
		(end 53.653944 -177.433224)
		(width 0.1016)
		(layer "F.Cu")
		(net "PSU_DC_OK_N")
	)
	(segment
		(start 47.88789 -176.221136)
		(end 47.64151 -176.221136)
		(width 0.1016)
		(layer "F.Cu")
		(net "PSU_DC_OK_N")
	)
	(segment
		(start 47.64151 -176.221136)
		(end 47.615348 -176.247298)
		(width 0.1016)
		(layer "F.Cu")
		(net "PSU_DC_OK_N")
	)
	(segment
		(start 51.16576 -177.687224)
		(end 50.5206 -177.687224)
		(width 0.1016)
		(layer "F.Cu")
		(net "PSU_DC_OK_N")
	)
	(segment
		(start 43.47972 -172.429678)
		(end 43.47972 -172.600366)
		(width 0.1016)
		(layer "F.Cu")
		(net "PSU_DC_OK_N")
	)
	(segment
		(start 65.783714 -177.67427)
		(end 65.783714 -176.26203)
		(width 0.1016)
		(layer "F.Cu")
		(net "PSU_DC_OK_N")
	)
	(segment
		(start 61.566552 -177.687224)
		(end 60.727336 -176.848008)
		(width 0.1016)
		(layer "F.Cu")
		(net "PSU_DC_OK_N")
	)
	(segment
		(start 58.40476 -177.687224)
		(end 58.875422 -177.687224)
		(width 0.1016)
		(layer "F.Cu")
		(net "PSU_DC_OK_N")
	)
	(segment
		(start 58.875422 -177.687224)
		(end 59.424316 -177.13833)
		(width 0.1016)
		(layer "F.Cu")
		(net "PSU_DC_OK_N")
	)
	(segment
		(start 48.35525 -176.688496)
		(end 47.88789 -176.221136)
		(width 0.1016)
		(layer "F.Cu")
		(net "PSU_DC_OK_N")
	)
	(segment
		(start 64.399668 -177.687224)
		(end 65.77076 -177.687224)
		(width 0.1016)
		(layer "F.Cu")
		(net "PSU_DC_OK_N")
	)
	(segment
		(start 45.572426 -169.625264)
		(end 45.572426 -170.336972)
		(width 0.1016)
		(layer "F.Cu")
		(net "PSU_DC_OK_N")
	)
	(segment
		(start 54.72176 -177.687224)
		(end 53.907944 -177.687224)
		(width 0.1016)
		(layer "F.Cu")
		(net "PSU_DC_OK_N")
	)
	(segment
		(start 62.08776 -177.687224)
		(end 61.566552 -177.687224)
		(width 0.1016)
		(layer "F.Cu")
		(net "PSU_DC_OK_N")
	)
	(segment
		(start 43.47972 -173.68901)
		(end 43.47972 -172.600366)
		(width 0.1016)
		(layer "F.Cu")
		(net "PSU_DC_OK_N")
	)
	(segment
		(start 53.653944 -177.433224)
		(end 53.653944 -176.678844)
		(width 0.1016)
		(layer "F.Cu")
		(net "PSU_DC_OK_N")
	)
	(via
		(at 43.47972 -173.68901)
		(size 0.508)
		(drill 0.254)
		(layers "F.Cu" "B.Cu")
		(net "PSU_DC_OK_N")
	)
	(via
		(at 63.868554 -177.15611)
		(size 0.508)
		(drill 0.254)
		(layers "F.Cu" "B.Cu")
		(net "PSU_DC_OK_N")
	)
	(via
		(at 60.727336 -176.848008)
		(size 0.508)
		(drill 0.254)
		(layers "F.Cu" "B.Cu")
		(net "PSU_DC_OK_N")
	)
	(via
		(at 59.424316 -177.13833)
		(size 0.508)
		(drill 0.254)
		(layers "F.Cu" "B.Cu")
		(net "PSU_DC_OK_N")
	)
	(via
		(at 50.099722 -177.266346)
		(size 0.508)
		(drill 0.254)
		(layers "F.Cu" "B.Cu")
		(net "PSU_DC_OK_N")
	)
	(via
		(at 53.653944 -176.678844)
		(size 0.508)
		(drill 0.254)
		(layers "F.Cu" "B.Cu")
		(net "PSU_DC_OK_N")
	)
	(via
		(at 48.35525 -176.688496)
		(size 0.508)
		(drill 0.254)
		(layers "F.Cu" "B.Cu")
		(net "PSU_DC_OK_N")
	)
	(segment
		(start 47.84852 -176.688496)
		(end 48.35525 -176.688496)
		(width 0.1016)
		(layer "B.Cu")
		(net "PSU_DC_OK_N")
	)
	(segment
		(start 44.849034 -173.68901)
		(end 47.84852 -176.688496)
		(width 0.1016)
		(layer "B.Cu")
		(net "PSU_DC_OK_N")
	)
	(segment
		(start 43.47972 -173.68901)
		(end 44.849034 -173.68901)
		(width 0.1016)
		(layer "B.Cu")
		(net "PSU_DC_OK_N")
	)
	(segment
		(start 53.653944 -176.678844)
		(end 55.353966 -178.378866)
		(width 0.1143)
		(layer "In6.Cu")
		(net "PSU_DC_OK_N")
	)
	(segment
		(start 60.727336 -176.848008)
		(end 61.035438 -177.15611)
		(width 0.1143)
		(layer "In6.Cu")
		(net "PSU_DC_OK_N")
	)
	(segment
		(start 59.174634 -177.13833)
		(end 59.424316 -177.13833)
		(width 0.1143)
		(layer "In6.Cu")
		(net "PSU_DC_OK_N")
	)
	(segment
		(start 60.727336 -176.84877)
		(end 60.727336 -176.848008)
		(width 0.1143)
		(layer "In6.Cu")
		(net "PSU_DC_OK_N")
	)
	(segment
		(start 49.696624 -177.266346)
		(end 50.099722 -177.266346)
		(width 0.1143)
		(layer "In6.Cu")
		(net "PSU_DC_OK_N")
	)
	(segment
		(start 61.035438 -177.15611)
		(end 63.868554 -177.15611)
		(width 0.1143)
		(layer "In6.Cu")
		(net "PSU_DC_OK_N")
	)
	(segment
		(start 55.353966 -178.378866)
		(end 57.934098 -178.378866)
		(width 0.1143)
		(layer "In6.Cu")
		(net "PSU_DC_OK_N")
	)
	(segment
		(start 60.437776 -177.13833)
		(end 60.727336 -176.84877)
		(width 0.1143)
		(layer "In6.Cu")
		(net "PSU_DC_OK_N")
	)
	(segment
		(start 57.934098 -178.378866)
		(end 59.174634 -177.13833)
		(width 0.1143)
		(layer "In6.Cu")
		(net "PSU_DC_OK_N")
	)
	(segment
		(start 50.099722 -177.266346)
		(end 52.00777 -177.266346)
		(width 0.1143)
		(layer "In6.Cu")
		(net "PSU_DC_OK_N")
	)
	(segment
		(start 48.35525 -176.688496)
		(end 49.118774 -176.688496)
		(width 0.1143)
		(layer "In6.Cu")
		(net "PSU_DC_OK_N")
	)
	(segment
		(start 59.424316 -177.13833)
		(end 60.437776 -177.13833)
		(width 0.1143)
		(layer "In6.Cu")
		(net "PSU_DC_OK_N")
	)
	(segment
		(start 52.00777 -177.266346)
		(end 52.595272 -176.678844)
		(width 0.1143)
		(layer "In6.Cu")
		(net "PSU_DC_OK_N")
	)
	(segment
		(start 49.118774 -176.688496)
		(end 49.696624 -177.266346)
		(width 0.1143)
		(layer "In6.Cu")
		(net "PSU_DC_OK_N")
	)
	(segment
		(start 52.595272 -176.678844)
		(end 53.653944 -176.678844)
		(width 0.1143)
		(layer "In6.Cu")
		(net "PSU_DC_OK_N")
	)
	(segment
		(start 103.214932 -169.657268)
		(end 104.302306 -169.657268)
		(width 0.1016)
		(layer "F.Cu")
		(net "FAN4_TACH_IN")
	)
	(segment
		(start 105.770426 -169.932858)
		(end 104.794304 -169.932858)
		(width 0.1016)
		(layer "F.Cu")
		(net "FAN4_TACH_IN")
	)
	(segment
		(start 104.302306 -169.657268)
		(end 104.41051 -169.549064)
		(width 0.1016)
		(layer "F.Cu")
		(net "FAN4_TACH_IN")
	)
	(segment
		(start 104.794304 -169.932858)
		(end 104.41051 -169.549064)
		(width 0.1016)
		(layer "F.Cu")
		(net "FAN4_TACH_IN")
	)
	(via
		(at 104.41051 -169.549064)
		(size 0.508)
		(drill 0.254)
		(layers "F.Cu" "B.Cu")
		(net "FAN4_TACH_IN")
	)
	(segment
		(start 58.941716 -132.859018)
		(end 58.540904 -132.458206)
		(width 0.1016)
		(layer "F.Cu")
		(net "BMC_NODE1_DDR_BA2")
	)
	(segment
		(start 41.63314 -132.163566)
		(end 42.799508 -132.163566)
		(width 0.1016)
		(layer "F.Cu")
		(net "BMC_NODE1_DDR_BA2")
	)
	(segment
		(start 42.799508 -132.163566)
		(end 43.08221 -131.880864)
		(width 0.1016)
		(layer "F.Cu")
		(net "BMC_NODE1_DDR_BA2")
	)
	(segment
		(start 58.941716 -132.859526)
		(end 58.941716 -132.859018)
		(width 0.1016)
		(layer "F.Cu")
		(net "BMC_NODE1_DDR_BA2")
	)
	(via
		(at 58.540904 -132.458206)
		(size 0.49022)
		(drill 0.254)
		(layers "F.Cu" "B.Cu")
		(net "BMC_NODE1_DDR_BA2")
	)
	(via
		(at 43.08221 -131.880864)
		(size 0.508)
		(drill 0.254)
		(layers "F.Cu" "B.Cu")
		(net "BMC_NODE1_DDR_BA2")
	)
	(segment
		(start 48.553116 -130.681222)
		(end 47.9679 -130.096006)
		(width 0.1143)
		(layer "In2.Cu")
		(net "BMC_NODE1_DDR_BA2")
	)
	(segment
		(start 51.161188 -130.863594)
		(end 51.161188 -131.048252)
		(width 0.1143)
		(layer "In2.Cu")
		(net "BMC_NODE1_DDR_BA2")
	)
	(segment
		(start 49.916588 -130.863594)
		(end 49.916588 -131.048252)
		(width 0.1143)
		(layer "In2.Cu")
		(net "BMC_NODE1_DDR_BA2")
	)
	(segment
		(start 49.916588 -131.048252)
		(end 49.734216 -131.230624)
		(width 0.1143)
		(layer "In2.Cu")
		(net "BMC_NODE1_DDR_BA2")
	)
	(segment
		(start 50.538888 -130.863594)
		(end 50.356516 -130.681222)
		(width 0.1143)
		(layer "In2.Cu")
		(net "BMC_NODE1_DDR_BA2")
	)
	(segment
		(start 43.41495 -131.548124)
		(end 43.08221 -131.880864)
		(width 0.1143)
		(layer "In2.Cu")
		(net "BMC_NODE1_DDR_BA2")
	)
	(segment
		(start 46.315122 -131.421124)
		(end 45.739558 -131.421124)
		(width 0.1143)
		(layer "In2.Cu")
		(net "BMC_NODE1_DDR_BA2")
	)
	(segment
		(start 51.161188 -131.048252)
		(end 50.978816 -131.230624)
		(width 0.1143)
		(layer "In2.Cu")
		(net "BMC_NODE1_DDR_BA2")
	)
	(segment
		(start 50.72126 -131.230624)
		(end 50.538888 -131.048252)
		(width 0.1143)
		(layer "In2.Cu")
		(net "BMC_NODE1_DDR_BA2")
	)
	(segment
		(start 51.44516 -130.579622)
		(end 51.161188 -130.863594)
		(width 0.1143)
		(layer "In2.Cu")
		(net "BMC_NODE1_DDR_BA2")
	)
	(segment
		(start 49.294288 -131.048252)
		(end 49.294288 -130.863594)
		(width 0.1143)
		(layer "In2.Cu")
		(net "BMC_NODE1_DDR_BA2")
	)
	(segment
		(start 46.928532 -130.807714)
		(end 46.315122 -131.421124)
		(width 0.1143)
		(layer "In2.Cu")
		(net "BMC_NODE1_DDR_BA2")
	)
	(segment
		(start 50.538888 -131.048252)
		(end 50.538888 -130.863594)
		(width 0.1143)
		(layer "In2.Cu")
		(net "BMC_NODE1_DDR_BA2")
	)
	(segment
		(start 52.756308 -130.579622)
		(end 51.44516 -130.579622)
		(width 0.1143)
		(layer "In2.Cu")
		(net "BMC_NODE1_DDR_BA2")
	)
	(segment
		(start 56.932068 -132.458206)
		(end 56.211724 -131.737862)
		(width 0.1143)
		(layer "In2.Cu")
		(net "BMC_NODE1_DDR_BA2")
	)
	(segment
		(start 45.599096 -131.280662)
		(end 44.70146 -131.280662)
		(width 0.1143)
		(layer "In2.Cu")
		(net "BMC_NODE1_DDR_BA2")
	)
	(segment
		(start 50.978816 -131.230624)
		(end 50.72126 -131.230624)
		(width 0.1143)
		(layer "In2.Cu")
		(net "BMC_NODE1_DDR_BA2")
	)
	(segment
		(start 46.928532 -130.331464)
		(end 46.928532 -130.807714)
		(width 0.1143)
		(layer "In2.Cu")
		(net "BMC_NODE1_DDR_BA2")
	)
	(segment
		(start 45.739558 -131.421124)
		(end 45.599096 -131.280662)
		(width 0.1143)
		(layer "In2.Cu")
		(net "BMC_NODE1_DDR_BA2")
	)
	(segment
		(start 52.92852 -130.751834)
		(end 52.756308 -130.579622)
		(width 0.1143)
		(layer "In2.Cu")
		(net "BMC_NODE1_DDR_BA2")
	)
	(segment
		(start 49.47666 -131.230624)
		(end 49.294288 -131.048252)
		(width 0.1143)
		(layer "In2.Cu")
		(net "BMC_NODE1_DDR_BA2")
	)
	(segment
		(start 49.734216 -131.230624)
		(end 49.47666 -131.230624)
		(width 0.1143)
		(layer "In2.Cu")
		(net "BMC_NODE1_DDR_BA2")
	)
	(segment
		(start 53.522118 -131.737862)
		(end 52.92852 -131.144264)
		(width 0.1143)
		(layer "In2.Cu")
		(net "BMC_NODE1_DDR_BA2")
	)
	(segment
		(start 47.16399 -130.096006)
		(end 46.928532 -130.331464)
		(width 0.1143)
		(layer "In2.Cu")
		(net "BMC_NODE1_DDR_BA2")
	)
	(segment
		(start 56.211724 -131.737862)
		(end 53.522118 -131.737862)
		(width 0.1143)
		(layer "In2.Cu")
		(net "BMC_NODE1_DDR_BA2")
	)
	(segment
		(start 58.540904 -132.458206)
		(end 56.932068 -132.458206)
		(width 0.1143)
		(layer "In2.Cu")
		(net "BMC_NODE1_DDR_BA2")
	)
	(segment
		(start 49.111916 -130.681222)
		(end 48.553116 -130.681222)
		(width 0.1143)
		(layer "In2.Cu")
		(net "BMC_NODE1_DDR_BA2")
	)
	(segment
		(start 49.294288 -130.863594)
		(end 49.111916 -130.681222)
		(width 0.1143)
		(layer "In2.Cu")
		(net "BMC_NODE1_DDR_BA2")
	)
	(segment
		(start 44.433998 -131.548124)
		(end 43.41495 -131.548124)
		(width 0.1143)
		(layer "In2.Cu")
		(net "BMC_NODE1_DDR_BA2")
	)
	(segment
		(start 44.70146 -131.280662)
		(end 44.433998 -131.548124)
		(width 0.1143)
		(layer "In2.Cu")
		(net "BMC_NODE1_DDR_BA2")
	)
	(segment
		(start 52.92852 -131.144264)
		(end 52.92852 -130.751834)
		(width 0.1143)
		(layer "In2.Cu")
		(net "BMC_NODE1_DDR_BA2")
	)
	(segment
		(start 50.356516 -130.681222)
		(end 50.09896 -130.681222)
		(width 0.1143)
		(layer "In2.Cu")
		(net "BMC_NODE1_DDR_BA2")
	)
	(segment
		(start 47.9679 -130.096006)
		(end 47.16399 -130.096006)
		(width 0.1143)
		(layer "In2.Cu")
		(net "BMC_NODE1_DDR_BA2")
	)
	(segment
		(start 50.09896 -130.681222)
		(end 49.916588 -130.863594)
		(width 0.1143)
		(layer "In2.Cu")
		(net "BMC_NODE1_DDR_BA2")
	)
	(segment
		(start 45.418248 -68.084446)
		(end 45.451014 -68.117212)
		(width 0.127)
		(layer "F.Cu")
		(net "TP_CPU_NODE1_RP0_PETP5")
	)
	(segment
		(start 45.451014 -68.117212)
		(end 45.451014 -68.62064)
		(width 0.127)
		(layer "F.Cu")
		(net "TP_CPU_NODE1_RP0_PETP5")
	)
	(via
		(at 48.000666 -69.454776)
		(size 0.6604)
		(drill 0.3302)
		(layers "F.Cu" "B.Cu")
		(net "TP_CPU_NODE1_RP0_PETP5")
	)
	(via
		(at 45.451014 -68.62064)
		(size 0.508)
		(drill 0.254)
		(layers "F.Cu" "B.Cu")
		(net "TP_CPU_NODE1_RP0_PETP5")
	)
	(segment
		(start 46.820328 -69.454776)
		(end 45.986192 -68.62064)
		(width 0.1016)
		(layer "B.Cu")
		(net "TP_CPU_NODE1_RP0_PETP5")
	)
	(segment
		(start 45.986192 -68.62064)
		(end 45.451014 -68.62064)
		(width 0.1016)
		(layer "B.Cu")
		(net "TP_CPU_NODE1_RP0_PETP5")
	)
	(segment
		(start 48.000666 -69.454776)
		(end 46.820328 -69.454776)
		(width 0.1016)
		(layer "B.Cu")
		(net "TP_CPU_NODE1_RP0_PETP5")
	)
	(segment
		(start 102.580948 -136.176258)
		(end 102.409498 -136.176258)
		(width 0.1016)
		(layer "F.Cu")
		(net "PWRGD_NODE1_PVCCP_PG")
	)
	(segment
		(start 99.973384 -144.146524)
		(end 99.351338 -143.524478)
		(width 0.1016)
		(layer "F.Cu")
		(net "PWRGD_NODE1_PVCCP_PG")
	)
	(segment
		(start 99.351338 -141.400022)
		(end 99.75088 -141.00048)
		(width 0.1016)
		(layer "F.Cu")
		(net "PWRGD_NODE1_PVCCP_PG")
	)
	(segment
		(start 102.409498 -136.469374)
		(end 102.409498 -136.176258)
		(width 0.1016)
		(layer "F.Cu")
		(net "PWRGD_NODE1_PVCCP_PG")
	)
	(segment
		(start 102.150672 -136.7282)
		(end 102.409498 -136.469374)
		(width 0.1016)
		(layer "F.Cu")
		(net "PWRGD_NODE1_PVCCP_PG")
	)
	(segment
		(start 178.49342 -125.165612)
		(end 178.493166 -125.165358)
		(width 0.1016)
		(layer "F.Cu")
		(net "PWRGD_NODE1_PVCCP_PG")
	)
	(segment
		(start 99.973384 -144.17802)
		(end 99.973384 -144.146524)
		(width 0.1016)
		(layer "F.Cu")
		(net "PWRGD_NODE1_PVCCP_PG")
	)
	(segment
		(start 104.36098 -136.697974)
		(end 103.997252 -137.061702)
		(width 0.1016)
		(layer "F.Cu")
		(net "PWRGD_NODE1_PVCCP_PG")
	)
	(segment
		(start 178.493166 -123.848368)
		(end 178.010566 -123.365768)
		(width 0.1016)
		(layer "F.Cu")
		(net "PWRGD_NODE1_PVCCP_PG")
	)
	(segment
		(start 103.997252 -137.061702)
		(end 103.466392 -137.061702)
		(width 0.1016)
		(layer "F.Cu")
		(net "PWRGD_NODE1_PVCCP_PG")
	)
	(segment
		(start 178.48072 -128.542288)
		(end 178.48072 -128.239774)
		(width 0.1016)
		(layer "F.Cu")
		(net "PWRGD_NODE1_PVCCP_PG")
	)
	(segment
		(start 177.982626 -129.040382)
		(end 178.48072 -128.542288)
		(width 0.1016)
		(layer "F.Cu")
		(net "PWRGD_NODE1_PVCCP_PG")
	)
	(segment
		(start 104.92867 -136.697974)
		(end 104.36098 -136.697974)
		(width 0.1016)
		(layer "F.Cu")
		(net "PWRGD_NODE1_PVCCP_PG")
	)
	(segment
		(start 99.75088 -141.00048)
		(end 99.75088 -137.21969)
		(width 0.1016)
		(layer "F.Cu")
		(net "PWRGD_NODE1_PVCCP_PG")
	)
	(segment
		(start 178.48072 -128.239774)
		(end 178.49342 -128.227074)
		(width 0.1016)
		(layer "F.Cu")
		(net "PWRGD_NODE1_PVCCP_PG")
	)
	(segment
		(start 100.24237 -136.7282)
		(end 102.150672 -136.7282)
		(width 0.1016)
		(layer "F.Cu")
		(net "PWRGD_NODE1_PVCCP_PG")
	)
	(segment
		(start 178.49342 -128.227074)
		(end 178.49342 -125.165612)
		(width 0.1016)
		(layer "F.Cu")
		(net "PWRGD_NODE1_PVCCP_PG")
	)
	(segment
		(start 177.982626 -131.306316)
		(end 177.982626 -129.040382)
		(width 0.1016)
		(layer "F.Cu")
		(net "PWRGD_NODE1_PVCCP_PG")
	)
	(segment
		(start 99.351338 -143.524478)
		(end 99.351338 -141.400022)
		(width 0.1016)
		(layer "F.Cu")
		(net "PWRGD_NODE1_PVCCP_PG")
	)
	(segment
		(start 178.493166 -125.165358)
		(end 178.493166 -123.848368)
		(width 0.1016)
		(layer "F.Cu")
		(net "PWRGD_NODE1_PVCCP_PG")
	)
	(segment
		(start 103.466392 -137.061702)
		(end 102.580948 -136.176258)
		(width 0.1016)
		(layer "F.Cu")
		(net "PWRGD_NODE1_PVCCP_PG")
	)
	(segment
		(start 99.75088 -137.21969)
		(end 100.24237 -136.7282)
		(width 0.1016)
		(layer "F.Cu")
		(net "PWRGD_NODE1_PVCCP_PG")
	)
	(via
		(at 99.973384 -144.17802)
		(size 0.508)
		(drill 0.254)
		(layers "F.Cu" "B.Cu")
		(net "PWRGD_NODE1_PVCCP_PG")
	)
	(via
		(at 177.982626 -131.306316)
		(size 0.508)
		(drill 0.254)
		(layers "F.Cu" "B.Cu")
		(net "PWRGD_NODE1_PVCCP_PG")
	)
	(segment
		(start 159.09671 -133.646926)
		(end 169.232326 -133.646926)
		(width 0.1143)
		(layer "In6.Cu")
		(net "PWRGD_NODE1_PVCCP_PG")
	)
	(segment
		(start 147.47748 -135.6233)
		(end 149.689312 -133.411468)
		(width 0.1143)
		(layer "In6.Cu")
		(net "PWRGD_NODE1_PVCCP_PG")
	)
	(segment
		(start 115.50269 -142.670276)
		(end 115.976146 -142.670276)
		(width 0.1143)
		(layer "In6.Cu")
		(net "PWRGD_NODE1_PVCCP_PG")
	)
	(segment
		(start 116.96192 -141.211554)
		(end 122.511566 -135.661908)
		(width 0.1143)
		(layer "In6.Cu")
		(net "PWRGD_NODE1_PVCCP_PG")
	)
	(segment
		(start 99.973384 -144.17802)
		(end 100.42144 -144.626076)
		(width 0.1143)
		(layer "In6.Cu")
		(net "PWRGD_NODE1_PVCCP_PG")
	)
	(segment
		(start 122.511566 -135.661908)
		(end 131.094734 -135.661908)
		(width 0.1143)
		(layer "In6.Cu")
		(net "PWRGD_NODE1_PVCCP_PG")
	)
	(segment
		(start 115.976146 -142.670276)
		(end 116.96192 -141.684502)
		(width 0.1143)
		(layer "In6.Cu")
		(net "PWRGD_NODE1_PVCCP_PG")
	)
	(segment
		(start 113.54689 -144.626076)
		(end 115.50269 -142.670276)
		(width 0.1143)
		(layer "In6.Cu")
		(net "PWRGD_NODE1_PVCCP_PG")
	)
	(segment
		(start 140.284962 -135.6233)
		(end 147.47748 -135.6233)
		(width 0.1143)
		(layer "In6.Cu")
		(net "PWRGD_NODE1_PVCCP_PG")
	)
	(segment
		(start 177.480722 -131.306316)
		(end 177.982626 -131.306316)
		(width 0.1143)
		(layer "In6.Cu")
		(net "PWRGD_NODE1_PVCCP_PG")
	)
	(segment
		(start 171.571666 -131.307586)
		(end 176.338992 -131.307586)
		(width 0.1143)
		(layer "In6.Cu")
		(net "PWRGD_NODE1_PVCCP_PG")
	)
	(segment
		(start 138.519662 -133.858)
		(end 140.284962 -135.6233)
		(width 0.1143)
		(layer "In6.Cu")
		(net "PWRGD_NODE1_PVCCP_PG")
	)
	(segment
		(start 176.495964 -131.464558)
		(end 177.32248 -131.464558)
		(width 0.1143)
		(layer "In6.Cu")
		(net "PWRGD_NODE1_PVCCP_PG")
	)
	(segment
		(start 116.96192 -141.684502)
		(end 116.96192 -141.211554)
		(width 0.1143)
		(layer "In6.Cu")
		(net "PWRGD_NODE1_PVCCP_PG")
	)
	(segment
		(start 149.689312 -133.411468)
		(end 158.861252 -133.411468)
		(width 0.1143)
		(layer "In6.Cu")
		(net "PWRGD_NODE1_PVCCP_PG")
	)
	(segment
		(start 158.861252 -133.411468)
		(end 159.09671 -133.646926)
		(width 0.1143)
		(layer "In6.Cu")
		(net "PWRGD_NODE1_PVCCP_PG")
	)
	(segment
		(start 176.338992 -131.307586)
		(end 176.495964 -131.464558)
		(width 0.1143)
		(layer "In6.Cu")
		(net "PWRGD_NODE1_PVCCP_PG")
	)
	(segment
		(start 169.232326 -133.646926)
		(end 171.571666 -131.307586)
		(width 0.1143)
		(layer "In6.Cu")
		(net "PWRGD_NODE1_PVCCP_PG")
	)
	(segment
		(start 132.898642 -133.858)
		(end 138.519662 -133.858)
		(width 0.1143)
		(layer "In6.Cu")
		(net "PWRGD_NODE1_PVCCP_PG")
	)
	(segment
		(start 177.32248 -131.464558)
		(end 177.480722 -131.306316)
		(width 0.1143)
		(layer "In6.Cu")
		(net "PWRGD_NODE1_PVCCP_PG")
	)
	(segment
		(start 131.094734 -135.661908)
		(end 132.898642 -133.858)
		(width 0.1143)
		(layer "In6.Cu")
		(net "PWRGD_NODE1_PVCCP_PG")
	)
	(segment
		(start 100.42144 -144.626076)
		(end 113.54689 -144.626076)
		(width 0.1143)
		(layer "In6.Cu")
		(net "PWRGD_NODE1_PVCCP_PG")
	)
	(via
		(at 89.33688 -163.624514)
		(size 0.6604)
		(drill 0.3302)
		(layers "F.Cu" "B.Cu")
		(net "I2C_SDC_SDA")
	)
	(segment
		(start 89.586816 -163.87445)
		(end 89.33688 -163.624514)
		(width 0.1016)
		(layer "B.Cu")
		(net "I2C_SDC_SDA")
	)
	(segment
		(start 90.41257 -163.87445)
		(end 89.586816 -163.87445)
		(width 0.1016)
		(layer "B.Cu")
		(net "I2C_SDC_SDA")
	)
	(segment
		(start 89.33688 -163.624514)
		(end 89.186258 -163.624514)
		(width 0.1016)
		(layer "B.Cu")
		(net "I2C_SDC_SDA")
	)
	(segment
		(start 88.456516 -164.354256)
		(end 87.748872 -164.354256)
		(width 0.1016)
		(layer "B.Cu")
		(net "I2C_SDC_SDA")
	)
	(segment
		(start 89.186258 -163.624514)
		(end 88.456516 -164.354256)
		(width 0.1016)
		(layer "B.Cu")
		(net "I2C_SDC_SDA")
	)
	(segment
		(start 152.59558 -91.110308)
		(end 152.59558 -84.50707)
		(width 0.1016)
		(layer "F.Cu")
		(net "FM_CPLD_NODE1_SATA_PERST_L")
	)
	(segment
		(start 143.130524 -68.799202)
		(end 143.130524 -69.612002)
		(width 0.1016)
		(layer "F.Cu")
		(net "FM_CPLD_NODE1_SATA_PERST_L")
	)
	(segment
		(start 174.01032 -118.365524)
		(end 173.510448 -117.865652)
		(width 0.1016)
		(layer "F.Cu")
		(net "FM_CPLD_NODE1_SATA_PERST_L")
	)
	(segment
		(start 152.7683 -84.33435)
		(end 152.7683 -82.933286)
		(width 0.1016)
		(layer "F.Cu")
		(net "FM_CPLD_NODE1_SATA_PERST_L")
	)
	(segment
		(start 142.45971 -70.282816)
		(end 142.45971 -72.500236)
		(width 0.1016)
		(layer "F.Cu")
		(net "FM_CPLD_NODE1_SATA_PERST_L")
	)
	(segment
		(start 143.130524 -69.612002)
		(end 142.45971 -70.282816)
		(width 0.1016)
		(layer "F.Cu")
		(net "FM_CPLD_NODE1_SATA_PERST_L")
	)
	(segment
		(start 152.59558 -84.50707)
		(end 152.7683 -84.33435)
		(width 0.1016)
		(layer "F.Cu")
		(net "FM_CPLD_NODE1_SATA_PERST_L")
	)
	(via
		(at 152.7683 -82.933286)
		(size 0.508)
		(drill 0.254)
		(layers "F.Cu" "B.Cu")
		(net "FM_CPLD_NODE1_SATA_PERST_L")
	)
	(via
		(at 173.510448 -117.865652)
		(size 0.49022)
		(drill 0.254)
		(layers "F.Cu" "B.Cu")
		(net "FM_CPLD_NODE1_SATA_PERST_L")
	)
	(via
		(at 152.59558 -91.110308)
		(size 0.508)
		(drill 0.254)
		(layers "F.Cu" "B.Cu")
		(net "FM_CPLD_NODE1_SATA_PERST_L")
	)
	(via
		(at 142.45971 -72.500236)
		(size 0.508)
		(drill 0.254)
		(layers "F.Cu" "B.Cu")
		(net "FM_CPLD_NODE1_SATA_PERST_L")
	)
	(segment
		(start 162.074606 -109.051852)
		(end 160.818576 -109.051852)
		(width 0.1143)
		(layer "In2.Cu")
		(net "FM_CPLD_NODE1_SATA_PERST_L")
	)
	(segment
		(start 173.510448 -117.865652)
		(end 173.510448 -117.15877)
		(width 0.1143)
		(layer "In2.Cu")
		(net "FM_CPLD_NODE1_SATA_PERST_L")
	)
	(segment
		(start 156.78912 -105.022396)
		(end 156.78912 -96.07931)
		(width 0.1143)
		(layer "In2.Cu")
		(net "FM_CPLD_NODE1_SATA_PERST_L")
	)
	(segment
		(start 142.05458 -73.325482)
		(end 142.05458 -76.12507)
		(width 0.1143)
		(layer "In2.Cu")
		(net "FM_CPLD_NODE1_SATA_PERST_L")
	)
	(segment
		(start 142.45971 -72.500236)
		(end 142.45971 -72.921622)
		(width 0.1143)
		(layer "In2.Cu")
		(net "FM_CPLD_NODE1_SATA_PERST_L")
	)
	(segment
		(start 156.78912 -96.07931)
		(end 152.59558 -91.88577)
		(width 0.1143)
		(layer "In2.Cu")
		(net "FM_CPLD_NODE1_SATA_PERST_L")
	)
	(segment
		(start 152.7683 -82.934556)
		(end 152.7683 -82.933286)
		(width 0.1143)
		(layer "In2.Cu")
		(net "FM_CPLD_NODE1_SATA_PERST_L")
	)
	(segment
		(start 142.45844 -72.921622)
		(end 142.05458 -73.325482)
		(width 0.1143)
		(layer "In2.Cu")
		(net "FM_CPLD_NODE1_SATA_PERST_L")
	)
	(segment
		(start 142.45971 -72.921622)
		(end 142.45844 -72.921622)
		(width 0.1143)
		(layer "In2.Cu")
		(net "FM_CPLD_NODE1_SATA_PERST_L")
	)
	(segment
		(start 152.6667 -83.036156)
		(end 152.7683 -82.934556)
		(width 0.1143)
		(layer "In2.Cu")
		(net "FM_CPLD_NODE1_SATA_PERST_L")
	)
	(segment
		(start 174.219362 -112.787684)
		(end 171.163234 -109.731556)
		(width 0.1143)
		(layer "In2.Cu")
		(net "FM_CPLD_NODE1_SATA_PERST_L")
	)
	(segment
		(start 148.965666 -83.036156)
		(end 152.6667 -83.036156)
		(width 0.1143)
		(layer "In2.Cu")
		(net "FM_CPLD_NODE1_SATA_PERST_L")
	)
	(segment
		(start 174.219362 -116.449856)
		(end 174.219362 -112.787684)
		(width 0.1143)
		(layer "In2.Cu")
		(net "FM_CPLD_NODE1_SATA_PERST_L")
	)
	(segment
		(start 152.59558 -91.88577)
		(end 152.59558 -91.110308)
		(width 0.1143)
		(layer "In2.Cu")
		(net "FM_CPLD_NODE1_SATA_PERST_L")
	)
	(segment
		(start 142.05458 -76.12507)
		(end 148.965666 -83.036156)
		(width 0.1143)
		(layer "In2.Cu")
		(net "FM_CPLD_NODE1_SATA_PERST_L")
	)
	(segment
		(start 162.75431 -109.731556)
		(end 162.074606 -109.051852)
		(width 0.1143)
		(layer "In2.Cu")
		(net "FM_CPLD_NODE1_SATA_PERST_L")
	)
	(segment
		(start 173.510448 -117.15877)
		(end 174.219362 -116.449856)
		(width 0.1143)
		(layer "In2.Cu")
		(net "FM_CPLD_NODE1_SATA_PERST_L")
	)
	(segment
		(start 160.818576 -109.051852)
		(end 156.78912 -105.022396)
		(width 0.1143)
		(layer "In2.Cu")
		(net "FM_CPLD_NODE1_SATA_PERST_L")
	)
	(segment
		(start 171.163234 -109.731556)
		(end 162.75431 -109.731556)
		(width 0.1143)
		(layer "In2.Cu")
		(net "FM_CPLD_NODE1_SATA_PERST_L")
	)
	(segment
		(start 44.833032 -137.763758)
		(end 44.833032 -137.76452)
		(width 0.1016)
		(layer "F.Cu")
		(net "BMC_NODE1_DDR_DM0")
	)
	(segment
		(start 44.833032 -137.76452)
		(end 43.233848 -139.363704)
		(width 0.1016)
		(layer "F.Cu")
		(net "BMC_NODE1_DDR_DM0")
	)
	(segment
		(start 59.741816 -136.059418)
		(end 59.73953 -136.059418)
		(width 0.1016)
		(layer "F.Cu")
		(net "BMC_NODE1_DDR_DM0")
	)
	(segment
		(start 59.73953 -136.059418)
		(end 59.341004 -136.457944)
		(width 0.1016)
		(layer "F.Cu")
		(net "BMC_NODE1_DDR_DM0")
	)
	(segment
		(start 43.233848 -139.363704)
		(end 42.965878 -139.363704)
		(width 0.1016)
		(layer "F.Cu")
		(net "BMC_NODE1_DDR_DM0")
	)
	(via
		(at 42.965878 -139.363704)
		(size 0.508)
		(drill 0.254)
		(layers "F.Cu" "B.Cu")
		(net "BMC_NODE1_DDR_DM0")
	)
	(via
		(at 59.341004 -136.457944)
		(size 0.49022)
		(drill 0.254)
		(layers "F.Cu" "B.Cu")
		(net "BMC_NODE1_DDR_DM0")
	)
	(segment
		(start 48.777906 -141.58849)
		(end 48.322992 -142.043404)
		(width 0.1143)
		(layer "In7.Cu")
		(net "BMC_NODE1_DDR_DM0")
	)
	(segment
		(start 43.593258 -140.467588)
		(end 42.965878 -139.462764)
		(width 0.1143)
		(layer "In7.Cu")
		(net "BMC_NODE1_DDR_DM0")
	)
	(segment
		(start 54.261258 -141.58849)
		(end 48.777906 -141.58849)
		(width 0.1143)
		(layer "In7.Cu")
		(net "BMC_NODE1_DDR_DM0")
	)
	(segment
		(start 42.965878 -139.462764)
		(end 42.965878 -139.363704)
		(width 0.1143)
		(layer "In7.Cu")
		(net "BMC_NODE1_DDR_DM0")
	)
	(segment
		(start 44.378118 -141.252448)
		(end 43.593258 -140.467588)
		(width 0.1143)
		(layer "In7.Cu")
		(net "BMC_NODE1_DDR_DM0")
	)
	(segment
		(start 56.783986 -138.430762)
		(end 54.510686 -141.339062)
		(width 0.1143)
		(layer "In7.Cu")
		(net "BMC_NODE1_DDR_DM0")
	)
	(segment
		(start 45.926502 -142.043404)
		(end 44.378118 -141.252448)
		(width 0.1143)
		(layer "In7.Cu")
		(net "BMC_NODE1_DDR_DM0")
	)
	(segment
		(start 58.357008 -136.85774)
		(end 56.783986 -138.430762)
		(width 0.1143)
		(layer "In7.Cu")
		(net "BMC_NODE1_DDR_DM0")
	)
	(segment
		(start 48.322992 -142.043404)
		(end 45.926502 -142.043404)
		(width 0.1143)
		(layer "In7.Cu")
		(net "BMC_NODE1_DDR_DM0")
	)
	(segment
		(start 58.941208 -136.85774)
		(end 58.357008 -136.85774)
		(width 0.1016)
		(layer "In7.Cu")
		(net "BMC_NODE1_DDR_DM0")
	)
	(segment
		(start 59.341004 -136.457944)
		(end 58.941208 -136.85774)
		(width 0.1016)
		(layer "In7.Cu")
		(net "BMC_NODE1_DDR_DM0")
	)
	(segment
		(start 54.510686 -141.339062)
		(end 54.261258 -141.58849)
		(width 0.1143)
		(layer "In7.Cu")
		(net "BMC_NODE1_DDR_DM0")
	)
	(segment
		(start 84.925662 -88.244934)
		(end 86.21268 -89.531952)
		(width 0.1016)
		(layer "F.Cu")
		(net "SPI_CPU_NODE1_WP_L")
	)
	(segment
		(start 81.673954 -88.995504)
		(end 82.424524 -88.244934)
		(width 0.1016)
		(layer "F.Cu")
		(net "SPI_CPU_NODE1_WP_L")
	)
	(segment
		(start 82.424524 -88.244934)
		(end 84.925662 -88.244934)
		(width 0.1016)
		(layer "F.Cu")
		(net "SPI_CPU_NODE1_WP_L")
	)
	(segment
		(start 86.21268 -89.531952)
		(end 86.21268 -90.153236)
		(width 0.1016)
		(layer "F.Cu")
		(net "SPI_CPU_NODE1_WP_L")
	)
	(segment
		(start 81.099152 -88.995504)
		(end 81.673954 -88.995504)
		(width 0.1016)
		(layer "F.Cu")
		(net "SPI_CPU_NODE1_WP_L")
	)
	(segment
		(start 86.21268 -90.153236)
		(end 90.698066 -94.638622)
		(width 0.1016)
		(layer "F.Cu")
		(net "SPI_CPU_NODE1_WP_L")
	)
	(segment
		(start 90.698066 -94.638622)
		(end 90.698066 -96.855026)
		(width 0.1016)
		(layer "F.Cu")
		(net "SPI_CPU_NODE1_WP_L")
	)
	(segment
		(start 80.363568 -88.995504)
		(end 81.099152 -88.995504)
		(width 0.1016)
		(layer "F.Cu")
		(net "SPI_CPU_NODE1_WP_L")
	)
	(segment
		(start 90.698066 -97.099628)
		(end 90.698066 -96.855026)
		(width 0.1016)
		(layer "F.Cu")
		(net "SPI_CPU_NODE1_WP_L")
	)
	(via
		(at 81.099152 -88.995504)
		(size 0.508)
		(drill 0.254)
		(layers "F.Cu" "B.Cu")
		(net "SPI_CPU_NODE1_WP_L")
	)
	(segment
		(start 52.399946 -74.599292)
		(end 52.799996 -74.999342)
		(width 0.3048)
		(layer "F.Cu")
		(net "PD_CPU_NODE1_AJ23")
	)
	(via
		(at 51.482498 -75.190096)
		(size 0.6604)
		(drill 0.3302)
		(layers "F.Cu" "B.Cu")
		(net "PD_CPU_NODE1_AJ23")
	)
	(via
		(at 52.399946 -74.599292)
		(size 0.508)
		(drill 0.254)
		(layers "F.Cu" "B.Cu")
		(net "PD_CPU_NODE1_AJ23")
	)
	(segment
		(start 52.32781 -76.135484)
		(end 51.684936 -75.49261)
		(width 0.381)
		(layer "B.Cu")
		(net "PD_CPU_NODE1_AJ23")
	)
	(segment
		(start 52.086002 -74.913236)
		(end 52.399946 -74.599292)
		(width 0.381)
		(layer "B.Cu")
		(net "PD_CPU_NODE1_AJ23")
	)
	(segment
		(start 52.32781 -76.312776)
		(end 52.32781 -76.135484)
		(width 0.381)
		(layer "B.Cu")
		(net "PD_CPU_NODE1_AJ23")
	)
	(segment
		(start 51.482498 -75.190096)
		(end 51.759358 -74.913236)
		(width 0.381)
		(layer "B.Cu")
		(net "PD_CPU_NODE1_AJ23")
	)
	(segment
		(start 51.684936 -75.49261)
		(end 51.684936 -75.392534)
		(width 0.381)
		(layer "B.Cu")
		(net "PD_CPU_NODE1_AJ23")
	)
	(segment
		(start 51.684936 -75.392534)
		(end 51.482498 -75.190096)
		(width 0.381)
		(layer "B.Cu")
		(net "PD_CPU_NODE1_AJ23")
	)
	(segment
		(start 51.759358 -74.913236)
		(end 52.086002 -74.913236)
		(width 0.381)
		(layer "B.Cu")
		(net "PD_CPU_NODE1_AJ23")
	)
	(segment
		(start 46.561248 -70.59168)
		(end 46.532292 -70.620636)
		(width 0.127)
		(layer "F.Cu")
		(net "TP_CPU_NODE1_RP0_PETN7")
	)
	(segment
		(start 46.561248 -70.070726)
		(end 46.561248 -70.59168)
		(width 0.127)
		(layer "F.Cu")
		(net "TP_CPU_NODE1_RP0_PETN7")
	)
	(via
		(at 46.532292 -70.620636)
		(size 0.508)
		(drill 0.254)
		(layers "F.Cu" "B.Cu")
		(net "TP_CPU_NODE1_RP0_PETN7")
	)
	(segment
		(start 108.203746 -131.420362)
		(end 108.203746 -131.117594)
		(width 0.1778)
		(layer "F.Cu")
		(net "VR_PVCCP_NODE1_LGATE1")
	)
	(segment
		(start 108.471462 -132.372862)
		(end 108.471462 -131.688078)
		(width 0.1778)
		(layer "F.Cu")
		(net "VR_PVCCP_NODE1_LGATE1")
	)
	(segment
		(start 108.471462 -131.688078)
		(end 108.203746 -131.420362)
		(width 0.1778)
		(layer "F.Cu")
		(net "VR_PVCCP_NODE1_LGATE1")
	)
	(via
		(at 108.203746 -131.117594)
		(size 0.508)
		(drill 0.254)
		(layers "F.Cu" "B.Cu")
		(net "VR_PVCCP_NODE1_LGATE1")
	)
	(via
		(at 105.056178 -123.34748)
		(size 0.508)
		(drill 0.254)
		(layers "F.Cu" "B.Cu")
		(net "VR_PVCCP_NODE1_LGATE1")
	)
	(via
		(at 104.294178 -123.34748)
		(size 0.508)
		(drill 0.254)
		(layers "F.Cu" "B.Cu")
		(net "VR_PVCCP_NODE1_LGATE1")
	)
	(via
		(at 107.917742 -130.535934)
		(size 0.508)
		(drill 0.254)
		(layers "F.Cu" "B.Cu")
		(net "VR_PVCCP_NODE1_LGATE1")
	)
	(segment
		(start 94.851982 -169.203624)
		(end 96.383348 -169.203624)
		(width 0.1016)
		(layer "F.Cu")
		(net "FAN2_TACH_IN")
	)
	(segment
		(start 96.383348 -169.593006)
		(end 96.383348 -169.203624)
		(width 0.1016)
		(layer "F.Cu")
		(net "FAN2_TACH_IN")
	)
	(segment
		(start 97.08261 -170.292268)
		(end 96.383348 -169.593006)
		(width 0.1016)
		(layer "F.Cu")
		(net "FAN2_TACH_IN")
	)
	(segment
		(start 97.728532 -170.292268)
		(end 97.08261 -170.292268)
		(width 0.1016)
		(layer "F.Cu")
		(net "FAN2_TACH_IN")
	)
	(via
		(at 96.383348 -169.203624)
		(size 0.508)
		(drill 0.254)
		(layers "F.Cu" "B.Cu")
		(net "FAN2_TACH_IN")
	)
	(segment
		(start 45.633132 -132.963666)
		(end 45.633132 -132.964682)
		(width 0.3556)
		(layer "F.Cu")
		(net "BMC_NODE1_DDR3_ZQ")
	)
	(segment
		(start 44.212002 -133.363716)
		(end 43.587924 -133.987794)
		(width 0.381)
		(layer "F.Cu")
		(net "BMC_NODE1_DDR3_ZQ")
	)
	(segment
		(start 45.633132 -132.964682)
		(end 45.234098 -133.363716)
		(width 0.3556)
		(layer "F.Cu")
		(net "BMC_NODE1_DDR3_ZQ")
	)
	(segment
		(start 45.234098 -133.363716)
		(end 44.212002 -133.363716)
		(width 0.1778)
		(layer "F.Cu")
		(net "BMC_NODE1_DDR3_ZQ")
	)
	(via
		(at 43.587924 -133.987794)
		(size 0.49022)
		(drill 0.254)
		(layers "F.Cu" "B.Cu")
		(net "BMC_NODE1_DDR3_ZQ")
	)
	(via
		(at 44.072302 -132.804916)
		(size 0.6604)
		(drill 0.3302)
		(layers "F.Cu" "B.Cu")
		(net "BMC_NODE1_DDR3_ZQ")
	)
	(segment
		(start 44.398184 -133.130798)
		(end 44.072302 -132.804916)
		(width 0.381)
		(layer "B.Cu")
		(net "BMC_NODE1_DDR3_ZQ")
	)
	(segment
		(start 45.312584 -133.130798)
		(end 44.398184 -133.130798)
		(width 0.381)
		(layer "B.Cu")
		(net "BMC_NODE1_DDR3_ZQ")
	)
	(segment
		(start 43.587924 -133.987794)
		(end 43.587924 -133.289294)
		(width 0.381)
		(layer "B.Cu")
		(net "BMC_NODE1_DDR3_ZQ")
	)
	(segment
		(start 43.587924 -133.289294)
		(end 44.072302 -132.804916)
		(width 0.381)
		(layer "B.Cu")
		(net "BMC_NODE1_DDR3_ZQ")
	)
	(segment
		(start 93.00845 -3.993134)
		(end 93.004386 -3.997198)
		(width 0.1016)
		(layer "F.Cu")
		(net "TPM_LPC_SERIRQ_PORT80_NODE1")
	)
	(segment
		(start 93.004386 -7.667752)
		(end 93.004386 -5.542788)
		(width 0.1016)
		(layer "F.Cu")
		(net "TPM_LPC_SERIRQ_PORT80_NODE1")
	)
	(segment
		(start 93.004386 -3.997198)
		(end 93.004386 -5.542788)
		(width 0.1016)
		(layer "F.Cu")
		(net "TPM_LPC_SERIRQ_PORT80_NODE1")
	)
	(via
		(at 93.004386 -5.542788)
		(size 0.508)
		(drill 0.254)
		(layers "F.Cu" "B.Cu")
		(net "TPM_LPC_SERIRQ_PORT80_NODE1")
	)
	(segment
		(start 82.640678 -88.702134)
		(end 82.05216 -89.290652)
		(width 0.1016)
		(layer "F.Cu")
		(net "FM_CPU_NODE1_SLPRDY_L")
	)
	(segment
		(start 82.05216 -89.290652)
		(end 82.05216 -90.03919)
		(width 0.1016)
		(layer "F.Cu")
		(net "FM_CPU_NODE1_SLPRDY_L")
	)
	(segment
		(start 70.202044 -82.229706)
		(end 69.981318 -82.450432)
		(width 0.1016)
		(layer "F.Cu")
		(net "FM_CPU_NODE1_SLPRDY_L")
	)
	(segment
		(start 69.981318 -82.450432)
		(end 69.981318 -82.763868)
		(width 0.1016)
		(layer "F.Cu")
		(net "FM_CPU_NODE1_SLPRDY_L")
	)
	(segment
		(start 70.202044 -82.228182)
		(end 70.202044 -82.229706)
		(width 0.1016)
		(layer "F.Cu")
		(net "FM_CPU_NODE1_SLPRDY_L")
	)
	(segment
		(start 83.060032 -88.702134)
		(end 82.640678 -88.702134)
		(width 0.1016)
		(layer "F.Cu")
		(net "FM_CPU_NODE1_SLPRDY_L")
	)
	(segment
		(start 177.010314 -128.848866)
		(end 177.010314 -125.365764)
		(width 0.1016)
		(layer "F.Cu")
		(net "FM_CPU_NODE1_SLPRDY_L")
	)
	(via
		(at 69.981318 -82.763868)
		(size 0.508)
		(drill 0.254)
		(layers "F.Cu" "B.Cu")
		(net "FM_CPU_NODE1_SLPRDY_L")
	)
	(via
		(at 82.05216 -90.03919)
		(size 0.508)
		(drill 0.254)
		(layers "F.Cu" "B.Cu")
		(net "FM_CPU_NODE1_SLPRDY_L")
	)
	(via
		(at 177.010314 -128.848866)
		(size 0.508)
		(drill 0.254)
		(layers "F.Cu" "B.Cu")
		(net "FM_CPU_NODE1_SLPRDY_L")
	)
	(segment
		(start 90.635836 -92.120974)
		(end 91.562682 -93.04782)
		(width 0.1143)
		(layer "In6.Cu")
		(net "FM_CPU_NODE1_SLPRDY_L")
	)
	(segment
		(start 81.34858 -90.46591)
		(end 79.214726 -90.46591)
		(width 0.1143)
		(layer "In6.Cu")
		(net "FM_CPU_NODE1_SLPRDY_L")
	)
	(segment
		(start 166.60876 -113.39068)
		(end 166.60876 -120.89003)
		(width 0.1143)
		(layer "In6.Cu")
		(net "FM_CPU_NODE1_SLPRDY_L")
	)
	(segment
		(start 88.08847 -92.120974)
		(end 90.635836 -92.120974)
		(width 0.1143)
		(layer "In6.Cu")
		(net "FM_CPU_NODE1_SLPRDY_L")
	)
	(segment
		(start 72.16013 -83.694778)
		(end 70.975982 -83.694778)
		(width 0.1143)
		(layer "In6.Cu")
		(net "FM_CPU_NODE1_SLPRDY_L")
	)
	(segment
		(start 82.05216 -90.03919)
		(end 81.66608 -90.42527)
		(width 0.1143)
		(layer "In6.Cu")
		(net "FM_CPU_NODE1_SLPRDY_L")
	)
	(segment
		(start 96.689164 -88.861646)
		(end 135.506714 -88.861646)
		(width 0.1143)
		(layer "In6.Cu")
		(net "FM_CPU_NODE1_SLPRDY_L")
	)
	(segment
		(start 150.86584 -106.214164)
		(end 156.04236 -111.390684)
		(width 0.1143)
		(layer "In6.Cu")
		(net "FM_CPU_NODE1_SLPRDY_L")
	)
	(segment
		(start 171.022772 -125.304042)
		(end 175.907954 -125.304042)
		(width 0.1143)
		(layer "In6.Cu")
		(net "FM_CPU_NODE1_SLPRDY_L")
	)
	(segment
		(start 86.799674 -90.832178)
		(end 88.08847 -92.120974)
		(width 0.1143)
		(layer "In6.Cu")
		(net "FM_CPU_NODE1_SLPRDY_L")
	)
	(segment
		(start 70.975982 -83.694778)
		(end 70.045072 -82.763868)
		(width 0.1143)
		(layer "In6.Cu")
		(net "FM_CPU_NODE1_SLPRDY_L")
	)
	(segment
		(start 156.04236 -111.390684)
		(end 164.608764 -111.390684)
		(width 0.1143)
		(layer "In6.Cu")
		(net "FM_CPU_NODE1_SLPRDY_L")
	)
	(segment
		(start 75.831954 -85.889084)
		(end 74.904346 -85.889084)
		(width 0.1143)
		(layer "In6.Cu")
		(net "FM_CPU_NODE1_SLPRDY_L")
	)
	(segment
		(start 135.506714 -88.861646)
		(end 150.86584 -104.220772)
		(width 0.1143)
		(layer "In6.Cu")
		(net "FM_CPU_NODE1_SLPRDY_L")
	)
	(segment
		(start 76.59116 -86.64829)
		(end 75.831954 -85.889084)
		(width 0.1143)
		(layer "In6.Cu")
		(net "FM_CPU_NODE1_SLPRDY_L")
	)
	(segment
		(start 79.214726 -90.46591)
		(end 76.59116 -87.842344)
		(width 0.1143)
		(layer "In6.Cu")
		(net "FM_CPU_NODE1_SLPRDY_L")
	)
	(segment
		(start 175.907954 -125.304042)
		(end 178.448716 -127.844804)
		(width 0.1143)
		(layer "In6.Cu")
		(net "FM_CPU_NODE1_SLPRDY_L")
	)
	(segment
		(start 73.800462 -84.7852)
		(end 73.250552 -84.7852)
		(width 0.1143)
		(layer "In6.Cu")
		(net "FM_CPU_NODE1_SLPRDY_L")
	)
	(segment
		(start 81.38922 -90.42527)
		(end 81.34858 -90.46591)
		(width 0.1143)
		(layer "In6.Cu")
		(net "FM_CPU_NODE1_SLPRDY_L")
	)
	(segment
		(start 178.448716 -127.844804)
		(end 178.448716 -128.208024)
		(width 0.1143)
		(layer "In6.Cu")
		(net "FM_CPU_NODE1_SLPRDY_L")
	)
	(segment
		(start 82.05216 -90.03919)
		(end 83.349592 -90.03919)
		(width 0.1143)
		(layer "In6.Cu")
		(net "FM_CPU_NODE1_SLPRDY_L")
	)
	(segment
		(start 178.448716 -128.208024)
		(end 177.807874 -128.848866)
		(width 0.1143)
		(layer "In6.Cu")
		(net "FM_CPU_NODE1_SLPRDY_L")
	)
	(segment
		(start 70.045072 -82.763868)
		(end 69.981318 -82.763868)
		(width 0.1143)
		(layer "In6.Cu")
		(net "FM_CPU_NODE1_SLPRDY_L")
	)
	(segment
		(start 81.66608 -90.42527)
		(end 81.38922 -90.42527)
		(width 0.1143)
		(layer "In6.Cu")
		(net "FM_CPU_NODE1_SLPRDY_L")
	)
	(segment
		(start 83.349592 -90.03919)
		(end 84.14258 -90.832178)
		(width 0.1143)
		(layer "In6.Cu")
		(net "FM_CPU_NODE1_SLPRDY_L")
	)
	(segment
		(start 164.608764 -111.390684)
		(end 166.60876 -113.39068)
		(width 0.1143)
		(layer "In6.Cu")
		(net "FM_CPU_NODE1_SLPRDY_L")
	)
	(segment
		(start 177.807874 -128.848866)
		(end 177.010314 -128.848866)
		(width 0.1143)
		(layer "In6.Cu")
		(net "FM_CPU_NODE1_SLPRDY_L")
	)
	(segment
		(start 76.59116 -87.842344)
		(end 76.59116 -86.64829)
		(width 0.1143)
		(layer "In6.Cu")
		(net "FM_CPU_NODE1_SLPRDY_L")
	)
	(segment
		(start 92.50299 -93.04782)
		(end 96.689164 -88.861646)
		(width 0.1143)
		(layer "In6.Cu")
		(net "FM_CPU_NODE1_SLPRDY_L")
	)
	(segment
		(start 91.562682 -93.04782)
		(end 92.50299 -93.04782)
		(width 0.1143)
		(layer "In6.Cu")
		(net "FM_CPU_NODE1_SLPRDY_L")
	)
	(segment
		(start 166.60876 -120.89003)
		(end 171.022772 -125.304042)
		(width 0.1143)
		(layer "In6.Cu")
		(net "FM_CPU_NODE1_SLPRDY_L")
	)
	(segment
		(start 84.14258 -90.832178)
		(end 86.799674 -90.832178)
		(width 0.1143)
		(layer "In6.Cu")
		(net "FM_CPU_NODE1_SLPRDY_L")
	)
	(segment
		(start 73.250552 -84.7852)
		(end 72.16013 -83.694778)
		(width 0.1143)
		(layer "In6.Cu")
		(net "FM_CPU_NODE1_SLPRDY_L")
	)
	(segment
		(start 74.904346 -85.889084)
		(end 73.800462 -84.7852)
		(width 0.1143)
		(layer "In6.Cu")
		(net "FM_CPU_NODE1_SLPRDY_L")
	)
	(segment
		(start 150.86584 -104.220772)
		(end 150.86584 -106.214164)
		(width 0.1143)
		(layer "In6.Cu")
		(net "FM_CPU_NODE1_SLPRDY_L")
	)
	(segment
		(start 104.381554 -119.861584)
		(end 103.361998 -120.88114)
		(width 0.254)
		(layer "F.Cu")
		(net "VR_PVCCP_NODE1_TSEN_R")
	)
	(segment
		(start 101.49586 -142.531084)
		(end 101.49586 -140.589508)
		(width 0.254)
		(layer "F.Cu")
		(net "VR_PVCCP_NODE1_TSEN_R")
	)
	(segment
		(start 107.652566 -142.794228)
		(end 107.652566 -143.67002)
		(width 0.254)
		(layer "F.Cu")
		(net "VR_PVCCP_NODE1_TSEN_R")
	)
	(segment
		(start 100.203762 -123.368054)
		(end 100.203762 -128.08585)
		(width 0.254)
		(layer "F.Cu")
		(net "VR_PVCCP_NODE1_TSEN_R")
	)
	(segment
		(start 107.450382 -144.229328)
		(end 103.194104 -144.229328)
		(width 0.254)
		(layer "F.Cu")
		(net "VR_PVCCP_NODE1_TSEN_R")
	)
	(segment
		(start 100.203762 -128.08585)
		(end 101.38791 -129.269998)
		(width 0.254)
		(layer "F.Cu")
		(net "VR_PVCCP_NODE1_TSEN_R")
	)
	(segment
		(start 103.361998 -120.88114)
		(end 102.690676 -120.88114)
		(width 0.254)
		(layer "F.Cu")
		(net "VR_PVCCP_NODE1_TSEN_R")
	)
	(segment
		(start 107.652566 -143.67002)
		(end 107.778296 -143.79575)
		(width 0.254)
		(layer "F.Cu")
		(net "VR_PVCCP_NODE1_TSEN_R")
	)
	(segment
		(start 107.778296 -143.79575)
		(end 107.778296 -143.901414)
		(width 0.254)
		(layer "F.Cu")
		(net "VR_PVCCP_NODE1_TSEN_R")
	)
	(segment
		(start 104.761792 -119.861584)
		(end 104.381554 -119.861584)
		(width 0.254)
		(layer "F.Cu")
		(net "VR_PVCCP_NODE1_TSEN_R")
	)
	(segment
		(start 102.690676 -120.88114)
		(end 100.203762 -123.368054)
		(width 0.254)
		(layer "F.Cu")
		(net "VR_PVCCP_NODE1_TSEN_R")
	)
	(segment
		(start 107.778296 -143.901414)
		(end 107.450382 -144.229328)
		(width 0.254)
		(layer "F.Cu")
		(net "VR_PVCCP_NODE1_TSEN_R")
	)
	(segment
		(start 103.194104 -144.229328)
		(end 101.49586 -142.531084)
		(width 0.254)
		(layer "F.Cu")
		(net "VR_PVCCP_NODE1_TSEN_R")
	)
	(segment
		(start 101.38791 -129.269998)
		(end 101.995224 -129.269998)
		(width 0.254)
		(layer "F.Cu")
		(net "VR_PVCCP_NODE1_TSEN_R")
	)
	(via
		(at 101.49586 -140.589508)
		(size 0.508)
		(drill 0.254)
		(layers "F.Cu" "B.Cu")
		(net "VR_PVCCP_NODE1_TSEN_R")
	)
	(via
		(at 101.995224 -129.269998)
		(size 0.508)
		(drill 0.254)
		(layers "F.Cu" "B.Cu")
		(net "VR_PVCCP_NODE1_TSEN_R")
	)
	(segment
		(start 101.873812 -139.798298)
		(end 102.161848 -139.510262)
		(width 0.254)
		(layer "In2.Cu")
		(net "VR_PVCCP_NODE1_TSEN_R")
	)
	(segment
		(start 102.161848 -129.436622)
		(end 101.995224 -129.269998)
		(width 0.254)
		(layer "In2.Cu")
		(net "VR_PVCCP_NODE1_TSEN_R")
	)
	(segment
		(start 101.49586 -140.210794)
		(end 101.873812 -139.832842)
		(width 0.254)
		(layer "In2.Cu")
		(net "VR_PVCCP_NODE1_TSEN_R")
	)
	(segment
		(start 101.49586 -140.589508)
		(end 101.49586 -140.210794)
		(width 0.254)
		(layer "In2.Cu")
		(net "VR_PVCCP_NODE1_TSEN_R")
	)
	(segment
		(start 101.873812 -139.832842)
		(end 101.873812 -139.798298)
		(width 0.254)
		(layer "In2.Cu")
		(net "VR_PVCCP_NODE1_TSEN_R")
	)
	(segment
		(start 102.161848 -139.510262)
		(end 102.161848 -129.436622)
		(width 0.254)
		(layer "In2.Cu")
		(net "VR_PVCCP_NODE1_TSEN_R")
	)
	(via
		(at 92.6973 -162.33013)
		(size 0.6604)
		(drill 0.3302)
		(layers "F.Cu" "B.Cu")
		(net "I2C_SDC_SCL")
	)
	(segment
		(start 88.504776 -163.70427)
		(end 89.362534 -162.846512)
		(width 0.1016)
		(layer "B.Cu")
		(net "I2C_SDC_SCL")
	)
	(segment
		(start 92.6973 -162.33013)
		(end 90.795856 -162.33013)
		(width 0.1016)
		(layer "B.Cu")
		(net "I2C_SDC_SCL")
	)
	(segment
		(start 87.748872 -163.70427)
		(end 88.504776 -163.70427)
		(width 0.1016)
		(layer "B.Cu")
		(net "I2C_SDC_SCL")
	)
	(segment
		(start 90.41257 -162.713416)
		(end 90.41257 -162.846512)
		(width 0.1016)
		(layer "B.Cu")
		(net "I2C_SDC_SCL")
	)
	(segment
		(start 90.795856 -162.33013)
		(end 90.41257 -162.713416)
		(width 0.1016)
		(layer "B.Cu")
		(net "I2C_SDC_SCL")
	)
	(segment
		(start 89.362534 -162.846512)
		(end 90.41257 -162.846512)
		(width 0.1016)
		(layer "B.Cu")
		(net "I2C_SDC_SCL")
	)
	(segment
		(start 59.741816 -130.458972)
		(end 59.341004 -130.05816)
		(width 0.1016)
		(layer "F.Cu")
		(net "BMC_NODE1_DDR_MA12")
	)
	(segment
		(start 59.741816 -130.45948)
		(end 59.741816 -130.458972)
		(width 0.1016)
		(layer "F.Cu")
		(net "BMC_NODE1_DDR_MA12")
	)
	(segment
		(start 44.832524 -131.36372)
		(end 44.59224 -131.123436)
		(width 0.1016)
		(layer "F.Cu")
		(net "BMC_NODE1_DDR_MA12")
	)
	(segment
		(start 44.59224 -131.123436)
		(end 43.710098 -129.676144)
		(width 0.1016)
		(layer "F.Cu")
		(net "BMC_NODE1_DDR_MA12")
	)
	(segment
		(start 44.833032 -131.36372)
		(end 44.832524 -131.36372)
		(width 0.1016)
		(layer "F.Cu")
		(net "BMC_NODE1_DDR_MA12")
	)
	(via
		(at 43.710098 -129.676144)
		(size 0.508)
		(drill 0.254)
		(layers "F.Cu" "B.Cu")
		(net "BMC_NODE1_DDR_MA12")
	)
	(via
		(at 59.341004 -130.05816)
		(size 0.49022)
		(drill 0.254)
		(layers "F.Cu" "B.Cu")
		(net "BMC_NODE1_DDR_MA12")
	)
	(segment
		(start 57.686194 -131.25577)
		(end 58.430414 -131.25577)
		(width 0.1143)
		(layer "In2.Cu")
		(net "BMC_NODE1_DDR_MA12")
	)
	(segment
		(start 44.02963 -128.939036)
		(end 45.801788 -127.166878)
		(width 0.1143)
		(layer "In2.Cu")
		(net "BMC_NODE1_DDR_MA12")
	)
	(segment
		(start 58.430414 -131.25577)
		(end 58.775854 -131.25577)
		(width 0.1016)
		(layer "In2.Cu")
		(net "BMC_NODE1_DDR_MA12")
	)
	(segment
		(start 59.44997 -131.25577)
		(end 59.59729 -131.25577)
		(width 0.1143)
		(layer "In2.Cu")
		(net "BMC_NODE1_DDR_MA12")
	)
	(segment
		(start 45.801788 -127.166878)
		(end 52.07508 -127.166878)
		(width 0.1143)
		(layer "In2.Cu")
		(net "BMC_NODE1_DDR_MA12")
	)
	(segment
		(start 59.738768 -131.114292)
		(end 59.738768 -130.938778)
		(width 0.1143)
		(layer "In2.Cu")
		(net "BMC_NODE1_DDR_MA12")
	)
	(segment
		(start 53.781706 -128.031494)
		(end 55.750968 -129.320544)
		(width 0.1143)
		(layer "In2.Cu")
		(net "BMC_NODE1_DDR_MA12")
	)
	(segment
		(start 59.738768 -130.675888)
		(end 59.738768 -130.451098)
		(width 0.1143)
		(layer "In2.Cu")
		(net "BMC_NODE1_DDR_MA12")
	)
	(segment
		(start 58.775854 -131.25577)
		(end 59.23788 -131.25577)
		(width 0.1143)
		(layer "In2.Cu")
		(net "BMC_NODE1_DDR_MA12")
	)
	(segment
		(start 59.34583 -130.05816)
		(end 59.341004 -130.05816)
		(width 0.1143)
		(layer "In2.Cu")
		(net "BMC_NODE1_DDR_MA12")
	)
	(segment
		(start 59.738768 -130.451098)
		(end 59.34583 -130.05816)
		(width 0.1143)
		(layer "In2.Cu")
		(net "BMC_NODE1_DDR_MA12")
	)
	(segment
		(start 59.59729 -131.25577)
		(end 59.738768 -131.114292)
		(width 0.1143)
		(layer "In2.Cu")
		(net "BMC_NODE1_DDR_MA12")
	)
	(segment
		(start 43.710098 -129.676144)
		(end 43.928538 -129.172462)
		(width 0.1143)
		(layer "In2.Cu")
		(net "BMC_NODE1_DDR_MA12")
	)
	(segment
		(start 55.750968 -129.320544)
		(end 57.686194 -131.25577)
		(width 0.1143)
		(layer "In2.Cu")
		(net "BMC_NODE1_DDR_MA12")
	)
	(segment
		(start 59.738768 -130.938778)
		(end 59.738768 -130.675888)
		(width 0.1016)
		(layer "In2.Cu")
		(net "BMC_NODE1_DDR_MA12")
	)
	(segment
		(start 59.23788 -131.25577)
		(end 59.44997 -131.25577)
		(width 0.1016)
		(layer "In2.Cu")
		(net "BMC_NODE1_DDR_MA12")
	)
	(segment
		(start 53.4162 -128.031494)
		(end 53.781706 -128.031494)
		(width 0.1143)
		(layer "In2.Cu")
		(net "BMC_NODE1_DDR_MA12")
	)
	(segment
		(start 52.07508 -127.166878)
		(end 53.4162 -128.031494)
		(width 0.1143)
		(layer "In2.Cu")
		(net "BMC_NODE1_DDR_MA12")
	)
	(segment
		(start 43.928538 -129.172462)
		(end 44.02963 -128.939036)
		(width 0.1143)
		(layer "In2.Cu")
		(net "BMC_NODE1_DDR_MA12")
	)
	(segment
		(start 178.010566 -125.365764)
		(end 178.010566 -128.026414)
		(width 0.1016)
		(layer "F.Cu")
		(net "FM_CPU_NODE1_SLPMODE")
	)
	(segment
		(start 69.440044 -82.657442)
		(end 69.333618 -82.763868)
		(width 0.1016)
		(layer "F.Cu")
		(net "FM_CPU_NODE1_SLPMODE")
	)
	(segment
		(start 69.440044 -82.228182)
		(end 69.440044 -82.657442)
		(width 0.1016)
		(layer "F.Cu")
		(net "FM_CPU_NODE1_SLPMODE")
	)
	(via
		(at 178.010566 -128.026414)
		(size 0.508)
		(drill 0.254)
		(layers "F.Cu" "B.Cu")
		(net "FM_CPU_NODE1_SLPMODE")
	)
	(via
		(at 69.333618 -82.763868)
		(size 0.508)
		(drill 0.254)
		(layers "F.Cu" "B.Cu")
		(net "FM_CPU_NODE1_SLPMODE")
	)
	(segment
		(start 73.85304 -85.383624)
		(end 76.15682 -87.687404)
		(width 0.1143)
		(layer "In6.Cu")
		(net "FM_CPU_NODE1_SLPMODE")
	)
	(segment
		(start 72.013064 -83.913726)
		(end 73.482962 -85.383624)
		(width 0.1143)
		(layer "In6.Cu")
		(net "FM_CPU_NODE1_SLPMODE")
	)
	(segment
		(start 172.4406 -125.57125)
		(end 174.895764 -128.026414)
		(width 0.1143)
		(layer "In6.Cu")
		(net "FM_CPU_NODE1_SLPMODE")
	)
	(segment
		(start 155.932378 -111.657892)
		(end 163.41344 -111.657892)
		(width 0.1143)
		(layer "In6.Cu")
		(net "FM_CPU_NODE1_SLPMODE")
	)
	(segment
		(start 79.673196 -91.30157)
		(end 82.025236 -91.30157)
		(width 0.1143)
		(layer "In6.Cu")
		(net "FM_CPU_NODE1_SLPMODE")
	)
	(segment
		(start 69.333618 -82.763868)
		(end 69.397372 -82.763868)
		(width 0.1143)
		(layer "In6.Cu")
		(net "FM_CPU_NODE1_SLPMODE")
	)
	(segment
		(start 70.838568 -83.913726)
		(end 72.013064 -83.913726)
		(width 0.1143)
		(layer "In6.Cu")
		(net "FM_CPU_NODE1_SLPMODE")
	)
	(segment
		(start 174.895764 -128.026414)
		(end 178.010566 -128.026414)
		(width 0.1143)
		(layer "In6.Cu")
		(net "FM_CPU_NODE1_SLPMODE")
	)
	(segment
		(start 76.15682 -87.785194)
		(end 79.673196 -91.30157)
		(width 0.1143)
		(layer "In6.Cu")
		(net "FM_CPU_NODE1_SLPMODE")
	)
	(segment
		(start 70.10146 -83.176618)
		(end 70.838568 -83.913726)
		(width 0.1143)
		(layer "In6.Cu")
		(net "FM_CPU_NODE1_SLPMODE")
	)
	(segment
		(start 96.9772 -89.128346)
		(end 135.396224 -89.128346)
		(width 0.1143)
		(layer "In6.Cu")
		(net "FM_CPU_NODE1_SLPMODE")
	)
	(segment
		(start 86.816184 -91.273122)
		(end 88.141556 -92.598494)
		(width 0.1143)
		(layer "In6.Cu")
		(net "FM_CPU_NODE1_SLPMODE")
	)
	(segment
		(start 89.58072 -93.3958)
		(end 92.709746 -93.3958)
		(width 0.1143)
		(layer "In6.Cu")
		(net "FM_CPU_NODE1_SLPMODE")
	)
	(segment
		(start 82.737452 -90.589354)
		(end 83.264502 -90.589354)
		(width 0.1143)
		(layer "In6.Cu")
		(net "FM_CPU_NODE1_SLPMODE")
	)
	(segment
		(start 69.810122 -83.176618)
		(end 70.10146 -83.176618)
		(width 0.1143)
		(layer "In6.Cu")
		(net "FM_CPU_NODE1_SLPMODE")
	)
	(segment
		(start 163.41344 -111.657892)
		(end 166.34206 -114.586512)
		(width 0.1143)
		(layer "In6.Cu")
		(net "FM_CPU_NODE1_SLPMODE")
	)
	(segment
		(start 166.34206 -122.510296)
		(end 169.403014 -125.57125)
		(width 0.1143)
		(layer "In6.Cu")
		(net "FM_CPU_NODE1_SLPMODE")
	)
	(segment
		(start 166.34206 -114.586512)
		(end 166.34206 -122.510296)
		(width 0.1143)
		(layer "In6.Cu")
		(net "FM_CPU_NODE1_SLPMODE")
	)
	(segment
		(start 88.783414 -92.598494)
		(end 89.58072 -93.3958)
		(width 0.1143)
		(layer "In6.Cu")
		(net "FM_CPU_NODE1_SLPMODE")
	)
	(segment
		(start 135.396224 -89.128346)
		(end 150.46198 -104.194102)
		(width 0.1143)
		(layer "In6.Cu")
		(net "FM_CPU_NODE1_SLPMODE")
	)
	(segment
		(start 92.709746 -93.3958)
		(end 96.9772 -89.128346)
		(width 0.1143)
		(layer "In6.Cu")
		(net "FM_CPU_NODE1_SLPMODE")
	)
	(segment
		(start 83.94827 -91.273122)
		(end 86.816184 -91.273122)
		(width 0.1143)
		(layer "In6.Cu")
		(net "FM_CPU_NODE1_SLPMODE")
	)
	(segment
		(start 88.141556 -92.598494)
		(end 88.783414 -92.598494)
		(width 0.1143)
		(layer "In6.Cu")
		(net "FM_CPU_NODE1_SLPMODE")
	)
	(segment
		(start 82.025236 -91.30157)
		(end 82.737452 -90.589354)
		(width 0.1143)
		(layer "In6.Cu")
		(net "FM_CPU_NODE1_SLPMODE")
	)
	(segment
		(start 83.264502 -90.589354)
		(end 83.94827 -91.273122)
		(width 0.1143)
		(layer "In6.Cu")
		(net "FM_CPU_NODE1_SLPMODE")
	)
	(segment
		(start 150.46198 -106.187494)
		(end 155.932378 -111.657892)
		(width 0.1143)
		(layer "In6.Cu")
		(net "FM_CPU_NODE1_SLPMODE")
	)
	(segment
		(start 76.15682 -87.687404)
		(end 76.15682 -87.785194)
		(width 0.1143)
		(layer "In6.Cu")
		(net "FM_CPU_NODE1_SLPMODE")
	)
	(segment
		(start 73.482962 -85.383624)
		(end 73.85304 -85.383624)
		(width 0.1143)
		(layer "In6.Cu")
		(net "FM_CPU_NODE1_SLPMODE")
	)
	(segment
		(start 69.397372 -82.763868)
		(end 69.810122 -83.176618)
		(width 0.1143)
		(layer "In6.Cu")
		(net "FM_CPU_NODE1_SLPMODE")
	)
	(segment
		(start 169.403014 -125.57125)
		(end 172.4406 -125.57125)
		(width 0.1143)
		(layer "In6.Cu")
		(net "FM_CPU_NODE1_SLPMODE")
	)
	(segment
		(start 150.46198 -104.194102)
		(end 150.46198 -106.187494)
		(width 0.1143)
		(layer "In6.Cu")
		(net "FM_CPU_NODE1_SLPMODE")
	)
	(segment
		(start 49.23917 -68.174108)
		(end 49.175924 -68.174108)
		(width 0.1016)
		(layer "F.Cu")
		(net "TP_CPU_NODE1_RP0_PETP1")
	)
	(segment
		(start 49.67224 -67.741038)
		(end 49.23917 -68.174108)
		(width 0.1016)
		(layer "F.Cu")
		(net "TP_CPU_NODE1_RP0_PETP1")
	)
	(segment
		(start 49.175924 -68.174108)
		(end 48.73244 -68.617592)
		(width 0.1016)
		(layer "F.Cu")
		(net "TP_CPU_NODE1_RP0_PETP1")
	)
	(segment
		(start 49.825402 -67.741038)
		(end 49.67224 -67.741038)
		(width 0.1016)
		(layer "F.Cu")
		(net "TP_CPU_NODE1_RP0_PETP1")
	)
	(via
		(at 48.73244 -68.617592)
		(size 0.508)
		(drill 0.254)
		(layers "F.Cu" "B.Cu")
		(net "TP_CPU_NODE1_RP0_PETP1")
	)
	(via
		(at 48.181006 -68.132198)
		(size 0.6604)
		(drill 0.3302)
		(layers "F.Cu" "B.Cu")
		(net "TP_CPU_NODE1_RP0_PETP1")
	)
	(segment
		(start 48.6664 -68.617592)
		(end 48.73244 -68.617592)
		(width 0.1016)
		(layer "B.Cu")
		(net "TP_CPU_NODE1_RP0_PETP1")
	)
	(segment
		(start 48.181006 -68.132198)
		(end 48.6664 -68.617592)
		(width 0.1016)
		(layer "B.Cu")
		(net "TP_CPU_NODE1_RP0_PETP1")
	)
	(segment
		(start 112.717072 -131.612894)
		(end 113.38941 -130.940556)
		(width 0.254)
		(layer "F.Cu")
		(net "ISENSE_PVCCP_NODE1_ISEN1P")
	)
	(segment
		(start 108.901738 -120.47347)
		(end 108.901738 -119.06758)
		(width 0.254)
		(layer "F.Cu")
		(net "ISENSE_PVCCP_NODE1_ISEN1P")
	)
	(segment
		(start 113.38941 -130.940556)
		(end 114.148108 -130.940556)
		(width 0.254)
		(layer "F.Cu")
		(net "ISENSE_PVCCP_NODE1_ISEN1P")
	)
	(via
		(at 114.148108 -130.940556)
		(size 0.508)
		(drill 0.254)
		(layers "F.Cu" "B.Cu")
		(net "ISENSE_PVCCP_NODE1_ISEN1P")
	)
	(via
		(at 108.901738 -119.06758)
		(size 0.508)
		(drill 0.254)
		(layers "F.Cu" "B.Cu")
		(net "ISENSE_PVCCP_NODE1_ISEN1P")
	)
	(segment
		(start 115.064794 -132.192268)
		(end 115.964716 -132.192268)
		(width 0.254)
		(layer "In6.Cu")
		(net "ISENSE_PVCCP_NODE1_ISEN1P")
	)
	(segment
		(start 114.148108 -131.275582)
		(end 115.064794 -132.192268)
		(width 0.254)
		(layer "In6.Cu")
		(net "ISENSE_PVCCP_NODE1_ISEN1P")
	)
	(segment
		(start 116.667026 -132.894578)
		(end 118.531894 -132.894578)
		(width 0.254)
		(layer "In6.Cu")
		(net "ISENSE_PVCCP_NODE1_ISEN1P")
	)
	(segment
		(start 109.39145 -118.577868)
		(end 108.901738 -119.06758)
		(width 0.254)
		(layer "In6.Cu")
		(net "ISENSE_PVCCP_NODE1_ISEN1P")
	)
	(segment
		(start 120.106186 -119.126508)
		(end 119.557546 -118.577868)
		(width 0.254)
		(layer "In6.Cu")
		(net "ISENSE_PVCCP_NODE1_ISEN1P")
	)
	(segment
		(start 115.964716 -132.192268)
		(end 116.667026 -132.894578)
		(width 0.254)
		(layer "In6.Cu")
		(net "ISENSE_PVCCP_NODE1_ISEN1P")
	)
	(segment
		(start 114.148108 -130.940556)
		(end 114.148108 -131.275582)
		(width 0.254)
		(layer "In6.Cu")
		(net "ISENSE_PVCCP_NODE1_ISEN1P")
	)
	(segment
		(start 119.557546 -118.577868)
		(end 109.39145 -118.577868)
		(width 0.254)
		(layer "In6.Cu")
		(net "ISENSE_PVCCP_NODE1_ISEN1P")
	)
	(segment
		(start 120.106186 -131.320286)
		(end 120.106186 -119.126508)
		(width 0.254)
		(layer "In6.Cu")
		(net "ISENSE_PVCCP_NODE1_ISEN1P")
	)
	(segment
		(start 118.531894 -132.894578)
		(end 120.106186 -131.320286)
		(width 0.254)
		(layer "In6.Cu")
		(net "ISENSE_PVCCP_NODE1_ISEN1P")
	)
	(segment
		(start 60.53963 -137.659618)
		(end 60.141104 -138.058144)
		(width 0.1016)
		(layer "F.Cu")
		(net "BMC_NODE1_DDR_DM1")
	)
	(segment
		(start 41.63314 -138.563604)
		(end 42.776902 -139.961112)
		(width 0.1016)
		(layer "F.Cu")
		(net "BMC_NODE1_DDR_DM1")
	)
	(segment
		(start 42.776902 -139.961112)
		(end 43.913806 -142.92834)
		(width 0.1016)
		(layer "F.Cu")
		(net "BMC_NODE1_DDR_DM1")
	)
	(segment
		(start 60.541916 -137.659618)
		(end 60.53963 -137.659618)
		(width 0.1016)
		(layer "F.Cu")
		(net "BMC_NODE1_DDR_DM1")
	)
	(via
		(at 43.913806 -142.92834)
		(size 0.508)
		(drill 0.254)
		(layers "F.Cu" "B.Cu")
		(net "BMC_NODE1_DDR_DM1")
	)
	(via
		(at 60.141104 -138.058144)
		(size 0.49022)
		(drill 0.254)
		(layers "F.Cu" "B.Cu")
		(net "BMC_NODE1_DDR_DM1")
	)
	(segment
		(start 59.567318 -138.46048)
		(end 59.895486 -138.230356)
		(width 0.1016)
		(layer "In7.Cu")
		(net "BMC_NODE1_DDR_DM1")
	)
	(segment
		(start 58.35523 -138.46048)
		(end 59.567318 -138.46048)
		(width 0.1016)
		(layer "In7.Cu")
		(net "BMC_NODE1_DDR_DM1")
	)
	(segment
		(start 56.053482 -142.21206)
		(end 58.117486 -138.698224)
		(width 0.1143)
		(layer "In7.Cu")
		(net "BMC_NODE1_DDR_DM1")
	)
	(segment
		(start 45.514514 -143.339312)
		(end 54.92623 -143.339312)
		(width 0.1143)
		(layer "In7.Cu")
		(net "BMC_NODE1_DDR_DM1")
	)
	(segment
		(start 43.913806 -142.92834)
		(end 45.514514 -143.339312)
		(width 0.1143)
		(layer "In7.Cu")
		(net "BMC_NODE1_DDR_DM1")
	)
	(segment
		(start 58.117486 -138.698224)
		(end 58.35523 -138.46048)
		(width 0.1143)
		(layer "In7.Cu")
		(net "BMC_NODE1_DDR_DM1")
	)
	(segment
		(start 54.92623 -143.339312)
		(end 56.053482 -142.21206)
		(width 0.1143)
		(layer "In7.Cu")
		(net "BMC_NODE1_DDR_DM1")
	)
	(segment
		(start 59.895486 -138.230356)
		(end 60.141104 -138.058144)
		(width 0.1016)
		(layer "In7.Cu")
		(net "BMC_NODE1_DDR_DM1")
	)
	(segment
		(start 84.82584 -107.510834)
		(end 85.53196 -106.804714)
		(width 0.1016)
		(layer "F.Cu")
		(net "SPI_CPU_NODE1_MOSI")
	)
	(segment
		(start 64.193166 -97.110042)
		(end 64.455548 -97.372424)
		(width 0.1016)
		(layer "F.Cu")
		(net "SPI_CPU_NODE1_MOSI")
	)
	(segment
		(start 64.455548 -97.372424)
		(end 64.455548 -97.85477)
		(width 0.1016)
		(layer "F.Cu")
		(net "SPI_CPU_NODE1_MOSI")
	)
	(segment
		(start 91.968066 -108.56595)
		(end 91.571826 -108.96219)
		(width 0.1016)
		(layer "F.Cu")
		(net "SPI_CPU_NODE1_MOSI")
	)
	(segment
		(start 91.571826 -108.96219)
		(end 85.684614 -108.96219)
		(width 0.1016)
		(layer "F.Cu")
		(net "SPI_CPU_NODE1_MOSI")
	)
	(segment
		(start 91.968066 -103.859584)
		(end 91.968066 -104.128062)
		(width 0.1016)
		(layer "F.Cu")
		(net "SPI_CPU_NODE1_MOSI")
	)
	(segment
		(start 91.968066 -104.128062)
		(end 91.968066 -108.56595)
		(width 0.1016)
		(layer "F.Cu")
		(net "SPI_CPU_NODE1_MOSI")
	)
	(segment
		(start 85.53196 -106.804714)
		(end 85.53196 -105.935526)
		(width 0.1016)
		(layer "F.Cu")
		(net "SPI_CPU_NODE1_MOSI")
	)
	(segment
		(start 85.684614 -108.96219)
		(end 84.82584 -108.103416)
		(width 0.1016)
		(layer "F.Cu")
		(net "SPI_CPU_NODE1_MOSI")
	)
	(segment
		(start 84.82584 -108.103416)
		(end 84.82584 -107.510834)
		(width 0.1016)
		(layer "F.Cu")
		(net "SPI_CPU_NODE1_MOSI")
	)
	(via
		(at 85.53196 -105.935526)
		(size 0.508)
		(drill 0.254)
		(layers "F.Cu" "B.Cu")
		(net "SPI_CPU_NODE1_MOSI")
	)
	(via
		(at 64.455548 -97.85477)
		(size 0.508)
		(drill 0.254)
		(layers "F.Cu" "B.Cu")
		(net "SPI_CPU_NODE1_MOSI")
	)
	(segment
		(start 69.77507 -100.523548)
		(end 70.334886 -101.083364)
		(width 0.1016)
		(layer "B.Cu")
		(net "SPI_CPU_NODE1_MOSI")
	)
	(segment
		(start 65.70091 -100.523548)
		(end 69.77507 -100.523548)
		(width 0.1016)
		(layer "B.Cu")
		(net "SPI_CPU_NODE1_MOSI")
	)
	(segment
		(start 64.455548 -97.85477)
		(end 64.455548 -99.278186)
		(width 0.1016)
		(layer "B.Cu")
		(net "SPI_CPU_NODE1_MOSI")
	)
	(segment
		(start 64.455548 -99.278186)
		(end 65.70091 -100.523548)
		(width 0.1016)
		(layer "B.Cu")
		(net "SPI_CPU_NODE1_MOSI")
	)
	(segment
		(start 70.334886 -101.083364)
		(end 75.221846 -101.083364)
		(width 0.1016)
		(layer "B.Cu")
		(net "SPI_CPU_NODE1_MOSI")
	)
	(segment
		(start 75.718162 -101.57968)
		(end 79.706724 -101.57968)
		(width 0.1016)
		(layer "B.Cu")
		(net "SPI_CPU_NODE1_MOSI")
	)
	(segment
		(start 82.033364 -102.43693)
		(end 85.53196 -105.935526)
		(width 0.1016)
		(layer "B.Cu")
		(net "SPI_CPU_NODE1_MOSI")
	)
	(segment
		(start 80.563974 -102.43693)
		(end 82.033364 -102.43693)
		(width 0.1016)
		(layer "B.Cu")
		(net "SPI_CPU_NODE1_MOSI")
	)
	(segment
		(start 79.706724 -101.57968)
		(end 80.563974 -102.43693)
		(width 0.1016)
		(layer "B.Cu")
		(net "SPI_CPU_NODE1_MOSI")
	)
	(segment
		(start 75.221846 -101.083364)
		(end 75.718162 -101.57968)
		(width 0.1016)
		(layer "B.Cu")
		(net "SPI_CPU_NODE1_MOSI")
	)
	(segment
		(start 109.766608 -142.010892)
		(end 109.766608 -141.63421)
		(width 0.254)
		(layer "F.Cu")
		(net "VR_PVCCP_NODE1_TEMPMAX")
	)
	(segment
		(start 109.766608 -141.63421)
		(end 109.51083 -141.378432)
		(width 0.254)
		(layer "F.Cu")
		(net "VR_PVCCP_NODE1_TEMPMAX")
	)
	(segment
		(start 108.871512 -138.08583)
		(end 109.333284 -138.547602)
		(width 0.1778)
		(layer "F.Cu")
		(net "VR_PVCCP_NODE1_TEMPMAX")
	)
	(segment
		(start 109.333284 -139.040362)
		(end 109.333284 -139.429998)
		(width 0.254)
		(layer "F.Cu")
		(net "VR_PVCCP_NODE1_TEMPMAX")
	)
	(segment
		(start 109.53877 -139.936982)
		(end 109.253782 -140.22197)
		(width 0.254)
		(layer "F.Cu")
		(net "VR_PVCCP_NODE1_TEMPMAX")
	)
	(segment
		(start 109.253782 -140.22197)
		(end 109.253782 -141.121384)
		(width 0.254)
		(layer "F.Cu")
		(net "VR_PVCCP_NODE1_TEMPMAX")
	)
	(segment
		(start 109.333284 -138.547602)
		(end 109.333284 -139.040362)
		(width 0.1778)
		(layer "F.Cu")
		(net "VR_PVCCP_NODE1_TEMPMAX")
	)
	(segment
		(start 109.333284 -139.429998)
		(end 109.817154 -139.913868)
		(width 0.254)
		(layer "F.Cu")
		(net "VR_PVCCP_NODE1_TEMPMAX")
	)
	(segment
		(start 108.871512 -137.42289)
		(end 108.871512 -138.08583)
		(width 0.1778)
		(layer "F.Cu")
		(net "VR_PVCCP_NODE1_TEMPMAX")
	)
	(segment
		(start 109.817154 -139.936982)
		(end 109.53877 -139.936982)
		(width 0.254)
		(layer "F.Cu")
		(net "VR_PVCCP_NODE1_TEMPMAX")
	)
	(segment
		(start 109.817154 -139.913868)
		(end 109.817154 -139.936982)
		(width 0.254)
		(layer "F.Cu")
		(net "VR_PVCCP_NODE1_TEMPMAX")
	)
	(segment
		(start 109.253782 -141.121384)
		(end 109.51083 -141.378432)
		(width 0.254)
		(layer "F.Cu")
		(net "VR_PVCCP_NODE1_TEMPMAX")
	)
	(via
		(at 109.51083 -141.378432)
		(size 0.508)
		(drill 0.254)
		(layers "F.Cu" "B.Cu")
		(net "VR_PVCCP_NODE1_TEMPMAX")
	)
	(segment
		(start 165.992556 -120.365774)
		(end 164.834824 -119.208042)
		(width 0.1016)
		(layer "F.Cu")
		(net "TP_CPLD_NODE1_IO39")
	)
	(segment
		(start 172.010324 -120.365774)
		(end 165.992556 -120.365774)
		(width 0.1016)
		(layer "F.Cu")
		(net "TP_CPLD_NODE1_IO39")
	)
	(via
		(at 164.834824 -119.208042)
		(size 0.508)
		(drill 0.254)
		(layers "F.Cu" "B.Cu")
		(net "TP_CPLD_NODE1_IO39")
	)
	(segment
		(start 41.63314 -128.963674)
		(end 42.089578 -128.563624)
		(width 0.1016)
		(layer "F.Cu")
		(net "BMC_NODE1_DDR_MA13")
	)
	(segment
		(start 58.941716 -130.458972)
		(end 58.540904 -130.05816)
		(width 0.1016)
		(layer "F.Cu")
		(net "BMC_NODE1_DDR_MA13")
	)
	(segment
		(start 58.941716 -130.45948)
		(end 58.941716 -130.458972)
		(width 0.1016)
		(layer "F.Cu")
		(net "BMC_NODE1_DDR_MA13")
	)
	(via
		(at 42.089578 -128.563624)
		(size 0.508)
		(drill 0.254)
		(layers "F.Cu" "B.Cu")
		(net "BMC_NODE1_DDR_MA13")
	)
	(via
		(at 58.540904 -130.05816)
		(size 0.49022)
		(drill 0.254)
		(layers "F.Cu" "B.Cu")
		(net "BMC_NODE1_DDR_MA13")
	)
	(segment
		(start 56.6039 -127.431292)
		(end 57.279286 -128.106678)
		(width 0.1143)
		(layer "In2.Cu")
		(net "BMC_NODE1_DDR_MA13")
	)
	(segment
		(start 42.09923 -128.550416)
		(end 45.044868 -125.604778)
		(width 0.1143)
		(layer "In2.Cu")
		(net "BMC_NODE1_DDR_MA13")
	)
	(segment
		(start 57.279286 -128.62814)
		(end 57.511442 -128.860296)
		(width 0.1143)
		(layer "In2.Cu")
		(net "BMC_NODE1_DDR_MA13")
	)
	(segment
		(start 57.969658 -128.860296)
		(end 58.142632 -129.03327)
		(width 0.1143)
		(layer "In2.Cu")
		(net "BMC_NODE1_DDR_MA13")
	)
	(segment
		(start 45.044868 -125.604778)
		(end 53.28666 -125.604778)
		(width 0.1143)
		(layer "In2.Cu")
		(net "BMC_NODE1_DDR_MA13")
	)
	(segment
		(start 58.142632 -129.169922)
		(end 58.142632 -129.420112)
		(width 0.1016)
		(layer "In2.Cu")
		(net "BMC_NODE1_DDR_MA13")
	)
	(segment
		(start 57.807098 -128.860296)
		(end 57.969658 -128.860296)
		(width 0.1143)
		(layer "In2.Cu")
		(net "BMC_NODE1_DDR_MA13")
	)
	(segment
		(start 57.511442 -128.860296)
		(end 57.67578 -128.860296)
		(width 0.1143)
		(layer "In2.Cu")
		(net "BMC_NODE1_DDR_MA13")
	)
	(segment
		(start 58.142632 -129.420112)
		(end 58.540904 -130.05816)
		(width 0.1143)
		(layer "In2.Cu")
		(net "BMC_NODE1_DDR_MA13")
	)
	(segment
		(start 53.28666 -125.604778)
		(end 55.35168 -126.741682)
		(width 0.1143)
		(layer "In2.Cu")
		(net "BMC_NODE1_DDR_MA13")
	)
	(segment
		(start 58.142632 -129.03327)
		(end 58.142632 -129.169922)
		(width 0.1143)
		(layer "In2.Cu")
		(net "BMC_NODE1_DDR_MA13")
	)
	(segment
		(start 57.67578 -128.860296)
		(end 57.807098 -128.860296)
		(width 0.1016)
		(layer "In2.Cu")
		(net "BMC_NODE1_DDR_MA13")
	)
	(segment
		(start 55.35168 -126.741682)
		(end 56.6039 -127.431292)
		(width 0.1143)
		(layer "In2.Cu")
		(net "BMC_NODE1_DDR_MA13")
	)
	(segment
		(start 42.089578 -128.563624)
		(end 42.09923 -128.550416)
		(width 0.1143)
		(layer "In2.Cu")
		(net "BMC_NODE1_DDR_MA13")
	)
	(segment
		(start 57.279286 -128.106678)
		(end 57.279286 -128.62814)
		(width 0.1143)
		(layer "In2.Cu")
		(net "BMC_NODE1_DDR_MA13")
	)
	(segment
		(start 101.00437 -7.667752)
		(end 101.00437 -5.419344)
		(width 0.1016)
		(layer "F.Cu")
		(net "TP_P3V3_NODE1_INIT_L")
	)
	(via
		(at 101.00437 -5.419344)
		(size 0.508)
		(drill 0.254)
		(layers "F.Cu" "B.Cu")
		(net "TP_P3V3_NODE1_INIT_L")
	)
	(segment
		(start 118.183914 -136.64819)
		(end 118.183914 -138.39317)
		(width 0.254)
		(layer "F.Cu")
		(net "VR_PVCCP_NODE1_VSEN")
	)
	(segment
		(start 115.616736 -138.065002)
		(end 115.998498 -138.065002)
		(width 0.254)
		(layer "F.Cu")
		(net "VR_PVCCP_NODE1_VSEN")
	)
	(segment
		(start 116.075714 -139.122912)
		(end 116.075714 -138.142218)
		(width 0.254)
		(layer "F.Cu")
		(net "VR_PVCCP_NODE1_VSEN")
	)
	(segment
		(start 114.393218 -138.794744)
		(end 114.886994 -138.794744)
		(width 0.254)
		(layer "F.Cu")
		(net "VR_PVCCP_NODE1_VSEN")
	)
	(segment
		(start 117.711982 -138.865102)
		(end 116.927122 -138.865102)
		(width 0.254)
		(layer "F.Cu")
		(net "VR_PVCCP_NODE1_VSEN")
	)
	(segment
		(start 116.669312 -139.122912)
		(end 116.075714 -139.122912)
		(width 0.254)
		(layer "F.Cu")
		(net "VR_PVCCP_NODE1_VSEN")
	)
	(segment
		(start 115.2398 -138.441938)
		(end 115.616736 -138.065002)
		(width 0.254)
		(layer "F.Cu")
		(net "VR_PVCCP_NODE1_VSEN")
	)
	(segment
		(start 116.927122 -138.865102)
		(end 116.669312 -139.122912)
		(width 0.254)
		(layer "F.Cu")
		(net "VR_PVCCP_NODE1_VSEN")
	)
	(segment
		(start 114.886994 -138.794744)
		(end 115.2398 -138.441938)
		(width 0.254)
		(layer "F.Cu")
		(net "VR_PVCCP_NODE1_VSEN")
	)
	(segment
		(start 116.075714 -138.142218)
		(end 115.998498 -138.065002)
		(width 0.254)
		(layer "F.Cu")
		(net "VR_PVCCP_NODE1_VSEN")
	)
	(segment
		(start 118.183914 -138.39317)
		(end 117.711982 -138.865102)
		(width 0.254)
		(layer "F.Cu")
		(net "VR_PVCCP_NODE1_VSEN")
	)
	(via
		(at 115.2398 -138.441938)
		(size 0.508)
		(drill 0.254)
		(layers "F.Cu" "B.Cu")
		(net "VR_PVCCP_NODE1_VSEN")
	)
	(segment
		(start 48.276764 -127.183642)
		(end 50.306224 -129.213102)
		(width 0.1016)
		(layer "F.Cu")
		(net "BMC_NODE1_DDR_MA14")
	)
	(segment
		(start 44.1833 -129.570226)
		(end 43.875706 -129.262632)
		(width 0.1016)
		(layer "F.Cu")
		(net "BMC_NODE1_DDR_MA14")
	)
	(segment
		(start 44.811442 -128.402842)
		(end 44.811442 -127.5334)
		(width 0.1016)
		(layer "F.Cu")
		(net "BMC_NODE1_DDR_MA14")
	)
	(segment
		(start 43.470576 -128.884172)
		(end 43.924474 -128.430274)
		(width 0.1016)
		(layer "F.Cu")
		(net "BMC_NODE1_DDR_MA14")
	)
	(segment
		(start 43.60926 -129.262632)
		(end 43.470576 -129.123948)
		(width 0.1016)
		(layer "F.Cu")
		(net "BMC_NODE1_DDR_MA14")
	)
	(segment
		(start 44.645834 -128.56845)
		(end 44.811442 -128.402842)
		(width 0.1016)
		(layer "F.Cu")
		(net "BMC_NODE1_DDR_MA14")
	)
	(segment
		(start 43.924474 -128.430274)
		(end 44.065698 -128.430274)
		(width 0.1016)
		(layer "F.Cu")
		(net "BMC_NODE1_DDR_MA14")
	)
	(segment
		(start 44.833032 -128.963674)
		(end 44.833032 -129.24536)
		(width 0.1016)
		(layer "F.Cu")
		(net "BMC_NODE1_DDR_MA14")
	)
	(segment
		(start 50.306224 -129.213102)
		(end 52.132738 -129.213102)
		(width 0.1016)
		(layer "F.Cu")
		(net "BMC_NODE1_DDR_MA14")
	)
	(segment
		(start 45.1612 -127.183642)
		(end 48.276764 -127.183642)
		(width 0.1016)
		(layer "F.Cu")
		(net "BMC_NODE1_DDR_MA14")
	)
	(segment
		(start 57.34177 -130.45948)
		(end 57.143904 -130.45948)
		(width 0.1016)
		(layer "F.Cu")
		(net "BMC_NODE1_DDR_MA14")
	)
	(segment
		(start 57.143904 -130.45948)
		(end 55.897526 -129.213102)
		(width 0.1016)
		(layer "F.Cu")
		(net "BMC_NODE1_DDR_MA14")
	)
	(segment
		(start 44.203874 -128.56845)
		(end 44.645834 -128.56845)
		(width 0.1016)
		(layer "F.Cu")
		(net "BMC_NODE1_DDR_MA14")
	)
	(segment
		(start 44.065698 -128.430274)
		(end 44.203874 -128.56845)
		(width 0.1016)
		(layer "F.Cu")
		(net "BMC_NODE1_DDR_MA14")
	)
	(segment
		(start 43.470576 -129.123948)
		(end 43.470576 -128.884172)
		(width 0.1016)
		(layer "F.Cu")
		(net "BMC_NODE1_DDR_MA14")
	)
	(segment
		(start 44.508166 -129.570226)
		(end 44.1833 -129.570226)
		(width 0.1016)
		(layer "F.Cu")
		(net "BMC_NODE1_DDR_MA14")
	)
	(segment
		(start 43.875706 -129.262632)
		(end 43.60926 -129.262632)
		(width 0.1016)
		(layer "F.Cu")
		(net "BMC_NODE1_DDR_MA14")
	)
	(segment
		(start 55.897526 -129.213102)
		(end 52.132738 -129.213102)
		(width 0.1016)
		(layer "F.Cu")
		(net "BMC_NODE1_DDR_MA14")
	)
	(segment
		(start 44.811442 -127.5334)
		(end 45.1612 -127.183642)
		(width 0.1016)
		(layer "F.Cu")
		(net "BMC_NODE1_DDR_MA14")
	)
	(segment
		(start 44.833032 -129.24536)
		(end 44.508166 -129.570226)
		(width 0.1016)
		(layer "F.Cu")
		(net "BMC_NODE1_DDR_MA14")
	)
	(via
		(at 52.132738 -129.213102)
		(size 0.762)
		(drill 0.381)
		(layers "F.Cu" "B.Cu")
		(net "BMC_NODE1_DDR_MA14")
	)
	(segment
		(start 69.332856 -83.78825)
		(end 69.332856 -83.989926)
		(width 0.1016)
		(layer "F.Cu")
		(net "FM_CPLD_NODE1_PWR_BTN_CPU")
	)
	(segment
		(start 69.059044 -83.514438)
		(end 69.332856 -83.78825)
		(width 0.1016)
		(layer "F.Cu")
		(net "FM_CPLD_NODE1_PWR_BTN_CPU")
	)
	(segment
		(start 182.71998 -119.998744)
		(end 182.35295 -120.365774)
		(width 0.1016)
		(layer "F.Cu")
		(net "FM_CPLD_NODE1_PWR_BTN_CPU")
	)
	(segment
		(start 182.35295 -120.365774)
		(end 181.01056 -120.365774)
		(width 0.1016)
		(layer "F.Cu")
		(net "FM_CPLD_NODE1_PWR_BTN_CPU")
	)
	(via
		(at 69.332856 -83.989926)
		(size 0.508)
		(drill 0.254)
		(layers "F.Cu" "B.Cu")
		(net "FM_CPLD_NODE1_PWR_BTN_CPU")
	)
	(via
		(at 182.71998 -119.998744)
		(size 0.508)
		(drill 0.254)
		(layers "F.Cu" "B.Cu")
		(net "FM_CPLD_NODE1_PWR_BTN_CPU")
	)
	(via
		(at 165.37432 -115.630452)
		(size 0.508)
		(drill 0.254)
		(layers "F.Cu" "B.Cu")
		(net "FM_CPLD_NODE1_PWR_BTN_CPU")
	)
	(segment
		(start 88.36025 -93.131894)
		(end 87.76208 -93.131894)
		(width 0.1143)
		(layer "In6.Cu")
		(net "FM_CPLD_NODE1_PWR_BTN_CPU")
	)
	(segment
		(start 163.194492 -112.193324)
		(end 155.71343 -112.193324)
		(width 0.1143)
		(layer "In6.Cu")
		(net "FM_CPLD_NODE1_PWR_BTN_CPU")
	)
	(segment
		(start 74.563224 -87.72271)
		(end 73.890886 -87.050372)
		(width 0.1143)
		(layer "In6.Cu")
		(net "FM_CPLD_NODE1_PWR_BTN_CPU")
	)
	(segment
		(start 149.92858 -106.408474)
		(end 149.92858 -104.416352)
		(width 0.1143)
		(layer "In6.Cu")
		(net "FM_CPLD_NODE1_PWR_BTN_CPU")
	)
	(segment
		(start 149.92858 -104.416352)
		(end 135.173974 -89.661746)
		(width 0.1143)
		(layer "In6.Cu")
		(net "FM_CPLD_NODE1_PWR_BTN_CPU")
	)
	(segment
		(start 135.173974 -89.661746)
		(end 97.571814 -89.661746)
		(width 0.1143)
		(layer "In6.Cu")
		(net "FM_CPLD_NODE1_PWR_BTN_CPU")
	)
	(segment
		(start 163.703 -113.790984)
		(end 163.703 -112.701832)
		(width 0.1143)
		(layer "In6.Cu")
		(net "FM_CPLD_NODE1_PWR_BTN_CPU")
	)
	(segment
		(start 97.571814 -89.661746)
		(end 93.30436 -93.9292)
		(width 0.1143)
		(layer "In6.Cu")
		(net "FM_CPLD_NODE1_PWR_BTN_CPU")
	)
	(segment
		(start 75.102466 -87.72271)
		(end 74.563224 -87.72271)
		(width 0.1143)
		(layer "In6.Cu")
		(net "FM_CPLD_NODE1_PWR_BTN_CPU")
	)
	(segment
		(start 86.63813 -92.007944)
		(end 79.3877 -92.007944)
		(width 0.1143)
		(layer "In6.Cu")
		(net "FM_CPLD_NODE1_PWR_BTN_CPU")
	)
	(segment
		(start 89.157556 -93.9292)
		(end 88.36025 -93.131894)
		(width 0.1143)
		(layer "In6.Cu")
		(net "FM_CPLD_NODE1_PWR_BTN_CPU")
	)
	(segment
		(start 73.890886 -87.050372)
		(end 73.890886 -86.402672)
		(width 0.1143)
		(layer "In6.Cu")
		(net "FM_CPLD_NODE1_PWR_BTN_CPU")
	)
	(segment
		(start 79.3877 -92.007944)
		(end 75.102466 -87.72271)
		(width 0.1143)
		(layer "In6.Cu")
		(net "FM_CPLD_NODE1_PWR_BTN_CPU")
	)
	(segment
		(start 93.30436 -93.9292)
		(end 89.157556 -93.9292)
		(width 0.1143)
		(layer "In6.Cu")
		(net "FM_CPLD_NODE1_PWR_BTN_CPU")
	)
	(segment
		(start 73.890886 -86.402672)
		(end 71.83374 -84.345526)
		(width 0.1143)
		(layer "In6.Cu")
		(net "FM_CPLD_NODE1_PWR_BTN_CPU")
	)
	(segment
		(start 163.703 -112.701832)
		(end 163.194492 -112.193324)
		(width 0.1143)
		(layer "In6.Cu")
		(net "FM_CPLD_NODE1_PWR_BTN_CPU")
	)
	(segment
		(start 71.83374 -84.345526)
		(end 69.688456 -84.345526)
		(width 0.1143)
		(layer "In6.Cu")
		(net "FM_CPLD_NODE1_PWR_BTN_CPU")
	)
	(segment
		(start 155.71343 -112.193324)
		(end 149.92858 -106.408474)
		(width 0.1143)
		(layer "In6.Cu")
		(net "FM_CPLD_NODE1_PWR_BTN_CPU")
	)
	(segment
		(start 165.37432 -115.462304)
		(end 163.703 -113.790984)
		(width 0.1143)
		(layer "In6.Cu")
		(net "FM_CPLD_NODE1_PWR_BTN_CPU")
	)
	(segment
		(start 87.76208 -93.131894)
		(end 86.63813 -92.007944)
		(width 0.1143)
		(layer "In6.Cu")
		(net "FM_CPLD_NODE1_PWR_BTN_CPU")
	)
	(segment
		(start 69.688456 -84.345526)
		(end 69.332856 -83.989926)
		(width 0.1143)
		(layer "In6.Cu")
		(net "FM_CPLD_NODE1_PWR_BTN_CPU")
	)
	(segment
		(start 165.37432 -115.630452)
		(end 165.37432 -115.462304)
		(width 0.1143)
		(layer "In6.Cu")
		(net "FM_CPLD_NODE1_PWR_BTN_CPU")
	)
	(segment
		(start 172.314616 -115.199414)
		(end 169.448988 -115.199414)
		(width 0.1143)
		(layer "In7.Cu")
		(net "FM_CPLD_NODE1_PWR_BTN_CPU")
	)
	(segment
		(start 177.169826 -115.368578)
		(end 172.48378 -115.368578)
		(width 0.1143)
		(layer "In7.Cu")
		(net "FM_CPLD_NODE1_PWR_BTN_CPU")
	)
	(segment
		(start 172.48378 -115.368578)
		(end 172.314616 -115.199414)
		(width 0.1143)
		(layer "In7.Cu")
		(net "FM_CPLD_NODE1_PWR_BTN_CPU")
	)
	(segment
		(start 169.448988 -115.199414)
		(end 169.01795 -115.630452)
		(width 0.1143)
		(layer "In7.Cu")
		(net "FM_CPLD_NODE1_PWR_BTN_CPU")
	)
	(segment
		(start 178.19878 -116.397532)
		(end 177.169826 -115.368578)
		(width 0.1143)
		(layer "In7.Cu")
		(net "FM_CPLD_NODE1_PWR_BTN_CPU")
	)
	(segment
		(start 179.118768 -116.397532)
		(end 178.19878 -116.397532)
		(width 0.1143)
		(layer "In7.Cu")
		(net "FM_CPLD_NODE1_PWR_BTN_CPU")
	)
	(segment
		(start 182.71998 -119.998744)
		(end 179.118768 -116.397532)
		(width 0.1143)
		(layer "In7.Cu")
		(net "FM_CPLD_NODE1_PWR_BTN_CPU")
	)
	(segment
		(start 169.01795 -115.630452)
		(end 165.37432 -115.630452)
		(width 0.1143)
		(layer "In7.Cu")
		(net "FM_CPLD_NODE1_PWR_BTN_CPU")
	)
	(segment
		(start 45.037248 -66.098166)
		(end 44.524422 -66.098166)
		(width 0.1016)
		(layer "F.Cu")
		(net "TP_CPU_NODE1_RP0_PETP3")
	)
	(segment
		(start 44.524422 -66.098166)
		(end 44.47794 -66.144648)
		(width 0.1016)
		(layer "F.Cu")
		(net "TP_CPU_NODE1_RP0_PETP3")
	)
	(via
		(at 43.307254 -65.826894)
		(size 0.6604)
		(drill 0.3302)
		(layers "F.Cu" "B.Cu")
		(net "TP_CPU_NODE1_RP0_PETP3")
	)
	(via
		(at 44.47794 -66.144648)
		(size 0.508)
		(drill 0.254)
		(layers "F.Cu" "B.Cu")
		(net "TP_CPU_NODE1_RP0_PETP3")
	)
	(segment
		(start 44.47794 -66.144648)
		(end 43.625008 -66.144648)
		(width 0.1016)
		(layer "B.Cu")
		(net "TP_CPU_NODE1_RP0_PETP3")
	)
	(segment
		(start 43.625008 -66.144648)
		(end 43.307254 -65.826894)
		(width 0.1016)
		(layer "B.Cu")
		(net "TP_CPU_NODE1_RP0_PETP3")
	)
	(segment
		(start 111.694976 -136.438386)
		(end 110.754414 -135.497824)
		(width 0.1778)
		(layer "F.Cu")
		(net "VR_PVCCP_NODE1_RGND")
	)
	(segment
		(start 114.393218 -137.994644)
		(end 113.384838 -137.994644)
		(width 0.1778)
		(layer "F.Cu")
		(net "VR_PVCCP_NODE1_RGND")
	)
	(segment
		(start 114.393218 -137.994644)
		(end 114.393218 -137.34288)
		(width 0.1016)
		(layer "F.Cu")
		(net "VR_PVCCP_NODE1_RGND")
	)
	(segment
		(start 110.754414 -135.497824)
		(end 109.996478 -135.497824)
		(width 0.1778)
		(layer "F.Cu")
		(net "VR_PVCCP_NODE1_RGND")
	)
	(segment
		(start 113.368836 -137.72515)
		(end 112.082072 -136.438386)
		(width 0.1778)
		(layer "F.Cu")
		(net "VR_PVCCP_NODE1_RGND")
	)
	(segment
		(start 112.082072 -136.438386)
		(end 111.694976 -136.438386)
		(width 0.1778)
		(layer "F.Cu")
		(net "VR_PVCCP_NODE1_RGND")
	)
	(segment
		(start 113.384838 -137.994644)
		(end 113.368836 -138.010646)
		(width 0.1778)
		(layer "F.Cu")
		(net "VR_PVCCP_NODE1_RGND")
	)
	(segment
		(start 113.368836 -138.010646)
		(end 113.368836 -137.72515)
		(width 0.1778)
		(layer "F.Cu")
		(net "VR_PVCCP_NODE1_RGND")
	)
	(via
		(at 114.393218 -137.34288)
		(size 0.508)
		(drill 0.254)
		(layers "F.Cu" "B.Cu")
		(net "VR_PVCCP_NODE1_RGND")
	)
	(segment
		(start 45.633132 -140.165328)
		(end 46.032928 -140.565124)
		(width 0.1016)
		(layer "F.Cu")
		(net "BMC_NODE1_DDR_D9")
	)
	(segment
		(start 57.34177 -136.859518)
		(end 57.22874 -136.972548)
		(width 0.1016)
		(layer "F.Cu")
		(net "BMC_NODE1_DDR_D9")
	)
	(segment
		(start 56.155082 -137.688066)
		(end 55.389526 -137.688066)
		(width 0.1016)
		(layer "F.Cu")
		(net "BMC_NODE1_DDR_D9")
	)
	(segment
		(start 56.8706 -136.972548)
		(end 56.155082 -137.688066)
		(width 0.1016)
		(layer "F.Cu")
		(net "BMC_NODE1_DDR_D9")
	)
	(segment
		(start 55.389526 -137.688066)
		(end 54.850284 -138.227308)
		(width 0.1016)
		(layer "F.Cu")
		(net "BMC_NODE1_DDR_D9")
	)
	(segment
		(start 45.633132 -140.16355)
		(end 45.633132 -140.165328)
		(width 0.1016)
		(layer "F.Cu")
		(net "BMC_NODE1_DDR_D9")
	)
	(segment
		(start 46.032928 -140.565124)
		(end 46.032928 -140.564108)
		(width 0.1016)
		(layer "F.Cu")
		(net "BMC_NODE1_DDR_D9")
	)
	(segment
		(start 57.22874 -136.972548)
		(end 56.8706 -136.972548)
		(width 0.1016)
		(layer "F.Cu")
		(net "BMC_NODE1_DDR_D9")
	)
	(via
		(at 46.032928 -140.564108)
		(size 0.508)
		(drill 0.254)
		(layers "F.Cu" "B.Cu")
		(net "BMC_NODE1_DDR_D9")
	)
	(via
		(at 54.850284 -138.227308)
		(size 0.508)
		(drill 0.254)
		(layers "F.Cu" "B.Cu")
		(net "BMC_NODE1_DDR_D9")
	)
	(segment
		(start 50.19294 -142.14602)
		(end 50.005234 -142.24381)
		(width 0.1143)
		(layer "In2.Cu")
		(net "BMC_NODE1_DDR_D9")
	)
	(segment
		(start 53.693568 -139.544806)
		(end 53.798978 -139.650216)
		(width 0.1143)
		(layer "In2.Cu")
		(net "BMC_NODE1_DDR_D9")
	)
	(segment
		(start 51.06797 -141.689836)
		(end 50.822352 -141.612366)
		(width 0.1143)
		(layer "In2.Cu")
		(net "BMC_NODE1_DDR_D9")
	)
	(segment
		(start 47.385986 -141.511782)
		(end 47.385986 -141.254226)
		(width 0.1143)
		(layer "In2.Cu")
		(net "BMC_NODE1_DDR_D9")
	)
	(segment
		(start 54.850284 -138.227308)
		(end 55.08244 -138.459464)
		(width 0.1143)
		(layer "In2.Cu")
		(net "BMC_NODE1_DDR_D9")
	)
	(segment
		(start 51.926236 -141.036548)
		(end 51.746658 -140.692378)
		(width 0.1143)
		(layer "In2.Cu")
		(net "BMC_NODE1_DDR_D9")
	)
	(segment
		(start 55.08244 -138.624818)
		(end 54.497224 -139.210034)
		(width 0.1143)
		(layer "In2.Cu")
		(net "BMC_NODE1_DDR_D9")
	)
	(segment
		(start 54.13375 -139.104624)
		(end 53.875686 -139.104624)
		(width 0.1143)
		(layer "In2.Cu")
		(net "BMC_NODE1_DDR_D9")
	)
	(segment
		(start 47.17923 -141.976348)
		(end 47.17923 -141.718792)
		(width 0.1143)
		(layer "In2.Cu")
		(net "BMC_NODE1_DDR_D9")
	)
	(segment
		(start 53.798978 -139.90828)
		(end 53.646324 -140.060934)
		(width 0.1143)
		(layer "In2.Cu")
		(net "BMC_NODE1_DDR_D9")
	)
	(segment
		(start 51.374294 -141.32433)
		(end 51.296824 -141.570456)
		(width 0.1143)
		(layer "In2.Cu")
		(net "BMC_NODE1_DDR_D9")
	)
	(segment
		(start 50.65268 -141.286484)
		(end 50.407062 -141.209014)
		(width 0.1143)
		(layer "In2.Cu")
		(net "BMC_NODE1_DDR_D9")
	)
	(segment
		(start 48.58512 -142.24381)
		(end 48.399446 -142.058136)
		(width 0.1143)
		(layer "In2.Cu")
		(net "BMC_NODE1_DDR_D9")
	)
	(segment
		(start 47.88662 -142.24381)
		(end 47.446692 -142.24381)
		(width 0.1143)
		(layer "In2.Cu")
		(net "BMC_NODE1_DDR_D9")
	)
	(segment
		(start 50.100738 -141.574266)
		(end 50.27041 -141.899894)
		(width 0.1143)
		(layer "In2.Cu")
		(net "BMC_NODE1_DDR_D9")
	)
	(segment
		(start 50.27041 -141.899894)
		(end 50.19294 -142.14602)
		(width 0.1143)
		(layer "In2.Cu")
		(net "BMC_NODE1_DDR_D9")
	)
	(segment
		(start 50.005234 -142.24381)
		(end 48.58512 -142.24381)
		(width 0.1143)
		(layer "In2.Cu")
		(net "BMC_NODE1_DDR_D9")
	)
	(segment
		(start 53.693568 -139.286742)
		(end 53.693568 -139.544806)
		(width 0.1143)
		(layer "In2.Cu")
		(net "BMC_NODE1_DDR_D9")
	)
	(segment
		(start 48.072294 -142.058136)
		(end 47.88662 -142.24381)
		(width 0.1143)
		(layer "In2.Cu")
		(net "BMC_NODE1_DDR_D9")
	)
	(segment
		(start 55.08244 -138.459464)
		(end 55.08244 -138.624818)
		(width 0.1143)
		(layer "In2.Cu")
		(net "BMC_NODE1_DDR_D9")
	)
	(segment
		(start 51.746658 -140.692378)
		(end 51.50104 -140.614908)
		(width 0.1143)
		(layer "In2.Cu")
		(net "BMC_NODE1_DDR_D9")
	)
	(segment
		(start 51.50104 -140.614908)
		(end 51.272186 -140.734288)
		(width 0.1143)
		(layer "In2.Cu")
		(net "BMC_NODE1_DDR_D9")
	)
	(segment
		(start 46.033436 -140.565124)
		(end 46.032928 -140.564616)
		(width 0.1143)
		(layer "In2.Cu")
		(net "BMC_NODE1_DDR_D9")
	)
	(segment
		(start 46.945804 -141.0716)
		(end 46.739048 -141.27861)
		(width 0.1143)
		(layer "In2.Cu")
		(net "BMC_NODE1_DDR_D9")
	)
	(segment
		(start 48.399446 -142.058136)
		(end 48.072294 -142.058136)
		(width 0.1143)
		(layer "In2.Cu")
		(net "BMC_NODE1_DDR_D9")
	)
	(segment
		(start 47.17923 -141.718792)
		(end 47.385986 -141.511782)
		(width 0.1143)
		(layer "In2.Cu")
		(net "BMC_NODE1_DDR_D9")
	)
	(segment
		(start 52.172108 -141.114272)
		(end 51.926236 -141.036548)
		(width 0.1143)
		(layer "In2.Cu")
		(net "BMC_NODE1_DDR_D9")
	)
	(segment
		(start 50.822352 -141.612366)
		(end 50.65268 -141.286484)
		(width 0.1143)
		(layer "In2.Cu")
		(net "BMC_NODE1_DDR_D9")
	)
	(segment
		(start 52.588414 -140.898118)
		(end 52.172108 -141.114272)
		(width 0.1143)
		(layer "In2.Cu")
		(net "BMC_NODE1_DDR_D9")
	)
	(segment
		(start 53.798978 -139.650216)
		(end 53.798978 -139.90828)
		(width 0.1143)
		(layer "In2.Cu")
		(net "BMC_NODE1_DDR_D9")
	)
	(segment
		(start 46.033436 -140.830554)
		(end 46.033436 -140.565124)
		(width 0.1143)
		(layer "In2.Cu")
		(net "BMC_NODE1_DDR_D9")
	)
	(segment
		(start 50.178208 -141.328394)
		(end 50.100738 -141.574266)
		(width 0.1143)
		(layer "In2.Cu")
		(net "BMC_NODE1_DDR_D9")
	)
	(segment
		(start 53.646324 -140.060934)
		(end 52.588414 -140.898118)
		(width 0.1143)
		(layer "In2.Cu")
		(net "BMC_NODE1_DDR_D9")
	)
	(segment
		(start 46.481492 -141.27861)
		(end 46.033436 -140.830554)
		(width 0.1143)
		(layer "In2.Cu")
		(net "BMC_NODE1_DDR_D9")
	)
	(segment
		(start 50.407062 -141.209014)
		(end 50.178208 -141.328394)
		(width 0.1143)
		(layer "In2.Cu")
		(net "BMC_NODE1_DDR_D9")
	)
	(segment
		(start 54.497224 -139.210034)
		(end 54.23916 -139.210034)
		(width 0.1143)
		(layer "In2.Cu")
		(net "BMC_NODE1_DDR_D9")
	)
	(segment
		(start 51.272186 -140.734288)
		(end 51.194716 -140.979906)
		(width 0.1143)
		(layer "In2.Cu")
		(net "BMC_NODE1_DDR_D9")
	)
	(segment
		(start 46.739048 -141.27861)
		(end 46.481492 -141.27861)
		(width 0.1143)
		(layer "In2.Cu")
		(net "BMC_NODE1_DDR_D9")
	)
	(segment
		(start 47.446692 -142.24381)
		(end 47.17923 -141.976348)
		(width 0.1143)
		(layer "In2.Cu")
		(net "BMC_NODE1_DDR_D9")
	)
	(segment
		(start 53.875686 -139.104624)
		(end 53.693568 -139.286742)
		(width 0.1143)
		(layer "In2.Cu")
		(net "BMC_NODE1_DDR_D9")
	)
	(segment
		(start 54.23916 -139.210034)
		(end 54.13375 -139.104624)
		(width 0.1143)
		(layer "In2.Cu")
		(net "BMC_NODE1_DDR_D9")
	)
	(segment
		(start 51.194716 -140.979906)
		(end 51.374294 -141.32433)
		(width 0.1143)
		(layer "In2.Cu")
		(net "BMC_NODE1_DDR_D9")
	)
	(segment
		(start 46.032928 -140.564616)
		(end 46.032928 -140.564108)
		(width 0.1143)
		(layer "In2.Cu")
		(net "BMC_NODE1_DDR_D9")
	)
	(segment
		(start 47.385986 -141.254226)
		(end 47.20336 -141.0716)
		(width 0.1143)
		(layer "In2.Cu")
		(net "BMC_NODE1_DDR_D9")
	)
	(segment
		(start 47.20336 -141.0716)
		(end 46.945804 -141.0716)
		(width 0.1143)
		(layer "In2.Cu")
		(net "BMC_NODE1_DDR_D9")
	)
	(segment
		(start 51.296824 -141.570456)
		(end 51.06797 -141.689836)
		(width 0.1143)
		(layer "In2.Cu")
		(net "BMC_NODE1_DDR_D9")
	)
	(segment
		(start 43.343322 -72.768968)
		(end 43.099736 -73.012554)
		(width 0.1016)
		(layer "F.Cu")
		(net "PD_CPU_NODE1_RP1_PERP")
	)
	(segment
		(start 43.099736 -73.012554)
		(end 42.359834 -73.752456)
		(width 0.1016)
		(layer "F.Cu")
		(net "PD_CPU_NODE1_RP1_PERP")
	)
	(segment
		(start 43.205908 -71.753476)
		(end 43.205908 -71.861426)
		(width 0.1016)
		(layer "F.Cu")
		(net "PD_CPU_NODE1_RP1_PERP")
	)
	(segment
		(start 42.194988 -70.742556)
		(end 42.69613 -71.243698)
		(width 0.1016)
		(layer "F.Cu")
		(net "PD_CPU_NODE1_RP1_PERP")
	)
	(segment
		(start 42.62501 -76.57846)
		(end 42.62501 -75.81773)
		(width 0.1016)
		(layer "F.Cu")
		(net "PD_CPU_NODE1_RP1_PERP")
	)
	(segment
		(start 37.107622 -73.402698)
		(end 38.069266 -73.402698)
		(width 0.1016)
		(layer "F.Cu")
		(net "PD_CPU_NODE1_RP1_PERP")
	)
	(segment
		(start 40.321484 -73.662794)
		(end 40.157146 -73.827132)
		(width 0.1016)
		(layer "F.Cu")
		(net "PD_CPU_NODE1_RP1_PERP")
	)
	(segment
		(start 42.62501 -75.81773)
		(end 42.69613 -75.74661)
		(width 0.1016)
		(layer "F.Cu")
		(net "PD_CPU_NODE1_RP1_PERP")
	)
	(segment
		(start 43.205908 -71.861426)
		(end 43.343322 -71.99884)
		(width 0.1016)
		(layer "F.Cu")
		(net "PD_CPU_NODE1_RP1_PERP")
	)
	(segment
		(start 42.882058 -75.74661)
		(end 43.205908 -76.07046)
		(width 0.1016)
		(layer "F.Cu")
		(net "PD_CPU_NODE1_RP1_PERP")
	)
	(segment
		(start 40.151304 -73.82129)
		(end 40.157146 -73.827132)
		(width 0.1016)
		(layer "F.Cu")
		(net "PD_CPU_NODE1_RP1_PERP")
	)
	(segment
		(start 40.157146 -74.896472)
		(end 42.013886 -76.753212)
		(width 0.1016)
		(layer "F.Cu")
		(net "PD_CPU_NODE1_RP1_PERP")
	)
	(segment
		(start 40.157146 -73.827132)
		(end 40.157146 -74.896472)
		(width 0.1016)
		(layer "F.Cu")
		(net "PD_CPU_NODE1_RP1_PERP")
	)
	(segment
		(start 43.205908 -76.07046)
		(end 43.205908 -76.364338)
		(width 0.1016)
		(layer "F.Cu")
		(net "PD_CPU_NODE1_RP1_PERP")
	)
	(segment
		(start 38.487858 -73.82129)
		(end 40.151304 -73.82129)
		(width 0.1016)
		(layer "F.Cu")
		(net "PD_CPU_NODE1_RP1_PERP")
	)
	(segment
		(start 42.013886 -76.753212)
		(end 42.450258 -76.753212)
		(width 0.1016)
		(layer "F.Cu")
		(net "PD_CPU_NODE1_RP1_PERP")
	)
	(segment
		(start 42.450258 -76.753212)
		(end 42.62501 -76.57846)
		(width 0.1016)
		(layer "F.Cu")
		(net "PD_CPU_NODE1_RP1_PERP")
	)
	(segment
		(start 42.114978 -73.662794)
		(end 40.321484 -73.662794)
		(width 0.1016)
		(layer "F.Cu")
		(net "PD_CPU_NODE1_RP1_PERP")
	)
	(segment
		(start 42.359834 -73.90765)
		(end 42.114978 -73.662794)
		(width 0.1016)
		(layer "F.Cu")
		(net "PD_CPU_NODE1_RP1_PERP")
	)
	(segment
		(start 42.194988 -70.433438)
		(end 42.194988 -70.742556)
		(width 0.1016)
		(layer "F.Cu")
		(net "PD_CPU_NODE1_RP1_PERP")
	)
	(segment
		(start 42.69613 -75.74661)
		(end 42.882058 -75.74661)
		(width 0.1016)
		(layer "F.Cu")
		(net "PD_CPU_NODE1_RP1_PERP")
	)
	(segment
		(start 38.069266 -73.402698)
		(end 38.487858 -73.82129)
		(width 0.1016)
		(layer "F.Cu")
		(net "PD_CPU_NODE1_RP1_PERP")
	)
	(segment
		(start 42.69613 -71.243698)
		(end 43.205908 -71.753476)
		(width 0.1016)
		(layer "F.Cu")
		(net "PD_CPU_NODE1_RP1_PERP")
	)
	(segment
		(start 43.343322 -71.99884)
		(end 43.343322 -72.768968)
		(width 0.1016)
		(layer "F.Cu")
		(net "PD_CPU_NODE1_RP1_PERP")
	)
	(segment
		(start 43.205908 -76.364338)
		(end 43.779694 -76.364338)
		(width 0.1016)
		(layer "F.Cu")
		(net "PD_CPU_NODE1_RP1_PERP")
	)
	(segment
		(start 42.359834 -73.752456)
		(end 42.359834 -73.90765)
		(width 0.1016)
		(layer "F.Cu")
		(net "PD_CPU_NODE1_RP1_PERP")
	)
	(segment
		(start 43.779694 -76.364338)
		(end 43.937428 -76.206604)
		(width 0.1016)
		(layer "F.Cu")
		(net "PD_CPU_NODE1_RP1_PERP")
	)
	(via
		(at 40.151304 -73.82129)
		(size 0.508)
		(drill 0.254)
		(layers "F.Cu" "B.Cu")
		(net "PD_CPU_NODE1_RP1_PERP")
	)
	(segment
		(start 107.271566 -138.678666)
		(end 107.051094 -138.899138)
		(width 0.1778)
		(layer "F.Cu")
		(net "VR_PVCCP_NODE1_OCSET")
	)
	(segment
		(start 106.469688 -139.789662)
		(end 106.466894 -139.786868)
		(width 0.254)
		(layer "F.Cu")
		(net "VR_PVCCP_NODE1_OCSET")
	)
	(segment
		(start 106.469688 -140.815822)
		(end 106.469688 -139.789662)
		(width 0.254)
		(layer "F.Cu")
		(net "VR_PVCCP_NODE1_OCSET")
	)
	(segment
		(start 106.466894 -139.786868)
		(end 106.466894 -139.700762)
		(width 0.254)
		(layer "F.Cu")
		(net "VR_PVCCP_NODE1_OCSET")
	)
	(segment
		(start 106.466894 -139.700762)
		(end 107.051094 -139.116562)
		(width 0.254)
		(layer "F.Cu")
		(net "VR_PVCCP_NODE1_OCSET")
	)
	(segment
		(start 107.271566 -137.42289)
		(end 107.271566 -138.678666)
		(width 0.1778)
		(layer "F.Cu")
		(net "VR_PVCCP_NODE1_OCSET")
	)
	(segment
		(start 107.051094 -138.899138)
		(end 107.051094 -139.116562)
		(width 0.254)
		(layer "F.Cu")
		(net "VR_PVCCP_NODE1_OCSET")
	)
	(via
		(at 107.051094 -139.116562)
		(size 0.508)
		(drill 0.254)
		(layers "F.Cu" "B.Cu")
		(net "VR_PVCCP_NODE1_OCSET")
	)
	(segment
		(start 51.990244 -137.720578)
		(end 51.990244 -137.24382)
		(width 0.10414)
		(layer "F.Cu")
		(net "BMC_NODE1_DDR_DQS0_DN")
	)
	(segment
		(start 57.479438 -136.423146)
		(end 56.990488 -136.423146)
		(width 0.10414)
		(layer "F.Cu")
		(net "BMC_NODE1_DDR_DQS0_DN")
	)
	(segment
		(start 41.63314 -136.165336)
		(end 41.825926 -136.358122)
		(width 0.10414)
		(layer "F.Cu")
		(net "BMC_NODE1_DDR_DQS0_DN")
	)
	(segment
		(start 56.267604 -137.14603)
		(end 55.096664 -137.14603)
		(width 0.10414)
		(layer "F.Cu")
		(net "BMC_NODE1_DDR_DQS0_DN")
	)
	(segment
		(start 52.360068 -138.090402)
		(end 51.990244 -137.720578)
		(width 0.10414)
		(layer "F.Cu")
		(net "BMC_NODE1_DDR_DQS0_DN")
	)
	(segment
		(start 56.990488 -136.423146)
		(end 56.267604 -137.14603)
		(width 0.10414)
		(layer "F.Cu")
		(net "BMC_NODE1_DDR_DQS0_DN")
	)
	(segment
		(start 58.14187 -136.059418)
		(end 58.066686 -136.10082)
		(width 0.10414)
		(layer "F.Cu")
		(net "BMC_NODE1_DDR_DQS0_DN")
	)
	(segment
		(start 42.30624 -136.358122)
		(end 42.424858 -136.239504)
		(width 0.10414)
		(layer "F.Cu")
		(net "BMC_NODE1_DDR_DQS0_DN")
	)
	(segment
		(start 51.990244 -137.24382)
		(end 51.894486 -137.148062)
		(width 0.10414)
		(layer "F.Cu")
		(net "BMC_NODE1_DDR_DQS0_DN")
	)
	(segment
		(start 58.066686 -136.10082)
		(end 57.479438 -136.423146)
		(width 0.10414)
		(layer "F.Cu")
		(net "BMC_NODE1_DDR_DQS0_DN")
	)
	(segment
		(start 55.096664 -137.14603)
		(end 54.152292 -138.090402)
		(width 0.10414)
		(layer "F.Cu")
		(net "BMC_NODE1_DDR_DQS0_DN")
	)
	(segment
		(start 41.63314 -136.163558)
		(end 41.63314 -136.165336)
		(width 0.10414)
		(layer "F.Cu")
		(net "BMC_NODE1_DDR_DQS0_DN")
	)
	(segment
		(start 54.152292 -138.090402)
		(end 52.360068 -138.090402)
		(width 0.10414)
		(layer "F.Cu")
		(net "BMC_NODE1_DDR_DQS0_DN")
	)
	(segment
		(start 41.825926 -136.358122)
		(end 42.30624 -136.358122)
		(width 0.10414)
		(layer "F.Cu")
		(net "BMC_NODE1_DDR_DQS0_DN")
	)
	(via
		(at 42.424858 -136.239504)
		(size 0.49022)
		(drill 0.254)
		(layers "F.Cu" "B.Cu")
		(net "BMC_NODE1_DDR_DQS0_DN")
	)
	(via
		(at 51.894486 -137.148062)
		(size 0.508)
		(drill 0.254)
		(layers "F.Cu" "B.Cu")
		(net "BMC_NODE1_DDR_DQS0_DN")
	)
	(segment
		(start 51.928776 -137.756138)
		(end 52.096416 -137.588498)
		(width 0.10414)
		(layer "In7.Cu")
		(net "BMC_NODE1_DDR_DQS0_DN")
	)
	(segment
		(start 43.889676 -136.840722)
		(end 44.753276 -136.840722)
		(width 0.10414)
		(layer "In7.Cu")
		(net "BMC_NODE1_DDR_DQS0_DN")
	)
	(segment
		(start 49.572672 -136.813544)
		(end 50.515266 -137.756138)
		(width 0.10414)
		(layer "In7.Cu")
		(net "BMC_NODE1_DDR_DQS0_DN")
	)
	(segment
		(start 45.017944 -137.10539)
		(end 47.178214 -137.10539)
		(width 0.10414)
		(layer "In7.Cu")
		(net "BMC_NODE1_DDR_DQS0_DN")
	)
	(segment
		(start 48.261524 -137.481564)
		(end 48.929544 -136.813544)
		(width 0.10414)
		(layer "In7.Cu")
		(net "BMC_NODE1_DDR_DQS0_DN")
	)
	(segment
		(start 48.929544 -136.813544)
		(end 49.572672 -136.813544)
		(width 0.10414)
		(layer "In7.Cu")
		(net "BMC_NODE1_DDR_DQS0_DN")
	)
	(segment
		(start 44.753276 -136.840722)
		(end 45.017944 -137.10539)
		(width 0.10414)
		(layer "In7.Cu")
		(net "BMC_NODE1_DDR_DQS0_DN")
	)
	(segment
		(start 47.178214 -137.10539)
		(end 47.554388 -137.481564)
		(width 0.10414)
		(layer "In7.Cu")
		(net "BMC_NODE1_DDR_DQS0_DN")
	)
	(segment
		(start 42.424858 -136.239504)
		(end 42.520616 -136.335262)
		(width 0.10414)
		(layer "In7.Cu")
		(net "BMC_NODE1_DDR_DQS0_DN")
	)
	(segment
		(start 43.813476 -136.764522)
		(end 43.889676 -136.840722)
		(width 0.10414)
		(layer "In7.Cu")
		(net "BMC_NODE1_DDR_DQS0_DN")
	)
	(segment
		(start 52.096416 -137.588498)
		(end 52.096416 -137.349992)
		(width 0.10414)
		(layer "In7.Cu")
		(net "BMC_NODE1_DDR_DQS0_DN")
	)
	(segment
		(start 47.554388 -137.481564)
		(end 48.261524 -137.481564)
		(width 0.10414)
		(layer "In7.Cu")
		(net "BMC_NODE1_DDR_DQS0_DN")
	)
	(segment
		(start 50.515266 -137.756138)
		(end 51.928776 -137.756138)
		(width 0.10414)
		(layer "In7.Cu")
		(net "BMC_NODE1_DDR_DQS0_DN")
	)
	(segment
		(start 42.520616 -136.335262)
		(end 43.104816 -136.335262)
		(width 0.10414)
		(layer "In7.Cu")
		(net "BMC_NODE1_DDR_DQS0_DN")
	)
	(segment
		(start 43.534076 -136.764522)
		(end 43.813476 -136.764522)
		(width 0.10414)
		(layer "In7.Cu")
		(net "BMC_NODE1_DDR_DQS0_DN")
	)
	(segment
		(start 52.096416 -137.349992)
		(end 51.894486 -137.148062)
		(width 0.10414)
		(layer "In7.Cu")
		(net "BMC_NODE1_DDR_DQS0_DN")
	)
	(segment
		(start 43.104816 -136.335262)
		(end 43.534076 -136.764522)
		(width 0.10414)
		(layer "In7.Cu")
		(net "BMC_NODE1_DDR_DQS0_DN")
	)
	(segment
		(start 97.004378 -7.667752)
		(end 97.004378 -5.462778)
		(width 0.1016)
		(layer "F.Cu")
		(net "TP_BIOS_NODE1_PORT80_ID0")
	)
	(via
		(at 97.004378 -5.462778)
		(size 0.508)
		(drill 0.254)
		(layers "F.Cu" "B.Cu")
		(net "TP_BIOS_NODE1_PORT80_ID0")
	)
	(segment
		(start 50.525426 -67.741038)
		(end 51.005994 -67.741038)
		(width 0.127)
		(layer "F.Cu")
		(net "P2E_CPU_SATA_NODE1_TX_C_DP")
	)
	(segment
		(start 51.005994 -67.741038)
		(end 51.185572 -67.56146)
		(width 0.127)
		(layer "F.Cu")
		(net "P2E_CPU_SATA_NODE1_TX_C_DP")
	)
	(via
		(at 51.185572 -67.56146)
		(size 0.508)
		(drill 0.254)
		(layers "F.Cu" "B.Cu")
		(net "P2E_CPU_SATA_NODE1_TX_C_DP")
	)
	(via
		(at 49.239424 -64.094614)
		(size 0.4064)
		(drill 0.2032)
		(layers "F.Cu" "B.Cu")
		(net "P2E_CPU_SATA_NODE1_TX_C_DP")
	)
	(segment
		(start 48.851058 -63.610236)
		(end 48.85055 -63.610744)
		(width 0.127)
		(layer "B.Cu")
		(net "P2E_CPU_SATA_NODE1_TX_C_DP")
	)
	(segment
		(start 47.756826 -62.516004)
		(end 47.851822 -62.516004)
		(width 0.127)
		(layer "B.Cu")
		(net "P2E_CPU_SATA_NODE1_TX_C_DP")
	)
	(segment
		(start 49.76368 -64.52743)
		(end 49.764188 -64.526922)
		(width 0.127)
		(layer "B.Cu")
		(net "P2E_CPU_SATA_NODE1_TX_C_DP")
	)
	(segment
		(start 50.497486 -66.751454)
		(end 50.497486 -67.132454)
		(width 0.127)
		(layer "B.Cu")
		(net "P2E_CPU_SATA_NODE1_TX_C_DP")
	)
	(segment
		(start 50.361342 -66.61531)
		(end 50.497486 -66.751454)
		(width 0.127)
		(layer "B.Cu")
		(net "P2E_CPU_SATA_NODE1_TX_C_DP")
	)
	(segment
		(start 47.756318 -62.516512)
		(end 47.756826 -62.516004)
		(width 0.127)
		(layer "B.Cu")
		(net "P2E_CPU_SATA_NODE1_TX_C_DP")
	)
	(segment
		(start 48.486314 -63.245492)
		(end 48.58131 -63.245492)
		(width 0.127)
		(layer "B.Cu")
		(net "P2E_CPU_SATA_NODE1_TX_C_DP")
	)
	(segment
		(start 45.3009 -61.6458)
		(end 45.800518 -62.145418)
		(width 0.127)
		(layer "B.Cu")
		(net "P2E_CPU_SATA_NODE1_TX_C_DP")
	)
	(segment
		(start 48.485806 -63.246)
		(end 48.486314 -63.245492)
		(width 0.127)
		(layer "B.Cu")
		(net "P2E_CPU_SATA_NODE1_TX_C_DP")
	)
	(segment
		(start 48.39081 -63.246)
		(end 48.485806 -63.246)
		(width 0.127)
		(layer "B.Cu")
		(net "P2E_CPU_SATA_NODE1_TX_C_DP")
	)
	(segment
		(start 49.764188 -64.526922)
		(end 49.855628 -64.526922)
		(width 0.127)
		(layer "B.Cu")
		(net "P2E_CPU_SATA_NODE1_TX_C_DP")
	)
	(segment
		(start 48.58131 -63.245492)
		(end 48.851058 -63.51524)
		(width 0.127)
		(layer "B.Cu")
		(net "P2E_CPU_SATA_NODE1_TX_C_DP")
	)
	(segment
		(start 49.67224 -64.52743)
		(end 49.76368 -64.52743)
		(width 0.127)
		(layer "B.Cu")
		(net "P2E_CPU_SATA_NODE1_TX_C_DP")
	)
	(segment
		(start 45.625258 -60.845446)
		(end 45.3009 -61.169804)
		(width 0.127)
		(layer "B.Cu")
		(net "P2E_CPU_SATA_NODE1_TX_C_DP")
	)
	(segment
		(start 50.983134 -67.763898)
		(end 51.185572 -67.56146)
		(width 0.127)
		(layer "B.Cu")
		(net "P2E_CPU_SATA_NODE1_TX_C_DP")
	)
	(segment
		(start 50.602642 -67.763898)
		(end 50.983134 -67.763898)
		(width 0.127)
		(layer "B.Cu")
		(net "P2E_CPU_SATA_NODE1_TX_C_DP")
	)
	(segment
		(start 50.361342 -65.216532)
		(end 50.361342 -66.61531)
		(width 0.127)
		(layer "B.Cu")
		(net "P2E_CPU_SATA_NODE1_TX_C_DP")
	)
	(segment
		(start 48.851058 -63.51524)
		(end 48.851058 -63.610236)
		(width 0.127)
		(layer "B.Cu")
		(net "P2E_CPU_SATA_NODE1_TX_C_DP")
	)
	(segment
		(start 48.12157 -62.880748)
		(end 48.121062 -62.881256)
		(width 0.127)
		(layer "B.Cu")
		(net "P2E_CPU_SATA_NODE1_TX_C_DP")
	)
	(segment
		(start 45.3009 -61.169804)
		(end 45.3009 -61.6458)
		(width 0.127)
		(layer "B.Cu")
		(net "P2E_CPU_SATA_NODE1_TX_C_DP")
	)
	(segment
		(start 49.239424 -64.094614)
		(end 49.67224 -64.52743)
		(width 0.127)
		(layer "B.Cu")
		(net "P2E_CPU_SATA_NODE1_TX_C_DP")
	)
	(segment
		(start 50.497486 -67.132454)
		(end 50.361342 -67.268598)
		(width 0.127)
		(layer "B.Cu")
		(net "P2E_CPU_SATA_NODE1_TX_C_DP")
	)
	(segment
		(start 48.85055 -63.610744)
		(end 48.85055 -63.70574)
		(width 0.127)
		(layer "B.Cu")
		(net "P2E_CPU_SATA_NODE1_TX_C_DP")
	)
	(segment
		(start 49.855628 -64.526922)
		(end 50.125376 -64.79667)
		(width 0.127)
		(layer "B.Cu")
		(net "P2E_CPU_SATA_NODE1_TX_C_DP")
	)
	(segment
		(start 50.361342 -67.268598)
		(end 50.361342 -67.522598)
		(width 0.127)
		(layer "B.Cu")
		(net "P2E_CPU_SATA_NODE1_TX_C_DP")
	)
	(segment
		(start 47.661322 -62.516512)
		(end 47.756318 -62.516512)
		(width 0.127)
		(layer "B.Cu")
		(net "P2E_CPU_SATA_NODE1_TX_C_DP")
	)
	(segment
		(start 50.361342 -67.522598)
		(end 50.602642 -67.763898)
		(width 0.127)
		(layer "B.Cu")
		(net "P2E_CPU_SATA_NODE1_TX_C_DP")
	)
	(segment
		(start 47.290228 -62.145418)
		(end 47.661322 -62.516512)
		(width 0.127)
		(layer "B.Cu")
		(net "P2E_CPU_SATA_NODE1_TX_C_DP")
	)
	(segment
		(start 50.124868 -64.888618)
		(end 50.124868 -64.980058)
		(width 0.127)
		(layer "B.Cu")
		(net "P2E_CPU_SATA_NODE1_TX_C_DP")
	)
	(segment
		(start 50.125376 -64.79667)
		(end 50.125376 -64.88811)
		(width 0.127)
		(layer "B.Cu")
		(net "P2E_CPU_SATA_NODE1_TX_C_DP")
	)
	(segment
		(start 48.12157 -62.785752)
		(end 48.12157 -62.880748)
		(width 0.127)
		(layer "B.Cu")
		(net "P2E_CPU_SATA_NODE1_TX_C_DP")
	)
	(segment
		(start 47.851822 -62.516004)
		(end 48.12157 -62.785752)
		(width 0.127)
		(layer "B.Cu")
		(net "P2E_CPU_SATA_NODE1_TX_C_DP")
	)
	(segment
		(start 48.121062 -62.881256)
		(end 48.121062 -62.976252)
		(width 0.127)
		(layer "B.Cu")
		(net "P2E_CPU_SATA_NODE1_TX_C_DP")
	)
	(segment
		(start 48.85055 -63.70574)
		(end 49.239424 -64.094614)
		(width 0.127)
		(layer "B.Cu")
		(net "P2E_CPU_SATA_NODE1_TX_C_DP")
	)
	(segment
		(start 45.800518 -62.145418)
		(end 47.290228 -62.145418)
		(width 0.127)
		(layer "B.Cu")
		(net "P2E_CPU_SATA_NODE1_TX_C_DP")
	)
	(segment
		(start 50.125376 -64.88811)
		(end 50.124868 -64.888618)
		(width 0.127)
		(layer "B.Cu")
		(net "P2E_CPU_SATA_NODE1_TX_C_DP")
	)
	(segment
		(start 48.121062 -62.976252)
		(end 48.39081 -63.246)
		(width 0.127)
		(layer "B.Cu")
		(net "P2E_CPU_SATA_NODE1_TX_C_DP")
	)
	(segment
		(start 50.124868 -64.980058)
		(end 50.361342 -65.216532)
		(width 0.127)
		(layer "B.Cu")
		(net "P2E_CPU_SATA_NODE1_TX_C_DP")
	)
	(segment
		(start 48.9458 -134.201662)
		(end 48.9458 -133.416548)
		(width 0.1016)
		(layer "F.Cu")
		(net "BMC_NODE1_DDR_CKE")
	)
	(segment
		(start 48.630078 -135.356854)
		(end 48.630078 -135.014462)
		(width 0.1016)
		(layer "F.Cu")
		(net "BMC_NODE1_DDR_CKE")
	)
	(segment
		(start 58.55081 -134.058152)
		(end 58.540904 -134.058152)
		(width 0.1016)
		(layer "F.Cu")
		(net "BMC_NODE1_DDR_CKE")
	)
	(segment
		(start 47.371 -134.249414)
		(end 47.579534 -134.04088)
		(width 0.1016)
		(layer "F.Cu")
		(net "BMC_NODE1_DDR_CKE")
	)
	(segment
		(start 58.941716 -134.449058)
		(end 58.55081 -134.058152)
		(width 0.1016)
		(layer "F.Cu")
		(net "BMC_NODE1_DDR_CKE")
	)
	(segment
		(start 48.1838 -133.312662)
		(end 48.3362 -133.465062)
		(width 0.1016)
		(layer "F.Cu")
		(net "BMC_NODE1_DDR_CKE")
	)
	(segment
		(start 47.579534 -134.04088)
		(end 47.579534 -133.538214)
		(width 0.1016)
		(layer "F.Cu")
		(net "BMC_NODE1_DDR_CKE")
	)
	(segment
		(start 47.805086 -133.312662)
		(end 48.1838 -133.312662)
		(width 0.1016)
		(layer "F.Cu")
		(net "BMC_NODE1_DDR_CKE")
	)
	(segment
		(start 47.579534 -133.538214)
		(end 47.805086 -133.312662)
		(width 0.1016)
		(layer "F.Cu")
		(net "BMC_NODE1_DDR_CKE")
	)
	(segment
		(start 48.9458 -133.416548)
		(end 49.049686 -133.312662)
		(width 0.1016)
		(layer "F.Cu")
		(net "BMC_NODE1_DDR_CKE")
	)
	(segment
		(start 48.4378 -134.303262)
		(end 48.8442 -134.303262)
		(width 0.1016)
		(layer "F.Cu")
		(net "BMC_NODE1_DDR_CKE")
	)
	(segment
		(start 47.114714 -134.249414)
		(end 47.371 -134.249414)
		(width 0.1016)
		(layer "F.Cu")
		(net "BMC_NODE1_DDR_CKE")
	)
	(segment
		(start 46.84522 -133.763766)
		(end 46.95825 -133.876796)
		(width 0.1016)
		(layer "F.Cu")
		(net "BMC_NODE1_DDR_CKE")
	)
	(segment
		(start 58.941716 -134.459472)
		(end 58.941716 -134.449058)
		(width 0.1016)
		(layer "F.Cu")
		(net "BMC_NODE1_DDR_CKE")
	)
	(segment
		(start 48.770286 -135.497062)
		(end 48.630078 -135.356854)
		(width 0.1016)
		(layer "F.Cu")
		(net "BMC_NODE1_DDR_CKE")
	)
	(segment
		(start 46.95825 -133.876796)
		(end 46.95825 -134.09295)
		(width 0.1016)
		(layer "F.Cu")
		(net "BMC_NODE1_DDR_CKE")
	)
	(segment
		(start 48.3362 -134.201662)
		(end 48.4378 -134.303262)
		(width 0.1016)
		(layer "F.Cu")
		(net "BMC_NODE1_DDR_CKE")
	)
	(segment
		(start 49.252886 -135.497062)
		(end 48.770286 -135.497062)
		(width 0.1016)
		(layer "F.Cu")
		(net "BMC_NODE1_DDR_CKE")
	)
	(segment
		(start 46.95825 -134.09295)
		(end 47.114714 -134.249414)
		(width 0.1016)
		(layer "F.Cu")
		(net "BMC_NODE1_DDR_CKE")
	)
	(segment
		(start 49.5554 -135.194548)
		(end 49.252886 -135.497062)
		(width 0.1016)
		(layer "F.Cu")
		(net "BMC_NODE1_DDR_CKE")
	)
	(segment
		(start 48.3362 -133.465062)
		(end 48.3362 -134.201662)
		(width 0.1016)
		(layer "F.Cu")
		(net "BMC_NODE1_DDR_CKE")
	)
	(segment
		(start 48.8442 -134.303262)
		(end 48.9458 -134.201662)
		(width 0.1016)
		(layer "F.Cu")
		(net "BMC_NODE1_DDR_CKE")
	)
	(segment
		(start 46.432978 -133.763766)
		(end 46.84522 -133.763766)
		(width 0.1016)
		(layer "F.Cu")
		(net "BMC_NODE1_DDR_CKE")
	)
	(segment
		(start 49.405286 -133.312662)
		(end 49.5554 -133.462776)
		(width 0.1016)
		(layer "F.Cu")
		(net "BMC_NODE1_DDR_CKE")
	)
	(segment
		(start 49.049686 -133.312662)
		(end 49.405286 -133.312662)
		(width 0.1016)
		(layer "F.Cu")
		(net "BMC_NODE1_DDR_CKE")
	)
	(segment
		(start 49.5554 -133.462776)
		(end 49.5554 -135.194548)
		(width 0.1016)
		(layer "F.Cu")
		(net "BMC_NODE1_DDR_CKE")
	)
	(via
		(at 58.540904 -134.058152)
		(size 0.49022)
		(drill 0.254)
		(layers "F.Cu" "B.Cu")
		(net "BMC_NODE1_DDR_CKE")
	)
	(via
		(at 48.630078 -135.014462)
		(size 0.508)
		(drill 0.254)
		(layers "F.Cu" "B.Cu")
		(net "BMC_NODE1_DDR_CKE")
	)
	(segment
		(start 50.803048 -134.823962)
		(end 51.209194 -134.823962)
		(width 0.1143)
		(layer "In2.Cu")
		(net "BMC_NODE1_DDR_CKE")
	)
	(segment
		(start 50.082196 -135.22325)
		(end 50.224944 -135.365998)
		(width 0.1143)
		(layer "In2.Cu")
		(net "BMC_NODE1_DDR_CKE")
	)
	(segment
		(start 50.082196 -134.897622)
		(end 50.082196 -135.22325)
		(width 0.1143)
		(layer "In2.Cu")
		(net "BMC_NODE1_DDR_CKE")
	)
	(segment
		(start 49.906936 -134.722362)
		(end 50.082196 -134.897622)
		(width 0.1143)
		(layer "In2.Cu")
		(net "BMC_NODE1_DDR_CKE")
	)
	(segment
		(start 51.209194 -134.823962)
		(end 51.768756 -135.383524)
		(width 0.1143)
		(layer "In2.Cu")
		(net "BMC_NODE1_DDR_CKE")
	)
	(segment
		(start 50.578766 -135.365998)
		(end 50.704496 -135.240268)
		(width 0.1143)
		(layer "In2.Cu")
		(net "BMC_NODE1_DDR_CKE")
	)
	(segment
		(start 50.704496 -134.922514)
		(end 50.803048 -134.823962)
		(width 0.1143)
		(layer "In2.Cu")
		(net "BMC_NODE1_DDR_CKE")
	)
	(segment
		(start 48.630078 -135.014462)
		(end 48.922178 -134.722362)
		(width 0.1143)
		(layer "In2.Cu")
		(net "BMC_NODE1_DDR_CKE")
	)
	(segment
		(start 56.656224 -135.383524)
		(end 57.981596 -134.058152)
		(width 0.1143)
		(layer "In2.Cu")
		(net "BMC_NODE1_DDR_CKE")
	)
	(segment
		(start 48.922178 -134.722362)
		(end 49.906936 -134.722362)
		(width 0.1143)
		(layer "In2.Cu")
		(net "BMC_NODE1_DDR_CKE")
	)
	(segment
		(start 51.768756 -135.383524)
		(end 56.656224 -135.383524)
		(width 0.1143)
		(layer "In2.Cu")
		(net "BMC_NODE1_DDR_CKE")
	)
	(segment
		(start 57.981596 -134.058152)
		(end 58.540904 -134.058152)
		(width 0.1143)
		(layer "In2.Cu")
		(net "BMC_NODE1_DDR_CKE")
	)
	(segment
		(start 50.704496 -135.240268)
		(end 50.704496 -134.922514)
		(width 0.1143)
		(layer "In2.Cu")
		(net "BMC_NODE1_DDR_CKE")
	)
	(segment
		(start 50.224944 -135.365998)
		(end 50.578766 -135.365998)
		(width 0.1143)
		(layer "In2.Cu")
		(net "BMC_NODE1_DDR_CKE")
	)
	(segment
		(start 174.01032 -119.373396)
		(end 173.510702 -119.873014)
		(width 0.1016)
		(layer "F.Cu")
		(net "FM_CPLD_NODE1_BMC_PERST_L")
	)
	(segment
		(start 174.01032 -119.365522)
		(end 174.01032 -119.373396)
		(width 0.1016)
		(layer "F.Cu")
		(net "FM_CPLD_NODE1_BMC_PERST_L")
	)
	(via
		(at 159.5755 -119.670068)
		(size 0.508)
		(drill 0.254)
		(layers "F.Cu" "B.Cu")
		(net "FM_CPLD_NODE1_BMC_PERST_L")
	)
	(via
		(at 173.510702 -119.873014)
		(size 0.49022)
		(drill 0.254)
		(layers "F.Cu" "B.Cu")
		(net "FM_CPLD_NODE1_BMC_PERST_L")
	)
	(via
		(at 71.21652 -118.690136)
		(size 0.508)
		(drill 0.254)
		(layers "F.Cu" "B.Cu")
		(net "FM_CPLD_NODE1_BMC_PERST_L")
	)
	(segment
		(start 71.14032 -120.213882)
		(end 71.14032 -118.766336)
		(width 0.1016)
		(layer "B.Cu")
		(net "FM_CPLD_NODE1_BMC_PERST_L")
	)
	(segment
		(start 71.14032 -118.766336)
		(end 71.21652 -118.690136)
		(width 0.1016)
		(layer "B.Cu")
		(net "FM_CPLD_NODE1_BMC_PERST_L")
	)
	(segment
		(start 70.690994 -120.663208)
		(end 71.14032 -120.213882)
		(width 0.1016)
		(layer "B.Cu")
		(net "FM_CPLD_NODE1_BMC_PERST_L")
	)
	(segment
		(start 135.20928 -123.595892)
		(end 134.198614 -124.606558)
		(width 0.1143)
		(layer "In6.Cu")
		(net "FM_CPLD_NODE1_BMC_PERST_L")
	)
	(segment
		(start 109.689138 -113.67897)
		(end 106.762804 -113.67897)
		(width 0.1143)
		(layer "In6.Cu")
		(net "FM_CPLD_NODE1_BMC_PERST_L")
	)
	(segment
		(start 85.058504 -119.965978)
		(end 82.798158 -117.705632)
		(width 0.1143)
		(layer "In6.Cu")
		(net "FM_CPLD_NODE1_BMC_PERST_L")
	)
	(segment
		(start 124.730256 -119.588026)
		(end 124.730256 -118.536974)
		(width 0.1143)
		(layer "In6.Cu")
		(net "FM_CPLD_NODE1_BMC_PERST_L")
	)
	(segment
		(start 106.762804 -113.67897)
		(end 106.48696 -113.954814)
		(width 0.1143)
		(layer "In6.Cu")
		(net "FM_CPLD_NODE1_BMC_PERST_L")
	)
	(segment
		(start 82.798158 -117.705632)
		(end 75.82027 -117.705632)
		(width 0.1143)
		(layer "In6.Cu")
		(net "FM_CPLD_NODE1_BMC_PERST_L")
	)
	(segment
		(start 97.9551 -118.1608)
		(end 96.412558 -119.703342)
		(width 0.1143)
		(layer "In6.Cu")
		(net "FM_CPLD_NODE1_BMC_PERST_L")
	)
	(segment
		(start 137.007854 -123.595892)
		(end 135.20928 -123.595892)
		(width 0.1143)
		(layer "In6.Cu")
		(net "FM_CPLD_NODE1_BMC_PERST_L")
	)
	(segment
		(start 134.198614 -124.606558)
		(end 129.748788 -124.606558)
		(width 0.1143)
		(layer "In6.Cu")
		(net "FM_CPLD_NODE1_BMC_PERST_L")
	)
	(segment
		(start 101.021134 -113.954814)
		(end 97.9551 -117.020848)
		(width 0.1143)
		(layer "In6.Cu")
		(net "FM_CPLD_NODE1_BMC_PERST_L")
	)
	(segment
		(start 93.48978 -119.703342)
		(end 93.227144 -119.965978)
		(width 0.1143)
		(layer "In6.Cu")
		(net "FM_CPLD_NODE1_BMC_PERST_L")
	)
	(segment
		(start 106.48696 -113.954814)
		(end 101.021134 -113.954814)
		(width 0.1143)
		(layer "In6.Cu")
		(net "FM_CPLD_NODE1_BMC_PERST_L")
	)
	(segment
		(start 152.92705 -119.670068)
		(end 148.66366 -123.933458)
		(width 0.1143)
		(layer "In6.Cu")
		(net "FM_CPLD_NODE1_BMC_PERST_L")
	)
	(segment
		(start 129.748788 -124.606558)
		(end 124.730256 -119.588026)
		(width 0.1143)
		(layer "In6.Cu")
		(net "FM_CPLD_NODE1_BMC_PERST_L")
	)
	(segment
		(start 75.751182 -117.636544)
		(end 72.270112 -117.636544)
		(width 0.1143)
		(layer "In6.Cu")
		(net "FM_CPLD_NODE1_BMC_PERST_L")
	)
	(segment
		(start 119.105172 -112.91189)
		(end 110.456218 -112.91189)
		(width 0.1143)
		(layer "In6.Cu")
		(net "FM_CPLD_NODE1_BMC_PERST_L")
	)
	(segment
		(start 137.34542 -123.933458)
		(end 137.007854 -123.595892)
		(width 0.1143)
		(layer "In6.Cu")
		(net "FM_CPLD_NODE1_BMC_PERST_L")
	)
	(segment
		(start 124.730256 -118.536974)
		(end 119.105172 -112.91189)
		(width 0.1143)
		(layer "In6.Cu")
		(net "FM_CPLD_NODE1_BMC_PERST_L")
	)
	(segment
		(start 75.82027 -117.705632)
		(end 75.751182 -117.636544)
		(width 0.1143)
		(layer "In6.Cu")
		(net "FM_CPLD_NODE1_BMC_PERST_L")
	)
	(segment
		(start 96.412558 -119.703342)
		(end 93.48978 -119.703342)
		(width 0.1143)
		(layer "In6.Cu")
		(net "FM_CPLD_NODE1_BMC_PERST_L")
	)
	(segment
		(start 159.5755 -119.670068)
		(end 152.92705 -119.670068)
		(width 0.1143)
		(layer "In6.Cu")
		(net "FM_CPLD_NODE1_BMC_PERST_L")
	)
	(segment
		(start 72.270112 -117.636544)
		(end 71.21652 -118.690136)
		(width 0.1143)
		(layer "In6.Cu")
		(net "FM_CPLD_NODE1_BMC_PERST_L")
	)
	(segment
		(start 93.227144 -119.965978)
		(end 85.058504 -119.965978)
		(width 0.1143)
		(layer "In6.Cu")
		(net "FM_CPLD_NODE1_BMC_PERST_L")
	)
	(segment
		(start 110.456218 -112.91189)
		(end 109.689138 -113.67897)
		(width 0.1143)
		(layer "In6.Cu")
		(net "FM_CPLD_NODE1_BMC_PERST_L")
	)
	(segment
		(start 148.66366 -123.933458)
		(end 137.34542 -123.933458)
		(width 0.1143)
		(layer "In6.Cu")
		(net "FM_CPLD_NODE1_BMC_PERST_L")
	)
	(segment
		(start 97.9551 -117.020848)
		(end 97.9551 -118.1608)
		(width 0.1143)
		(layer "In6.Cu")
		(net "FM_CPLD_NODE1_BMC_PERST_L")
	)
	(segment
		(start 163.69538 -118.769892)
		(end 168.302686 -118.769892)
		(width 0.1143)
		(layer "In7.Cu")
		(net "FM_CPLD_NODE1_BMC_PERST_L")
	)
	(segment
		(start 169.405808 -119.873014)
		(end 173.510702 -119.873014)
		(width 0.1143)
		(layer "In7.Cu")
		(net "FM_CPLD_NODE1_BMC_PERST_L")
	)
	(segment
		(start 159.5755 -119.670068)
		(end 161.137346 -119.670068)
		(width 0.1143)
		(layer "In7.Cu")
		(net "FM_CPLD_NODE1_BMC_PERST_L")
	)
	(segment
		(start 162.591242 -119.87403)
		(end 163.69538 -118.769892)
		(width 0.1143)
		(layer "In7.Cu")
		(net "FM_CPLD_NODE1_BMC_PERST_L")
	)
	(segment
		(start 161.137346 -119.670068)
		(end 161.341308 -119.87403)
		(width 0.1143)
		(layer "In7.Cu")
		(net "FM_CPLD_NODE1_BMC_PERST_L")
	)
	(segment
		(start 168.302686 -118.769892)
		(end 169.405808 -119.873014)
		(width 0.1143)
		(layer "In7.Cu")
		(net "FM_CPLD_NODE1_BMC_PERST_L")
	)
	(segment
		(start 161.341308 -119.87403)
		(end 162.591242 -119.87403)
		(width 0.1143)
		(layer "In7.Cu")
		(net "FM_CPLD_NODE1_BMC_PERST_L")
	)
	(segment
		(start 120.8024 -119.702834)
		(end 120.8024 -137.63498)
		(width 0.254)
		(layer "F.Cu")
		(net "PV_VCCP_NODE1")
	)
	(segment
		(start 118.619778 -139.817602)
		(end 117.243352 -139.817602)
		(width 0.254)
		(layer "F.Cu")
		(net "PV_VCCP_NODE1")
	)
	(segment
		(start 116.202968 -117.38737)
		(end 118.486936 -117.38737)
		(width 0.254)
		(layer "F.Cu")
		(net "PV_VCCP_NODE1")
	)
	(segment
		(start 115.07978 -112.242092)
		(end 115.07978 -116.264182)
		(width 0.254)
		(layer "F.Cu")
		(net "PV_VCCP_NODE1")
	)
	(segment
		(start 118.486936 -117.38737)
		(end 120.8024 -119.702834)
		(width 0.254)
		(layer "F.Cu")
		(net "PV_VCCP_NODE1")
	)
	(segment
		(start 115.07978 -116.264182)
		(end 116.202968 -117.38737)
		(width 0.254)
		(layer "F.Cu")
		(net "PV_VCCP_NODE1")
	)
	(segment
		(start 120.8024 -137.63498)
		(end 118.619778 -139.817602)
		(width 0.254)
		(layer "F.Cu")
		(net "PV_VCCP_NODE1")
	)
	(segment
		(start 114.268758 -111.43107)
		(end 115.07978 -112.242092)
		(width 0.254)
		(layer "F.Cu")
		(net "PV_VCCP_NODE1")
	)
	(segment
		(start 111.649764 -111.43107)
		(end 114.268758 -111.43107)
		(width 0.254)
		(layer "F.Cu")
		(net "PV_VCCP_NODE1")
	)
	(via
		(at 107.20832 -104.255316)
		(size 0.508)
		(drill 0.254)
		(layers "F.Cu" "B.Cu")
		(net "PV_VCCP_NODE1")
	)
	(via
		(at 113.5253 -105.959148)
		(size 0.508)
		(drill 0.254)
		(layers "F.Cu" "B.Cu")
		(net "PV_VCCP_NODE1")
	)
	(via
		(at 109.13618 -114.186208)
		(size 0.508)
		(drill 0.254)
		(layers "F.Cu" "B.Cu")
		(net "PV_VCCP_NODE1")
	)
	(via
		(at 109.8423 -106.366564)
		(size 0.508)
		(drill 0.254)
		(layers "F.Cu" "B.Cu")
		(net "PV_VCCP_NODE1")
	)
	(via
		(at 107.40644 -112.21466)
		(size 0.508)
		(drill 0.254)
		(layers "F.Cu" "B.Cu")
		(net "PV_VCCP_NODE1")
	)
	(via
		(at 70.202044 -79.168498)
		(size 0.508)
		(drill 0.254)
		(layers "F.Cu" "B.Cu")
		(net "PV_VCCP_NODE1")
	)
	(via
		(at 78.898242 -79.651606)
		(size 0.508)
		(drill 0.254)
		(layers "F.Cu" "B.Cu")
		(net "PV_VCCP_NODE1")
	)
	(via
		(at 79.533242 -79.651606)
		(size 0.508)
		(drill 0.254)
		(layers "F.Cu" "B.Cu")
		(net "PV_VCCP_NODE1")
	)
	(via
		(at 81.438242 -79.651606)
		(size 0.508)
		(drill 0.254)
		(layers "F.Cu" "B.Cu")
		(net "PV_VCCP_NODE1")
	)
	(via
		(at 112.78108 -104.234996)
		(size 0.508)
		(drill 0.254)
		(layers "F.Cu" "B.Cu")
		(net "PV_VCCP_NODE1")
	)
	(via
		(at 64.44234 -80.179926)
		(size 0.508)
		(drill 0.254)
		(layers "F.Cu" "B.Cu")
		(net "PV_VCCP_NODE1")
	)
	(via
		(at 111.38408 -114.890296)
		(size 0.508)
		(drill 0.254)
		(layers "F.Cu" "B.Cu")
		(net "PV_VCCP_NODE1")
	)
	(via
		(at 107.38104 -113.177574)
		(size 0.508)
		(drill 0.254)
		(layers "F.Cu" "B.Cu")
		(net "PV_VCCP_NODE1")
	)
	(via
		(at 109.97184 -105.381044)
		(size 0.508)
		(drill 0.254)
		(layers "F.Cu" "B.Cu")
		(net "PV_VCCP_NODE1")
	)
	(via
		(at 63.601854 -80.191102)
		(size 0.508)
		(drill 0.254)
		(layers "F.Cu" "B.Cu")
		(net "PV_VCCP_NODE1")
	)
	(via
		(at 107.12958 -110.029498)
		(size 0.508)
		(drill 0.254)
		(layers "F.Cu" "B.Cu")
		(net "PV_VCCP_NODE1")
	)
	(via
		(at 80.43418 -80.40624)
		(size 0.6604)
		(drill 0.3302)
		(layers "F.Cu" "B.Cu")
		(net "PV_VCCP_NODE1")
	)
	(via
		(at 106.53268 -115.104672)
		(size 0.508)
		(drill 0.254)
		(layers "F.Cu" "B.Cu")
		(net "PV_VCCP_NODE1")
	)
	(via
		(at 111.71682 -104.234996)
		(size 0.508)
		(drill 0.254)
		(layers "F.Cu" "B.Cu")
		(net "PV_VCCP_NODE1")
	)
	(via
		(at 107.21848 -106.245152)
		(size 0.508)
		(drill 0.254)
		(layers "F.Cu" "B.Cu")
		(net "PV_VCCP_NODE1")
	)
	(via
		(at 106.53268 -116.168932)
		(size 0.508)
		(drill 0.254)
		(layers "F.Cu" "B.Cu")
		(net "PV_VCCP_NODE1")
	)
	(via
		(at 111.9886 -113.35004)
		(size 0.508)
		(drill 0.254)
		(layers "F.Cu" "B.Cu")
		(net "PV_VCCP_NODE1")
	)
	(via
		(at 67.128898 -79.168498)
		(size 0.508)
		(drill 0.254)
		(layers "F.Cu" "B.Cu")
		(net "PV_VCCP_NODE1")
	)
	(via
		(at 108.17098 -114.175286)
		(size 0.508)
		(drill 0.254)
		(layers "F.Cu" "B.Cu")
		(net "PV_VCCP_NODE1")
	)
	(via
		(at 107.30484 -114.164618)
		(size 0.508)
		(drill 0.254)
		(layers "F.Cu" "B.Cu")
		(net "PV_VCCP_NODE1")
	)
	(via
		(at 109.30636 -105.809542)
		(size 0.508)
		(drill 0.254)
		(layers "F.Cu" "B.Cu")
		(net "PV_VCCP_NODE1")
	)
	(via
		(at 113.45164 -104.98455)
		(size 0.508)
		(drill 0.254)
		(layers "F.Cu" "B.Cu")
		(net "PV_VCCP_NODE1")
	)
	(via
		(at 107.11434 -107.829858)
		(size 0.508)
		(drill 0.254)
		(layers "F.Cu" "B.Cu")
		(net "PV_VCCP_NODE1")
	)
	(via
		(at 80.168242 -79.651606)
		(size 0.508)
		(drill 0.254)
		(layers "F.Cu" "B.Cu")
		(net "PV_VCCP_NODE1")
	)
	(via
		(at 110.92434 -113.35004)
		(size 0.508)
		(drill 0.254)
		(layers "F.Cu" "B.Cu")
		(net "PV_VCCP_NODE1")
	)
	(via
		(at 65.68186 -79.13624)
		(size 0.508)
		(drill 0.254)
		(layers "F.Cu" "B.Cu")
		(net "PV_VCCP_NODE1")
	)
	(via
		(at 68.711572 -79.155798)
		(size 0.508)
		(drill 0.254)
		(layers "F.Cu" "B.Cu")
		(net "PV_VCCP_NODE1")
	)
	(via
		(at 110.83798 -104.277922)
		(size 0.508)
		(drill 0.254)
		(layers "F.Cu" "B.Cu")
		(net "PV_VCCP_NODE1")
	)
	(via
		(at 111.35106 -115.856766)
		(size 0.508)
		(drill 0.254)
		(layers "F.Cu" "B.Cu")
		(net "PV_VCCP_NODE1")
	)
	(via
		(at 67.886072 -79.157068)
		(size 0.508)
		(drill 0.254)
		(layers "F.Cu" "B.Cu")
		(net "PV_VCCP_NODE1")
	)
	(via
		(at 80.803242 -79.651606)
		(size 0.508)
		(drill 0.254)
		(layers "F.Cu" "B.Cu")
		(net "PV_VCCP_NODE1")
	)
	(via
		(at 105.37698 -114.547904)
		(size 0.508)
		(drill 0.254)
		(layers "F.Cu" "B.Cu")
		(net "PV_VCCP_NODE1")
	)
	(via
		(at 110.16488 -114.164618)
		(size 0.508)
		(drill 0.254)
		(layers "F.Cu" "B.Cu")
		(net "PV_VCCP_NODE1")
	)
	(via
		(at 107.20832 -105.319576)
		(size 0.508)
		(drill 0.254)
		(layers "F.Cu" "B.Cu")
		(net "PV_VCCP_NODE1")
	)
	(via
		(at 112.9919 -113.369598)
		(size 0.508)
		(drill 0.254)
		(layers "F.Cu" "B.Cu")
		(net "PV_VCCP_NODE1")
	)
	(via
		(at 82.073242 -79.651606)
		(size 0.508)
		(drill 0.254)
		(layers "F.Cu" "B.Cu")
		(net "PV_VCCP_NODE1")
	)
	(via
		(at 105.37698 -115.612164)
		(size 0.508)
		(drill 0.254)
		(layers "F.Cu" "B.Cu")
		(net "PV_VCCP_NODE1")
	)
	(segment
		(start 45.799248 -66.258694)
		(end 45.447966 -66.609976)
		(width 0.1016)
		(layer "F.Cu")
		(net "TP_CPU_NODE1_RP0_PETN3")
	)
	(segment
		(start 45.799248 -66.098166)
		(end 45.799248 -66.258694)
		(width 0.1016)
		(layer "F.Cu")
		(net "TP_CPU_NODE1_RP0_PETN3")
	)
	(via
		(at 45.447966 -66.609976)
		(size 0.508)
		(drill 0.254)
		(layers "F.Cu" "B.Cu")
		(net "TP_CPU_NODE1_RP0_PETN3")
	)
	(via
		(at 34.17316 -68.017644)
		(size 0.508)
		(drill 0.254)
		(layers "F.Cu" "B.Cu")
		(net "TP_CPU_NODE1_RP0_PETN3")
	)
	(segment
		(start 34.821876 -67.368928)
		(end 45.137578 -67.368928)
		(width 0.1143)
		(layer "In2.Cu")
		(net "TP_CPU_NODE1_RP0_PETN3")
	)
	(segment
		(start 45.137578 -67.368928)
		(end 45.447966 -67.05854)
		(width 0.1143)
		(layer "In2.Cu")
		(net "TP_CPU_NODE1_RP0_PETN3")
	)
	(segment
		(start 34.17316 -68.017644)
		(end 34.821876 -67.368928)
		(width 0.1143)
		(layer "In2.Cu")
		(net "TP_CPU_NODE1_RP0_PETN3")
	)
	(segment
		(start 45.447966 -67.05854)
		(end 45.447966 -66.609976)
		(width 0.1143)
		(layer "In2.Cu")
		(net "TP_CPU_NODE1_RP0_PETN3")
	)
	(segment
		(start 52.410614 -138.69543)
		(end 52.304442 -138.801602)
		(width 0.10414)
		(layer "F.Cu")
		(net "BMC_NODE1_DDR_DQS1_DN")
	)
	(segment
		(start 44.833032 -140.164058)
		(end 45.233082 -140.564108)
		(width 0.10414)
		(layer "F.Cu")
		(net "BMC_NODE1_DDR_DQS1_DN")
	)
	(segment
		(start 52.723034 -138.69543)
		(end 52.410614 -138.69543)
		(width 0.10414)
		(layer "F.Cu")
		(net "BMC_NODE1_DDR_DQS1_DN")
	)
	(segment
		(start 52.304442 -138.801602)
		(end 52.16906 -138.801602)
		(width 0.10414)
		(layer "F.Cu")
		(net "BMC_NODE1_DDR_DQS1_DN")
	)
	(segment
		(start 55.870094 -138.801602)
		(end 54.503574 -138.801602)
		(width 0.10414)
		(layer "F.Cu")
		(net "BMC_NODE1_DDR_DQS1_DN")
	)
	(segment
		(start 52.16906 -138.801602)
		(end 51.709066 -139.261596)
		(width 0.10414)
		(layer "F.Cu")
		(net "BMC_NODE1_DDR_DQS1_DN")
	)
	(segment
		(start 54.397402 -138.69543)
		(end 54.084982 -138.69543)
		(width 0.10414)
		(layer "F.Cu")
		(net "BMC_NODE1_DDR_DQS1_DN")
	)
	(segment
		(start 56.097424 -138.576304)
		(end 56.095392 -138.576304)
		(width 0.10414)
		(layer "F.Cu")
		(net "BMC_NODE1_DDR_DQS1_DN")
	)
	(segment
		(start 56.095392 -138.576304)
		(end 55.870094 -138.801602)
		(width 0.10414)
		(layer "F.Cu")
		(net "BMC_NODE1_DDR_DQS1_DN")
	)
	(segment
		(start 51.709066 -139.839446)
		(end 51.561492 -139.98702)
		(width 0.10414)
		(layer "F.Cu")
		(net "BMC_NODE1_DDR_DQS1_DN")
	)
	(segment
		(start 53.658262 -138.793474)
		(end 53.560218 -138.69543)
		(width 0.10414)
		(layer "F.Cu")
		(net "BMC_NODE1_DDR_DQS1_DN")
	)
	(segment
		(start 57.01411 -137.659618)
		(end 56.097424 -138.576304)
		(width 0.10414)
		(layer "F.Cu")
		(net "BMC_NODE1_DDR_DQS1_DN")
	)
	(segment
		(start 51.709066 -139.261596)
		(end 51.709066 -139.839446)
		(width 0.10414)
		(layer "F.Cu")
		(net "BMC_NODE1_DDR_DQS1_DN")
	)
	(segment
		(start 53.247798 -138.69543)
		(end 53.141626 -138.801602)
		(width 0.10414)
		(layer "F.Cu")
		(net "BMC_NODE1_DDR_DQS1_DN")
	)
	(segment
		(start 57.34177 -137.659618)
		(end 57.01411 -137.659618)
		(width 0.10414)
		(layer "F.Cu")
		(net "BMC_NODE1_DDR_DQS1_DN")
	)
	(segment
		(start 51.561492 -139.98702)
		(end 51.431444 -139.98702)
		(width 0.10414)
		(layer "F.Cu")
		(net "BMC_NODE1_DDR_DQS1_DN")
	)
	(segment
		(start 52.829206 -138.801602)
		(end 52.723034 -138.69543)
		(width 0.10414)
		(layer "F.Cu")
		(net "BMC_NODE1_DDR_DQS1_DN")
	)
	(segment
		(start 54.503574 -138.801602)
		(end 54.397402 -138.69543)
		(width 0.10414)
		(layer "F.Cu")
		(net "BMC_NODE1_DDR_DQS1_DN")
	)
	(segment
		(start 54.084982 -138.69543)
		(end 53.986938 -138.793474)
		(width 0.10414)
		(layer "F.Cu")
		(net "BMC_NODE1_DDR_DQS1_DN")
	)
	(segment
		(start 44.833032 -140.16355)
		(end 44.833032 -140.164058)
		(width 0.10414)
		(layer "F.Cu")
		(net "BMC_NODE1_DDR_DQS1_DN")
	)
	(segment
		(start 53.141626 -138.801602)
		(end 52.829206 -138.801602)
		(width 0.10414)
		(layer "F.Cu")
		(net "BMC_NODE1_DDR_DQS1_DN")
	)
	(segment
		(start 53.986938 -138.793474)
		(end 53.658262 -138.793474)
		(width 0.10414)
		(layer "F.Cu")
		(net "BMC_NODE1_DDR_DQS1_DN")
	)
	(segment
		(start 53.560218 -138.69543)
		(end 53.247798 -138.69543)
		(width 0.10414)
		(layer "F.Cu")
		(net "BMC_NODE1_DDR_DQS1_DN")
	)
	(via
		(at 45.233082 -140.564108)
		(size 0.508)
		(drill 0.254)
		(layers "F.Cu" "B.Cu")
		(net "BMC_NODE1_DDR_DQS1_DN")
	)
	(via
		(at 51.431444 -139.98702)
		(size 0.49022)
		(drill 0.254)
		(layers "F.Cu" "B.Cu")
		(net "BMC_NODE1_DDR_DQS1_DN")
	)
	(segment
		(start 48.156876 -140.351256)
		(end 48.156876 -140.645896)
		(width 0.10414)
		(layer "In2.Cu")
		(net "BMC_NODE1_DDR_DQS1_DN")
	)
	(segment
		(start 47.906686 -139.688062)
		(end 48.160686 -139.688062)
		(width 0.10414)
		(layer "In2.Cu")
		(net "BMC_NODE1_DDR_DQS1_DN")
	)
	(segment
		(start 51.533552 -139.884658)
		(end 51.431444 -139.98702)
		(width 0.10414)
		(layer "In2.Cu")
		(net "BMC_NODE1_DDR_DQS1_DN")
	)
	(segment
		(start 47.500286 -139.764262)
		(end 47.830486 -139.764262)
		(width 0.10414)
		(layer "In2.Cu")
		(net "BMC_NODE1_DDR_DQS1_DN")
	)
	(segment
		(start 48.273716 -139.801092)
		(end 48.273716 -140.23467)
		(width 0.10414)
		(layer "In2.Cu")
		(net "BMC_NODE1_DDR_DQS1_DN")
	)
	(segment
		(start 48.643794 -141.478)
		(end 49.193958 -141.478)
		(width 0.10414)
		(layer "In2.Cu")
		(net "BMC_NODE1_DDR_DQS1_DN")
	)
	(segment
		(start 51.397662 -139.610338)
		(end 51.533552 -139.746228)
		(width 0.10414)
		(layer "In2.Cu")
		(net "BMC_NODE1_DDR_DQS1_DN")
	)
	(segment
		(start 49.901348 -139.610338)
		(end 51.397662 -139.610338)
		(width 0.10414)
		(layer "In2.Cu")
		(net "BMC_NODE1_DDR_DQS1_DN")
	)
	(segment
		(start 46.662086 -139.688062)
		(end 46.778926 -139.804902)
		(width 0.10414)
		(layer "In2.Cu")
		(net "BMC_NODE1_DDR_DQS1_DN")
	)
	(segment
		(start 49.602136 -139.90955)
		(end 49.901348 -139.610338)
		(width 0.10414)
		(layer "In2.Cu")
		(net "BMC_NODE1_DDR_DQS1_DN")
	)
	(segment
		(start 49.602136 -141.069822)
		(end 49.602136 -140.678662)
		(width 0.10414)
		(layer "In2.Cu")
		(net "BMC_NODE1_DDR_DQS1_DN")
	)
	(segment
		(start 46.778926 -139.804902)
		(end 47.129446 -139.804902)
		(width 0.10414)
		(layer "In2.Cu")
		(net "BMC_NODE1_DDR_DQS1_DN")
	)
	(segment
		(start 47.424086 -139.688062)
		(end 47.500286 -139.764262)
		(width 0.10414)
		(layer "In2.Cu")
		(net "BMC_NODE1_DDR_DQS1_DN")
	)
	(segment
		(start 49.718976 -140.562076)
		(end 49.718976 -140.261848)
		(width 0.10414)
		(layer "In2.Cu")
		(net "BMC_NODE1_DDR_DQS1_DN")
	)
	(segment
		(start 48.273716 -141.107922)
		(end 48.643794 -141.478)
		(width 0.10414)
		(layer "In2.Cu")
		(net "BMC_NODE1_DDR_DQS1_DN")
	)
	(segment
		(start 45.233082 -140.428218)
		(end 45.382688 -140.278612)
		(width 0.10414)
		(layer "In2.Cu")
		(net "BMC_NODE1_DDR_DQS1_DN")
	)
	(segment
		(start 49.718976 -140.261848)
		(end 49.602136 -140.145262)
		(width 0.10414)
		(layer "In2.Cu")
		(net "BMC_NODE1_DDR_DQS1_DN")
	)
	(segment
		(start 46.330616 -139.688062)
		(end 46.662086 -139.688062)
		(width 0.10414)
		(layer "In2.Cu")
		(net "BMC_NODE1_DDR_DQS1_DN")
	)
	(segment
		(start 49.602136 -140.145262)
		(end 49.602136 -139.90955)
		(width 0.10414)
		(layer "In2.Cu")
		(net "BMC_NODE1_DDR_DQS1_DN")
	)
	(segment
		(start 49.602136 -140.678662)
		(end 49.718976 -140.562076)
		(width 0.10414)
		(layer "In2.Cu")
		(net "BMC_NODE1_DDR_DQS1_DN")
	)
	(segment
		(start 45.382688 -140.278612)
		(end 45.740066 -140.278612)
		(width 0.10414)
		(layer "In2.Cu")
		(net "BMC_NODE1_DDR_DQS1_DN")
	)
	(segment
		(start 48.273716 -140.762482)
		(end 48.273716 -141.107922)
		(width 0.10414)
		(layer "In2.Cu")
		(net "BMC_NODE1_DDR_DQS1_DN")
	)
	(segment
		(start 48.273716 -140.23467)
		(end 48.156876 -140.351256)
		(width 0.10414)
		(layer "In2.Cu")
		(net "BMC_NODE1_DDR_DQS1_DN")
	)
	(segment
		(start 48.156876 -140.645896)
		(end 48.273716 -140.762482)
		(width 0.10414)
		(layer "In2.Cu")
		(net "BMC_NODE1_DDR_DQS1_DN")
	)
	(segment
		(start 47.830486 -139.764262)
		(end 47.906686 -139.688062)
		(width 0.10414)
		(layer "In2.Cu")
		(net "BMC_NODE1_DDR_DQS1_DN")
	)
	(segment
		(start 48.160686 -139.688062)
		(end 48.273716 -139.801092)
		(width 0.10414)
		(layer "In2.Cu")
		(net "BMC_NODE1_DDR_DQS1_DN")
	)
	(segment
		(start 45.740066 -140.278612)
		(end 46.330616 -139.688062)
		(width 0.10414)
		(layer "In2.Cu")
		(net "BMC_NODE1_DDR_DQS1_DN")
	)
	(segment
		(start 47.129446 -139.804902)
		(end 47.246286 -139.688062)
		(width 0.10414)
		(layer "In2.Cu")
		(net "BMC_NODE1_DDR_DQS1_DN")
	)
	(segment
		(start 49.193958 -141.478)
		(end 49.602136 -141.069822)
		(width 0.10414)
		(layer "In2.Cu")
		(net "BMC_NODE1_DDR_DQS1_DN")
	)
	(segment
		(start 45.233082 -140.564108)
		(end 45.233082 -140.428218)
		(width 0.10414)
		(layer "In2.Cu")
		(net "BMC_NODE1_DDR_DQS1_DN")
	)
	(segment
		(start 47.246286 -139.688062)
		(end 47.424086 -139.688062)
		(width 0.10414)
		(layer "In2.Cu")
		(net "BMC_NODE1_DDR_DQS1_DN")
	)
	(segment
		(start 51.533552 -139.746228)
		(end 51.533552 -139.884658)
		(width 0.10414)
		(layer "In2.Cu")
		(net "BMC_NODE1_DDR_DQS1_DN")
	)
	(segment
		(start 114.500406 -139.793472)
		(end 113.420144 -139.793472)
		(width 0.254)
		(layer "F.Cu")
		(net "VSENSE_VSS_CPU_NODE1")
	)
	(segment
		(start 114.50066 -139.793726)
		(end 114.500406 -139.793472)
		(width 0.254)
		(layer "F.Cu")
		(net "VSENSE_VSS_CPU_NODE1")
	)
	(segment
		(start 61.601096 -76.599542)
		(end 61.201046 -76.999592)
		(width 0.254)
		(layer "F.Cu")
		(net "VSENSE_VSS_CPU_NODE1")
	)
	(segment
		(start 113.368836 -139.742164)
		(end 113.420144 -139.793472)
		(width 0.254)
		(layer "F.Cu")
		(net "VSENSE_VSS_CPU_NODE1")
	)
	(segment
		(start 115.218718 -139.793726)
		(end 115.294918 -139.717526)
		(width 0.254)
		(layer "F.Cu")
		(net "VSENSE_VSS_CPU_NODE1")
	)
	(segment
		(start 114.50066 -139.793726)
		(end 115.218718 -139.793726)
		(width 0.254)
		(layer "F.Cu")
		(net "VSENSE_VSS_CPU_NODE1")
	)
	(segment
		(start 113.368836 -138.810746)
		(end 113.368836 -139.742164)
		(width 0.254)
		(layer "F.Cu")
		(net "VSENSE_VSS_CPU_NODE1")
	)
	(via
		(at 61.201046 -76.999592)
		(size 0.508)
		(drill 0.254)
		(layers "F.Cu" "B.Cu")
		(net "VSENSE_VSS_CPU_NODE1")
	)
	(via
		(at 115.294918 -139.717526)
		(size 0.508)
		(drill 0.254)
		(layers "F.Cu" "B.Cu")
		(net "VSENSE_VSS_CPU_NODE1")
	)
	(segment
		(start 115.973098 -140.158216)
		(end 115.742212 -140.155168)
		(width 0.254)
		(layer "In2.Cu")
		(net "VSENSE_VSS_CPU_NODE1")
	)
	(segment
		(start 94.072202 -127.796036)
		(end 94.615 -127.796036)
		(width 0.254)
		(layer "In2.Cu")
		(net "VSENSE_VSS_CPU_NODE1")
	)
	(segment
		(start 67.01917 -80.188816)
		(end 67.43192 -80.601566)
		(width 0.254)
		(layer "In2.Cu")
		(net "VSENSE_VSS_CPU_NODE1")
	)
	(segment
		(start 95.181166 -128.362202)
		(end 97.065846 -128.362202)
		(width 0.254)
		(layer "In2.Cu")
		(net "VSENSE_VSS_CPU_NODE1")
	)
	(segment
		(start 115.47348 -140.154914)
		(end 115.294918 -139.97178)
		(width 0.254)
		(layer "In2.Cu")
		(net "VSENSE_VSS_CPU_NODE1")
	)
	(segment
		(start 89.0016 -82.428334)
		(end 89.0016 -85.363304)
		(width 0.254)
		(layer "In2.Cu")
		(net "VSENSE_VSS_CPU_NODE1")
	)
	(segment
		(start 98.84918 -130.145536)
		(end 98.84918 -140.771372)
		(width 0.254)
		(layer "In2.Cu")
		(net "VSENSE_VSS_CPU_NODE1")
	)
	(segment
		(start 116.075714 -140.158216)
		(end 115.973098 -140.158216)
		(width 0.254)
		(layer "In2.Cu")
		(net "VSENSE_VSS_CPU_NODE1")
	)
	(segment
		(start 115.72113 -140.154914)
		(end 115.47348 -140.154914)
		(width 0.254)
		(layer "In2.Cu")
		(net "VSENSE_VSS_CPU_NODE1")
	)
	(segment
		(start 65.367154 -80.188816)
		(end 67.01917 -80.188816)
		(width 0.254)
		(layer "In2.Cu")
		(net "VSENSE_VSS_CPU_NODE1")
	)
	(segment
		(start 115.742212 -140.155168)
		(end 115.734084 -140.155168)
		(width 0.254)
		(layer "In2.Cu")
		(net "VSENSE_VSS_CPU_NODE1")
	)
	(segment
		(start 92.17152 -122.490738)
		(end 92.99702 -123.316238)
		(width 0.254)
		(layer "In2.Cu")
		(net "VSENSE_VSS_CPU_NODE1")
	)
	(segment
		(start 61.201046 -76.999592)
		(end 62.641734 -78.44028)
		(width 0.254)
		(layer "In2.Cu")
		(net "VSENSE_VSS_CPU_NODE1")
	)
	(segment
		(start 90.55608 -103.07828)
		(end 90.55608 -105.543604)
		(width 0.254)
		(layer "In2.Cu")
		(net "VSENSE_VSS_CPU_NODE1")
	)
	(segment
		(start 78.144116 -80.908144)
		(end 83.422236 -80.908144)
		(width 0.254)
		(layer "In2.Cu")
		(net "VSENSE_VSS_CPU_NODE1")
	)
	(segment
		(start 93.69552 -99.93884)
		(end 90.55608 -103.07828)
		(width 0.254)
		(layer "In2.Cu")
		(net "VSENSE_VSS_CPU_NODE1")
	)
	(segment
		(start 93.69552 -86.789514)
		(end 93.69552 -99.93884)
		(width 0.254)
		(layer "In2.Cu")
		(net "VSENSE_VSS_CPU_NODE1")
	)
	(segment
		(start 89.0016 -85.363304)
		(end 90.023188 -86.384892)
		(width 0.254)
		(layer "In2.Cu")
		(net "VSENSE_VSS_CPU_NODE1")
	)
	(segment
		(start 63.614554 -78.44028)
		(end 65.030604 -79.85633)
		(width 0.254)
		(layer "In2.Cu")
		(net "VSENSE_VSS_CPU_NODE1")
	)
	(segment
		(start 115.734084 -140.155168)
		(end 115.72113 -140.154914)
		(width 0.254)
		(layer "In2.Cu")
		(net "VSENSE_VSS_CPU_NODE1")
	)
	(segment
		(start 92.99702 -126.720854)
		(end 94.072202 -127.796036)
		(width 0.254)
		(layer "In2.Cu")
		(net "VSENSE_VSS_CPU_NODE1")
	)
	(segment
		(start 90.023188 -86.384892)
		(end 93.290898 -86.384892)
		(width 0.254)
		(layer "In2.Cu")
		(net "VSENSE_VSS_CPU_NODE1")
	)
	(segment
		(start 94.615 -127.796036)
		(end 95.181166 -128.362202)
		(width 0.254)
		(layer "In2.Cu")
		(net "VSENSE_VSS_CPU_NODE1")
	)
	(segment
		(start 65.030604 -79.85633)
		(end 65.034668 -79.85633)
		(width 0.254)
		(layer "In2.Cu")
		(net "VSENSE_VSS_CPU_NODE1")
	)
	(segment
		(start 116.577872 -142.742158)
		(end 116.577872 -140.660374)
		(width 0.254)
		(layer "In2.Cu")
		(net "VSENSE_VSS_CPU_NODE1")
	)
	(segment
		(start 98.84918 -140.771372)
		(end 101.938836 -143.861028)
		(width 0.254)
		(layer "In2.Cu")
		(net "VSENSE_VSS_CPU_NODE1")
	)
	(segment
		(start 116.577872 -140.660374)
		(end 116.075714 -140.158216)
		(width 0.254)
		(layer "In2.Cu")
		(net "VSENSE_VSS_CPU_NODE1")
	)
	(segment
		(start 88.145112 -81.571846)
		(end 89.0016 -82.428334)
		(width 0.254)
		(layer "In2.Cu")
		(net "VSENSE_VSS_CPU_NODE1")
	)
	(segment
		(start 97.065846 -128.362202)
		(end 98.84918 -130.145536)
		(width 0.254)
		(layer "In2.Cu")
		(net "VSENSE_VSS_CPU_NODE1")
	)
	(segment
		(start 83.422236 -80.908144)
		(end 84.085938 -81.571846)
		(width 0.254)
		(layer "In2.Cu")
		(net "VSENSE_VSS_CPU_NODE1")
	)
	(segment
		(start 65.034668 -79.85633)
		(end 65.367154 -80.188816)
		(width 0.254)
		(layer "In2.Cu")
		(net "VSENSE_VSS_CPU_NODE1")
	)
	(segment
		(start 67.43192 -80.601566)
		(end 77.837538 -80.601566)
		(width 0.254)
		(layer "In2.Cu")
		(net "VSENSE_VSS_CPU_NODE1")
	)
	(segment
		(start 115.294918 -139.97178)
		(end 115.294918 -139.717526)
		(width 0.254)
		(layer "In2.Cu")
		(net "VSENSE_VSS_CPU_NODE1")
	)
	(segment
		(start 92.99702 -123.316238)
		(end 92.99702 -126.720854)
		(width 0.254)
		(layer "In2.Cu")
		(net "VSENSE_VSS_CPU_NODE1")
	)
	(segment
		(start 90.55608 -105.543604)
		(end 92.17152 -107.159044)
		(width 0.254)
		(layer "In2.Cu")
		(net "VSENSE_VSS_CPU_NODE1")
	)
	(segment
		(start 77.837538 -80.601566)
		(end 78.144116 -80.908144)
		(width 0.254)
		(layer "In2.Cu")
		(net "VSENSE_VSS_CPU_NODE1")
	)
	(segment
		(start 115.459002 -143.861028)
		(end 116.577872 -142.742158)
		(width 0.254)
		(layer "In2.Cu")
		(net "VSENSE_VSS_CPU_NODE1")
	)
	(segment
		(start 101.938836 -143.861028)
		(end 115.459002 -143.861028)
		(width 0.254)
		(layer "In2.Cu")
		(net "VSENSE_VSS_CPU_NODE1")
	)
	(segment
		(start 62.641734 -78.44028)
		(end 63.614554 -78.44028)
		(width 0.254)
		(layer "In2.Cu")
		(net "VSENSE_VSS_CPU_NODE1")
	)
	(segment
		(start 92.17152 -107.159044)
		(end 92.17152 -122.490738)
		(width 0.254)
		(layer "In2.Cu")
		(net "VSENSE_VSS_CPU_NODE1")
	)
	(segment
		(start 93.290898 -86.384892)
		(end 93.69552 -86.789514)
		(width 0.254)
		(layer "In2.Cu")
		(net "VSENSE_VSS_CPU_NODE1")
	)
	(segment
		(start 84.085938 -81.571846)
		(end 88.145112 -81.571846)
		(width 0.254)
		(layer "In2.Cu")
		(net "VSENSE_VSS_CPU_NODE1")
	)
	(segment
		(start 43.09364 -70.833488)
		(end 43.09364 -71.316596)
		(width 0.1143)
		(layer "F.Cu")
		(net "PD_CPU_NODE1_RP1_PERN")
	)
	(segment
		(start 38.794182 -73.283318)
		(end 38.800024 -73.28916)
		(width 0.1016)
		(layer "F.Cu")
		(net "PD_CPU_NODE1_RP1_PERN")
	)
	(segment
		(start 43.09364 -71.316596)
		(end 43.31081 -71.533766)
		(width 0.1143)
		(layer "F.Cu")
		(net "PD_CPU_NODE1_RP1_PERN")
	)
	(segment
		(start 42.779696 -71.914258)
		(end 42.248328 -71.914258)
		(width 0.1143)
		(layer "F.Cu")
		(net "PD_CPU_NODE1_RP1_PERN")
	)
	(segment
		(start 43.584114 -72.278494)
		(end 43.584114 -72.827896)
		(width 0.1143)
		(layer "F.Cu")
		(net "PD_CPU_NODE1_RP1_PERN")
	)
	(segment
		(start 42.36974 -70.109588)
		(end 43.09364 -70.833488)
		(width 0.1143)
		(layer "F.Cu")
		(net "PD_CPU_NODE1_RP1_PERN")
	)
	(segment
		(start 43.45813 -75.69581)
		(end 43.185588 -75.423268)
		(width 0.1143)
		(layer "F.Cu")
		(net "PD_CPU_NODE1_RP1_PERN")
	)
	(segment
		(start 37.107622 -72.386698)
		(end 37.897562 -72.386698)
		(width 0.1016)
		(layer "F.Cu")
		(net "PD_CPU_NODE1_RP1_PERN")
	)
	(segment
		(start 43.767502 -71.533766)
		(end 43.937428 -71.703692)
		(width 0.1143)
		(layer "F.Cu")
		(net "PD_CPU_NODE1_RP1_PERN")
	)
	(segment
		(start 42.248328 -76.41717)
		(end 42.068242 -76.41717)
		(width 0.1143)
		(layer "F.Cu")
		(net "PD_CPU_NODE1_RP1_PERN")
	)
	(segment
		(start 43.46194 -72.95007)
		(end 43.46194 -73.24979)
		(width 0.1143)
		(layer "F.Cu")
		(net "PD_CPU_NODE1_RP1_PERN")
	)
	(segment
		(start 43.116246 -72.250808)
		(end 42.779696 -71.914258)
		(width 0.1143)
		(layer "F.Cu")
		(net "PD_CPU_NODE1_RP1_PERN")
	)
	(segment
		(start 43.099736 -73.611994)
		(end 43.099736 -73.901554)
		(width 0.1143)
		(layer "F.Cu")
		(net "PD_CPU_NODE1_RP1_PERN")
	)
	(segment
		(start 43.099736 -73.901554)
		(end 43.099736 -74.06259)
		(width 0.1016)
		(layer "F.Cu")
		(net "PD_CPU_NODE1_RP1_PERN")
	)
	(segment
		(start 40.636698 -73.28916)
		(end 40.72382 -73.376282)
		(width 0.1016)
		(layer "F.Cu")
		(net "PD_CPU_NODE1_RP1_PERN")
	)
	(segment
		(start 41.75125 -76.100178)
		(end 41.75125 -75.69581)
		(width 0.1143)
		(layer "F.Cu")
		(net "PD_CPU_NODE1_RP1_PERN")
	)
	(segment
		(start 43.584114 -72.827896)
		(end 43.46194 -72.95007)
		(width 0.1143)
		(layer "F.Cu")
		(net "PD_CPU_NODE1_RP1_PERN")
	)
	(segment
		(start 42.6466 -72.981058)
		(end 43.116246 -72.511412)
		(width 0.1143)
		(layer "F.Cu")
		(net "PD_CPU_NODE1_RP1_PERN")
	)
	(segment
		(start 43.937428 -71.703692)
		(end 43.937428 -71.92518)
		(width 0.1143)
		(layer "F.Cu")
		(net "PD_CPU_NODE1_RP1_PERN")
	)
	(segment
		(start 41.922192 -72.981058)
		(end 42.361612 -72.981058)
		(width 0.1016)
		(layer "F.Cu")
		(net "PD_CPU_NODE1_RP1_PERN")
	)
	(segment
		(start 43.607228 -75.546712)
		(end 43.45813 -75.69581)
		(width 0.1016)
		(layer "F.Cu")
		(net "PD_CPU_NODE1_RP1_PERN")
	)
	(segment
		(start 40.72382 -73.376282)
		(end 41.526968 -73.376282)
		(width 0.1016)
		(layer "F.Cu")
		(net "PD_CPU_NODE1_RP1_PERN")
	)
	(segment
		(start 41.75125 -71.560182)
		(end 41.75125 -71.192898)
		(width 0.1143)
		(layer "F.Cu")
		(net "PD_CPU_NODE1_RP1_PERN")
	)
	(segment
		(start 43.185588 -75.423268)
		(end 42.530268 -75.423268)
		(width 0.1143)
		(layer "F.Cu")
		(net "PD_CPU_NODE1_RP1_PERN")
	)
	(segment
		(start 42.105326 -71.914258)
		(end 41.75125 -71.560182)
		(width 0.1143)
		(layer "F.Cu")
		(net "PD_CPU_NODE1_RP1_PERN")
	)
	(segment
		(start 37.897562 -72.386698)
		(end 38.794182 -73.283318)
		(width 0.1016)
		(layer "F.Cu")
		(net "PD_CPU_NODE1_RP1_PERN")
	)
	(segment
		(start 43.46194 -73.24979)
		(end 43.099736 -73.611994)
		(width 0.1143)
		(layer "F.Cu")
		(net "PD_CPU_NODE1_RP1_PERN")
	)
	(segment
		(start 42.342054 -75.611482)
		(end 42.342054 -76.323444)
		(width 0.1143)
		(layer "F.Cu")
		(net "PD_CPU_NODE1_RP1_PERN")
	)
	(segment
		(start 43.607228 -74.570082)
		(end 43.607228 -75.546712)
		(width 0.1016)
		(layer "F.Cu")
		(net "PD_CPU_NODE1_RP1_PERN")
	)
	(segment
		(start 43.31081 -71.533766)
		(end 43.767502 -71.533766)
		(width 0.1143)
		(layer "F.Cu")
		(net "PD_CPU_NODE1_RP1_PERN")
	)
	(segment
		(start 43.937428 -71.92518)
		(end 43.635168 -72.227694)
		(width 0.1143)
		(layer "F.Cu")
		(net "PD_CPU_NODE1_RP1_PERN")
	)
	(segment
		(start 42.361612 -72.981058)
		(end 42.6466 -72.981058)
		(width 0.1143)
		(layer "F.Cu")
		(net "PD_CPU_NODE1_RP1_PERN")
	)
	(segment
		(start 42.068242 -76.41717)
		(end 41.75125 -76.100178)
		(width 0.1143)
		(layer "F.Cu")
		(net "PD_CPU_NODE1_RP1_PERN")
	)
	(segment
		(start 43.116246 -72.511412)
		(end 43.116246 -72.250808)
		(width 0.1143)
		(layer "F.Cu")
		(net "PD_CPU_NODE1_RP1_PERN")
	)
	(segment
		(start 42.530268 -75.423268)
		(end 42.342054 -75.611482)
		(width 0.1143)
		(layer "F.Cu")
		(net "PD_CPU_NODE1_RP1_PERN")
	)
	(segment
		(start 41.75125 -71.192898)
		(end 41.75125 -70.326758)
		(width 0.1143)
		(layer "F.Cu")
		(net "PD_CPU_NODE1_RP1_PERN")
	)
	(segment
		(start 43.099736 -74.06259)
		(end 43.607228 -74.570082)
		(width 0.1016)
		(layer "F.Cu")
		(net "PD_CPU_NODE1_RP1_PERN")
	)
	(segment
		(start 41.75125 -70.326758)
		(end 41.96842 -70.109588)
		(width 0.1143)
		(layer "F.Cu")
		(net "PD_CPU_NODE1_RP1_PERN")
	)
	(segment
		(start 43.635168 -72.227694)
		(end 43.584114 -72.278494)
		(width 0.1143)
		(layer "F.Cu")
		(net "PD_CPU_NODE1_RP1_PERN")
	)
	(segment
		(start 42.248328 -71.914258)
		(end 42.105326 -71.914258)
		(width 0.1143)
		(layer "F.Cu")
		(net "PD_CPU_NODE1_RP1_PERN")
	)
	(segment
		(start 41.526968 -73.376282)
		(end 41.922192 -72.981058)
		(width 0.1016)
		(layer "F.Cu")
		(net "PD_CPU_NODE1_RP1_PERN")
	)
	(segment
		(start 38.800024 -73.28916)
		(end 40.636698 -73.28916)
		(width 0.1016)
		(layer "F.Cu")
		(net "PD_CPU_NODE1_RP1_PERN")
	)
	(segment
		(start 41.96842 -70.109588)
		(end 42.36974 -70.109588)
		(width 0.1143)
		(layer "F.Cu")
		(net "PD_CPU_NODE1_RP1_PERN")
	)
	(segment
		(start 42.342054 -76.323444)
		(end 42.248328 -76.41717)
		(width 0.1143)
		(layer "F.Cu")
		(net "PD_CPU_NODE1_RP1_PERN")
	)
	(via
		(at 38.794182 -73.283318)
		(size 0.508)
		(drill 0.254)
		(layers "F.Cu" "B.Cu")
		(net "PD_CPU_NODE1_RP1_PERN")
	)
	(via
		(at 110.38967 -132.457952)
		(size 0.508)
		(drill 0.254)
		(layers "F.Cu" "B.Cu")
		(net "VR_PVCCP_NODE1_BOOT1")
	)
	(segment
		(start 161.890964 -98.890836)
		(end 160.78327 -97.783142)
		(width 0.1016)
		(layer "F.Cu")
		(net "FM_CPLD_NODE1_USB_PONRST_L")
	)
	(segment
		(start 160.78327 -97.783142)
		(end 160.78327 -97.315528)
		(width 0.1016)
		(layer "F.Cu")
		(net "FM_CPLD_NODE1_USB_PONRST_L")
	)
	(segment
		(start 160.003744 -96.536002)
		(end 154.846528 -96.536002)
		(width 0.1016)
		(layer "F.Cu")
		(net "FM_CPLD_NODE1_USB_PONRST_L")
	)
	(segment
		(start 151.89327 -99.48926)
		(end 151.74976 -99.48926)
		(width 0.1016)
		(layer "F.Cu")
		(net "FM_CPLD_NODE1_USB_PONRST_L")
	)
	(segment
		(start 172.010324 -118.365524)
		(end 171.835318 -118.365524)
		(width 0.1016)
		(layer "F.Cu")
		(net "FM_CPLD_NODE1_USB_PONRST_L")
	)
	(segment
		(start 162.31489 -98.935794)
		(end 162.269932 -98.890836)
		(width 0.1016)
		(layer "F.Cu")
		(net "FM_CPLD_NODE1_USB_PONRST_L")
	)
	(segment
		(start 163.340034 -98.935794)
		(end 162.31489 -98.935794)
		(width 0.1016)
		(layer "F.Cu")
		(net "FM_CPLD_NODE1_USB_PONRST_L")
	)
	(segment
		(start 154.846528 -96.536002)
		(end 151.89327 -99.48926)
		(width 0.1016)
		(layer "F.Cu")
		(net "FM_CPLD_NODE1_USB_PONRST_L")
	)
	(segment
		(start 171.835318 -118.365524)
		(end 171.285662 -117.815868)
		(width 0.1016)
		(layer "F.Cu")
		(net "FM_CPLD_NODE1_USB_PONRST_L")
	)
	(segment
		(start 160.78327 -97.315528)
		(end 160.003744 -96.536002)
		(width 0.1016)
		(layer "F.Cu")
		(net "FM_CPLD_NODE1_USB_PONRST_L")
	)
	(segment
		(start 162.269932 -98.890836)
		(end 161.890964 -98.890836)
		(width 0.1016)
		(layer "F.Cu")
		(net "FM_CPLD_NODE1_USB_PONRST_L")
	)
	(via
		(at 151.74976 -99.48926)
		(size 0.508)
		(drill 0.254)
		(layers "F.Cu" "B.Cu")
		(net "FM_CPLD_NODE1_USB_PONRST_L")
	)
	(via
		(at 171.285662 -117.815868)
		(size 0.49022)
		(drill 0.254)
		(layers "F.Cu" "B.Cu")
		(net "FM_CPLD_NODE1_USB_PONRST_L")
	)
	(segment
		(start 169.65168 -116.181886)
		(end 171.285662 -117.815868)
		(width 0.1143)
		(layer "In6.Cu")
		(net "FM_CPLD_NODE1_USB_PONRST_L")
	)
	(segment
		(start 153.377392 -106.603292)
		(end 156.522674 -109.748574)
		(width 0.1143)
		(layer "In6.Cu")
		(net "FM_CPLD_NODE1_USB_PONRST_L")
	)
	(segment
		(start 156.522674 -109.748574)
		(end 165.799008 -109.748574)
		(width 0.1143)
		(layer "In6.Cu")
		(net "FM_CPLD_NODE1_USB_PONRST_L")
	)
	(segment
		(start 151.74976 -99.48926)
		(end 153.377392 -101.116892)
		(width 0.1143)
		(layer "In6.Cu")
		(net "FM_CPLD_NODE1_USB_PONRST_L")
	)
	(segment
		(start 153.377392 -101.116892)
		(end 153.377392 -106.603292)
		(width 0.1143)
		(layer "In6.Cu")
		(net "FM_CPLD_NODE1_USB_PONRST_L")
	)
	(segment
		(start 165.799008 -109.748574)
		(end 169.65168 -113.601246)
		(width 0.1143)
		(layer "In6.Cu")
		(net "FM_CPLD_NODE1_USB_PONRST_L")
	)
	(segment
		(start 169.65168 -113.601246)
		(end 169.65168 -116.181886)
		(width 0.1143)
		(layer "In6.Cu")
		(net "FM_CPLD_NODE1_USB_PONRST_L")
	)
	(segment
		(start 41.233344 -139.764008)
		(end 41.233344 -139.764262)
		(width 0.1016)
		(layer "F.Cu")
		(net "BMC_NODE1_DDR_D12")
	)
	(segment
		(start 59.73953 -136.859518)
		(end 59.341004 -137.258044)
		(width 0.1016)
		(layer "F.Cu")
		(net "BMC_NODE1_DDR_D12")
	)
	(segment
		(start 40.83304 -139.363704)
		(end 41.233344 -139.764008)
		(width 0.1016)
		(layer "F.Cu")
		(net "BMC_NODE1_DDR_D12")
	)
	(segment
		(start 59.741816 -136.859518)
		(end 59.73953 -136.859518)
		(width 0.1016)
		(layer "F.Cu")
		(net "BMC_NODE1_DDR_D12")
	)
	(via
		(at 59.341004 -137.258044)
		(size 0.49022)
		(drill 0.254)
		(layers "F.Cu" "B.Cu")
		(net "BMC_NODE1_DDR_D12")
	)
	(via
		(at 41.233344 -139.764262)
		(size 0.49022)
		(drill 0.254)
		(layers "F.Cu" "B.Cu")
		(net "BMC_NODE1_DDR_D12")
	)
	(segment
		(start 55.20563 -140.821664)
		(end 54.179978 -141.494764)
		(width 0.1143)
		(layer "In2.Cu")
		(net "BMC_NODE1_DDR_D12")
	)
	(segment
		(start 58.942986 -137.81659)
		(end 58.942986 -137.92835)
		(width 0.1143)
		(layer "In2.Cu")
		(net "BMC_NODE1_DDR_D12")
	)
	(segment
		(start 43.331638 -141.48943)
		(end 42.544746 -141.10335)
		(width 0.1143)
		(layer "In2.Cu")
		(net "BMC_NODE1_DDR_D12")
	)
	(segment
		(start 50.65014 -143.50111)
		(end 47.04588 -143.50111)
		(width 0.1143)
		(layer "In2.Cu")
		(net "BMC_NODE1_DDR_D12")
	)
	(segment
		(start 43.601386 -141.68247)
		(end 43.331638 -141.48943)
		(width 0.1143)
		(layer "In2.Cu")
		(net "BMC_NODE1_DDR_D12")
	)
	(segment
		(start 54.179978 -141.494764)
		(end 50.65014 -143.50111)
		(width 0.1143)
		(layer "In2.Cu")
		(net "BMC_NODE1_DDR_D12")
	)
	(segment
		(start 58.603896 -138.592052)
		(end 55.20563 -140.821664)
		(width 0.1143)
		(layer "In2.Cu")
		(net "BMC_NODE1_DDR_D12")
	)
	(segment
		(start 47.04588 -143.50111)
		(end 46.977554 -143.43253)
		(width 0.1143)
		(layer "In2.Cu")
		(net "BMC_NODE1_DDR_D12")
	)
	(segment
		(start 42.544746 -141.10335)
		(end 42.228516 -140.906246)
		(width 0.1143)
		(layer "In2.Cu")
		(net "BMC_NODE1_DDR_D12")
	)
	(segment
		(start 42.228516 -140.906246)
		(end 42.025316 -140.703046)
		(width 0.1143)
		(layer "In2.Cu")
		(net "BMC_NODE1_DDR_D12")
	)
	(segment
		(start 44.45762 -142.295626)
		(end 43.601386 -141.68247)
		(width 0.1143)
		(layer "In2.Cu")
		(net "BMC_NODE1_DDR_D12")
	)
	(segment
		(start 58.942986 -137.92835)
		(end 58.942986 -138.160506)
		(width 0.1016)
		(layer "In2.Cu")
		(net "BMC_NODE1_DDR_D12")
	)
	(segment
		(start 58.942986 -138.160506)
		(end 58.942986 -138.252962)
		(width 0.1143)
		(layer "In2.Cu")
		(net "BMC_NODE1_DDR_D12")
	)
	(segment
		(start 58.942986 -138.252962)
		(end 58.603896 -138.592052)
		(width 0.1143)
		(layer "In2.Cu")
		(net "BMC_NODE1_DDR_D12")
	)
	(segment
		(start 46.977554 -143.43253)
		(end 44.45762 -142.295626)
		(width 0.1143)
		(layer "In2.Cu")
		(net "BMC_NODE1_DDR_D12")
	)
	(segment
		(start 59.341004 -137.258044)
		(end 58.942986 -137.81659)
		(width 0.1143)
		(layer "In2.Cu")
		(net "BMC_NODE1_DDR_D12")
	)
	(segment
		(start 42.025316 -140.703046)
		(end 41.233344 -139.764262)
		(width 0.1143)
		(layer "In2.Cu")
		(net "BMC_NODE1_DDR_D12")
	)
	(segment
		(start 89.162128 -106.905552)
		(end 89.162128 -107.83824)
		(width 0.1016)
		(layer "F.Cu")
		(net "SPI_CPU_NODE1_HOLD_L")
	)
	(segment
		(start 89.3191 -106.74858)
		(end 89.162128 -106.905552)
		(width 0.1016)
		(layer "F.Cu")
		(net "SPI_CPU_NODE1_HOLD_L")
	)
	(segment
		(start 89.428066 -104.128062)
		(end 89.428066 -106.639614)
		(width 0.1016)
		(layer "F.Cu")
		(net "SPI_CPU_NODE1_HOLD_L")
	)
	(segment
		(start 89.428066 -106.639614)
		(end 89.3191 -106.74858)
		(width 0.1016)
		(layer "F.Cu")
		(net "SPI_CPU_NODE1_HOLD_L")
	)
	(segment
		(start 89.428066 -104.128062)
		(end 89.428066 -103.859584)
		(width 0.1016)
		(layer "F.Cu")
		(net "SPI_CPU_NODE1_HOLD_L")
	)
	(via
		(at 89.3191 -106.74858)
		(size 0.508)
		(drill 0.254)
		(layers "F.Cu" "B.Cu")
		(net "SPI_CPU_NODE1_HOLD_L")
	)
	(segment
		(start 116.787422 -138.053826)
		(end 116.798598 -138.065002)
		(width 0.254)
		(layer "F.Cu")
		(net "VR_PVCCP_NODE1_FB_RC")
	)
	(segment
		(start 116.787422 -137.018522)
		(end 116.787422 -138.053826)
		(width 0.254)
		(layer "F.Cu")
		(net "VR_PVCCP_NODE1_FB_RC")
	)
	(segment
		(start 117.609874 -138.065002)
		(end 116.798598 -138.065002)
		(width 0.254)
		(layer "F.Cu")
		(net "VR_PVCCP_NODE1_FB_RC")
	)
	(via
		(at 117.609874 -138.065002)
		(size 0.508)
		(drill 0.254)
		(layers "F.Cu" "B.Cu")
		(net "VR_PVCCP_NODE1_FB_RC")
	)
	(segment
		(start 44.006008 -131.3688)
		(end 44.006008 -130.986022)
		(width 0.1016)
		(layer "F.Cu")
		(net "BMC_NODE1_DDR_MA10")
	)
	(segment
		(start 44.833032 -132.963666)
		(end 44.545504 -132.676138)
		(width 0.1016)
		(layer "F.Cu")
		(net "BMC_NODE1_DDR_MA10")
	)
	(segment
		(start 58.941716 -132.058918)
		(end 58.540904 -131.658106)
		(width 0.1016)
		(layer "F.Cu")
		(net "BMC_NODE1_DDR_MA10")
	)
	(segment
		(start 58.941716 -132.059426)
		(end 58.941716 -132.058918)
		(width 0.1016)
		(layer "F.Cu")
		(net "BMC_NODE1_DDR_MA10")
	)
	(segment
		(start 44.545504 -132.676138)
		(end 44.006008 -131.3688)
		(width 0.1016)
		(layer "F.Cu")
		(net "BMC_NODE1_DDR_MA10")
	)
	(via
		(at 44.006008 -130.986022)
		(size 0.508)
		(drill 0.254)
		(layers "F.Cu" "B.Cu")
		(net "BMC_NODE1_DDR_MA10")
	)
	(via
		(at 58.540904 -131.658106)
		(size 0.49022)
		(drill 0.254)
		(layers "F.Cu" "B.Cu")
		(net "BMC_NODE1_DDR_MA10")
	)
	(segment
		(start 44.256198 -129.449068)
		(end 46.017688 -127.687578)
		(width 0.1143)
		(layer "In2.Cu")
		(net "BMC_NODE1_DDR_MA10")
	)
	(segment
		(start 53.634386 -128.569974)
		(end 54.581806 -129.517394)
		(width 0.1143)
		(layer "In2.Cu")
		(net "BMC_NODE1_DDR_MA10")
	)
	(segment
		(start 52.035456 -128.077468)
		(end 52.50053 -128.077468)
		(width 0.1143)
		(layer "In2.Cu")
		(net "BMC_NODE1_DDR_MA10")
	)
	(segment
		(start 57.35193 -131.658106)
		(end 58.540904 -131.658106)
		(width 0.1143)
		(layer "In2.Cu")
		(net "BMC_NODE1_DDR_MA10")
	)
	(segment
		(start 44.006008 -130.423158)
		(end 44.246546 -129.449068)
		(width 0.1143)
		(layer "In2.Cu")
		(net "BMC_NODE1_DDR_MA10")
	)
	(segment
		(start 44.006008 -130.986022)
		(end 44.006008 -130.423158)
		(width 0.1143)
		(layer "In2.Cu")
		(net "BMC_NODE1_DDR_MA10")
	)
	(segment
		(start 46.017688 -127.687578)
		(end 51.645566 -127.687578)
		(width 0.1143)
		(layer "In2.Cu")
		(net "BMC_NODE1_DDR_MA10")
	)
	(segment
		(start 52.50053 -128.077468)
		(end 52.993036 -128.569974)
		(width 0.1143)
		(layer "In2.Cu")
		(net "BMC_NODE1_DDR_MA10")
	)
	(segment
		(start 52.993036 -128.569974)
		(end 53.634386 -128.569974)
		(width 0.1143)
		(layer "In2.Cu")
		(net "BMC_NODE1_DDR_MA10")
	)
	(segment
		(start 55.211218 -129.517394)
		(end 57.35193 -131.658106)
		(width 0.1143)
		(layer "In2.Cu")
		(net "BMC_NODE1_DDR_MA10")
	)
	(segment
		(start 44.246546 -129.449068)
		(end 44.256198 -129.449068)
		(width 0.1143)
		(layer "In2.Cu")
		(net "BMC_NODE1_DDR_MA10")
	)
	(segment
		(start 51.645566 -127.687578)
		(end 52.035456 -128.077468)
		(width 0.1143)
		(layer "In2.Cu")
		(net "BMC_NODE1_DDR_MA10")
	)
	(segment
		(start 54.581806 -129.517394)
		(end 55.211218 -129.517394)
		(width 0.1143)
		(layer "In2.Cu")
		(net "BMC_NODE1_DDR_MA10")
	)
	(segment
		(start 36.069778 -81.036922)
		(end 38.102286 -81.036922)
		(width 0.1016)
		(layer "F.Cu")
		(net "PD_CPU_NODE1_W1")
	)
	(segment
		(start 41.24198 -80.10398)
		(end 40.29075 -80.10398)
		(width 0.1016)
		(layer "F.Cu")
		(net "PD_CPU_NODE1_W1")
	)
	(segment
		(start 39.429182 -80.147922)
		(end 38.771068 -80.806036)
		(width 0.1016)
		(layer "F.Cu")
		(net "PD_CPU_NODE1_W1")
	)
	(segment
		(start 40.246808 -80.147922)
		(end 39.429182 -80.147922)
		(width 0.1016)
		(layer "F.Cu")
		(net "PD_CPU_NODE1_W1")
	)
	(segment
		(start 38.102286 -81.036922)
		(end 38.333172 -80.806036)
		(width 0.1016)
		(layer "F.Cu")
		(net "PD_CPU_NODE1_W1")
	)
	(segment
		(start 41.336722 -80.198722)
		(end 41.24198 -80.10398)
		(width 0.1016)
		(layer "F.Cu")
		(net "PD_CPU_NODE1_W1")
	)
	(segment
		(start 40.29075 -80.10398)
		(end 40.246808 -80.147922)
		(width 0.1016)
		(layer "F.Cu")
		(net "PD_CPU_NODE1_W1")
	)
	(segment
		(start 41.75125 -80.198722)
		(end 41.336722 -80.198722)
		(width 0.1016)
		(layer "F.Cu")
		(net "PD_CPU_NODE1_W1")
	)
	(segment
		(start 38.771068 -80.806036)
		(end 38.333172 -80.806036)
		(width 0.1016)
		(layer "F.Cu")
		(net "PD_CPU_NODE1_W1")
	)
	(via
		(at 38.333172 -80.806036)
		(size 0.508)
		(drill 0.254)
		(layers "F.Cu" "B.Cu")
		(net "PD_CPU_NODE1_W1")
	)
	(segment
		(start 102.416356 -134.11581)
		(end 102.732078 -134.11581)
		(width 0.1016)
		(layer "F.Cu")
		(net "SVID_CPU_NODE1_DAT_R")
	)
	(segment
		(start 103.354632 -135.497824)
		(end 103.112316 -135.255508)
		(width 0.1016)
		(layer "F.Cu")
		(net "SVID_CPU_NODE1_DAT_R")
	)
	(segment
		(start 104.94645 -135.497824)
		(end 103.354632 -135.497824)
		(width 0.1016)
		(layer "F.Cu")
		(net "SVID_CPU_NODE1_DAT_R")
	)
	(segment
		(start 103.112316 -134.496048)
		(end 103.112316 -135.255508)
		(width 0.1016)
		(layer "F.Cu")
		(net "SVID_CPU_NODE1_DAT_R")
	)
	(segment
		(start 102.732078 -134.11581)
		(end 103.112316 -134.496048)
		(width 0.1016)
		(layer "F.Cu")
		(net "SVID_CPU_NODE1_DAT_R")
	)
	(via
		(at 103.112316 -135.255508)
		(size 0.508)
		(drill 0.254)
		(layers "F.Cu" "B.Cu")
		(net "SVID_CPU_NODE1_DAT_R")
	)
	(segment
		(start 52.424584 -137.540492)
		(end 52.424584 -137.239502)
		(width 0.10414)
		(layer "F.Cu")
		(net "BMC_NODE1_DDR_DQS0_DP")
	)
	(segment
		(start 52.540154 -137.656062)
		(end 52.424584 -137.540492)
		(width 0.10414)
		(layer "F.Cu")
		(net "BMC_NODE1_DDR_DQS0_DP")
	)
	(segment
		(start 53.520086 -137.656062)
		(end 52.540154 -137.656062)
		(width 0.10414)
		(layer "F.Cu")
		(net "BMC_NODE1_DDR_DQS0_DP")
	)
	(segment
		(start 42.177716 -136.792462)
		(end 42.424858 -137.039604)
		(width 0.10414)
		(layer "F.Cu")
		(net "BMC_NODE1_DDR_DQS0_DP")
	)
	(segment
		(start 41.804336 -136.792462)
		(end 42.177716 -136.792462)
		(width 0.10414)
		(layer "F.Cu")
		(net "BMC_NODE1_DDR_DQS0_DP")
	)
	(segment
		(start 52.424584 -137.239502)
		(end 52.516024 -137.148062)
		(width 0.10414)
		(layer "F.Cu")
		(net "BMC_NODE1_DDR_DQS0_DP")
	)
	(segment
		(start 57.34177 -136.059418)
		(end 57.147714 -135.865362)
		(width 0.10414)
		(layer "F.Cu")
		(net "BMC_NODE1_DDR_DQS0_DP")
	)
	(segment
		(start 54.989222 -136.639046)
		(end 53.972206 -137.656062)
		(width 0.10414)
		(layer "F.Cu")
		(net "BMC_NODE1_DDR_DQS0_DP")
	)
	(segment
		(start 41.63314 -136.963658)
		(end 41.804336 -136.792462)
		(width 0.10414)
		(layer "F.Cu")
		(net "BMC_NODE1_DDR_DQS0_DP")
	)
	(segment
		(start 56.933846 -135.865362)
		(end 56.160162 -136.639046)
		(width 0.10414)
		(layer "F.Cu")
		(net "BMC_NODE1_DDR_DQS0_DP")
	)
	(segment
		(start 56.160162 -136.639046)
		(end 54.989222 -136.639046)
		(width 0.10414)
		(layer "F.Cu")
		(net "BMC_NODE1_DDR_DQS0_DP")
	)
	(segment
		(start 53.972206 -137.656062)
		(end 53.520086 -137.656062)
		(width 0.10414)
		(layer "F.Cu")
		(net "BMC_NODE1_DDR_DQS0_DP")
	)
	(segment
		(start 52.516024 -137.148062)
		(end 52.656486 -137.148062)
		(width 0.10414)
		(layer "F.Cu")
		(net "BMC_NODE1_DDR_DQS0_DP")
	)
	(segment
		(start 57.147714 -135.865362)
		(end 56.933846 -135.865362)
		(width 0.10414)
		(layer "F.Cu")
		(net "BMC_NODE1_DDR_DQS0_DP")
	)
	(via
		(at 53.520086 -137.656062)
		(size 0.508)
		(drill 0.254)
		(layers "F.Cu" "B.Cu")
		(net "BMC_NODE1_DDR_DQS0_DP")
	)
	(via
		(at 42.424858 -137.039604)
		(size 0.49022)
		(drill 0.254)
		(layers "F.Cu" "B.Cu")
		(net "BMC_NODE1_DDR_DQS0_DP")
	)
	(via
		(at 52.656486 -137.148062)
		(size 0.49022)
		(drill 0.254)
		(layers "F.Cu" "B.Cu")
		(net "BMC_NODE1_DDR_DQS0_DP")
	)
	(segment
		(start 50.606706 -138.231118)
		(end 50.919126 -138.231118)
		(width 0.10414)
		(layer "In7.Cu")
		(net "BMC_NODE1_DDR_DQS0_DP")
	)
	(segment
		(start 51.035966 -138.114278)
		(end 51.348386 -138.114278)
		(width 0.10414)
		(layer "In7.Cu")
		(net "BMC_NODE1_DDR_DQS0_DP")
	)
	(segment
		(start 47.029624 -137.46353)
		(end 47.405798 -137.839704)
		(width 0.10414)
		(layer "In7.Cu")
		(net "BMC_NODE1_DDR_DQS0_DP")
	)
	(segment
		(start 44.604686 -137.198862)
		(end 44.869354 -137.46353)
		(width 0.10414)
		(layer "In7.Cu")
		(net "BMC_NODE1_DDR_DQS0_DP")
	)
	(segment
		(start 42.956226 -136.693402)
		(end 43.385486 -137.122662)
		(width 0.10414)
		(layer "In7.Cu")
		(net "BMC_NODE1_DDR_DQS0_DP")
	)
	(segment
		(start 50.489866 -138.114278)
		(end 50.606706 -138.231118)
		(width 0.10414)
		(layer "In7.Cu")
		(net "BMC_NODE1_DDR_DQS0_DP")
	)
	(segment
		(start 49.424082 -137.171684)
		(end 49.603152 -137.350754)
		(width 0.10414)
		(layer "In7.Cu")
		(net "BMC_NODE1_DDR_DQS0_DP")
	)
	(segment
		(start 49.602898 -137.504678)
		(end 49.823878 -137.725658)
		(width 0.10414)
		(layer "In7.Cu")
		(net "BMC_NODE1_DDR_DQS0_DP")
	)
	(segment
		(start 49.603152 -137.350754)
		(end 49.603152 -137.504424)
		(width 0.10414)
		(layer "In7.Cu")
		(net "BMC_NODE1_DDR_DQS0_DP")
	)
	(segment
		(start 49.978056 -137.725658)
		(end 50.366676 -138.114278)
		(width 0.10414)
		(layer "In7.Cu")
		(net "BMC_NODE1_DDR_DQS0_DP")
	)
	(segment
		(start 48.410114 -137.839704)
		(end 49.078134 -137.171684)
		(width 0.10414)
		(layer "In7.Cu")
		(net "BMC_NODE1_DDR_DQS0_DP")
	)
	(segment
		(start 43.664886 -137.122662)
		(end 43.741086 -137.198862)
		(width 0.10414)
		(layer "In7.Cu")
		(net "BMC_NODE1_DDR_DQS0_DP")
	)
	(segment
		(start 52.077366 -138.114278)
		(end 52.454556 -137.737088)
		(width 0.10414)
		(layer "In7.Cu")
		(net "BMC_NODE1_DDR_DQS0_DP")
	)
	(segment
		(start 44.869354 -137.46353)
		(end 47.029624 -137.46353)
		(width 0.10414)
		(layer "In7.Cu")
		(net "BMC_NODE1_DDR_DQS0_DP")
	)
	(segment
		(start 42.424858 -137.039604)
		(end 42.424858 -136.813544)
		(width 0.10414)
		(layer "In7.Cu")
		(net "BMC_NODE1_DDR_DQS0_DP")
	)
	(segment
		(start 52.454556 -137.349992)
		(end 52.656486 -137.148062)
		(width 0.10414)
		(layer "In7.Cu")
		(net "BMC_NODE1_DDR_DQS0_DP")
	)
	(segment
		(start 43.741086 -137.198862)
		(end 44.604686 -137.198862)
		(width 0.10414)
		(layer "In7.Cu")
		(net "BMC_NODE1_DDR_DQS0_DP")
	)
	(segment
		(start 47.405798 -137.839704)
		(end 48.410114 -137.839704)
		(width 0.10414)
		(layer "In7.Cu")
		(net "BMC_NODE1_DDR_DQS0_DP")
	)
	(segment
		(start 50.919126 -138.231118)
		(end 51.035966 -138.114278)
		(width 0.10414)
		(layer "In7.Cu")
		(net "BMC_NODE1_DDR_DQS0_DP")
	)
	(segment
		(start 49.078134 -137.171684)
		(end 49.424082 -137.171684)
		(width 0.10414)
		(layer "In7.Cu")
		(net "BMC_NODE1_DDR_DQS0_DP")
	)
	(segment
		(start 49.603152 -137.504424)
		(end 49.602898 -137.504678)
		(width 0.10414)
		(layer "In7.Cu")
		(net "BMC_NODE1_DDR_DQS0_DP")
	)
	(segment
		(start 49.823878 -137.725658)
		(end 49.978056 -137.725658)
		(width 0.10414)
		(layer "In7.Cu")
		(net "BMC_NODE1_DDR_DQS0_DP")
	)
	(segment
		(start 50.366676 -138.114278)
		(end 50.489866 -138.114278)
		(width 0.10414)
		(layer "In7.Cu")
		(net "BMC_NODE1_DDR_DQS0_DP")
	)
	(segment
		(start 51.465226 -138.231118)
		(end 51.777646 -138.231118)
		(width 0.10414)
		(layer "In7.Cu")
		(net "BMC_NODE1_DDR_DQS0_DP")
	)
	(segment
		(start 52.454556 -137.737088)
		(end 52.454556 -137.349992)
		(width 0.10414)
		(layer "In7.Cu")
		(net "BMC_NODE1_DDR_DQS0_DP")
	)
	(segment
		(start 42.545 -136.693402)
		(end 42.956226 -136.693402)
		(width 0.10414)
		(layer "In7.Cu")
		(net "BMC_NODE1_DDR_DQS0_DP")
	)
	(segment
		(start 51.894486 -138.114278)
		(end 52.077366 -138.114278)
		(width 0.10414)
		(layer "In7.Cu")
		(net "BMC_NODE1_DDR_DQS0_DP")
	)
	(segment
		(start 51.777646 -138.231118)
		(end 51.894486 -138.114278)
		(width 0.10414)
		(layer "In7.Cu")
		(net "BMC_NODE1_DDR_DQS0_DP")
	)
	(segment
		(start 43.385486 -137.122662)
		(end 43.664886 -137.122662)
		(width 0.10414)
		(layer "In7.Cu")
		(net "BMC_NODE1_DDR_DQS0_DP")
	)
	(segment
		(start 42.424858 -136.813544)
		(end 42.545 -136.693402)
		(width 0.10414)
		(layer "In7.Cu")
		(net "BMC_NODE1_DDR_DQS0_DP")
	)
	(segment
		(start 51.348386 -138.114278)
		(end 51.465226 -138.231118)
		(width 0.10414)
		(layer "In7.Cu")
		(net "BMC_NODE1_DDR_DQS0_DP")
	)
	(segment
		(start 100.35032 -16.38554)
		(end 101.152706 -16.38554)
		(width 0.1016)
		(layer "F.Cu")
		(net "LPC_CPU_NODE1_CLKOUT0")
	)
	(segment
		(start 67.241166 -97.110042)
		(end 67.241166 -97.664016)
		(width 0.1016)
		(layer "F.Cu")
		(net "LPC_CPU_NODE1_CLKOUT0")
	)
	(segment
		(start 67.241166 -97.664016)
		(end 67.162934 -97.742248)
		(width 0.1016)
		(layer "F.Cu")
		(net "LPC_CPU_NODE1_CLKOUT0")
	)
	(segment
		(start 101.152706 -16.38554)
		(end 101.93274 -15.605506)
		(width 0.1016)
		(layer "F.Cu")
		(net "LPC_CPU_NODE1_CLKOUT0")
	)
	(via
		(at 67.162934 -97.742248)
		(size 0.508)
		(drill 0.254)
		(layers "F.Cu" "B.Cu")
		(net "LPC_CPU_NODE1_CLKOUT0")
	)
	(via
		(at 101.93274 -15.605506)
		(size 0.508)
		(drill 0.254)
		(layers "F.Cu" "B.Cu")
		(net "LPC_CPU_NODE1_CLKOUT0")
	)
	(via
		(at 97.07626 -98.571558)
		(size 0.508)
		(drill 0.254)
		(layers "F.Cu" "B.Cu")
		(net "LPC_CPU_NODE1_CLKOUT0")
	)
	(segment
		(start 119.147082 -56.10225)
		(end 119.147082 -67.42557)
		(width 0.1143)
		(layer "In2.Cu")
		(net "LPC_CPU_NODE1_CLKOUT0")
	)
	(segment
		(start 101.93274 -15.605506)
		(end 104.806242 -15.605506)
		(width 0.1143)
		(layer "In2.Cu")
		(net "LPC_CPU_NODE1_CLKOUT0")
	)
	(segment
		(start 97.07626 -98.445828)
		(end 97.07626 -98.571558)
		(width 0.1143)
		(layer "In2.Cu")
		(net "LPC_CPU_NODE1_CLKOUT0")
	)
	(segment
		(start 114.24539 -50.973482)
		(end 114.296952 -50.973482)
		(width 0.1143)
		(layer "In2.Cu")
		(net "LPC_CPU_NODE1_CLKOUT0")
	)
	(segment
		(start 114.296952 -50.973482)
		(end 115.33378 -52.01031)
		(width 0.1143)
		(layer "In2.Cu")
		(net "LPC_CPU_NODE1_CLKOUT0")
	)
	(segment
		(start 111.21136 -22.010624)
		(end 111.21136 -47.939452)
		(width 0.1143)
		(layer "In2.Cu")
		(net "LPC_CPU_NODE1_CLKOUT0")
	)
	(segment
		(start 104.806242 -15.605506)
		(end 111.21136 -22.010624)
		(width 0.1143)
		(layer "In2.Cu")
		(net "LPC_CPU_NODE1_CLKOUT0")
	)
	(segment
		(start 118.90248 -77.103986)
		(end 108.454698 -87.551768)
		(width 0.1143)
		(layer "In2.Cu")
		(net "LPC_CPU_NODE1_CLKOUT0")
	)
	(segment
		(start 119.147082 -67.42557)
		(end 118.90248 -67.670172)
		(width 0.1143)
		(layer "In2.Cu")
		(net "LPC_CPU_NODE1_CLKOUT0")
	)
	(segment
		(start 115.33378 -52.288948)
		(end 119.147082 -56.10225)
		(width 0.1143)
		(layer "In2.Cu")
		(net "LPC_CPU_NODE1_CLKOUT0")
	)
	(segment
		(start 108.454698 -87.551768)
		(end 104.860598 -87.551768)
		(width 0.1143)
		(layer "In2.Cu")
		(net "LPC_CPU_NODE1_CLKOUT0")
	)
	(segment
		(start 99.26574 -96.256348)
		(end 97.07626 -98.445828)
		(width 0.1143)
		(layer "In2.Cu")
		(net "LPC_CPU_NODE1_CLKOUT0")
	)
	(segment
		(start 118.90248 -67.670172)
		(end 118.90248 -77.103986)
		(width 0.1143)
		(layer "In2.Cu")
		(net "LPC_CPU_NODE1_CLKOUT0")
	)
	(segment
		(start 115.33378 -52.01031)
		(end 115.33378 -52.288948)
		(width 0.1143)
		(layer "In2.Cu")
		(net "LPC_CPU_NODE1_CLKOUT0")
	)
	(segment
		(start 104.860598 -87.551768)
		(end 99.26574 -93.146626)
		(width 0.1143)
		(layer "In2.Cu")
		(net "LPC_CPU_NODE1_CLKOUT0")
	)
	(segment
		(start 111.21136 -47.939452)
		(end 114.24539 -50.973482)
		(width 0.1143)
		(layer "In2.Cu")
		(net "LPC_CPU_NODE1_CLKOUT0")
	)
	(segment
		(start 99.26574 -93.146626)
		(end 99.26574 -96.256348)
		(width 0.1143)
		(layer "In2.Cu")
		(net "LPC_CPU_NODE1_CLKOUT0")
	)
	(segment
		(start 92.320364 -99.821492)
		(end 93.361256 -99.821492)
		(width 0.1143)
		(layer "In7.Cu")
		(net "LPC_CPU_NODE1_CLKOUT0")
	)
	(segment
		(start 92.00388 -99.505008)
		(end 92.320364 -99.821492)
		(width 0.1143)
		(layer "In7.Cu")
		(net "LPC_CPU_NODE1_CLKOUT0")
	)
	(segment
		(start 87.64016 -99.505008)
		(end 92.00388 -99.505008)
		(width 0.1143)
		(layer "In7.Cu")
		(net "LPC_CPU_NODE1_CLKOUT0")
	)
	(segment
		(start 85.05825 -96.923098)
		(end 87.64016 -99.505008)
		(width 0.1143)
		(layer "In7.Cu")
		(net "LPC_CPU_NODE1_CLKOUT0")
	)
	(segment
		(start 96.14281 -99.505008)
		(end 97.07626 -98.571558)
		(width 0.1143)
		(layer "In7.Cu")
		(net "LPC_CPU_NODE1_CLKOUT0")
	)
	(segment
		(start 93.361256 -99.821492)
		(end 93.67774 -99.505008)
		(width 0.1143)
		(layer "In7.Cu")
		(net "LPC_CPU_NODE1_CLKOUT0")
	)
	(segment
		(start 67.162934 -97.742248)
		(end 67.181476 -97.742248)
		(width 0.1143)
		(layer "In7.Cu")
		(net "LPC_CPU_NODE1_CLKOUT0")
	)
	(segment
		(start 93.67774 -99.505008)
		(end 96.14281 -99.505008)
		(width 0.1143)
		(layer "In7.Cu")
		(net "LPC_CPU_NODE1_CLKOUT0")
	)
	(segment
		(start 67.181476 -97.742248)
		(end 68.000626 -96.923098)
		(width 0.1143)
		(layer "In7.Cu")
		(net "LPC_CPU_NODE1_CLKOUT0")
	)
	(segment
		(start 68.000626 -96.923098)
		(end 85.05825 -96.923098)
		(width 0.1143)
		(layer "In7.Cu")
		(net "LPC_CPU_NODE1_CLKOUT0")
	)
	(segment
		(start 58.470546 -65.455038)
		(end 58.497978 -65.455038)
		(width 0.254)
		(layer "F.Cu")
		(net "M_DDR3_NODE1_CMDPU")
	)
	(segment
		(start 58.497978 -65.455038)
		(end 58.864246 -65.821306)
		(width 0.254)
		(layer "F.Cu")
		(net "M_DDR3_NODE1_CMDPU")
	)
	(via
		(at 58.864246 -65.821306)
		(size 0.508)
		(drill 0.254)
		(layers "F.Cu" "B.Cu")
		(net "M_DDR3_NODE1_CMDPU")
	)
	(via
		(at 58.500772 -63.35395)
		(size 0.6604)
		(drill 0.3302)
		(layers "F.Cu" "B.Cu")
		(net "M_DDR3_NODE1_CMDPU")
	)
	(segment
		(start 58.16854 -62.869826)
		(end 58.500772 -63.202058)
		(width 0.254)
		(layer "B.Cu")
		(net "M_DDR3_NODE1_CMDPU")
	)
	(segment
		(start 58.65876 -65.61582)
		(end 58.864246 -65.821306)
		(width 0.254)
		(layer "B.Cu")
		(net "M_DDR3_NODE1_CMDPU")
	)
	(segment
		(start 58.65876 -64.594486)
		(end 58.65876 -65.61582)
		(width 0.254)
		(layer "B.Cu")
		(net "M_DDR3_NODE1_CMDPU")
	)
	(segment
		(start 58.500772 -64.436498)
		(end 58.65876 -64.594486)
		(width 0.254)
		(layer "B.Cu")
		(net "M_DDR3_NODE1_CMDPU")
	)
	(segment
		(start 58.500772 -63.35395)
		(end 58.500772 -64.436498)
		(width 0.254)
		(layer "B.Cu")
		(net "M_DDR3_NODE1_CMDPU")
	)
	(segment
		(start 58.500772 -63.202058)
		(end 58.500772 -63.35395)
		(width 0.254)
		(layer "B.Cu")
		(net "M_DDR3_NODE1_CMDPU")
	)
	(segment
		(start 57.26303 -62.869826)
		(end 58.16854 -62.869826)
		(width 0.254)
		(layer "B.Cu")
		(net "M_DDR3_NODE1_CMDPU")
	)
	(segment
		(start 115.021868 -137.127488)
		(end 115.321588 -137.427208)
		(width 0.381)
		(layer "F.Cu")
		(net "AGND_PVCCP_NODE1")
	)
	(segment
		(start 109.996478 -135.897874)
		(end 110.6424 -135.897874)
		(width 0.1778)
		(layer "F.Cu")
		(net "AGND_PVCCP_NODE1")
	)
	(segment
		(start 113.67262 -135.685784)
		(end 113.875566 -135.88873)
		(width 0.381)
		(layer "F.Cu")
		(net "AGND_PVCCP_NODE1")
	)
	(segment
		(start 113.215166 -135.685784)
		(end 113.67262 -135.685784)
		(width 0.381)
		(layer "F.Cu")
		(net "AGND_PVCCP_NODE1")
	)
	(segment
		(start 109.817154 -140.870432)
		(end 110.283498 -141.336776)
		(width 0.381)
		(layer "F.Cu")
		(net "AGND_PVCCP_NODE1")
	)
	(segment
		(start 113.87836 -133.735572)
		(end 113.87836 -133.209538)
		(width 0.381)
		(layer "F.Cu")
		(net "AGND_PVCCP_NODE1")
	)
	(segment
		(start 111.696246 -129.447798)
		(end 111.696246 -128.656842)
		(width 0.4572)
		(layer "F.Cu")
		(net "AGND_PVCCP_NODE1")
	)
	(segment
		(start 111.23549 -136.490964)
		(end 111.23549 -136.66597)
		(width 0.1778)
		(layer "F.Cu")
		(net "AGND_PVCCP_NODE1")
	)
	(segment
		(start 107.65663 -141.355826)
		(end 107.660694 -141.35989)
		(width 0.381)
		(layer "F.Cu")
		(net "AGND_PVCCP_NODE1")
	)
	(segment
		(start 108.721906 -140.741146)
		(end 108.721906 -141.360906)
		(width 0.381)
		(layer "F.Cu")
		(net "AGND_PVCCP_NODE1")
	)
	(segment
		(start 111.435388 -136.865868)
		(end 111.23549 -136.66597)
		(width 0.1778)
		(layer "F.Cu")
		(net "AGND_PVCCP_NODE1")
	)
	(segment
		(start 113.87836 -133.209538)
		(end 113.736374 -133.067552)
		(width 0.381)
		(layer "F.Cu")
		(net "AGND_PVCCP_NODE1")
	)
	(segment
		(start 109.817154 -140.737082)
		(end 109.817154 -140.870432)
		(width 0.381)
		(layer "F.Cu")
		(net "AGND_PVCCP_NODE1")
	)
	(segment
		(start 111.61776 -140.547598)
		(end 112.32896 -140.547598)
		(width 0.4572)
		(layer "F.Cu")
		(net "AGND_PVCCP_NODE1")
	)
	(segment
		(start 107.65663 -140.747242)
		(end 107.65663 -141.355826)
		(width 0.381)
		(layer "F.Cu")
		(net "AGND_PVCCP_NODE1")
	)
	(segment
		(start 115.021868 -136.67359)
		(end 115.021868 -137.127488)
		(width 0.381)
		(layer "F.Cu")
		(net "AGND_PVCCP_NODE1")
	)
	(segment
		(start 110.6424 -135.897874)
		(end 111.23549 -136.490964)
		(width 0.1778)
		(layer "F.Cu")
		(net "AGND_PVCCP_NODE1")
	)
	(via
		(at 107.660694 -141.35989)
		(size 0.508)
		(drill 0.254)
		(layers "F.Cu" "B.Cu")
		(net "AGND_PVCCP_NODE1")
	)
	(via
		(at 104.988868 -141.279626)
		(size 0.508)
		(drill 0.254)
		(layers "F.Cu" "B.Cu")
		(net "AGND_PVCCP_NODE1")
	)
	(via
		(at 108.721906 -141.360906)
		(size 0.508)
		(drill 0.254)
		(layers "F.Cu" "B.Cu")
		(net "AGND_PVCCP_NODE1")
	)
	(via
		(at 113.736374 -133.067552)
		(size 0.508)
		(drill 0.254)
		(layers "F.Cu" "B.Cu")
		(net "AGND_PVCCP_NODE1")
	)
	(via
		(at 112.32896 -140.547598)
		(size 0.508)
		(drill 0.254)
		(layers "F.Cu" "B.Cu")
		(net "AGND_PVCCP_NODE1")
	)
	(via
		(at 111.435388 -136.865868)
		(size 0.508)
		(drill 0.254)
		(layers "F.Cu" "B.Cu")
		(net "AGND_PVCCP_NODE1")
	)
	(via
		(at 111.696246 -128.656842)
		(size 0.508)
		(drill 0.254)
		(layers "F.Cu" "B.Cu")
		(net "AGND_PVCCP_NODE1")
	)
	(via
		(at 113.875566 -135.88873)
		(size 0.508)
		(drill 0.254)
		(layers "F.Cu" "B.Cu")
		(net "AGND_PVCCP_NODE1")
	)
	(via
		(at 110.283498 -141.336776)
		(size 0.508)
		(drill 0.254)
		(layers "F.Cu" "B.Cu")
		(net "AGND_PVCCP_NODE1")
	)
	(via
		(at 115.321588 -137.427208)
		(size 0.508)
		(drill 0.254)
		(layers "F.Cu" "B.Cu")
		(net "AGND_PVCCP_NODE1")
	)
	(via
		(at 112.030002 -137.303002)
		(size 0.508)
		(drill 0.254)
		(layers "F.Cu" "B.Cu")
		(net "AGND_PVCCP_NODE1")
	)
	(via
		(at 103.818944 -140.088366)
		(size 0.508)
		(drill 0.254)
		(layers "F.Cu" "B.Cu")
		(net "AGND_PVCCP_NODE1")
	)
	(segment
		(start 41.817544 -161.119566)
		(end 41.28262 -161.65449)
		(width 0.1016)
		(layer "F.Cu")
		(net "N21311592")
	)
	(segment
		(start 41.817544 -159.472884)
		(end 41.817544 -161.119566)
		(width 0.1016)
		(layer "F.Cu")
		(net "N21311592")
	)
	(via
		(at 41.28262 -161.65449)
		(size 0.508)
		(drill 0.254)
		(layers "F.Cu" "B.Cu")
		(net "N21311592")
	)
	(segment
		(start 40.685974 -162.317176)
		(end 40.685974 -162.251136)
		(width 0.1016)
		(layer "B.Cu")
		(net "N21311592")
	)
	(segment
		(start 40.685974 -162.251136)
		(end 41.28262 -161.65449)
		(width 0.1016)
		(layer "B.Cu")
		(net "N21311592")
	)
	(segment
		(start 51.79568 -130.998468)
		(end 52.144676 -130.649472)
		(width 0.1016)
		(layer "F.Cu")
		(net "BMC_NODE1_DDR_MA11")
	)
	(segment
		(start 52.364386 -129.820162)
		(end 52.364386 -130.429762)
		(width 0.1016)
		(layer "F.Cu")
		(net "BMC_NODE1_DDR_MA11")
	)
	(segment
		(start 49.4919 -129.439416)
		(end 49.6316 -129.439416)
		(width 0.1016)
		(layer "F.Cu")
		(net "BMC_NODE1_DDR_MA11")
	)
	(segment
		(start 51.310286 -130.589274)
		(end 51.310286 -130.870452)
		(width 0.1016)
		(layer "F.Cu")
		(net "BMC_NODE1_DDR_MA11")
	)
	(segment
		(start 45.222668 -127.869188)
		(end 45.501814 -127.590042)
		(width 0.1016)
		(layer "F.Cu")
		(net "BMC_NODE1_DDR_MA11")
	)
	(segment
		(start 49.6316 -129.439416)
		(end 49.923446 -129.731262)
		(width 0.1016)
		(layer "F.Cu")
		(net "BMC_NODE1_DDR_MA11")
	)
	(segment
		(start 52.776628 -129.847086)
		(end 52.650644 -129.721102)
		(width 0.1016)
		(layer "F.Cu")
		(net "BMC_NODE1_DDR_MA11")
	)
	(segment
		(start 51.438302 -130.998468)
		(end 51.79568 -130.998468)
		(width 0.1016)
		(layer "F.Cu")
		(net "BMC_NODE1_DDR_MA11")
	)
	(segment
		(start 48.073564 -127.590042)
		(end 49.37379 -128.890268)
		(width 0.1016)
		(layer "F.Cu")
		(net "BMC_NODE1_DDR_MA11")
	)
	(segment
		(start 53.047646 -129.721102)
		(end 52.921662 -129.847086)
		(width 0.1016)
		(layer "F.Cu")
		(net "BMC_NODE1_DDR_MA11")
	)
	(segment
		(start 51.754786 -130.144774)
		(end 51.310286 -130.589274)
		(width 0.1016)
		(layer "F.Cu")
		(net "BMC_NODE1_DDR_MA11")
	)
	(segment
		(start 58.14187 -131.25958)
		(end 57.717436 -130.835146)
		(width 0.1016)
		(layer "F.Cu")
		(net "BMC_NODE1_DDR_MA11")
	)
	(segment
		(start 49.923446 -129.731262)
		(end 50.776632 -129.731262)
		(width 0.1016)
		(layer "F.Cu")
		(net "BMC_NODE1_DDR_MA11")
	)
	(segment
		(start 51.099974 -129.896362)
		(end 51.265074 -129.731262)
		(width 0.1016)
		(layer "F.Cu")
		(net "BMC_NODE1_DDR_MA11")
	)
	(segment
		(start 50.776632 -129.731262)
		(end 50.941732 -129.896362)
		(width 0.1016)
		(layer "F.Cu")
		(net "BMC_NODE1_DDR_MA11")
	)
	(segment
		(start 52.463446 -129.721102)
		(end 52.364386 -129.820162)
		(width 0.1016)
		(layer "F.Cu")
		(net "BMC_NODE1_DDR_MA11")
	)
	(segment
		(start 55.872126 -129.721102)
		(end 53.047646 -129.721102)
		(width 0.1016)
		(layer "F.Cu")
		(net "BMC_NODE1_DDR_MA11")
	)
	(segment
		(start 52.921662 -129.847086)
		(end 52.776628 -129.847086)
		(width 0.1016)
		(layer "F.Cu")
		(net "BMC_NODE1_DDR_MA11")
	)
	(segment
		(start 45.273214 -129.640584)
		(end 45.273214 -129.112518)
		(width 0.1016)
		(layer "F.Cu")
		(net "BMC_NODE1_DDR_MA11")
	)
	(segment
		(start 44.833032 -129.763774)
		(end 45.150024 -129.763774)
		(width 0.1016)
		(layer "F.Cu")
		(net "BMC_NODE1_DDR_MA11")
	)
	(segment
		(start 57.717436 -130.835146)
		(end 56.98617 -130.835146)
		(width 0.1016)
		(layer "F.Cu")
		(net "BMC_NODE1_DDR_MA11")
	)
	(segment
		(start 51.310286 -130.870452)
		(end 51.438302 -130.998468)
		(width 0.1016)
		(layer "F.Cu")
		(net "BMC_NODE1_DDR_MA11")
	)
	(segment
		(start 56.98617 -130.835146)
		(end 55.872126 -129.721102)
		(width 0.1016)
		(layer "F.Cu")
		(net "BMC_NODE1_DDR_MA11")
	)
	(segment
		(start 52.650644 -129.721102)
		(end 52.463446 -129.721102)
		(width 0.1016)
		(layer "F.Cu")
		(net "BMC_NODE1_DDR_MA11")
	)
	(segment
		(start 52.364386 -130.429762)
		(end 52.144676 -130.649472)
		(width 0.1016)
		(layer "F.Cu")
		(net "BMC_NODE1_DDR_MA11")
	)
	(segment
		(start 51.615086 -129.731262)
		(end 51.754786 -129.870962)
		(width 0.1016)
		(layer "F.Cu")
		(net "BMC_NODE1_DDR_MA11")
	)
	(segment
		(start 49.37379 -128.890268)
		(end 49.37379 -129.321306)
		(width 0.1016)
		(layer "F.Cu")
		(net "BMC_NODE1_DDR_MA11")
	)
	(segment
		(start 51.265074 -129.731262)
		(end 51.615086 -129.731262)
		(width 0.1016)
		(layer "F.Cu")
		(net "BMC_NODE1_DDR_MA11")
	)
	(segment
		(start 45.273214 -129.112518)
		(end 45.222668 -129.061972)
		(width 0.1016)
		(layer "F.Cu")
		(net "BMC_NODE1_DDR_MA11")
	)
	(segment
		(start 45.501814 -127.590042)
		(end 48.073564 -127.590042)
		(width 0.1016)
		(layer "F.Cu")
		(net "BMC_NODE1_DDR_MA11")
	)
	(segment
		(start 50.941732 -129.896362)
		(end 51.099974 -129.896362)
		(width 0.1016)
		(layer "F.Cu")
		(net "BMC_NODE1_DDR_MA11")
	)
	(segment
		(start 49.37379 -129.321306)
		(end 49.4919 -129.439416)
		(width 0.1016)
		(layer "F.Cu")
		(net "BMC_NODE1_DDR_MA11")
	)
	(segment
		(start 45.222668 -129.061972)
		(end 45.222668 -127.869188)
		(width 0.1016)
		(layer "F.Cu")
		(net "BMC_NODE1_DDR_MA11")
	)
	(segment
		(start 51.754786 -129.870962)
		(end 51.754786 -130.144774)
		(width 0.1016)
		(layer "F.Cu")
		(net "BMC_NODE1_DDR_MA11")
	)
	(segment
		(start 45.150024 -129.763774)
		(end 45.273214 -129.640584)
		(width 0.1016)
		(layer "F.Cu")
		(net "BMC_NODE1_DDR_MA11")
	)
	(via
		(at 52.144676 -130.649472)
		(size 0.762)
		(drill 0.381)
		(layers "F.Cu" "B.Cu")
		(net "BMC_NODE1_DDR_MA11")
	)
	(segment
		(start 94.00794 -96.189292)
		(end 94.00794 -97.978722)
		(width 0.1016)
		(layer "F.Cu")
		(net "SPI_CPU_NODE1_MISO_R")
	)
	(segment
		(start 93.660722 -95.842074)
		(end 94.00794 -96.189292)
		(width 0.1016)
		(layer "F.Cu")
		(net "SPI_CPU_NODE1_MISO_R")
	)
	(segment
		(start 90.637614 -99.383342)
		(end 89.428066 -98.173794)
		(width 0.1016)
		(layer "F.Cu")
		(net "SPI_CPU_NODE1_MISO_R")
	)
	(segment
		(start 93.660722 -94.109032)
		(end 93.660722 -95.842074)
		(width 0.1016)
		(layer "F.Cu")
		(net "SPI_CPU_NODE1_MISO_R")
	)
	(segment
		(start 94.00794 -97.978722)
		(end 92.60332 -99.383342)
		(width 0.1016)
		(layer "F.Cu")
		(net "SPI_CPU_NODE1_MISO_R")
	)
	(segment
		(start 92.60332 -99.383342)
		(end 90.637614 -99.383342)
		(width 0.1016)
		(layer "F.Cu")
		(net "SPI_CPU_NODE1_MISO_R")
	)
	(segment
		(start 89.428066 -98.173794)
		(end 89.428066 -97.099628)
		(width 0.1016)
		(layer "F.Cu")
		(net "SPI_CPU_NODE1_MISO_R")
	)
	(via
		(at 92.60332 -99.383342)
		(size 0.508)
		(drill 0.254)
		(layers "F.Cu" "B.Cu")
		(net "SPI_CPU_NODE1_MISO_R")
	)
	(segment
		(start 49.667668 -68.503038)
		(end 49.32807 -68.842636)
		(width 0.1016)
		(layer "F.Cu")
		(net "TP_CPU_NODE1_RP0_PETN1")
	)
	(segment
		(start 49.825402 -68.503038)
		(end 49.667668 -68.503038)
		(width 0.1016)
		(layer "F.Cu")
		(net "TP_CPU_NODE1_RP0_PETN1")
	)
	(via
		(at 49.32807 -68.842636)
		(size 0.508)
		(drill 0.254)
		(layers "F.Cu" "B.Cu")
		(net "TP_CPU_NODE1_RP0_PETN1")
	)
	(via
		(at 49.08423 -71.19239)
		(size 0.6604)
		(drill 0.3302)
		(layers "F.Cu" "B.Cu")
		(net "TP_CPU_NODE1_RP0_PETN1")
	)
	(segment
		(start 49.32807 -70.94855)
		(end 49.08423 -71.19239)
		(width 0.1016)
		(layer "B.Cu")
		(net "TP_CPU_NODE1_RP0_PETN1")
	)
	(segment
		(start 49.32807 -68.842636)
		(end 49.32807 -70.94855)
		(width 0.1016)
		(layer "B.Cu")
		(net "TP_CPU_NODE1_RP0_PETN1")
	)
	(segment
		(start 60.456826 -65.836038)
		(end 60.484258 -65.836038)
		(width 0.127)
		(layer "F.Cu")
		(net "M_DDR3_NODE1_MON1N")
	)
	(segment
		(start 60.484258 -65.836038)
		(end 60.850526 -66.202306)
		(width 0.127)
		(layer "F.Cu")
		(net "M_DDR3_NODE1_MON1N")
	)
	(via
		(at 58.85434 -61.021468)
		(size 0.508)
		(drill 0.254)
		(layers "F.Cu" "B.Cu")
		(net "M_DDR3_NODE1_MON1N")
	)
	(via
		(at 60.850526 -66.202306)
		(size 0.508)
		(drill 0.254)
		(layers "F.Cu" "B.Cu")
		(net "M_DDR3_NODE1_MON1N")
	)
	(segment
		(start 58.21934 -61.145928)
		(end 58.38952 -61.316108)
		(width 0.17018)
		(layer "B.Cu")
		(net "M_DDR3_NODE1_MON1N")
	)
	(segment
		(start 58.5597 -61.316108)
		(end 58.85434 -61.021468)
		(width 0.17018)
		(layer "B.Cu")
		(net "M_DDR3_NODE1_MON1N")
	)
	(segment
		(start 58.156348 -55.845964)
		(end 58.419238 -56.108854)
		(width 0.17018)
		(layer "B.Cu")
		(net "M_DDR3_NODE1_MON1N")
	)
	(segment
		(start 58.21934 -56.308752)
		(end 58.21934 -61.145928)
		(width 0.17018)
		(layer "B.Cu")
		(net "M_DDR3_NODE1_MON1N")
	)
	(segment
		(start 58.38952 -61.316108)
		(end 58.5597 -61.316108)
		(width 0.17018)
		(layer "B.Cu")
		(net "M_DDR3_NODE1_MON1N")
	)
	(segment
		(start 58.156348 -55.355744)
		(end 58.156348 -55.845964)
		(width 0.17018)
		(layer "B.Cu")
		(net "M_DDR3_NODE1_MON1N")
	)
	(segment
		(start 58.419238 -56.108854)
		(end 58.21934 -56.308752)
		(width 0.17018)
		(layer "B.Cu")
		(net "M_DDR3_NODE1_MON1N")
	)
	(segment
		(start 58.419238 -55.092854)
		(end 58.156348 -55.355744)
		(width 0.17018)
		(layer "B.Cu")
		(net "M_DDR3_NODE1_MON1N")
	)
	(segment
		(start 59.540902 -62.552834)
		(end 59.540902 -61.70803)
		(width 0.17018)
		(layer "In7.Cu")
		(net "M_DDR3_NODE1_MON1N")
	)
	(segment
		(start 59.439302 -62.654434)
		(end 59.540902 -62.552834)
		(width 0.17018)
		(layer "In7.Cu")
		(net "M_DDR3_NODE1_MON1N")
	)
	(segment
		(start 58.597292 -63.493904)
		(end 59.438032 -62.653164)
		(width 0.17018)
		(layer "In7.Cu")
		(net "M_DDR3_NODE1_MON1N")
	)
	(segment
		(start 59.540902 -61.70803)
		(end 58.85434 -61.021468)
		(width 0.17018)
		(layer "In7.Cu")
		(net "M_DDR3_NODE1_MON1N")
	)
	(segment
		(start 60.49391 -66.202306)
		(end 60.377578 -66.085974)
		(width 0.17018)
		(layer "In7.Cu")
		(net "M_DDR3_NODE1_MON1N")
	)
	(segment
		(start 60.377578 -66.085974)
		(end 60.377578 -65.164462)
		(width 0.17018)
		(layer "In7.Cu")
		(net "M_DDR3_NODE1_MON1N")
	)
	(segment
		(start 58.804302 -64.650874)
		(end 58.597292 -64.443864)
		(width 0.17018)
		(layer "In7.Cu")
		(net "M_DDR3_NODE1_MON1N")
	)
	(segment
		(start 58.597292 -64.443864)
		(end 58.597292 -63.493904)
		(width 0.17018)
		(layer "In7.Cu")
		(net "M_DDR3_NODE1_MON1N")
	)
	(segment
		(start 60.850526 -66.202306)
		(end 60.49391 -66.202306)
		(width 0.17018)
		(layer "In7.Cu")
		(net "M_DDR3_NODE1_MON1N")
	)
	(segment
		(start 59.86399 -64.650874)
		(end 58.804302 -64.650874)
		(width 0.17018)
		(layer "In7.Cu")
		(net "M_DDR3_NODE1_MON1N")
	)
	(segment
		(start 60.377578 -65.164462)
		(end 59.86399 -64.650874)
		(width 0.17018)
		(layer "In7.Cu")
		(net "M_DDR3_NODE1_MON1N")
	)
	(segment
		(start 59.438032 -62.653164)
		(end 59.439302 -62.654434)
		(width 0.17018)
		(layer "In7.Cu")
		(net "M_DDR3_NODE1_MON1N")
	)
	(segment
		(start 58.941716 -136.859518)
		(end 58.93943 -136.859518)
		(width 0.1016)
		(layer "F.Cu")
		(net "BMC_NODE1_DDR_D11")
	)
	(segment
		(start 58.93943 -136.859518)
		(end 58.540904 -137.258044)
		(width 0.1016)
		(layer "F.Cu")
		(net "BMC_NODE1_DDR_D11")
	)
	(segment
		(start 41.63314 -139.363704)
		(end 42.44467 -140.432028)
		(width 0.1016)
		(layer "F.Cu")
		(net "BMC_NODE1_DDR_D11")
	)
	(via
		(at 58.540904 -137.258044)
		(size 0.49022)
		(drill 0.254)
		(layers "F.Cu" "B.Cu")
		(net "BMC_NODE1_DDR_D11")
	)
	(via
		(at 42.44467 -140.432028)
		(size 0.508)
		(drill 0.254)
		(layers "F.Cu" "B.Cu")
		(net "BMC_NODE1_DDR_D11")
	)
	(segment
		(start 54.730396 -140.274294)
		(end 52.83073 -141.778228)
		(width 0.1143)
		(layer "In2.Cu")
		(net "BMC_NODE1_DDR_D11")
	)
	(segment
		(start 52.83073 -141.778482)
		(end 50.538888 -143.08201)
		(width 0.1143)
		(layer "In2.Cu")
		(net "BMC_NODE1_DDR_D11")
	)
	(segment
		(start 44.667932 -141.930628)
		(end 43.902376 -141.38148)
		(width 0.1143)
		(layer "In2.Cu")
		(net "BMC_NODE1_DDR_D11")
	)
	(segment
		(start 50.538888 -143.08201)
		(end 47.22114 -143.08201)
		(width 0.1143)
		(layer "In2.Cu")
		(net "BMC_NODE1_DDR_D11")
	)
	(segment
		(start 56.230266 -139.087098)
		(end 54.730396 -140.274294)
		(width 0.1143)
		(layer "In2.Cu")
		(net "BMC_NODE1_DDR_D11")
	)
	(segment
		(start 52.83073 -141.778228)
		(end 52.83073 -141.778482)
		(width 0.1143)
		(layer "In2.Cu")
		(net "BMC_NODE1_DDR_D11")
	)
	(segment
		(start 43.659806 -141.207236)
		(end 42.44467 -140.432028)
		(width 0.1143)
		(layer "In2.Cu")
		(net "BMC_NODE1_DDR_D11")
	)
	(segment
		(start 58.540904 -137.258044)
		(end 56.230266 -139.087098)
		(width 0.1143)
		(layer "In2.Cu")
		(net "BMC_NODE1_DDR_D11")
	)
	(segment
		(start 47.22114 -143.08201)
		(end 44.667932 -141.930628)
		(width 0.1143)
		(layer "In2.Cu")
		(net "BMC_NODE1_DDR_D11")
	)
	(segment
		(start 43.902376 -141.38148)
		(end 43.659806 -141.207236)
		(width 0.1143)
		(layer "In2.Cu")
		(net "BMC_NODE1_DDR_D11")
	)
	(segment
		(start 100.496624 -131.939538)
		(end 100.21697 -132.219192)
		(width 0.1016)
		(layer "F.Cu")
		(net "SVID_CPU_NODE1_PVCCP_DAT")
	)
	(segment
		(start 101.616256 -134.11581)
		(end 102.439216 -134.93877)
		(width 0.1016)
		(layer "F.Cu")
		(net "SVID_CPU_NODE1_PVCCP_DAT")
	)
	(segment
		(start 102.439216 -134.93877)
		(end 102.439216 -135.132064)
		(width 0.1016)
		(layer "F.Cu")
		(net "SVID_CPU_NODE1_PVCCP_DAT")
	)
	(segment
		(start 100.21697 -132.219192)
		(end 100.21697 -133.586728)
		(width 0.1016)
		(layer "F.Cu")
		(net "SVID_CPU_NODE1_PVCCP_DAT")
	)
	(segment
		(start 100.70338 -134.073138)
		(end 100.746052 -134.11581)
		(width 0.1016)
		(layer "F.Cu")
		(net "SVID_CPU_NODE1_PVCCP_DAT")
	)
	(segment
		(start 100.21697 -133.586728)
		(end 100.70338 -134.073138)
		(width 0.1016)
		(layer "F.Cu")
		(net "SVID_CPU_NODE1_PVCCP_DAT")
	)
	(segment
		(start 100.746052 -134.11581)
		(end 101.616256 -134.11581)
		(width 0.1016)
		(layer "F.Cu")
		(net "SVID_CPU_NODE1_PVCCP_DAT")
	)
	(via
		(at 100.70338 -134.073138)
		(size 0.508)
		(drill 0.254)
		(layers "F.Cu" "B.Cu")
		(net "SVID_CPU_NODE1_PVCCP_DAT")
	)
	(segment
		(start 75.74026 -79.092552)
		(end 76.549758 -78.283054)
		(width 0.1016)
		(layer "B.Cu")
		(net "SVID_CPU_NODE1_PVCCP_DAT")
	)
	(segment
		(start 98.16592 -93.474794)
		(end 98.16592 -100.734622)
		(width 0.1016)
		(layer "B.Cu")
		(net "SVID_CPU_NODE1_PVCCP_DAT")
	)
	(segment
		(start 101.36378 -133.412738)
		(end 100.70338 -134.073138)
		(width 0.1016)
		(layer "B.Cu")
		(net "SVID_CPU_NODE1_PVCCP_DAT")
	)
	(segment
		(start 98.48088 -104.025446)
		(end 99.39274 -104.937306)
		(width 0.1016)
		(layer "B.Cu")
		(net "SVID_CPU_NODE1_PVCCP_DAT")
	)
	(segment
		(start 82.467196 -78.491842)
		(end 83.18881 -79.213456)
		(width 0.1016)
		(layer "B.Cu")
		(net "SVID_CPU_NODE1_PVCCP_DAT")
	)
	(segment
		(start 98.48088 -101.049582)
		(end 98.48088 -104.025446)
		(width 0.1016)
		(layer "B.Cu")
		(net "SVID_CPU_NODE1_PVCCP_DAT")
	)
	(segment
		(start 91.694254 -82.012536)
		(end 95.23476 -85.553042)
		(width 0.1016)
		(layer "B.Cu")
		(net "SVID_CPU_NODE1_PVCCP_DAT")
	)
	(segment
		(start 100.70338 -129.798572)
		(end 101.36378 -130.458972)
		(width 0.1016)
		(layer "B.Cu")
		(net "SVID_CPU_NODE1_PVCCP_DAT")
	)
	(segment
		(start 99.39274 -104.937306)
		(end 99.39274 -117.890798)
		(width 0.1016)
		(layer "B.Cu")
		(net "SVID_CPU_NODE1_PVCCP_DAT")
	)
	(segment
		(start 74.191368 -77.94625)
		(end 74.191368 -78.577948)
		(width 0.1016)
		(layer "B.Cu")
		(net "SVID_CPU_NODE1_PVCCP_DAT")
	)
	(segment
		(start 78.383638 -78.491842)
		(end 82.467196 -78.491842)
		(width 0.1016)
		(layer "B.Cu")
		(net "SVID_CPU_NODE1_PVCCP_DAT")
	)
	(segment
		(start 95.23476 -85.553042)
		(end 95.23476 -90.543634)
		(width 0.1016)
		(layer "B.Cu")
		(net "SVID_CPU_NODE1_PVCCP_DAT")
	)
	(segment
		(start 78.17485 -78.283054)
		(end 78.383638 -78.491842)
		(width 0.1016)
		(layer "B.Cu")
		(net "SVID_CPU_NODE1_PVCCP_DAT")
	)
	(segment
		(start 74.191368 -78.577948)
		(end 74.705972 -79.092552)
		(width 0.1016)
		(layer "B.Cu")
		(net "SVID_CPU_NODE1_PVCCP_DAT")
	)
	(segment
		(start 76.549758 -78.283054)
		(end 78.17485 -78.283054)
		(width 0.1016)
		(layer "B.Cu")
		(net "SVID_CPU_NODE1_PVCCP_DAT")
	)
	(segment
		(start 88.539574 -82.012536)
		(end 91.694254 -82.012536)
		(width 0.1016)
		(layer "B.Cu")
		(net "SVID_CPU_NODE1_PVCCP_DAT")
	)
	(segment
		(start 95.23476 -90.543634)
		(end 98.16592 -93.474794)
		(width 0.1016)
		(layer "B.Cu")
		(net "SVID_CPU_NODE1_PVCCP_DAT")
	)
	(segment
		(start 83.18881 -80.397096)
		(end 83.941158 -81.149444)
		(width 0.1016)
		(layer "B.Cu")
		(net "SVID_CPU_NODE1_PVCCP_DAT")
	)
	(segment
		(start 101.36378 -130.458972)
		(end 101.36378 -133.412738)
		(width 0.1016)
		(layer "B.Cu")
		(net "SVID_CPU_NODE1_PVCCP_DAT")
	)
	(segment
		(start 74.705972 -79.092552)
		(end 75.74026 -79.092552)
		(width 0.1016)
		(layer "B.Cu")
		(net "SVID_CPU_NODE1_PVCCP_DAT")
	)
	(segment
		(start 87.676482 -81.149444)
		(end 88.539574 -82.012536)
		(width 0.1016)
		(layer "B.Cu")
		(net "SVID_CPU_NODE1_PVCCP_DAT")
	)
	(segment
		(start 98.16592 -100.734622)
		(end 98.48088 -101.049582)
		(width 0.1016)
		(layer "B.Cu")
		(net "SVID_CPU_NODE1_PVCCP_DAT")
	)
	(segment
		(start 99.39274 -117.890798)
		(end 100.70338 -119.201438)
		(width 0.1016)
		(layer "B.Cu")
		(net "SVID_CPU_NODE1_PVCCP_DAT")
	)
	(segment
		(start 83.941158 -81.149444)
		(end 87.676482 -81.149444)
		(width 0.1016)
		(layer "B.Cu")
		(net "SVID_CPU_NODE1_PVCCP_DAT")
	)
	(segment
		(start 100.70338 -119.201438)
		(end 100.70338 -129.798572)
		(width 0.1016)
		(layer "B.Cu")
		(net "SVID_CPU_NODE1_PVCCP_DAT")
	)
	(segment
		(start 83.18881 -79.213456)
		(end 83.18881 -80.397096)
		(width 0.1016)
		(layer "B.Cu")
		(net "SVID_CPU_NODE1_PVCCP_DAT")
	)
	(segment
		(start 165.11143 -117.851174)
		(end 164.523928 -117.263672)
		(width 0.1016)
		(layer "F.Cu")
		(net "RST_CPU_NODE1_SRTCRST_L")
	)
	(segment
		(start 158.012638 -116.760752)
		(end 162.640772 -116.760752)
		(width 0.1016)
		(layer "F.Cu")
		(net "RST_CPU_NODE1_SRTCRST_L")
	)
	(segment
		(start 72.205088 -82.997294)
		(end 72.56526 -82.637122)
		(width 0.1016)
		(layer "F.Cu")
		(net "RST_CPU_NODE1_SRTCRST_L")
	)
	(segment
		(start 163.7919 -117.319552)
		(end 163.096956 -117.319552)
		(width 0.1016)
		(layer "F.Cu")
		(net "RST_CPU_NODE1_SRTCRST_L")
	)
	(segment
		(start 163.096956 -117.319552)
		(end 163.096956 -116.304568)
		(width 0.1016)
		(layer "F.Cu")
		(net "RST_CPU_NODE1_SRTCRST_L")
	)
	(segment
		(start 155.965652 -118.807738)
		(end 158.012638 -116.760752)
		(width 0.1016)
		(layer "F.Cu")
		(net "RST_CPU_NODE1_SRTCRST_L")
	)
	(segment
		(start 163.096956 -116.303552)
		(end 163.096956 -116.304568)
		(width 0.1016)
		(layer "F.Cu")
		(net "RST_CPU_NODE1_SRTCRST_L")
	)
	(segment
		(start 152.70734 -118.12397)
		(end 153.391108 -118.807738)
		(width 0.1016)
		(layer "F.Cu")
		(net "RST_CPU_NODE1_SRTCRST_L")
	)
	(segment
		(start 168.990772 -119.942864)
		(end 168.885108 -120.048528)
		(width 0.1016)
		(layer "F.Cu")
		(net "RST_CPU_NODE1_SRTCRST_L")
	)
	(segment
		(start 172.519848 -119.942864)
		(end 168.990772 -119.942864)
		(width 0.1016)
		(layer "F.Cu")
		(net "RST_CPU_NODE1_SRTCRST_L")
	)
	(segment
		(start 166.251128 -120.048528)
		(end 165.686486 -119.483886)
		(width 0.1016)
		(layer "F.Cu")
		(net "RST_CPU_NODE1_SRTCRST_L")
	)
	(segment
		(start 168.885108 -120.048528)
		(end 166.251128 -120.048528)
		(width 0.1016)
		(layer "F.Cu")
		(net "RST_CPU_NODE1_SRTCRST_L")
	)
	(segment
		(start 162.640772 -116.760752)
		(end 163.096956 -116.304568)
		(width 0.1016)
		(layer "F.Cu")
		(net "RST_CPU_NODE1_SRTCRST_L")
	)
	(segment
		(start 150.1394 -114.332512)
		(end 152.70734 -116.900452)
		(width 0.1016)
		(layer "F.Cu")
		(net "RST_CPU_NODE1_SRTCRST_L")
	)
	(segment
		(start 153.391108 -118.807738)
		(end 155.965652 -118.807738)
		(width 0.1016)
		(layer "F.Cu")
		(net "RST_CPU_NODE1_SRTCRST_L")
	)
	(segment
		(start 72.56526 -82.637122)
		(end 73.270364 -82.637122)
		(width 0.1016)
		(layer "F.Cu")
		(net "RST_CPU_NODE1_SRTCRST_L")
	)
	(segment
		(start 152.70734 -116.900452)
		(end 152.70734 -118.12397)
		(width 0.1016)
		(layer "F.Cu")
		(net "RST_CPU_NODE1_SRTCRST_L")
	)
	(segment
		(start 173.010322 -120.365774)
		(end 172.942758 -120.365774)
		(width 0.1016)
		(layer "F.Cu")
		(net "RST_CPU_NODE1_SRTCRST_L")
	)
	(segment
		(start 164.523928 -117.263672)
		(end 163.84778 -117.263672)
		(width 0.1016)
		(layer "F.Cu")
		(net "RST_CPU_NODE1_SRTCRST_L")
	)
	(segment
		(start 165.686486 -119.29745)
		(end 165.11143 -118.722394)
		(width 0.1016)
		(layer "F.Cu")
		(net "RST_CPU_NODE1_SRTCRST_L")
	)
	(segment
		(start 165.686486 -119.483886)
		(end 165.686486 -119.29745)
		(width 0.1016)
		(layer "F.Cu")
		(net "RST_CPU_NODE1_SRTCRST_L")
	)
	(segment
		(start 172.942758 -120.365774)
		(end 172.519848 -119.942864)
		(width 0.1016)
		(layer "F.Cu")
		(net "RST_CPU_NODE1_SRTCRST_L")
	)
	(segment
		(start 165.11143 -118.722394)
		(end 165.11143 -117.851174)
		(width 0.1016)
		(layer "F.Cu")
		(net "RST_CPU_NODE1_SRTCRST_L")
	)
	(segment
		(start 163.84778 -117.263672)
		(end 163.7919 -117.319552)
		(width 0.1016)
		(layer "F.Cu")
		(net "RST_CPU_NODE1_SRTCRST_L")
	)
	(via
		(at 73.270364 -82.637122)
		(size 0.508)
		(drill 0.254)
		(layers "F.Cu" "B.Cu")
		(net "RST_CPU_NODE1_SRTCRST_L")
	)
	(via
		(at 150.1394 -114.332512)
		(size 0.508)
		(drill 0.254)
		(layers "F.Cu" "B.Cu")
		(net "RST_CPU_NODE1_SRTCRST_L")
	)
	(segment
		(start 141.550898 -106.721148)
		(end 138.023854 -103.194104)
		(width 0.1143)
		(layer "In7.Cu")
		(net "RST_CPU_NODE1_SRTCRST_L")
	)
	(segment
		(start 125.75032 -103.194104)
		(end 109.17682 -86.620604)
		(width 0.1143)
		(layer "In7.Cu")
		(net "RST_CPU_NODE1_SRTCRST_L")
	)
	(segment
		(start 96.71685 -83.7057)
		(end 94.314518 -81.303368)
		(width 0.1143)
		(layer "In7.Cu")
		(net "RST_CPU_NODE1_SRTCRST_L")
	)
	(segment
		(start 82.853022 -81.303368)
		(end 81.948528 -82.207862)
		(width 0.1143)
		(layer "In7.Cu")
		(net "RST_CPU_NODE1_SRTCRST_L")
	)
	(segment
		(start 150.1394 -114.332512)
		(end 150.1394 -113.812574)
		(width 0.1143)
		(layer "In7.Cu")
		(net "RST_CPU_NODE1_SRTCRST_L")
	)
	(segment
		(start 81.948528 -82.207862)
		(end 77.960474 -82.207862)
		(width 0.1143)
		(layer "In7.Cu")
		(net "RST_CPU_NODE1_SRTCRST_L")
	)
	(segment
		(start 73.752202 -82.155284)
		(end 73.270364 -82.637122)
		(width 0.1143)
		(layer "In7.Cu")
		(net "RST_CPU_NODE1_SRTCRST_L")
	)
	(segment
		(start 150.1394 -113.812574)
		(end 143.047974 -106.721148)
		(width 0.1143)
		(layer "In7.Cu")
		(net "RST_CPU_NODE1_SRTCRST_L")
	)
	(segment
		(start 77.960474 -82.207862)
		(end 77.907896 -82.155284)
		(width 0.1143)
		(layer "In7.Cu")
		(net "RST_CPU_NODE1_SRTCRST_L")
	)
	(segment
		(start 143.047974 -106.721148)
		(end 141.550898 -106.721148)
		(width 0.1143)
		(layer "In7.Cu")
		(net "RST_CPU_NODE1_SRTCRST_L")
	)
	(segment
		(start 138.023854 -103.194104)
		(end 125.75032 -103.194104)
		(width 0.1143)
		(layer "In7.Cu")
		(net "RST_CPU_NODE1_SRTCRST_L")
	)
	(segment
		(start 102.228904 -86.620604)
		(end 99.314 -83.7057)
		(width 0.1143)
		(layer "In7.Cu")
		(net "RST_CPU_NODE1_SRTCRST_L")
	)
	(segment
		(start 99.314 -83.7057)
		(end 96.71685 -83.7057)
		(width 0.1143)
		(layer "In7.Cu")
		(net "RST_CPU_NODE1_SRTCRST_L")
	)
	(segment
		(start 109.17682 -86.620604)
		(end 102.228904 -86.620604)
		(width 0.1143)
		(layer "In7.Cu")
		(net "RST_CPU_NODE1_SRTCRST_L")
	)
	(segment
		(start 77.907896 -82.155284)
		(end 73.752202 -82.155284)
		(width 0.1143)
		(layer "In7.Cu")
		(net "RST_CPU_NODE1_SRTCRST_L")
	)
	(segment
		(start 94.314518 -81.303368)
		(end 82.853022 -81.303368)
		(width 0.1143)
		(layer "In7.Cu")
		(net "RST_CPU_NODE1_SRTCRST_L")
	)
	(segment
		(start 59.38266 -99.297744)
		(end 59.767216 -98.913188)
		(width 0.1016)
		(layer "F.Cu")
		(net "SPI_CPU_NODE1_CS0_L")
	)
	(segment
		(start 59.092338 -100.586794)
		(end 59.0931 -100.586794)
		(width 0.1016)
		(layer "F.Cu")
		(net "SPI_CPU_NODE1_CS0_L")
	)
	(segment
		(start 88.158066 -97.099628)
		(end 88.158066 -99.955604)
		(width 0.1016)
		(layer "F.Cu")
		(net "SPI_CPU_NODE1_CS0_L")
	)
	(segment
		(start 88.158066 -99.955604)
		(end 83.713066 -104.400604)
		(width 0.1016)
		(layer "F.Cu")
		(net "SPI_CPU_NODE1_CS0_L")
	)
	(segment
		(start 62.030864 -97.110042)
		(end 62.161166 -97.110042)
		(width 0.1016)
		(layer "F.Cu")
		(net "SPI_CPU_NODE1_CS0_L")
	)
	(segment
		(start 59.0931 -100.586794)
		(end 59.38266 -100.297234)
		(width 0.1016)
		(layer "F.Cu")
		(net "SPI_CPU_NODE1_CS0_L")
	)
	(segment
		(start 60.227718 -98.913188)
		(end 62.030864 -97.110042)
		(width 0.1016)
		(layer "F.Cu")
		(net "SPI_CPU_NODE1_CS0_L")
	)
	(segment
		(start 59.38266 -100.297234)
		(end 59.38266 -99.297744)
		(width 0.1016)
		(layer "F.Cu")
		(net "SPI_CPU_NODE1_CS0_L")
	)
	(segment
		(start 81.990438 -104.400604)
		(end 81.76514 -104.175306)
		(width 0.1016)
		(layer "F.Cu")
		(net "SPI_CPU_NODE1_CS0_L")
	)
	(segment
		(start 83.713066 -104.400604)
		(end 81.990438 -104.400604)
		(width 0.1016)
		(layer "F.Cu")
		(net "SPI_CPU_NODE1_CS0_L")
	)
	(segment
		(start 59.767216 -98.913188)
		(end 60.227718 -98.913188)
		(width 0.1016)
		(layer "F.Cu")
		(net "SPI_CPU_NODE1_CS0_L")
	)
	(via
		(at 59.092338 -100.586794)
		(size 0.508)
		(drill 0.254)
		(layers "F.Cu" "B.Cu")
		(net "SPI_CPU_NODE1_CS0_L")
	)
	(via
		(at 81.76514 -104.175306)
		(size 0.508)
		(drill 0.254)
		(layers "F.Cu" "B.Cu")
		(net "SPI_CPU_NODE1_CS0_L")
	)
	(segment
		(start 79.92364 -103.229918)
		(end 80.819752 -103.229918)
		(width 0.1016)
		(layer "B.Cu")
		(net "SPI_CPU_NODE1_CS0_L")
	)
	(segment
		(start 59.479942 -100.586794)
		(end 59.928506 -101.035358)
		(width 0.1016)
		(layer "B.Cu")
		(net "SPI_CPU_NODE1_CS0_L")
	)
	(segment
		(start 80.819752 -103.229918)
		(end 81.76514 -104.175306)
		(width 0.1016)
		(layer "B.Cu")
		(net "SPI_CPU_NODE1_CS0_L")
	)
	(segment
		(start 78.912974 -102.219252)
		(end 79.92364 -103.229918)
		(width 0.1016)
		(layer "B.Cu")
		(net "SPI_CPU_NODE1_CS0_L")
	)
	(segment
		(start 59.092338 -100.586794)
		(end 59.479942 -100.586794)
		(width 0.1016)
		(layer "B.Cu")
		(net "SPI_CPU_NODE1_CS0_L")
	)
	(segment
		(start 74.92746 -101.657912)
		(end 75.4888 -102.219252)
		(width 0.1016)
		(layer "B.Cu")
		(net "SPI_CPU_NODE1_CS0_L")
	)
	(segment
		(start 75.4888 -102.219252)
		(end 78.912974 -102.219252)
		(width 0.1016)
		(layer "B.Cu")
		(net "SPI_CPU_NODE1_CS0_L")
	)
	(segment
		(start 69.511926 -101.15804)
		(end 70.011798 -101.657912)
		(width 0.1016)
		(layer "B.Cu")
		(net "SPI_CPU_NODE1_CS0_L")
	)
	(segment
		(start 70.011798 -101.657912)
		(end 74.92746 -101.657912)
		(width 0.1016)
		(layer "B.Cu")
		(net "SPI_CPU_NODE1_CS0_L")
	)
	(segment
		(start 59.928506 -101.035358)
		(end 65.33388 -101.035358)
		(width 0.1016)
		(layer "B.Cu")
		(net "SPI_CPU_NODE1_CS0_L")
	)
	(segment
		(start 65.33388 -101.035358)
		(end 65.456562 -101.15804)
		(width 0.1016)
		(layer "B.Cu")
		(net "SPI_CPU_NODE1_CS0_L")
	)
	(segment
		(start 65.456562 -101.15804)
		(end 69.511926 -101.15804)
		(width 0.1016)
		(layer "B.Cu")
		(net "SPI_CPU_NODE1_CS0_L")
	)
	(segment
		(start 59.756802 -65.862454)
		(end 59.402218 -66.217038)
		(width 0.127)
		(layer "F.Cu")
		(net "M_DDR3_NODE1_MON1P")
	)
	(segment
		(start 59.402218 -66.217038)
		(end 59.383422 -66.217038)
		(width 0.127)
		(layer "F.Cu")
		(net "M_DDR3_NODE1_MON1P")
	)
	(segment
		(start 59.756802 -65.836038)
		(end 59.756802 -65.862454)
		(width 0.127)
		(layer "F.Cu")
		(net "M_DDR3_NODE1_MON1P")
	)
	(via
		(at 57.94502 -57.361836)
		(size 0.508)
		(drill 0.254)
		(layers "F.Cu" "B.Cu")
		(net "M_DDR3_NODE1_MON1P")
	)
	(via
		(at 58.85434 -61.885068)
		(size 0.508)
		(drill 0.254)
		(layers "F.Cu" "B.Cu")
		(net "M_DDR3_NODE1_MON1P")
	)
	(via
		(at 59.383422 -66.217038)
		(size 0.508)
		(drill 0.254)
		(layers "F.Cu" "B.Cu")
		(net "M_DDR3_NODE1_MON1P")
	)
	(segment
		(start 58.5597 -61.590428)
		(end 58.85434 -61.885068)
		(width 0.17018)
		(layer "B.Cu")
		(net "M_DDR3_NODE1_MON1P")
	)
	(segment
		(start 58.275728 -61.590428)
		(end 58.5597 -61.590428)
		(width 0.17018)
		(layer "B.Cu")
		(net "M_DDR3_NODE1_MON1P")
	)
	(segment
		(start 57.94502 -57.361836)
		(end 57.94502 -61.25972)
		(width 0.17018)
		(layer "B.Cu")
		(net "M_DDR3_NODE1_MON1P")
	)
	(segment
		(start 57.882028 -55.355744)
		(end 57.882028 -55.845964)
		(width 0.17018)
		(layer "B.Cu")
		(net "M_DDR3_NODE1_MON1P")
	)
	(segment
		(start 57.619138 -55.092854)
		(end 57.882028 -55.355744)
		(width 0.17018)
		(layer "B.Cu")
		(net "M_DDR3_NODE1_MON1P")
	)
	(segment
		(start 57.619138 -56.108854)
		(end 57.94502 -56.434736)
		(width 0.17018)
		(layer "B.Cu")
		(net "M_DDR3_NODE1_MON1P")
	)
	(segment
		(start 57.94502 -61.25972)
		(end 58.275728 -61.590428)
		(width 0.17018)
		(layer "B.Cu")
		(net "M_DDR3_NODE1_MON1P")
	)
	(segment
		(start 57.882028 -55.845964)
		(end 57.619138 -56.108854)
		(width 0.17018)
		(layer "B.Cu")
		(net "M_DDR3_NODE1_MON1P")
	)
	(segment
		(start 57.94502 -56.434736)
		(end 57.94502 -57.361836)
		(width 0.17018)
		(layer "B.Cu")
		(net "M_DDR3_NODE1_MON1P")
	)
	(segment
		(start 59.227974 -62.442852)
		(end 58.300112 -63.370714)
		(width 0.17018)
		(layer "In7.Cu")
		(net "M_DDR3_NODE1_MON1P")
	)
	(segment
		(start 59.807602 -66.217038)
		(end 59.383422 -66.217038)
		(width 0.17018)
		(layer "In7.Cu")
		(net "M_DDR3_NODE1_MON1P")
	)
	(segment
		(start 58.85434 -61.885068)
		(end 59.227974 -62.258702)
		(width 0.17018)
		(layer "In7.Cu")
		(net "M_DDR3_NODE1_MON1P")
	)
	(segment
		(start 60.080398 -65.944242)
		(end 59.807602 -66.217038)
		(width 0.17018)
		(layer "In7.Cu")
		(net "M_DDR3_NODE1_MON1P")
	)
	(segment
		(start 58.300112 -63.370714)
		(end 58.300112 -64.567054)
		(width 0.17018)
		(layer "In7.Cu")
		(net "M_DDR3_NODE1_MON1P")
	)
	(segment
		(start 59.7408 -64.948054)
		(end 60.080398 -65.287652)
		(width 0.17018)
		(layer "In7.Cu")
		(net "M_DDR3_NODE1_MON1P")
	)
	(segment
		(start 58.681112 -64.948054)
		(end 59.7408 -64.948054)
		(width 0.17018)
		(layer "In7.Cu")
		(net "M_DDR3_NODE1_MON1P")
	)
	(segment
		(start 60.080398 -65.287652)
		(end 60.080398 -65.944242)
		(width 0.17018)
		(layer "In7.Cu")
		(net "M_DDR3_NODE1_MON1P")
	)
	(segment
		(start 59.227974 -62.258702)
		(end 59.227974 -62.442852)
		(width 0.17018)
		(layer "In7.Cu")
		(net "M_DDR3_NODE1_MON1P")
	)
	(segment
		(start 58.300112 -64.567054)
		(end 58.681112 -64.948054)
		(width 0.17018)
		(layer "In7.Cu")
		(net "M_DDR3_NODE1_MON1P")
	)
	(segment
		(start 175.554894 -129.797048)
		(end 175.554894 -130.23977)
		(width 0.1016)
		(layer "F.Cu")
		(net "FM_CPLD_NODE1_DEBUG_MODE")
	)
	(segment
		(start 176.01057 -124.365766)
		(end 176.01057 -124.46127)
		(width 0.1016)
		(layer "F.Cu")
		(net "FM_CPLD_NODE1_DEBUG_MODE")
	)
	(segment
		(start 175.191166 -128.81229)
		(end 175.191166 -129.43332)
		(width 0.1016)
		(layer "F.Cu")
		(net "FM_CPLD_NODE1_DEBUG_MODE")
	)
	(segment
		(start 176.01057 -124.46127)
		(end 175.554894 -124.916946)
		(width 0.1016)
		(layer "F.Cu")
		(net "FM_CPLD_NODE1_DEBUG_MODE")
	)
	(segment
		(start 175.554894 -124.916946)
		(end 175.554894 -128.448562)
		(width 0.1016)
		(layer "F.Cu")
		(net "FM_CPLD_NODE1_DEBUG_MODE")
	)
	(segment
		(start 175.554894 -128.448562)
		(end 175.191166 -128.81229)
		(width 0.1016)
		(layer "F.Cu")
		(net "FM_CPLD_NODE1_DEBUG_MODE")
	)
	(segment
		(start 175.554894 -130.23977)
		(end 174.411894 -130.23977)
		(width 0.1016)
		(layer "F.Cu")
		(net "FM_CPLD_NODE1_DEBUG_MODE")
	)
	(segment
		(start 175.191166 -129.43332)
		(end 175.554894 -129.797048)
		(width 0.1016)
		(layer "F.Cu")
		(net "FM_CPLD_NODE1_DEBUG_MODE")
	)
	(via
		(at 175.191166 -129.43332)
		(size 0.508)
		(drill 0.254)
		(layers "F.Cu" "B.Cu")
		(net "FM_CPLD_NODE1_DEBUG_MODE")
	)
	(segment
		(start 42.31767 -160.06064)
		(end 42.12082 -160.25749)
		(width 0.1016)
		(layer "F.Cu")
		(net "N21311590")
	)
	(segment
		(start 42.12082 -162.54349)
		(end 41.28262 -163.38169)
		(width 0.1016)
		(layer "F.Cu")
		(net "N21311590")
	)
	(segment
		(start 42.12082 -160.25749)
		(end 42.12082 -162.54349)
		(width 0.1016)
		(layer "F.Cu")
		(net "N21311590")
	)
	(segment
		(start 42.31767 -159.472884)
		(end 42.31767 -160.06064)
		(width 0.1016)
		(layer "F.Cu")
		(net "N21311590")
	)
	(via
		(at 41.28262 -163.38169)
		(size 0.508)
		(drill 0.254)
		(layers "F.Cu" "B.Cu")
		(net "N21311590")
	)
	(segment
		(start 41.4274 -163.52647)
		(end 41.28262 -163.38169)
		(width 0.1016)
		(layer "B.Cu")
		(net "N21311590")
	)
	(segment
		(start 42.113962 -163.52647)
		(end 41.4274 -163.52647)
		(width 0.1016)
		(layer "B.Cu")
		(net "N21311590")
	)
	(segment
		(start 58.14187 -134.459472)
		(end 57.390538 -134.063994)
		(width 0.10414)
		(layer "F.Cu")
		(net "BMC_NODE1_DDR_CLK_DN")
	)
	(segment
		(start 56.801766 -134.063994)
		(end 56.091836 -134.773924)
		(width 0.10414)
		(layer "F.Cu")
		(net "BMC_NODE1_DDR_CLK_DN")
	)
	(segment
		(start 57.390538 -134.063994)
		(end 56.801766 -134.063994)
		(width 0.10414)
		(layer "F.Cu")
		(net "BMC_NODE1_DDR_CLK_DN")
	)
	(segment
		(start 54.385972 -134.438136)
		(end 54.385972 -134.260082)
		(width 0.10414)
		(layer "F.Cu")
		(net "BMC_NODE1_DDR_CLK_DN")
	)
	(segment
		(start 44.638214 -133.763766)
		(end 44.29633 -134.10565)
		(width 0.10414)
		(layer "F.Cu")
		(net "BMC_NODE1_DDR_CLK_DN")
	)
	(segment
		(start 56.091836 -134.773924)
		(end 54.72176 -134.773924)
		(width 0.10414)
		(layer "F.Cu")
		(net "BMC_NODE1_DDR_CLK_DN")
	)
	(segment
		(start 54.72176 -134.773924)
		(end 54.385972 -134.438136)
		(width 0.10414)
		(layer "F.Cu")
		(net "BMC_NODE1_DDR_CLK_DN")
	)
	(segment
		(start 44.833032 -133.763766)
		(end 44.638214 -133.763766)
		(width 0.10414)
		(layer "F.Cu")
		(net "BMC_NODE1_DDR_CLK_DN")
	)
	(via
		(at 44.29633 -134.10565)
		(size 0.508)
		(drill 0.254)
		(layers "F.Cu" "B.Cu")
		(net "BMC_NODE1_DDR_CLK_DN")
	)
	(via
		(at 54.385972 -134.260082)
		(size 0.49022)
		(drill 0.254)
		(layers "F.Cu" "B.Cu")
		(net "BMC_NODE1_DDR_CLK_DN")
	)
	(segment
		(start 54.193186 -134.067296)
		(end 54.193186 -133.571742)
		(width 0.10414)
		(layer "In7.Cu")
		(net "BMC_NODE1_DDR_CLK_DN")
	)
	(segment
		(start 54.385972 -134.260082)
		(end 54.193186 -134.067296)
		(width 0.10414)
		(layer "In7.Cu")
		(net "BMC_NODE1_DDR_CLK_DN")
	)
	(segment
		(start 44.43349 -133.96849)
		(end 44.29633 -134.10565)
		(width 0.10414)
		(layer "In7.Cu")
		(net "BMC_NODE1_DDR_CLK_DN")
	)
	(segment
		(start 44.43349 -133.872986)
		(end 44.43349 -133.96849)
		(width 0.10414)
		(layer "In7.Cu")
		(net "BMC_NODE1_DDR_CLK_DN")
	)
	(segment
		(start 51.0667 -129.765044)
		(end 47.033688 -129.765044)
		(width 0.10414)
		(layer "In7.Cu")
		(net "BMC_NODE1_DDR_CLK_DN")
	)
	(segment
		(start 47.033688 -129.765044)
		(end 46.477428 -130.321304)
		(width 0.10414)
		(layer "In7.Cu")
		(net "BMC_NODE1_DDR_CLK_DN")
	)
	(segment
		(start 54.193186 -133.571742)
		(end 53.219858 -131.917948)
		(width 0.10414)
		(layer "In7.Cu")
		(net "BMC_NODE1_DDR_CLK_DN")
	)
	(segment
		(start 46.477428 -131.829048)
		(end 44.43349 -133.872986)
		(width 0.10414)
		(layer "In7.Cu")
		(net "BMC_NODE1_DDR_CLK_DN")
	)
	(segment
		(start 46.477428 -130.321304)
		(end 46.477428 -131.829048)
		(width 0.10414)
		(layer "In7.Cu")
		(net "BMC_NODE1_DDR_CLK_DN")
	)
	(segment
		(start 53.219858 -131.917948)
		(end 51.0667 -129.765044)
		(width 0.10414)
		(layer "In7.Cu")
		(net "BMC_NODE1_DDR_CLK_DN")
	)
	(segment
		(start 90.698066 -102.64394)
		(end 90.698066 -103.859584)
		(width 0.1016)
		(layer "F.Cu")
		(net "SPI_CPU_NODE1_SCLK")
	)
	(segment
		(start 84.3026 -106.506518)
		(end 84.3026 -104.865678)
		(width 0.1016)
		(layer "F.Cu")
		(net "SPI_CPU_NODE1_SCLK")
	)
	(segment
		(start 90.35796 -102.303834)
		(end 90.698066 -102.64394)
		(width 0.1016)
		(layer "F.Cu")
		(net "SPI_CPU_NODE1_SCLK")
	)
	(segment
		(start 86.864444 -102.303834)
		(end 90.35796 -102.303834)
		(width 0.1016)
		(layer "F.Cu")
		(net "SPI_CPU_NODE1_SCLK")
	)
	(segment
		(start 84.3026 -104.865678)
		(end 86.864444 -102.303834)
		(width 0.1016)
		(layer "F.Cu")
		(net "SPI_CPU_NODE1_SCLK")
	)
	(segment
		(start 90.698066 -103.859584)
		(end 90.698066 -104.128062)
		(width 0.1016)
		(layer "F.Cu")
		(net "SPI_CPU_NODE1_SCLK")
	)
	(via
		(at 84.3026 -106.506518)
		(size 0.508)
		(drill 0.254)
		(layers "F.Cu" "B.Cu")
		(net "SPI_CPU_NODE1_SCLK")
	)
	(segment
		(start 58.997596 -101.33584)
		(end 57.99074 -100.328984)
		(width 0.1016)
		(layer "B.Cu")
		(net "SPI_CPU_NODE1_SCLK")
	)
	(segment
		(start 80.59801 -104.18191)
		(end 79.857854 -104.18191)
		(width 0.1016)
		(layer "B.Cu")
		(net "SPI_CPU_NODE1_SCLK")
	)
	(segment
		(start 78.46187 -102.785926)
		(end 66.661538 -102.785926)
		(width 0.1016)
		(layer "B.Cu")
		(net "SPI_CPU_NODE1_SCLK")
	)
	(segment
		(start 57.99074 -100.328984)
		(end 57.99074 -98.653854)
		(width 0.1016)
		(layer "B.Cu")
		(net "SPI_CPU_NODE1_SCLK")
	)
	(segment
		(start 84.11845 -106.506518)
		(end 83.186778 -105.574846)
		(width 0.1016)
		(layer "B.Cu")
		(net "SPI_CPU_NODE1_SCLK")
	)
	(segment
		(start 81.990946 -105.574846)
		(end 80.59801 -104.18191)
		(width 0.1016)
		(layer "B.Cu")
		(net "SPI_CPU_NODE1_SCLK")
	)
	(segment
		(start 58.55716 -98.087434)
		(end 58.55716 -95.474536)
		(width 0.1016)
		(layer "B.Cu")
		(net "SPI_CPU_NODE1_SCLK")
	)
	(segment
		(start 57.99074 -98.653854)
		(end 58.55716 -98.087434)
		(width 0.1016)
		(layer "B.Cu")
		(net "SPI_CPU_NODE1_SCLK")
	)
	(segment
		(start 59.15406 -94.264734)
		(end 60.615322 -92.803472)
		(width 0.1016)
		(layer "B.Cu")
		(net "SPI_CPU_NODE1_SCLK")
	)
	(segment
		(start 60.615322 -92.803472)
		(end 60.615322 -92.442284)
		(width 0.1016)
		(layer "B.Cu")
		(net "SPI_CPU_NODE1_SCLK")
	)
	(segment
		(start 65.211452 -101.33584)
		(end 58.997596 -101.33584)
		(width 0.1016)
		(layer "B.Cu")
		(net "SPI_CPU_NODE1_SCLK")
	)
	(segment
		(start 83.186778 -105.574846)
		(end 81.990946 -105.574846)
		(width 0.1016)
		(layer "B.Cu")
		(net "SPI_CPU_NODE1_SCLK")
	)
	(segment
		(start 59.15406 -94.877636)
		(end 59.15406 -94.264734)
		(width 0.1016)
		(layer "B.Cu")
		(net "SPI_CPU_NODE1_SCLK")
	)
	(segment
		(start 66.661538 -102.785926)
		(end 65.211452 -101.33584)
		(width 0.1016)
		(layer "B.Cu")
		(net "SPI_CPU_NODE1_SCLK")
	)
	(segment
		(start 84.3026 -106.506518)
		(end 84.11845 -106.506518)
		(width 0.1016)
		(layer "B.Cu")
		(net "SPI_CPU_NODE1_SCLK")
	)
	(segment
		(start 58.55716 -95.474536)
		(end 59.15406 -94.877636)
		(width 0.1016)
		(layer "B.Cu")
		(net "SPI_CPU_NODE1_SCLK")
	)
	(segment
		(start 79.857854 -104.18191)
		(end 78.46187 -102.785926)
		(width 0.1016)
		(layer "B.Cu")
		(net "SPI_CPU_NODE1_SCLK")
	)
	(segment
		(start 50.979832 -68.503038)
		(end 51.185572 -68.297298)
		(width 0.127)
		(layer "F.Cu")
		(net "P2E_CPU_SATA_NODE1_TX_C_DN")
	)
	(segment
		(start 50.525426 -68.503038)
		(end 50.979832 -68.503038)
		(width 0.127)
		(layer "F.Cu")
		(net "P2E_CPU_SATA_NODE1_TX_C_DN")
	)
	(via
		(at 50.056542 -67.315588)
		(size 0.4064)
		(drill 0.2032)
		(layers "F.Cu" "B.Cu")
		(net "P2E_CPU_SATA_NODE1_TX_C_DN")
	)
	(via
		(at 51.185572 -68.297298)
		(size 0.508)
		(drill 0.254)
		(layers "F.Cu" "B.Cu")
		(net "P2E_CPU_SATA_NODE1_TX_C_DN")
	)
	(segment
		(start 45.674026 -62.450218)
		(end 47.163736 -62.450218)
		(width 0.127)
		(layer "B.Cu")
		(net "P2E_CPU_SATA_NODE1_TX_C_DN")
	)
	(segment
		(start 50.056542 -67.64909)
		(end 50.056542 -67.315588)
		(width 0.127)
		(layer "B.Cu")
		(net "P2E_CPU_SATA_NODE1_TX_C_DN")
	)
	(segment
		(start 50.956972 -68.068698)
		(end 50.47615 -68.068698)
		(width 0.127)
		(layer "B.Cu")
		(net "P2E_CPU_SATA_NODE1_TX_C_DN")
	)
	(segment
		(start 44.9961 -61.232288)
		(end 44.9961 -61.772292)
		(width 0.127)
		(layer "B.Cu")
		(net "P2E_CPU_SATA_NODE1_TX_C_DN")
	)
	(segment
		(start 50.47615 -68.068698)
		(end 50.056542 -67.64909)
		(width 0.127)
		(layer "B.Cu")
		(net "P2E_CPU_SATA_NODE1_TX_C_DN")
	)
	(segment
		(start 44.609258 -60.845446)
		(end 44.9961 -61.232288)
		(width 0.127)
		(layer "B.Cu")
		(net "P2E_CPU_SATA_NODE1_TX_C_DN")
	)
	(segment
		(start 44.9961 -61.772292)
		(end 45.674026 -62.450218)
		(width 0.127)
		(layer "B.Cu")
		(net "P2E_CPU_SATA_NODE1_TX_C_DN")
	)
	(segment
		(start 47.163736 -62.450218)
		(end 50.056542 -65.343024)
		(width 0.127)
		(layer "B.Cu")
		(net "P2E_CPU_SATA_NODE1_TX_C_DN")
	)
	(segment
		(start 50.056542 -65.343024)
		(end 50.056542 -67.315588)
		(width 0.127)
		(layer "B.Cu")
		(net "P2E_CPU_SATA_NODE1_TX_C_DN")
	)
	(segment
		(start 51.185572 -68.297298)
		(end 50.956972 -68.068698)
		(width 0.127)
		(layer "B.Cu")
		(net "P2E_CPU_SATA_NODE1_TX_C_DN")
	)
	(segment
		(start 57.770522 -65.455038)
		(end 57.770522 -65.462658)
		(width 0.254)
		(layer "F.Cu")
		(net "M_DDR3_NODE1_ODTPU")
	)
	(segment
		(start 57.770522 -65.462658)
		(end 57.397142 -65.836038)
		(width 0.254)
		(layer "F.Cu")
		(net "M_DDR3_NODE1_ODTPU")
	)
	(via
		(at 57.397142 -65.836038)
		(size 0.508)
		(drill 0.254)
		(layers "F.Cu" "B.Cu")
		(net "M_DDR3_NODE1_ODTPU")
	)
	(via
		(at 56.333136 -65.10401)
		(size 0.6604)
		(drill 0.3302)
		(layers "F.Cu" "B.Cu")
		(net "M_DDR3_NODE1_ODTPU")
	)
	(segment
		(start 56.333136 -65.01257)
		(end 56.333136 -65.10401)
		(width 0.254)
		(layer "B.Cu")
		(net "M_DDR3_NODE1_ODTPU")
	)
	(segment
		(start 56.333136 -65.365376)
		(end 56.333136 -65.10401)
		(width 0.254)
		(layer "B.Cu")
		(net "M_DDR3_NODE1_ODTPU")
	)
	(segment
		(start 55.261256 -63.488316)
		(end 55.334408 -63.561468)
		(width 0.254)
		(layer "B.Cu")
		(net "M_DDR3_NODE1_ODTPU")
	)
	(segment
		(start 57.397142 -65.836038)
		(end 56.803798 -65.836038)
		(width 0.254)
		(layer "B.Cu")
		(net "M_DDR3_NODE1_ODTPU")
	)
	(segment
		(start 55.334408 -63.561468)
		(end 55.334408 -64.407542)
		(width 0.254)
		(layer "B.Cu")
		(net "M_DDR3_NODE1_ODTPU")
	)
	(segment
		(start 55.591202 -64.664336)
		(end 55.984902 -64.664336)
		(width 0.254)
		(layer "B.Cu")
		(net "M_DDR3_NODE1_ODTPU")
	)
	(segment
		(start 55.984902 -64.664336)
		(end 56.333136 -65.01257)
		(width 0.254)
		(layer "B.Cu")
		(net "M_DDR3_NODE1_ODTPU")
	)
	(segment
		(start 56.803798 -65.836038)
		(end 56.333136 -65.365376)
		(width 0.254)
		(layer "B.Cu")
		(net "M_DDR3_NODE1_ODTPU")
	)
	(segment
		(start 55.334408 -64.407542)
		(end 55.591202 -64.664336)
		(width 0.254)
		(layer "B.Cu")
		(net "M_DDR3_NODE1_ODTPU")
	)
	(segment
		(start 42.328084 -123.872752)
		(end 43.104816 -123.872752)
		(width 0.1016)
		(layer "F.Cu")
		(net "BMC_NODE1_DDR_RST_L")
	)
	(segment
		(start 41.54678 -123.872752)
		(end 42.328084 -123.872752)
		(width 0.1016)
		(layer "F.Cu")
		(net "BMC_NODE1_DDR_RST_L")
	)
	(segment
		(start 40.83304 -128.963674)
		(end 40.83304 -124.586492)
		(width 0.1016)
		(layer "F.Cu")
		(net "BMC_NODE1_DDR_RST_L")
	)
	(segment
		(start 44.168568 -123.866656)
		(end 43.110912 -123.866656)
		(width 0.1016)
		(layer "F.Cu")
		(net "BMC_NODE1_DDR_RST_L")
	)
	(segment
		(start 43.104816 -123.872752)
		(end 43.110912 -123.866656)
		(width 0.1016)
		(layer "F.Cu")
		(net "BMC_NODE1_DDR_RST_L")
	)
	(segment
		(start 40.83304 -124.586492)
		(end 41.54678 -123.872752)
		(width 0.1016)
		(layer "F.Cu")
		(net "BMC_NODE1_DDR_RST_L")
	)
	(via
		(at 43.110912 -123.866656)
		(size 0.508)
		(drill 0.254)
		(layers "F.Cu" "B.Cu")
		(net "BMC_NODE1_DDR_RST_L")
	)
	(segment
		(start 68.297044 -83.514438)
		(end 68.654422 -83.871816)
		(width 0.1016)
		(layer "F.Cu")
		(net "FM_CPU_NODE1_RSTRDY_L")
	)
	(segment
		(start 68.654422 -83.871816)
		(end 68.654422 -83.95716)
		(width 0.1016)
		(layer "F.Cu")
		(net "FM_CPU_NODE1_RSTRDY_L")
	)
	(segment
		(start 177.010314 -124.667518)
		(end 177.010314 -124.365766)
		(width 0.1016)
		(layer "F.Cu")
		(net "FM_CPU_NODE1_RSTRDY_L")
	)
	(segment
		(start 177.442114 -125.099318)
		(end 177.010314 -124.667518)
		(width 0.1016)
		(layer "F.Cu")
		(net "FM_CPU_NODE1_RSTRDY_L")
	)
	(segment
		(start 83.072732 -89.865454)
		(end 83.072732 -91.027504)
		(width 0.1016)
		(layer "F.Cu")
		(net "FM_CPU_NODE1_RSTRDY_L")
	)
	(segment
		(start 177.442114 -129.94132)
		(end 177.442114 -125.099318)
		(width 0.1016)
		(layer "F.Cu")
		(net "FM_CPU_NODE1_RSTRDY_L")
	)
	(segment
		(start 176.909476 -130.473958)
		(end 177.442114 -129.94132)
		(width 0.1016)
		(layer "F.Cu")
		(net "FM_CPU_NODE1_RSTRDY_L")
	)
	(via
		(at 176.909476 -130.473958)
		(size 0.508)
		(drill 0.254)
		(layers "F.Cu" "B.Cu")
		(net "FM_CPU_NODE1_RSTRDY_L")
	)
	(via
		(at 68.654422 -83.95716)
		(size 0.508)
		(drill 0.254)
		(layers "F.Cu" "B.Cu")
		(net "FM_CPU_NODE1_RSTRDY_L")
	)
	(via
		(at 83.072732 -91.027504)
		(size 0.508)
		(drill 0.254)
		(layers "F.Cu" "B.Cu")
		(net "FM_CPU_NODE1_RSTRDY_L")
	)
	(segment
		(start 73.66 -85.866224)
		(end 71.923402 -84.129626)
		(width 0.1143)
		(layer "In6.Cu")
		(net "FM_CPU_NODE1_RSTRDY_L")
	)
	(segment
		(start 176.909476 -130.473958)
		(end 172.555408 -126.11989)
		(width 0.1143)
		(layer "In6.Cu")
		(net "FM_CPU_NODE1_RSTRDY_L")
	)
	(segment
		(start 70.748906 -84.129626)
		(end 70.196456 -83.577176)
		(width 0.1143)
		(layer "In6.Cu")
		(net "FM_CPU_NODE1_RSTRDY_L")
	)
	(segment
		(start 88.02878 -92.865194)
		(end 86.78926 -91.625674)
		(width 0.1143)
		(layer "In6.Cu")
		(net "FM_CPU_NODE1_RSTRDY_L")
	)
	(segment
		(start 150.19528 -104.305862)
		(end 135.284464 -89.395046)
		(width 0.1143)
		(layer "In6.Cu")
		(net "FM_CPU_NODE1_RSTRDY_L")
	)
	(segment
		(start 83.072732 -91.029536)
		(end 82.451448 -91.65082)
		(width 0.1143)
		(layer "In6.Cu")
		(net "FM_CPU_NODE1_RSTRDY_L")
	)
	(segment
		(start 135.284464 -89.395046)
		(end 97.089214 -89.395046)
		(width 0.1143)
		(layer "In6.Cu")
		(net "FM_CPU_NODE1_RSTRDY_L")
	)
	(segment
		(start 83.072732 -91.028774)
		(end 83.072732 -91.027504)
		(width 0.1143)
		(layer "In6.Cu")
		(net "FM_CPU_NODE1_RSTRDY_L")
	)
	(segment
		(start 163.97097 -112.592612)
		(end 163.303458 -111.9251)
		(width 0.1143)
		(layer "In6.Cu")
		(net "FM_CPU_NODE1_RSTRDY_L")
	)
	(segment
		(start 83.669632 -91.625674)
		(end 83.072732 -91.028774)
		(width 0.1143)
		(layer "In6.Cu")
		(net "FM_CPU_NODE1_RSTRDY_L")
	)
	(segment
		(start 166.07536 -124.110496)
		(end 166.07536 -115.711732)
		(width 0.1143)
		(layer "In6.Cu")
		(net "FM_CPU_NODE1_RSTRDY_L")
	)
	(segment
		(start 88.6714 -92.865194)
		(end 88.02878 -92.865194)
		(width 0.1143)
		(layer "In6.Cu")
		(net "FM_CPU_NODE1_RSTRDY_L")
	)
	(segment
		(start 163.97097 -113.681764)
		(end 163.97097 -112.592612)
		(width 0.1143)
		(layer "In6.Cu")
		(net "FM_CPU_NODE1_RSTRDY_L")
	)
	(segment
		(start 71.923402 -84.129626)
		(end 70.748906 -84.129626)
		(width 0.1143)
		(layer "In6.Cu")
		(net "FM_CPU_NODE1_RSTRDY_L")
	)
	(segment
		(start 168.084754 -126.11989)
		(end 166.07536 -124.110496)
		(width 0.1143)
		(layer "In6.Cu")
		(net "FM_CPU_NODE1_RSTRDY_L")
	)
	(segment
		(start 172.555408 -126.11989)
		(end 168.084754 -126.11989)
		(width 0.1143)
		(layer "In6.Cu")
		(net "FM_CPU_NODE1_RSTRDY_L")
	)
	(segment
		(start 70.196456 -83.577176)
		(end 69.034406 -83.577176)
		(width 0.1143)
		(layer "In6.Cu")
		(net "FM_CPU_NODE1_RSTRDY_L")
	)
	(segment
		(start 92.82176 -93.6625)
		(end 89.468706 -93.6625)
		(width 0.1143)
		(layer "In6.Cu")
		(net "FM_CPU_NODE1_RSTRDY_L")
	)
	(segment
		(start 166.07536 -115.711732)
		(end 164.430202 -114.066574)
		(width 0.1143)
		(layer "In6.Cu")
		(net "FM_CPU_NODE1_RSTRDY_L")
	)
	(segment
		(start 79.527146 -91.65082)
		(end 75.77074 -87.894414)
		(width 0.1143)
		(layer "In6.Cu")
		(net "FM_CPU_NODE1_RSTRDY_L")
	)
	(segment
		(start 73.95845 -85.866224)
		(end 73.66 -85.866224)
		(width 0.1143)
		(layer "In6.Cu")
		(net "FM_CPU_NODE1_RSTRDY_L")
	)
	(segment
		(start 69.034406 -83.577176)
		(end 68.654422 -83.95716)
		(width 0.1143)
		(layer "In6.Cu")
		(net "FM_CPU_NODE1_RSTRDY_L")
	)
	(segment
		(start 82.451448 -91.65082)
		(end 79.527146 -91.65082)
		(width 0.1143)
		(layer "In6.Cu")
		(net "FM_CPU_NODE1_RSTRDY_L")
	)
	(segment
		(start 86.78926 -91.625674)
		(end 83.669632 -91.625674)
		(width 0.1143)
		(layer "In6.Cu")
		(net "FM_CPU_NODE1_RSTRDY_L")
	)
	(segment
		(start 164.35578 -114.066574)
		(end 163.97097 -113.681764)
		(width 0.1143)
		(layer "In6.Cu")
		(net "FM_CPU_NODE1_RSTRDY_L")
	)
	(segment
		(start 164.430202 -114.066574)
		(end 164.35578 -114.066574)
		(width 0.1143)
		(layer "In6.Cu")
		(net "FM_CPU_NODE1_RSTRDY_L")
	)
	(segment
		(start 75.77074 -87.678514)
		(end 73.95845 -85.866224)
		(width 0.1143)
		(layer "In6.Cu")
		(net "FM_CPU_NODE1_RSTRDY_L")
	)
	(segment
		(start 75.77074 -87.894414)
		(end 75.77074 -87.678514)
		(width 0.1143)
		(layer "In6.Cu")
		(net "FM_CPU_NODE1_RSTRDY_L")
	)
	(segment
		(start 83.072732 -91.028774)
		(end 83.072732 -91.029536)
		(width 0.1143)
		(layer "In6.Cu")
		(net "FM_CPU_NODE1_RSTRDY_L")
	)
	(segment
		(start 97.089214 -89.395046)
		(end 92.82176 -93.6625)
		(width 0.1143)
		(layer "In6.Cu")
		(net "FM_CPU_NODE1_RSTRDY_L")
	)
	(segment
		(start 150.19528 -106.297984)
		(end 150.19528 -104.305862)
		(width 0.1143)
		(layer "In6.Cu")
		(net "FM_CPU_NODE1_RSTRDY_L")
	)
	(segment
		(start 89.468706 -93.6625)
		(end 88.6714 -92.865194)
		(width 0.1143)
		(layer "In6.Cu")
		(net "FM_CPU_NODE1_RSTRDY_L")
	)
	(segment
		(start 155.822396 -111.9251)
		(end 150.19528 -106.297984)
		(width 0.1143)
		(layer "In6.Cu")
		(net "FM_CPU_NODE1_RSTRDY_L")
	)
	(segment
		(start 163.303458 -111.9251)
		(end 155.822396 -111.9251)
		(width 0.1143)
		(layer "In6.Cu")
		(net "FM_CPU_NODE1_RSTRDY_L")
	)
	(segment
		(start 58.497978 -66.217038)
		(end 58.864246 -66.583306)
		(width 0.254)
		(layer "F.Cu")
		(net "M_DDR3_NODE1_DQPU")
	)
	(segment
		(start 58.470546 -66.217038)
		(end 58.497978 -66.217038)
		(width 0.254)
		(layer "F.Cu")
		(net "M_DDR3_NODE1_DQPU")
	)
	(via
		(at 58.864246 -66.583306)
		(size 0.508)
		(drill 0.254)
		(layers "F.Cu" "B.Cu")
		(net "M_DDR3_NODE1_DQPU")
	)
	(via
		(at 58.03773 -65.121536)
		(size 0.6604)
		(drill 0.3302)
		(layers "F.Cu" "B.Cu")
		(net "M_DDR3_NODE1_DQPU")
	)
	(segment
		(start 58.03773 -65.757044)
		(end 58.863992 -66.583306)
		(width 0.254)
		(layer "B.Cu")
		(net "M_DDR3_NODE1_DQPU")
	)
	(segment
		(start 58.03773 -64.660526)
		(end 58.03773 -65.121536)
		(width 0.254)
		(layer "B.Cu")
		(net "M_DDR3_NODE1_DQPU")
	)
	(segment
		(start 57.26303 -63.885826)
		(end 58.03773 -64.660526)
		(width 0.254)
		(layer "B.Cu")
		(net "M_DDR3_NODE1_DQPU")
	)
	(segment
		(start 58.863992 -66.583306)
		(end 58.864246 -66.583306)
		(width 0.254)
		(layer "B.Cu")
		(net "M_DDR3_NODE1_DQPU")
	)
	(segment
		(start 58.03773 -65.121536)
		(end 58.03773 -65.757044)
		(width 0.254)
		(layer "B.Cu")
		(net "M_DDR3_NODE1_DQPU")
	)
	(segment
		(start 60.541916 -131.259072)
		(end 60.141104 -130.85826)
		(width 0.381)
		(layer "F.Cu")
		(net "BMC_NODE1_DDR_IOZ")
	)
	(segment
		(start 60.541916 -131.25958)
		(end 60.541916 -131.259072)
		(width 0.381)
		(layer "F.Cu")
		(net "BMC_NODE1_DDR_IOZ")
	)
	(via
		(at 60.141104 -130.85826)
		(size 0.49022)
		(drill 0.254)
		(layers "F.Cu" "B.Cu")
		(net "BMC_NODE1_DDR_IOZ")
	)
	(via
		(at 59.96559 -127.219964)
		(size 0.6604)
		(drill 0.3302)
		(layers "F.Cu" "B.Cu")
		(net "BMC_NODE1_DDR_IOZ")
	)
	(segment
		(start 60.141104 -131.035044)
		(end 59.915552 -131.260596)
		(width 0.1016)
		(layer "B.Cu")
		(net "BMC_NODE1_DDR_IOZ")
	)
	(segment
		(start 60.141104 -130.85826)
		(end 60.141104 -131.035044)
		(width 0.1016)
		(layer "B.Cu")
		(net "BMC_NODE1_DDR_IOZ")
	)
	(segment
		(start 57.99582 -131.260596)
		(end 57.857136 -131.121912)
		(width 0.1016)
		(layer "B.Cu")
		(net "BMC_NODE1_DDR_IOZ")
	)
	(segment
		(start 59.739784 -127.923036)
		(end 59.960256 -127.702564)
		(width 0.1016)
		(layer "B.Cu")
		(net "BMC_NODE1_DDR_IOZ")
	)
	(segment
		(start 58.276998 -130.46075)
		(end 59.512708 -130.46075)
		(width 0.1016)
		(layer "B.Cu")
		(net "BMC_NODE1_DDR_IOZ")
	)
	(segment
		(start 60.141104 -130.85826)
		(end 60.141104 -130.716782)
		(width 0.1016)
		(layer "B.Cu")
		(net "BMC_NODE1_DDR_IOZ")
	)
	(segment
		(start 59.960256 -127.225298)
		(end 59.96559 -127.219964)
		(width 0.1016)
		(layer "B.Cu")
		(net "BMC_NODE1_DDR_IOZ")
	)
	(segment
		(start 57.857136 -131.026662)
		(end 57.857136 -130.880612)
		(width 0.1016)
		(layer "B.Cu")
		(net "BMC_NODE1_DDR_IOZ")
	)
	(segment
		(start 60.141104 -130.716782)
		(end 59.739784 -130.315462)
		(width 0.1016)
		(layer "B.Cu")
		(net "BMC_NODE1_DDR_IOZ")
	)
	(segment
		(start 59.512708 -130.46075)
		(end 59.910218 -130.85826)
		(width 0.1016)
		(layer "B.Cu")
		(net "BMC_NODE1_DDR_IOZ")
	)
	(segment
		(start 57.857136 -130.880612)
		(end 58.276998 -130.46075)
		(width 0.1016)
		(layer "B.Cu")
		(net "BMC_NODE1_DDR_IOZ")
	)
	(segment
		(start 59.739784 -130.315462)
		(end 59.739784 -127.923036)
		(width 0.1016)
		(layer "B.Cu")
		(net "BMC_NODE1_DDR_IOZ")
	)
	(segment
		(start 57.857136 -131.121912)
		(end 57.857136 -131.026662)
		(width 0.1016)
		(layer "B.Cu")
		(net "BMC_NODE1_DDR_IOZ")
	)
	(segment
		(start 59.910218 -130.85826)
		(end 60.141104 -130.85826)
		(width 0.1016)
		(layer "B.Cu")
		(net "BMC_NODE1_DDR_IOZ")
	)
	(segment
		(start 59.915552 -131.260596)
		(end 57.99582 -131.260596)
		(width 0.1016)
		(layer "B.Cu")
		(net "BMC_NODE1_DDR_IOZ")
	)
	(segment
		(start 59.960256 -127.702564)
		(end 59.960256 -127.225298)
		(width 0.1016)
		(layer "B.Cu")
		(net "BMC_NODE1_DDR_IOZ")
	)
	(segment
		(start 59.756802 -66.598038)
		(end 59.756802 -66.605658)
		(width 0.127)
		(layer "F.Cu")
		(net "M_DDR3_NODE1_MON2P")
	)
	(segment
		(start 59.756802 -66.605658)
		(end 59.383422 -66.979038)
		(width 0.127)
		(layer "F.Cu")
		(net "M_DDR3_NODE1_MON2P")
	)
	(via
		(at 59.383422 -66.979038)
		(size 0.508)
		(drill 0.254)
		(layers "F.Cu" "B.Cu")
		(net "M_DDR3_NODE1_MON2P")
	)
	(via
		(at 60.094622 -65.757298)
		(size 0.508)
		(drill 0.254)
		(layers "F.Cu" "B.Cu")
		(net "M_DDR3_NODE1_MON2P")
	)
	(segment
		(start 60.094622 -66.267838)
		(end 60.094622 -65.757298)
		(width 0.17018)
		(layer "B.Cu")
		(net "M_DDR3_NODE1_MON2P")
	)
	(segment
		(start 61.747146 -62.279022)
		(end 61.484256 -62.541912)
		(width 0.17018)
		(layer "B.Cu")
		(net "M_DDR3_NODE1_MON2P")
	)
	(segment
		(start 60.094622 -65.12687)
		(end 60.094622 -65.757298)
		(width 0.17018)
		(layer "B.Cu")
		(net "M_DDR3_NODE1_MON2P")
	)
	(segment
		(start 61.747146 -61.788802)
		(end 61.747146 -62.279022)
		(width 0.17018)
		(layer "B.Cu")
		(net "M_DDR3_NODE1_MON2P")
	)
	(segment
		(start 61.709808 -64.0842)
		(end 61.364622 -64.430148)
		(width 0.17018)
		(layer "B.Cu")
		(net "M_DDR3_NODE1_MON2P")
	)
	(segment
		(start 61.484256 -62.541912)
		(end 61.709808 -62.767464)
		(width 0.17018)
		(layer "B.Cu")
		(net "M_DDR3_NODE1_MON2P")
	)
	(segment
		(start 61.484256 -61.525912)
		(end 61.747146 -61.788802)
		(width 0.17018)
		(layer "B.Cu")
		(net "M_DDR3_NODE1_MON2P")
	)
	(segment
		(start 61.364622 -64.430148)
		(end 61.107828 -64.686688)
		(width 0.17018)
		(layer "B.Cu")
		(net "M_DDR3_NODE1_MON2P")
	)
	(segment
		(start 61.107828 -64.686688)
		(end 60.534804 -64.686688)
		(width 0.17018)
		(layer "B.Cu")
		(net "M_DDR3_NODE1_MON2P")
	)
	(segment
		(start 60.534804 -64.686688)
		(end 60.094622 -65.12687)
		(width 0.17018)
		(layer "B.Cu")
		(net "M_DDR3_NODE1_MON2P")
	)
	(segment
		(start 61.709808 -62.767464)
		(end 61.709808 -64.0842)
		(width 0.17018)
		(layer "B.Cu")
		(net "M_DDR3_NODE1_MON2P")
	)
	(segment
		(start 59.383422 -66.979038)
		(end 60.094622 -66.267838)
		(width 0.17018)
		(layer "B.Cu")
		(net "M_DDR3_NODE1_MON2P")
	)
	(segment
		(start 169.903902 -114.902742)
		(end 172.370242 -114.902742)
		(width 0.1016)
		(layer "F.Cu")
		(net "FM_CPLD_NODE1_CLK_PG")
	)
	(segment
		(start 162.15741 -115.073684)
		(end 164.457634 -112.77346)
		(width 0.1016)
		(layer "F.Cu")
		(net "FM_CPLD_NODE1_CLK_PG")
	)
	(segment
		(start 126.445772 -113.104676)
		(end 126.445772 -111.82731)
		(width 0.1016)
		(layer "F.Cu")
		(net "FM_CPLD_NODE1_CLK_PG")
	)
	(segment
		(start 153.289 -116.659406)
		(end 153.289 -117.882924)
		(width 0.1016)
		(layer "F.Cu")
		(net "FM_CPLD_NODE1_CLK_PG")
	)
	(segment
		(start 150.470362 -113.840768)
		(end 153.289 -116.659406)
		(width 0.1016)
		(layer "F.Cu")
		(net "FM_CPLD_NODE1_CLK_PG")
	)
	(segment
		(start 153.289 -117.882924)
		(end 153.632154 -118.226078)
		(width 0.1016)
		(layer "F.Cu")
		(net "FM_CPLD_NODE1_CLK_PG")
	)
	(segment
		(start 173.51756 -116.05006)
		(end 173.51756 -116.872766)
		(width 0.1016)
		(layer "F.Cu")
		(net "FM_CPLD_NODE1_CLK_PG")
	)
	(segment
		(start 172.370242 -114.902742)
		(end 173.51756 -116.05006)
		(width 0.1016)
		(layer "F.Cu")
		(net "FM_CPLD_NODE1_CLK_PG")
	)
	(segment
		(start 164.457634 -112.77346)
		(end 167.77462 -112.77346)
		(width 0.1016)
		(layer "F.Cu")
		(net "FM_CPLD_NODE1_CLK_PG")
	)
	(segment
		(start 173.51756 -116.872766)
		(end 174.01032 -117.365526)
		(width 0.1016)
		(layer "F.Cu")
		(net "FM_CPLD_NODE1_CLK_PG")
	)
	(segment
		(start 160.995106 -115.073684)
		(end 162.15741 -115.073684)
		(width 0.1016)
		(layer "F.Cu")
		(net "FM_CPLD_NODE1_CLK_PG")
	)
	(segment
		(start 160.759394 -115.309396)
		(end 160.995106 -115.073684)
		(width 0.1016)
		(layer "F.Cu")
		(net "FM_CPLD_NODE1_CLK_PG")
	)
	(segment
		(start 155.072334 -118.226078)
		(end 157.989016 -115.309396)
		(width 0.1016)
		(layer "F.Cu")
		(net "FM_CPLD_NODE1_CLK_PG")
	)
	(segment
		(start 167.77462 -112.77346)
		(end 169.903902 -114.902742)
		(width 0.1016)
		(layer "F.Cu")
		(net "FM_CPLD_NODE1_CLK_PG")
	)
	(segment
		(start 147.02282 -113.840768)
		(end 150.470362 -113.840768)
		(width 0.1016)
		(layer "F.Cu")
		(net "FM_CPLD_NODE1_CLK_PG")
	)
	(segment
		(start 157.989016 -115.309396)
		(end 160.759394 -115.309396)
		(width 0.1016)
		(layer "F.Cu")
		(net "FM_CPLD_NODE1_CLK_PG")
	)
	(segment
		(start 153.632154 -118.226078)
		(end 155.072334 -118.226078)
		(width 0.1016)
		(layer "F.Cu")
		(net "FM_CPLD_NODE1_CLK_PG")
	)
	(via
		(at 147.02282 -113.840768)
		(size 0.508)
		(drill 0.254)
		(layers "F.Cu" "B.Cu")
		(net "FM_CPLD_NODE1_CLK_PG")
	)
	(via
		(at 126.445772 -111.82731)
		(size 0.508)
		(drill 0.254)
		(layers "F.Cu" "B.Cu")
		(net "FM_CPLD_NODE1_CLK_PG")
	)
	(segment
		(start 126.445772 -111.369602)
		(end 126.114302 -111.038132)
		(width 0.1143)
		(layer "In7.Cu")
		(net "FM_CPLD_NODE1_CLK_PG")
	)
	(segment
		(start 140.52804 -108.816394)
		(end 140.52804 -108.817664)
		(width 0.1143)
		(layer "In7.Cu")
		(net "FM_CPLD_NODE1_CLK_PG")
	)
	(segment
		(start 126.74473 -105.315512)
		(end 137.027158 -105.315512)
		(width 0.1143)
		(layer "In7.Cu")
		(net "FM_CPLD_NODE1_CLK_PG")
	)
	(segment
		(start 126.114302 -105.94594)
		(end 126.74473 -105.315512)
		(width 0.1143)
		(layer "In7.Cu")
		(net "FM_CPLD_NODE1_CLK_PG")
	)
	(segment
		(start 141.999716 -108.817664)
		(end 147.02282 -113.840768)
		(width 0.1143)
		(layer "In7.Cu")
		(net "FM_CPLD_NODE1_CLK_PG")
	)
	(segment
		(start 126.445772 -111.82731)
		(end 126.445772 -111.369602)
		(width 0.1143)
		(layer "In7.Cu")
		(net "FM_CPLD_NODE1_CLK_PG")
	)
	(segment
		(start 137.027158 -105.315512)
		(end 140.52804 -108.816394)
		(width 0.1143)
		(layer "In7.Cu")
		(net "FM_CPLD_NODE1_CLK_PG")
	)
	(segment
		(start 126.114302 -111.038132)
		(end 126.114302 -105.94594)
		(width 0.1143)
		(layer "In7.Cu")
		(net "FM_CPLD_NODE1_CLK_PG")
	)
	(segment
		(start 140.52804 -108.817664)
		(end 141.999716 -108.817664)
		(width 0.1143)
		(layer "In7.Cu")
		(net "FM_CPLD_NODE1_CLK_PG")
	)
	(segment
		(start 98.573082 -16.341344)
		(end 98.297746 -16.341344)
		(width 0.1016)
		(layer "F.Cu")
		(net "LPC_CPU_NODE1_LAD0")
	)
	(segment
		(start 98.98126 -15.933166)
		(end 98.573082 -16.341344)
		(width 0.1016)
		(layer "F.Cu")
		(net "LPC_CPU_NODE1_LAD0")
	)
	(segment
		(start 88.366346 -125.19152)
		(end 88.366346 -123.64847)
		(width 0.1016)
		(layer "F.Cu")
		(net "LPC_CPU_NODE1_LAD0")
	)
	(segment
		(start 88.366346 -123.64847)
		(end 88.44788 -123.566936)
		(width 0.1016)
		(layer "F.Cu")
		(net "LPC_CPU_NODE1_LAD0")
	)
	(segment
		(start 98.98126 -15.40891)
		(end 98.98126 -15.933166)
		(width 0.1016)
		(layer "F.Cu")
		(net "LPC_CPU_NODE1_LAD0")
	)
	(via
		(at 92.67952 -97.65157)
		(size 0.508)
		(drill 0.254)
		(layers "F.Cu" "B.Cu")
		(net "LPC_CPU_NODE1_LAD0")
	)
	(via
		(at 88.44788 -123.566936)
		(size 0.508)
		(drill 0.254)
		(layers "F.Cu" "B.Cu")
		(net "LPC_CPU_NODE1_LAD0")
	)
	(via
		(at 96.4565 -97.52711)
		(size 0.508)
		(drill 0.254)
		(layers "F.Cu" "B.Cu")
		(net "LPC_CPU_NODE1_LAD0")
	)
	(via
		(at 120.55602 -44.410122)
		(size 0.508)
		(drill 0.254)
		(layers "F.Cu" "B.Cu")
		(net "LPC_CPU_NODE1_LAD0")
	)
	(via
		(at 60.844684 -99.194112)
		(size 0.508)
		(drill 0.254)
		(layers "F.Cu" "B.Cu")
		(net "LPC_CPU_NODE1_LAD0")
	)
	(via
		(at 98.98126 -15.40891)
		(size 0.508)
		(drill 0.254)
		(layers "F.Cu" "B.Cu")
		(net "LPC_CPU_NODE1_LAD0")
	)
	(segment
		(start 121.212864 -44.410122)
		(end 120.55602 -44.410122)
		(width 0.1016)
		(layer "B.Cu")
		(net "LPC_CPU_NODE1_LAD0")
	)
	(segment
		(start 61.366146 -96.824038)
		(end 61.36259 -97.073466)
		(width 0.1016)
		(layer "B.Cu")
		(net "LPC_CPU_NODE1_LAD0")
	)
	(segment
		(start 61.36259 -98.388932)
		(end 60.844684 -98.906838)
		(width 0.1016)
		(layer "B.Cu")
		(net "LPC_CPU_NODE1_LAD0")
	)
	(segment
		(start 61.36259 -97.073466)
		(end 61.36259 -98.388932)
		(width 0.1016)
		(layer "B.Cu")
		(net "LPC_CPU_NODE1_LAD0")
	)
	(segment
		(start 60.844684 -98.906838)
		(end 60.844684 -99.194112)
		(width 0.1016)
		(layer "B.Cu")
		(net "LPC_CPU_NODE1_LAD0")
	)
	(segment
		(start 121.535444 -44.732702)
		(end 121.212864 -44.410122)
		(width 0.1016)
		(layer "B.Cu")
		(net "LPC_CPU_NODE1_LAD0")
	)
	(segment
		(start 121.69775 -44.732702)
		(end 121.535444 -44.732702)
		(width 0.1016)
		(layer "B.Cu")
		(net "LPC_CPU_NODE1_LAD0")
	)
	(segment
		(start 88.44788 -123.566936)
		(end 89.57183 -120.10771)
		(width 0.1143)
		(layer "In2.Cu")
		(net "LPC_CPU_NODE1_LAD0")
	)
	(segment
		(start 110.79226 -48.9331)
		(end 118.308882 -56.449722)
		(width 0.1143)
		(layer "In2.Cu")
		(net "LPC_CPU_NODE1_LAD0")
	)
	(segment
		(start 117.89156 -67.27317)
		(end 117.89156 -76.927456)
		(width 0.1143)
		(layer "In2.Cu")
		(net "LPC_CPU_NODE1_LAD0")
	)
	(segment
		(start 91.744546 -98.118168)
		(end 92.67952 -97.65157)
		(width 0.1143)
		(layer "In2.Cu")
		(net "LPC_CPU_NODE1_LAD0")
	)
	(segment
		(start 59.4106 -98.577908)
		(end 59.4106 -98.71456)
		(width 0.1143)
		(layer "In2.Cu")
		(net "LPC_CPU_NODE1_LAD0")
	)
	(segment
		(start 84.91728 -113.62309)
		(end 84.007198 -112.713008)
		(width 0.1143)
		(layer "In2.Cu")
		(net "LPC_CPU_NODE1_LAD0")
	)
	(segment
		(start 104.509824 -86.713568)
		(end 98.3234 -92.899992)
		(width 0.1143)
		(layer "In2.Cu")
		(net "LPC_CPU_NODE1_LAD0")
	)
	(segment
		(start 69.210936 -103.331772)
		(end 66.578226 -102.761288)
		(width 0.1143)
		(layer "In2.Cu")
		(net "LPC_CPU_NODE1_LAD0")
	)
	(segment
		(start 90.403934 -99.4537)
		(end 90.409014 -99.4537)
		(width 0.1143)
		(layer "In2.Cu")
		(net "LPC_CPU_NODE1_LAD0")
	)
	(segment
		(start 84.50834 -116.74348)
		(end 84.50834 -115.089686)
		(width 0.1143)
		(layer "In2.Cu")
		(net "LPC_CPU_NODE1_LAD0")
	)
	(segment
		(start 81.941924 -112.713008)
		(end 81.204816 -113.450116)
		(width 0.1143)
		(layer "In2.Cu")
		(net "LPC_CPU_NODE1_LAD0")
	)
	(segment
		(start 89.29624 -101.187758)
		(end 90.403934 -99.4537)
		(width 0.1143)
		(layer "In2.Cu")
		(net "LPC_CPU_NODE1_LAD0")
	)
	(segment
		(start 118.308882 -56.449722)
		(end 118.308882 -66.855848)
		(width 0.1143)
		(layer "In2.Cu")
		(net "LPC_CPU_NODE1_LAD0")
	)
	(segment
		(start 58.790078 -98.320606)
		(end 59.153298 -98.320606)
		(width 0.1143)
		(layer "In2.Cu")
		(net "LPC_CPU_NODE1_LAD0")
	)
	(segment
		(start 84.95538 -122.290332)
		(end 84.95538 -118.272052)
		(width 0.1143)
		(layer "In2.Cu")
		(net "LPC_CPU_NODE1_LAD0")
	)
	(segment
		(start 58.141362 -98.969322)
		(end 58.790078 -98.320606)
		(width 0.1143)
		(layer "In2.Cu")
		(net "LPC_CPU_NODE1_LAD0")
	)
	(segment
		(start 88.174576 -123.293632)
		(end 85.95868 -123.293632)
		(width 0.1143)
		(layer "In2.Cu")
		(net "LPC_CPU_NODE1_LAD0")
	)
	(segment
		(start 81.204816 -113.450116)
		(end 78.872842 -113.450116)
		(width 0.1143)
		(layer "In2.Cu")
		(net "LPC_CPU_NODE1_LAD0")
	)
	(segment
		(start 105.244138 -16.636238)
		(end 110.79226 -22.18436)
		(width 0.1143)
		(layer "In2.Cu")
		(net "LPC_CPU_NODE1_LAD0")
	)
	(segment
		(start 118.308882 -66.855848)
		(end 117.89156 -67.27317)
		(width 0.1143)
		(layer "In2.Cu")
		(net "LPC_CPU_NODE1_LAD0")
	)
	(segment
		(start 88.44788 -123.566936)
		(end 88.174576 -123.293632)
		(width 0.1143)
		(layer "In2.Cu")
		(net "LPC_CPU_NODE1_LAD0")
	)
	(segment
		(start 59.890152 -99.194112)
		(end 60.844684 -99.194112)
		(width 0.1143)
		(layer "In2.Cu")
		(net "LPC_CPU_NODE1_LAD0")
	)
	(segment
		(start 58.114692 -99.74961)
		(end 58.114692 -99.052888)
		(width 0.1143)
		(layer "In2.Cu")
		(net "LPC_CPU_NODE1_LAD0")
	)
	(segment
		(start 98.98126 -15.40891)
		(end 99.17684 -15.60449)
		(width 0.1143)
		(layer "In2.Cu")
		(net "LPC_CPU_NODE1_LAD0")
	)
	(segment
		(start 89.57183 -110.00232)
		(end 87.664798 -108.095288)
		(width 0.1143)
		(layer "In2.Cu")
		(net "LPC_CPU_NODE1_LAD0")
	)
	(segment
		(start 73.264014 -103.331772)
		(end 69.210936 -103.331772)
		(width 0.1143)
		(layer "In2.Cu")
		(net "LPC_CPU_NODE1_LAD0")
	)
	(segment
		(start 96.744028 -97.354898)
		(end 96.628712 -97.354898)
		(width 0.1143)
		(layer "In2.Cu")
		(net "LPC_CPU_NODE1_LAD0")
	)
	(segment
		(start 65.68186 -102.216966)
		(end 64.949832 -101.484938)
		(width 0.1143)
		(layer "In2.Cu")
		(net "LPC_CPU_NODE1_LAD0")
	)
	(segment
		(start 89.29624 -101.195632)
		(end 89.29624 -101.187758)
		(width 0.1143)
		(layer "In2.Cu")
		(net "LPC_CPU_NODE1_LAD0")
	)
	(segment
		(start 66.033904 -102.216966)
		(end 65.68186 -102.216966)
		(width 0.1143)
		(layer "In2.Cu")
		(net "LPC_CPU_NODE1_LAD0")
	)
	(segment
		(start 84.50834 -115.089686)
		(end 84.91728 -114.680746)
		(width 0.1143)
		(layer "In2.Cu")
		(net "LPC_CPU_NODE1_LAD0")
	)
	(segment
		(start 103.43388 -16.096996)
		(end 105.244138 -16.636238)
		(width 0.1143)
		(layer "In2.Cu")
		(net "LPC_CPU_NODE1_LAD0")
	)
	(segment
		(start 78.872842 -113.450116)
		(end 76.01458 -110.591854)
		(width 0.1143)
		(layer "In2.Cu")
		(net "LPC_CPU_NODE1_LAD0")
	)
	(segment
		(start 84.95538 -118.272052)
		(end 84.50834 -116.74348)
		(width 0.1143)
		(layer "In2.Cu")
		(net "LPC_CPU_NODE1_LAD0")
	)
	(segment
		(start 99.17684 -15.60449)
		(end 100.525072 -16.096996)
		(width 0.1143)
		(layer "In2.Cu")
		(net "LPC_CPU_NODE1_LAD0")
	)
	(segment
		(start 89.57183 -120.10771)
		(end 89.57183 -110.00232)
		(width 0.1143)
		(layer "In2.Cu")
		(net "LPC_CPU_NODE1_LAD0")
	)
	(segment
		(start 76.01458 -106.082338)
		(end 73.264014 -103.331772)
		(width 0.1143)
		(layer "In2.Cu")
		(net "LPC_CPU_NODE1_LAD0")
	)
	(segment
		(start 98.3234 -92.899992)
		(end 98.3234 -95.775526)
		(width 0.1143)
		(layer "In2.Cu")
		(net "LPC_CPU_NODE1_LAD0")
	)
	(segment
		(start 110.79226 -22.18436)
		(end 110.79226 -48.9331)
		(width 0.1143)
		(layer "In2.Cu")
		(net "LPC_CPU_NODE1_LAD0")
	)
	(segment
		(start 100.525072 -16.096996)
		(end 103.43388 -16.096996)
		(width 0.1143)
		(layer "In2.Cu")
		(net "LPC_CPU_NODE1_LAD0")
	)
	(segment
		(start 98.3234 -95.775526)
		(end 96.744028 -97.354898)
		(width 0.1143)
		(layer "In2.Cu")
		(net "LPC_CPU_NODE1_LAD0")
	)
	(segment
		(start 90.409014 -99.4537)
		(end 91.744546 -98.118168)
		(width 0.1143)
		(layer "In2.Cu")
		(net "LPC_CPU_NODE1_LAD0")
	)
	(segment
		(start 87.664798 -108.095288)
		(end 87.664798 -102.827074)
		(width 0.1143)
		(layer "In2.Cu")
		(net "LPC_CPU_NODE1_LAD0")
	)
	(segment
		(start 117.89156 -76.927456)
		(end 108.105448 -86.713568)
		(width 0.1143)
		(layer "In2.Cu")
		(net "LPC_CPU_NODE1_LAD0")
	)
	(segment
		(start 58.98896 -101.149912)
		(end 58.587386 -100.748338)
		(width 0.1143)
		(layer "In2.Cu")
		(net "LPC_CPU_NODE1_LAD0")
	)
	(segment
		(start 85.95868 -123.293632)
		(end 84.95538 -122.290332)
		(width 0.1143)
		(layer "In2.Cu")
		(net "LPC_CPU_NODE1_LAD0")
	)
	(segment
		(start 96.628712 -97.354898)
		(end 96.4565 -97.52711)
		(width 0.1143)
		(layer "In2.Cu")
		(net "LPC_CPU_NODE1_LAD0")
	)
	(segment
		(start 108.105448 -86.713568)
		(end 104.509824 -86.713568)
		(width 0.1143)
		(layer "In2.Cu")
		(net "LPC_CPU_NODE1_LAD0")
	)
	(segment
		(start 64.949832 -101.484938)
		(end 60.097416 -101.484938)
		(width 0.1143)
		(layer "In2.Cu")
		(net "LPC_CPU_NODE1_LAD0")
	)
	(segment
		(start 76.01458 -110.591854)
		(end 76.01458 -106.082338)
		(width 0.1143)
		(layer "In2.Cu")
		(net "LPC_CPU_NODE1_LAD0")
	)
	(segment
		(start 58.114692 -99.052888)
		(end 58.141362 -98.969322)
		(width 0.1143)
		(layer "In2.Cu")
		(net "LPC_CPU_NODE1_LAD0")
	)
	(segment
		(start 60.097416 -101.484938)
		(end 58.98896 -101.149912)
		(width 0.1143)
		(layer "In2.Cu")
		(net "LPC_CPU_NODE1_LAD0")
	)
	(segment
		(start 58.587386 -100.748338)
		(end 58.114692 -99.74961)
		(width 0.1143)
		(layer "In2.Cu")
		(net "LPC_CPU_NODE1_LAD0")
	)
	(segment
		(start 66.578226 -102.761288)
		(end 66.033904 -102.216966)
		(width 0.1143)
		(layer "In2.Cu")
		(net "LPC_CPU_NODE1_LAD0")
	)
	(segment
		(start 87.664798 -102.827074)
		(end 89.29624 -101.195632)
		(width 0.1143)
		(layer "In2.Cu")
		(net "LPC_CPU_NODE1_LAD0")
	)
	(segment
		(start 84.007198 -112.713008)
		(end 81.941924 -112.713008)
		(width 0.1143)
		(layer "In2.Cu")
		(net "LPC_CPU_NODE1_LAD0")
	)
	(segment
		(start 59.4106 -98.71456)
		(end 59.890152 -99.194112)
		(width 0.1143)
		(layer "In2.Cu")
		(net "LPC_CPU_NODE1_LAD0")
	)
	(segment
		(start 84.91728 -114.680746)
		(end 84.91728 -113.62309)
		(width 0.1143)
		(layer "In2.Cu")
		(net "LPC_CPU_NODE1_LAD0")
	)
	(segment
		(start 59.153298 -98.320606)
		(end 59.4106 -98.577908)
		(width 0.1143)
		(layer "In2.Cu")
		(net "LPC_CPU_NODE1_LAD0")
	)
	(segment
		(start 98.98126 -15.40891)
		(end 98.98126 -15.244826)
		(width 0.1143)
		(layer "In7.Cu")
		(net "LPC_CPU_NODE1_LAD0")
	)
	(segment
		(start 115.5827 -30.159706)
		(end 115.5827 -31.787084)
		(width 0.1143)
		(layer "In7.Cu")
		(net "LPC_CPU_NODE1_LAD0")
	)
	(segment
		(start 92.67952 -97.65157)
		(end 92.813632 -97.517458)
		(width 0.1143)
		(layer "In7.Cu")
		(net "LPC_CPU_NODE1_LAD0")
	)
	(segment
		(start 120.758712 -44.410122)
		(end 120.55602 -44.410122)
		(width 0.1143)
		(layer "In7.Cu")
		(net "LPC_CPU_NODE1_LAD0")
	)
	(segment
		(start 98.98126 -15.244826)
		(end 99.546664 -14.679422)
		(width 0.1143)
		(layer "In7.Cu")
		(net "LPC_CPU_NODE1_LAD0")
	)
	(segment
		(start 92.813632 -97.517458)
		(end 96.446848 -97.517458)
		(width 0.1143)
		(layer "In7.Cu")
		(net "LPC_CPU_NODE1_LAD0")
	)
	(segment
		(start 104.180386 -14.679422)
		(end 111.78794 -22.286976)
		(width 0.1143)
		(layer "In7.Cu")
		(net "LPC_CPU_NODE1_LAD0")
	)
	(segment
		(start 121.878852 -43.289982)
		(end 120.758712 -44.410122)
		(width 0.1143)
		(layer "In7.Cu")
		(net "LPC_CPU_NODE1_LAD0")
	)
	(segment
		(start 99.546664 -14.679422)
		(end 104.180386 -14.679422)
		(width 0.1143)
		(layer "In7.Cu")
		(net "LPC_CPU_NODE1_LAD0")
	)
	(segment
		(start 115.5827 -31.787084)
		(end 121.878852 -38.083236)
		(width 0.1143)
		(layer "In7.Cu")
		(net "LPC_CPU_NODE1_LAD0")
	)
	(segment
		(start 96.446848 -97.517458)
		(end 96.4565 -97.52711)
		(width 0.1143)
		(layer "In7.Cu")
		(net "LPC_CPU_NODE1_LAD0")
	)
	(segment
		(start 111.78794 -26.364946)
		(end 115.5827 -30.159706)
		(width 0.1143)
		(layer "In7.Cu")
		(net "LPC_CPU_NODE1_LAD0")
	)
	(segment
		(start 111.78794 -22.286976)
		(end 111.78794 -26.364946)
		(width 0.1143)
		(layer "In7.Cu")
		(net "LPC_CPU_NODE1_LAD0")
	)
	(segment
		(start 121.878852 -38.083236)
		(end 121.878852 -43.289982)
		(width 0.1143)
		(layer "In7.Cu")
		(net "LPC_CPU_NODE1_LAD0")
	)
	(segment
		(start 60.456826 -66.598038)
		(end 60.484258 -66.598038)
		(width 0.127)
		(layer "F.Cu")
		(net "M_DDR3_NODE1_MON2N")
	)
	(segment
		(start 60.484258 -66.598038)
		(end 60.850526 -66.964306)
		(width 0.127)
		(layer "F.Cu")
		(net "M_DDR3_NODE1_MON2N")
	)
	(via
		(at 60.850526 -66.964306)
		(size 0.508)
		(drill 0.254)
		(layers "F.Cu" "B.Cu")
		(net "M_DDR3_NODE1_MON2N")
	)
	(via
		(at 62.006988 -63.746888)
		(size 0.508)
		(drill 0.254)
		(layers "F.Cu" "B.Cu")
		(net "M_DDR3_NODE1_MON2N")
	)
	(segment
		(start 60.850526 -66.964306)
		(end 60.391802 -66.505582)
		(width 0.17018)
		(layer "B.Cu")
		(net "M_DDR3_NODE1_MON2N")
	)
	(segment
		(start 62.006988 -64.207136)
		(end 62.006988 -63.746888)
		(width 0.17018)
		(layer "B.Cu")
		(net "M_DDR3_NODE1_MON2N")
	)
	(segment
		(start 62.006988 -62.81928)
		(end 62.006988 -63.746888)
		(width 0.17018)
		(layer "B.Cu")
		(net "M_DDR3_NODE1_MON2N")
	)
	(segment
		(start 61.574934 -64.640206)
		(end 62.006988 -64.207136)
		(width 0.17018)
		(layer "B.Cu")
		(net "M_DDR3_NODE1_MON2N")
	)
	(segment
		(start 60.391802 -66.505582)
		(end 60.391802 -65.25006)
		(width 0.17018)
		(layer "B.Cu")
		(net "M_DDR3_NODE1_MON2N")
	)
	(segment
		(start 61.231018 -64.983868)
		(end 61.574934 -64.640206)
		(width 0.17018)
		(layer "B.Cu")
		(net "M_DDR3_NODE1_MON2N")
	)
	(segment
		(start 62.021466 -61.788802)
		(end 62.021466 -62.279022)
		(width 0.17018)
		(layer "B.Cu")
		(net "M_DDR3_NODE1_MON2N")
	)
	(segment
		(start 62.284356 -62.541912)
		(end 62.006988 -62.81928)
		(width 0.17018)
		(layer "B.Cu")
		(net "M_DDR3_NODE1_MON2N")
	)
	(segment
		(start 62.284356 -61.525912)
		(end 62.021466 -61.788802)
		(width 0.17018)
		(layer "B.Cu")
		(net "M_DDR3_NODE1_MON2N")
	)
	(segment
		(start 60.391802 -65.25006)
		(end 60.657994 -64.983868)
		(width 0.17018)
		(layer "B.Cu")
		(net "M_DDR3_NODE1_MON2N")
	)
	(segment
		(start 60.657994 -64.983868)
		(end 61.231018 -64.983868)
		(width 0.17018)
		(layer "B.Cu")
		(net "M_DDR3_NODE1_MON2N")
	)
	(segment
		(start 62.021466 -62.279022)
		(end 62.284356 -62.541912)
		(width 0.17018)
		(layer "B.Cu")
		(net "M_DDR3_NODE1_MON2N")
	)
	(segment
		(start 103.498142 -157.06217)
		(end 103.091742 -156.65577)
		(width 0.254)
		(layer "F.Cu")
		(net "PWRGD_NODE1_P1V8_STB_PG")
	)
	(segment
		(start 104.514142 -157.877002)
		(end 103.498142 -157.877002)
		(width 0.254)
		(layer "F.Cu")
		(net "PWRGD_NODE1_P1V8_STB_PG")
	)
	(segment
		(start 180.010562 -119.365522)
		(end 180.010562 -119.36603)
		(width 0.1016)
		(layer "F.Cu")
		(net "PWRGD_NODE1_P1V8_STB_PG")
	)
	(segment
		(start 103.091742 -156.65577)
		(end 103.091742 -156.249878)
		(width 0.254)
		(layer "F.Cu")
		(net "PWRGD_NODE1_P1V8_STB_PG")
	)
	(segment
		(start 180.010562 -119.36603)
		(end 180.510434 -119.865902)
		(width 0.1016)
		(layer "F.Cu")
		(net "PWRGD_NODE1_P1V8_STB_PG")
	)
	(segment
		(start 104.514142 -157.408118)
		(end 104.514142 -157.877002)
		(width 0.254)
		(layer "F.Cu")
		(net "PWRGD_NODE1_P1V8_STB_PG")
	)
	(segment
		(start 104.16159 -157.055566)
		(end 104.514142 -157.408118)
		(width 0.254)
		(layer "F.Cu")
		(net "PWRGD_NODE1_P1V8_STB_PG")
	)
	(segment
		(start 103.498142 -157.877002)
		(end 103.498142 -157.06217)
		(width 0.254)
		(layer "F.Cu")
		(net "PWRGD_NODE1_P1V8_STB_PG")
	)
	(via
		(at 104.16159 -157.055566)
		(size 0.508)
		(drill 0.254)
		(layers "F.Cu" "B.Cu")
		(net "PWRGD_NODE1_P1V8_STB_PG")
	)
	(via
		(at 180.510434 -119.865902)
		(size 0.49022)
		(drill 0.254)
		(layers "F.Cu" "B.Cu")
		(net "PWRGD_NODE1_P1V8_STB_PG")
	)
	(via
		(at 145.98142 -158.882334)
		(size 0.508)
		(drill 0.254)
		(layers "F.Cu" "B.Cu")
		(net "PWRGD_NODE1_P1V8_STB_PG")
	)
	(segment
		(start 152.22474 -151.18715)
		(end 152.22474 -142.169896)
		(width 0.1143)
		(layer "In2.Cu")
		(net "PWRGD_NODE1_P1V8_STB_PG")
	)
	(segment
		(start 150.016718 -153.413968)
		(end 150.62454 -153.413968)
		(width 0.1143)
		(layer "In2.Cu")
		(net "PWRGD_NODE1_P1V8_STB_PG")
	)
	(segment
		(start 173.587664 -120.387364)
		(end 179.988972 -120.387364)
		(width 0.1143)
		(layer "In2.Cu")
		(net "PWRGD_NODE1_P1V8_STB_PG")
	)
	(segment
		(start 151.2824 -152.12949)
		(end 152.22474 -151.18715)
		(width 0.1143)
		(layer "In2.Cu")
		(net "PWRGD_NODE1_P1V8_STB_PG")
	)
	(segment
		(start 151.2824 -152.756108)
		(end 151.2824 -152.12949)
		(width 0.1143)
		(layer "In2.Cu")
		(net "PWRGD_NODE1_P1V8_STB_PG")
	)
	(segment
		(start 156.535882 -135.189468)
		(end 158.834582 -135.189468)
		(width 0.1143)
		(layer "In2.Cu")
		(net "PWRGD_NODE1_P1V8_STB_PG")
	)
	(segment
		(start 164.28593 -134.6581)
		(end 165.34384 -133.60019)
		(width 0.1143)
		(layer "In2.Cu")
		(net "PWRGD_NODE1_P1V8_STB_PG")
	)
	(segment
		(start 165.34384 -129.924048)
		(end 165.41623 -129.851404)
		(width 0.1143)
		(layer "In2.Cu")
		(net "PWRGD_NODE1_P1V8_STB_PG")
	)
	(segment
		(start 165.41623 -129.851404)
		(end 166.93642 -128.331214)
		(width 0.1143)
		(layer "In2.Cu")
		(net "PWRGD_NODE1_P1V8_STB_PG")
	)
	(segment
		(start 148.54174 -154.888946)
		(end 150.016718 -153.413968)
		(width 0.1143)
		(layer "In2.Cu")
		(net "PWRGD_NODE1_P1V8_STB_PG")
	)
	(segment
		(start 166.93642 -128.331214)
		(end 166.93642 -127.038608)
		(width 0.1143)
		(layer "In2.Cu")
		(net "PWRGD_NODE1_P1V8_STB_PG")
	)
	(segment
		(start 152.22474 -142.169896)
		(end 152.36825 -142.026386)
		(width 0.1143)
		(layer "In2.Cu")
		(net "PWRGD_NODE1_P1V8_STB_PG")
	)
	(segment
		(start 152.36825 -142.026386)
		(end 152.36825 -139.3571)
		(width 0.1143)
		(layer "In2.Cu")
		(net "PWRGD_NODE1_P1V8_STB_PG")
	)
	(segment
		(start 145.98142 -158.882334)
		(end 148.54174 -156.322014)
		(width 0.1143)
		(layer "In2.Cu")
		(net "PWRGD_NODE1_P1V8_STB_PG")
	)
	(segment
		(start 148.54174 -156.322014)
		(end 148.54174 -154.888946)
		(width 0.1143)
		(layer "In2.Cu")
		(net "PWRGD_NODE1_P1V8_STB_PG")
	)
	(segment
		(start 158.834582 -135.189468)
		(end 159.36595 -134.6581)
		(width 0.1143)
		(layer "In2.Cu")
		(net "PWRGD_NODE1_P1V8_STB_PG")
	)
	(segment
		(start 166.93642 -127.038608)
		(end 173.587664 -120.387364)
		(width 0.1143)
		(layer "In2.Cu")
		(net "PWRGD_NODE1_P1V8_STB_PG")
	)
	(segment
		(start 179.988972 -120.387364)
		(end 180.510434 -119.865902)
		(width 0.1143)
		(layer "In2.Cu")
		(net "PWRGD_NODE1_P1V8_STB_PG")
	)
	(segment
		(start 165.34384 -133.60019)
		(end 165.34384 -129.924048)
		(width 0.1143)
		(layer "In2.Cu")
		(net "PWRGD_NODE1_P1V8_STB_PG")
	)
	(segment
		(start 150.62454 -153.413968)
		(end 151.2824 -152.756108)
		(width 0.1143)
		(layer "In2.Cu")
		(net "PWRGD_NODE1_P1V8_STB_PG")
	)
	(segment
		(start 152.36825 -139.3571)
		(end 156.535882 -135.189468)
		(width 0.1143)
		(layer "In2.Cu")
		(net "PWRGD_NODE1_P1V8_STB_PG")
	)
	(segment
		(start 159.36595 -134.6581)
		(end 164.28593 -134.6581)
		(width 0.1143)
		(layer "In2.Cu")
		(net "PWRGD_NODE1_P1V8_STB_PG")
	)
	(segment
		(start 119.59336 -160.21558)
		(end 122.22353 -157.58541)
		(width 0.1143)
		(layer "In6.Cu")
		(net "PWRGD_NODE1_P1V8_STB_PG")
	)
	(segment
		(start 137.188448 -157.099508)
		(end 142.418562 -157.099508)
		(width 0.1143)
		(layer "In6.Cu")
		(net "PWRGD_NODE1_P1V8_STB_PG")
	)
	(segment
		(start 105.750614 -158.64459)
		(end 107.766358 -158.64459)
		(width 0.1143)
		(layer "In6.Cu")
		(net "PWRGD_NODE1_P1V8_STB_PG")
	)
	(segment
		(start 111.75111 -159.828992)
		(end 112.137698 -160.21558)
		(width 0.1143)
		(layer "In6.Cu")
		(net "PWRGD_NODE1_P1V8_STB_PG")
	)
	(segment
		(start 107.766358 -158.64459)
		(end 108.95076 -159.828992)
		(width 0.1143)
		(layer "In6.Cu")
		(net "PWRGD_NODE1_P1V8_STB_PG")
	)
	(segment
		(start 108.95076 -159.828992)
		(end 111.75111 -159.828992)
		(width 0.1143)
		(layer "In6.Cu")
		(net "PWRGD_NODE1_P1V8_STB_PG")
	)
	(segment
		(start 112.137698 -160.21558)
		(end 119.59336 -160.21558)
		(width 0.1143)
		(layer "In6.Cu")
		(net "PWRGD_NODE1_P1V8_STB_PG")
	)
	(segment
		(start 136.702546 -157.58541)
		(end 137.188448 -157.099508)
		(width 0.1143)
		(layer "In6.Cu")
		(net "PWRGD_NODE1_P1V8_STB_PG")
	)
	(segment
		(start 143.7132 -158.394146)
		(end 145.493232 -158.394146)
		(width 0.1143)
		(layer "In6.Cu")
		(net "PWRGD_NODE1_P1V8_STB_PG")
	)
	(segment
		(start 122.22353 -157.58541)
		(end 136.702546 -157.58541)
		(width 0.1143)
		(layer "In6.Cu")
		(net "PWRGD_NODE1_P1V8_STB_PG")
	)
	(segment
		(start 104.16159 -157.055566)
		(end 105.750614 -158.64459)
		(width 0.1143)
		(layer "In6.Cu")
		(net "PWRGD_NODE1_P1V8_STB_PG")
	)
	(segment
		(start 142.418562 -157.099508)
		(end 143.7132 -158.394146)
		(width 0.1143)
		(layer "In6.Cu")
		(net "PWRGD_NODE1_P1V8_STB_PG")
	)
	(segment
		(start 145.493232 -158.394146)
		(end 145.98142 -158.882334)
		(width 0.1143)
		(layer "In6.Cu")
		(net "PWRGD_NODE1_P1V8_STB_PG")
	)
	(segment
		(start 70.941692 -126.997206)
		(end 71.319136 -126.619762)
		(width 0.127)
		(layer "F.Cu")
		(net "P2E_CPU_BMC_NODE1_RX_C_DN")
	)
	(segment
		(start 70.941692 -127.259588)
		(end 70.941692 -126.997206)
		(width 0.127)
		(layer "F.Cu")
		(net "P2E_CPU_BMC_NODE1_RX_C_DN")
	)
	(segment
		(start 73.078086 -124.582936)
		(end 73.078086 -122.839226)
		(width 0.127)
		(layer "F.Cu")
		(net "P2E_CPU_BMC_NODE1_RX_C_DN")
	)
	(segment
		(start 73.078086 -121.013728)
		(end 73.078086 -122.839226)
		(width 0.127)
		(layer "F.Cu")
		(net "P2E_CPU_BMC_NODE1_RX_C_DN")
	)
	(segment
		(start 74.774806 -120.964706)
		(end 74.435462 -120.625362)
		(width 0.127)
		(layer "F.Cu")
		(net "P2E_CPU_BMC_NODE1_RX_C_DN")
	)
	(segment
		(start 71.319136 -126.341886)
		(end 73.078086 -124.582936)
		(width 0.127)
		(layer "F.Cu")
		(net "P2E_CPU_BMC_NODE1_RX_C_DN")
	)
	(segment
		(start 71.319136 -126.619762)
		(end 71.319136 -126.341886)
		(width 0.127)
		(layer "F.Cu")
		(net "P2E_CPU_BMC_NODE1_RX_C_DN")
	)
	(segment
		(start 74.435462 -120.625362)
		(end 73.466452 -120.625362)
		(width 0.127)
		(layer "F.Cu")
		(net "P2E_CPU_BMC_NODE1_RX_C_DN")
	)
	(segment
		(start 73.466452 -120.625362)
		(end 73.078086 -121.013728)
		(width 0.127)
		(layer "F.Cu")
		(net "P2E_CPU_BMC_NODE1_RX_C_DN")
	)
	(via
		(at 73.078086 -122.839226)
		(size 0.4064)
		(drill 0.2032)
		(layers "F.Cu" "B.Cu")
		(net "P2E_CPU_BMC_NODE1_RX_C_DN")
	)
	(segment
		(start 72.614028 -121.887488)
		(end 72.614028 -121.604786)
		(width 0.127)
		(layer "F.Cu")
		(net "P2E_CPU_BMC_NODE1_RX_C_DP")
	)
	(segment
		(start 72.608186 -123.007628)
		(end 72.608186 -122.69851)
		(width 0.127)
		(layer "F.Cu")
		(net "P2E_CPU_BMC_NODE1_RX_C_DP")
	)
	(segment
		(start 70.941692 -126.459488)
		(end 70.941692 -126.288038)
		(width 0.127)
		(layer "F.Cu")
		(net "P2E_CPU_BMC_NODE1_RX_C_DP")
	)
	(segment
		(start 72.773286 -123.172728)
		(end 72.608186 -123.007628)
		(width 0.127)
		(layer "F.Cu")
		(net "P2E_CPU_BMC_NODE1_RX_C_DP")
	)
	(segment
		(start 72.773286 -121.445528)
		(end 72.773286 -120.887236)
		(width 0.127)
		(layer "F.Cu")
		(net "P2E_CPU_BMC_NODE1_RX_C_DP")
	)
	(segment
		(start 72.608186 -122.69851)
		(end 72.773286 -122.53341)
		(width 0.127)
		(layer "F.Cu")
		(net "P2E_CPU_BMC_NODE1_RX_C_DP")
	)
	(segment
		(start 70.941692 -126.288038)
		(end 72.773286 -124.456444)
		(width 0.127)
		(layer "F.Cu")
		(net "P2E_CPU_BMC_NODE1_RX_C_DP")
	)
	(segment
		(start 73.33996 -120.320562)
		(end 73.78446 -120.320562)
		(width 0.127)
		(layer "F.Cu")
		(net "P2E_CPU_BMC_NODE1_RX_C_DP")
	)
	(segment
		(start 72.773286 -120.887236)
		(end 73.33996 -120.320562)
		(width 0.127)
		(layer "F.Cu")
		(net "P2E_CPU_BMC_NODE1_RX_C_DP")
	)
	(segment
		(start 72.773286 -122.046746)
		(end 72.614028 -121.887488)
		(width 0.127)
		(layer "F.Cu")
		(net "P2E_CPU_BMC_NODE1_RX_C_DP")
	)
	(segment
		(start 74.78522 -119.870728)
		(end 74.335386 -120.320562)
		(width 0.127)
		(layer "F.Cu")
		(net "P2E_CPU_BMC_NODE1_RX_C_DP")
	)
	(segment
		(start 74.335386 -120.320562)
		(end 73.78446 -120.320562)
		(width 0.127)
		(layer "F.Cu")
		(net "P2E_CPU_BMC_NODE1_RX_C_DP")
	)
	(segment
		(start 72.773286 -122.53341)
		(end 72.773286 -122.046746)
		(width 0.127)
		(layer "F.Cu")
		(net "P2E_CPU_BMC_NODE1_RX_C_DP")
	)
	(segment
		(start 72.614028 -121.604786)
		(end 72.773286 -121.445528)
		(width 0.127)
		(layer "F.Cu")
		(net "P2E_CPU_BMC_NODE1_RX_C_DP")
	)
	(segment
		(start 72.773286 -124.456444)
		(end 72.773286 -123.172728)
		(width 0.127)
		(layer "F.Cu")
		(net "P2E_CPU_BMC_NODE1_RX_C_DP")
	)
	(via
		(at 73.78446 -120.320562)
		(size 0.4064)
		(drill 0.2032)
		(layers "F.Cu" "B.Cu")
		(net "P2E_CPU_BMC_NODE1_RX_C_DP")
	)
	(segment
		(start 34.392362 -4.867148)
		(end 33.06953 -4.867148)
		(width 0.508)
		(layer "F.Cu")
		(net "VR_NODE1_VDDR_1V5_CNTL")
	)
	(segment
		(start 70.583044 -84.214462)
		(end 70.583044 -84.257642)
		(width 0.254)
		(layer "F.Cu")
		(net "VR_NODE1_VDDR_1V5_CNTL")
	)
	(segment
		(start 70.583044 -84.257642)
		(end 71.048372 -84.72297)
		(width 0.254)
		(layer "F.Cu")
		(net "VR_NODE1_VDDR_1V5_CNTL")
	)
	(segment
		(start 71.048372 -84.72297)
		(end 71.048372 -84.758276)
		(width 0.254)
		(layer "F.Cu")
		(net "VR_NODE1_VDDR_1V5_CNTL")
	)
	(via
		(at 86.2965 -18.639282)
		(size 0.508)
		(drill 0.254)
		(layers "F.Cu" "B.Cu")
		(net "VR_NODE1_VDDR_1V5_CNTL")
	)
	(via
		(at 33.06953 -4.867148)
		(size 0.508)
		(drill 0.254)
		(layers "F.Cu" "B.Cu")
		(net "VR_NODE1_VDDR_1V5_CNTL")
	)
	(via
		(at 71.048372 -84.758276)
		(size 0.508)
		(drill 0.254)
		(layers "F.Cu" "B.Cu")
		(net "VR_NODE1_VDDR_1V5_CNTL")
	)
	(via
		(at 99.08032 -84.22005)
		(size 0.508)
		(drill 0.254)
		(layers "F.Cu" "B.Cu")
		(net "VR_NODE1_VDDR_1V5_CNTL")
	)
	(segment
		(start 71.225156 -83.960208)
		(end 71.048372 -84.136992)
		(width 0.508)
		(layer "B.Cu")
		(net "VR_NODE1_VDDR_1V5_CNTL")
	)
	(segment
		(start 71.048372 -84.136992)
		(end 71.048372 -84.758276)
		(width 0.508)
		(layer "B.Cu")
		(net "VR_NODE1_VDDR_1V5_CNTL")
	)
	(segment
		(start 35.140138 -20.271486)
		(end 35.38474 -20.027138)
		(width 0.508)
		(layer "B.Cu")
		(net "VR_NODE1_VDDR_1V5_CNTL")
	)
	(segment
		(start 85.3948 -17.737582)
		(end 86.2965 -18.639282)
		(width 0.508)
		(layer "B.Cu")
		(net "VR_NODE1_VDDR_1V5_CNTL")
	)
	(segment
		(start 30.8102 -7.126478)
		(end 30.8102 -15.941548)
		(width 0.508)
		(layer "B.Cu")
		(net "VR_NODE1_VDDR_1V5_CNTL")
	)
	(segment
		(start 35.91306 -20.027138)
		(end 35.91306 -20.028154)
		(width 0.508)
		(layer "B.Cu")
		(net "VR_NODE1_VDDR_1V5_CNTL")
	)
	(segment
		(start 36.210748 -20.325842)
		(end 42.77868 -20.325842)
		(width 0.508)
		(layer "B.Cu")
		(net "VR_NODE1_VDDR_1V5_CNTL")
	)
	(segment
		(start 35.38474 -20.027138)
		(end 35.91306 -20.027138)
		(width 0.508)
		(layer "B.Cu")
		(net "VR_NODE1_VDDR_1V5_CNTL")
	)
	(segment
		(start 71.245476 -83.960208)
		(end 71.225156 -83.960208)
		(width 0.508)
		(layer "B.Cu")
		(net "VR_NODE1_VDDR_1V5_CNTL")
	)
	(segment
		(start 30.8102 -15.941548)
		(end 35.140138 -20.271486)
		(width 0.508)
		(layer "B.Cu")
		(net "VR_NODE1_VDDR_1V5_CNTL")
	)
	(segment
		(start 65.206118 -19.484848)
		(end 66.953384 -17.737582)
		(width 0.508)
		(layer "B.Cu")
		(net "VR_NODE1_VDDR_1V5_CNTL")
	)
	(segment
		(start 33.06953 -4.867148)
		(end 30.8102 -7.126478)
		(width 0.508)
		(layer "B.Cu")
		(net "VR_NODE1_VDDR_1V5_CNTL")
	)
	(segment
		(start 43.619674 -19.484848)
		(end 65.206118 -19.484848)
		(width 0.508)
		(layer "B.Cu")
		(net "VR_NODE1_VDDR_1V5_CNTL")
	)
	(segment
		(start 42.77868 -20.325842)
		(end 43.619674 -19.484848)
		(width 0.508)
		(layer "B.Cu")
		(net "VR_NODE1_VDDR_1V5_CNTL")
	)
	(segment
		(start 66.953384 -17.737582)
		(end 85.3948 -17.737582)
		(width 0.508)
		(layer "B.Cu")
		(net "VR_NODE1_VDDR_1V5_CNTL")
	)
	(segment
		(start 35.91306 -20.028154)
		(end 36.210748 -20.325842)
		(width 0.508)
		(layer "B.Cu")
		(net "VR_NODE1_VDDR_1V5_CNTL")
	)
	(segment
		(start 88.474296 -20.817078)
		(end 102.927658 -20.817078)
		(width 0.508)
		(layer "In2.Cu")
		(net "VR_NODE1_VDDR_1V5_CNTL")
	)
	(segment
		(start 106.644948 -30.002988)
		(end 105.85196 -30.795976)
		(width 0.508)
		(layer "In2.Cu")
		(net "VR_NODE1_VDDR_1V5_CNTL")
	)
	(segment
		(start 113.811304 -59.808618)
		(end 114.10442 -60.101734)
		(width 0.508)
		(layer "In2.Cu")
		(net "VR_NODE1_VDDR_1V5_CNTL")
	)
	(segment
		(start 107.496102 -83.760564)
		(end 99.539806 -83.760564)
		(width 0.508)
		(layer "In2.Cu")
		(net "VR_NODE1_VDDR_1V5_CNTL")
	)
	(segment
		(start 114.11966 -71.235824)
		(end 114.11966 -77.137006)
		(width 0.508)
		(layer "In2.Cu")
		(net "VR_NODE1_VDDR_1V5_CNTL")
	)
	(segment
		(start 114.89944 -70.456044)
		(end 114.11966 -71.235824)
		(width 0.508)
		(layer "In2.Cu")
		(net "VR_NODE1_VDDR_1V5_CNTL")
	)
	(segment
		(start 114.89944 -66.93154)
		(end 114.89944 -70.456044)
		(width 0.508)
		(layer "In2.Cu")
		(net "VR_NODE1_VDDR_1V5_CNTL")
	)
	(segment
		(start 113.811304 -56.236362)
		(end 113.811304 -59.808618)
		(width 0.508)
		(layer "In2.Cu")
		(net "VR_NODE1_VDDR_1V5_CNTL")
	)
	(segment
		(start 106.644948 -24.534368)
		(end 106.644948 -30.002988)
		(width 0.508)
		(layer "In2.Cu")
		(net "VR_NODE1_VDDR_1V5_CNTL")
	)
	(segment
		(start 102.927658 -20.817078)
		(end 106.644948 -24.534368)
		(width 0.508)
		(layer "In2.Cu")
		(net "VR_NODE1_VDDR_1V5_CNTL")
	)
	(segment
		(start 114.10442 -66.13652)
		(end 114.89944 -66.93154)
		(width 0.508)
		(layer "In2.Cu")
		(net "VR_NODE1_VDDR_1V5_CNTL")
	)
	(segment
		(start 99.539806 -83.760564)
		(end 99.08032 -84.22005)
		(width 0.508)
		(layer "In2.Cu")
		(net "VR_NODE1_VDDR_1V5_CNTL")
	)
	(segment
		(start 114.10442 -60.101734)
		(end 114.10442 -66.13652)
		(width 0.508)
		(layer "In2.Cu")
		(net "VR_NODE1_VDDR_1V5_CNTL")
	)
	(segment
		(start 105.85196 -48.277018)
		(end 113.811304 -56.236362)
		(width 0.508)
		(layer "In2.Cu")
		(net "VR_NODE1_VDDR_1V5_CNTL")
	)
	(segment
		(start 114.11966 -77.137006)
		(end 107.496102 -83.760564)
		(width 0.508)
		(layer "In2.Cu")
		(net "VR_NODE1_VDDR_1V5_CNTL")
	)
	(segment
		(start 105.85196 -30.795976)
		(end 105.85196 -48.277018)
		(width 0.508)
		(layer "In2.Cu")
		(net "VR_NODE1_VDDR_1V5_CNTL")
	)
	(segment
		(start 86.2965 -18.639282)
		(end 88.474296 -20.817078)
		(width 0.508)
		(layer "In2.Cu")
		(net "VR_NODE1_VDDR_1V5_CNTL")
	)
	(segment
		(start 80.821784 -83.328002)
		(end 79.850488 -83.328002)
		(width 0.508)
		(layer "In7.Cu")
		(net "VR_NODE1_VDDR_1V5_CNTL")
	)
	(segment
		(start 73.8251 -83.196684)
		(end 73.8251 -83.565492)
		(width 0.508)
		(layer "In7.Cu")
		(net "VR_NODE1_VDDR_1V5_CNTL")
	)
	(segment
		(start 77.052678 -82.669634)
		(end 74.35215 -82.669634)
		(width 0.508)
		(layer "In7.Cu")
		(net "VR_NODE1_VDDR_1V5_CNTL")
	)
	(segment
		(start 79.440786 -83.737704)
		(end 78.120748 -83.737704)
		(width 0.508)
		(layer "In7.Cu")
		(net "VR_NODE1_VDDR_1V5_CNTL")
	)
	(segment
		(start 72.293734 -84.349336)
		(end 72.021192 -84.076794)
		(width 0.508)
		(layer "In7.Cu")
		(net "VR_NODE1_VDDR_1V5_CNTL")
	)
	(segment
		(start 78.120748 -83.737704)
		(end 77.052678 -82.669634)
		(width 0.508)
		(layer "In7.Cu")
		(net "VR_NODE1_VDDR_1V5_CNTL")
	)
	(segment
		(start 99.08032 -84.222082)
		(end 98.89998 -84.402422)
		(width 0.508)
		(layer "In7.Cu")
		(net "VR_NODE1_VDDR_1V5_CNTL")
	)
	(segment
		(start 79.850488 -83.328002)
		(end 79.440786 -83.737704)
		(width 0.508)
		(layer "In7.Cu")
		(net "VR_NODE1_VDDR_1V5_CNTL")
	)
	(segment
		(start 83.289902 -81.817718)
		(end 82.71764 -82.38998)
		(width 0.508)
		(layer "In7.Cu")
		(net "VR_NODE1_VDDR_1V5_CNTL")
	)
	(segment
		(start 82.71764 -82.38998)
		(end 82.71764 -83.446874)
		(width 0.508)
		(layer "In7.Cu")
		(net "VR_NODE1_VDDR_1V5_CNTL")
	)
	(segment
		(start 73.041256 -84.349336)
		(end 72.293734 -84.349336)
		(width 0.508)
		(layer "In7.Cu")
		(net "VR_NODE1_VDDR_1V5_CNTL")
	)
	(segment
		(start 85.964268 -82.07375)
		(end 85.708236 -81.817718)
		(width 0.508)
		(layer "In7.Cu")
		(net "VR_NODE1_VDDR_1V5_CNTL")
	)
	(segment
		(start 97.898712 -84.402422)
		(end 97.8789 -84.38261)
		(width 0.508)
		(layer "In7.Cu")
		(net "VR_NODE1_VDDR_1V5_CNTL")
	)
	(segment
		(start 85.708236 -81.817718)
		(end 83.289902 -81.817718)
		(width 0.508)
		(layer "In7.Cu")
		(net "VR_NODE1_VDDR_1V5_CNTL")
	)
	(segment
		(start 82.71764 -83.446874)
		(end 82.259932 -83.904582)
		(width 0.508)
		(layer "In7.Cu")
		(net "VR_NODE1_VDDR_1V5_CNTL")
	)
	(segment
		(start 71.422514 -84.076794)
		(end 71.048372 -84.450936)
		(width 0.508)
		(layer "In7.Cu")
		(net "VR_NODE1_VDDR_1V5_CNTL")
	)
	(segment
		(start 93.58503 -83.12785)
		(end 92.53093 -82.07375)
		(width 0.508)
		(layer "In7.Cu")
		(net "VR_NODE1_VDDR_1V5_CNTL")
	)
	(segment
		(start 99.08032 -84.22005)
		(end 99.08032 -84.222082)
		(width 0.508)
		(layer "In7.Cu")
		(net "VR_NODE1_VDDR_1V5_CNTL")
	)
	(segment
		(start 96.09328 -84.381086)
		(end 94.840044 -83.12785)
		(width 0.508)
		(layer "In7.Cu")
		(net "VR_NODE1_VDDR_1V5_CNTL")
	)
	(segment
		(start 97.8789 -84.381086)
		(end 96.09328 -84.381086)
		(width 0.508)
		(layer "In7.Cu")
		(net "VR_NODE1_VDDR_1V5_CNTL")
	)
	(segment
		(start 73.8251 -83.565492)
		(end 73.041256 -84.349336)
		(width 0.508)
		(layer "In7.Cu")
		(net "VR_NODE1_VDDR_1V5_CNTL")
	)
	(segment
		(start 81.398364 -83.904582)
		(end 80.821784 -83.328002)
		(width 0.508)
		(layer "In7.Cu")
		(net "VR_NODE1_VDDR_1V5_CNTL")
	)
	(segment
		(start 94.840044 -83.12785)
		(end 93.58503 -83.12785)
		(width 0.508)
		(layer "In7.Cu")
		(net "VR_NODE1_VDDR_1V5_CNTL")
	)
	(segment
		(start 92.53093 -82.07375)
		(end 85.964268 -82.07375)
		(width 0.508)
		(layer "In7.Cu")
		(net "VR_NODE1_VDDR_1V5_CNTL")
	)
	(segment
		(start 71.048372 -84.450936)
		(end 71.048372 -84.758276)
		(width 0.508)
		(layer "In7.Cu")
		(net "VR_NODE1_VDDR_1V5_CNTL")
	)
	(segment
		(start 98.89998 -84.402422)
		(end 97.898712 -84.402422)
		(width 0.508)
		(layer "In7.Cu")
		(net "VR_NODE1_VDDR_1V5_CNTL")
	)
	(segment
		(start 82.259932 -83.904582)
		(end 81.398364 -83.904582)
		(width 0.508)
		(layer "In7.Cu")
		(net "VR_NODE1_VDDR_1V5_CNTL")
	)
	(segment
		(start 72.021192 -84.076794)
		(end 71.422514 -84.076794)
		(width 0.508)
		(layer "In7.Cu")
		(net "VR_NODE1_VDDR_1V5_CNTL")
	)
	(segment
		(start 74.35215 -82.669634)
		(end 73.8251 -83.196684)
		(width 0.508)
		(layer "In7.Cu")
		(net "VR_NODE1_VDDR_1V5_CNTL")
	)
	(segment
		(start 97.8789 -84.38261)
		(end 97.8789 -84.381086)
		(width 0.508)
		(layer "In7.Cu")
		(net "VR_NODE1_VDDR_1V5_CNTL")
	)
	(segment
		(start 94.461584 -100.944172)
		(end 94.461584 -94.109794)
		(width 0.1016)
		(layer "F.Cu")
		(net "SPI_CPU_NODE1_MISO")
	)
	(segment
		(start 60.81395 -86.468712)
		(end 60.77966 -86.468712)
		(width 0.1016)
		(layer "F.Cu")
		(net "SPI_CPU_NODE1_MISO")
	)
	(segment
		(start 94.461584 -94.109794)
		(end 94.460822 -94.109032)
		(width 0.1016)
		(layer "F.Cu")
		(net "SPI_CPU_NODE1_MISO")
	)
	(segment
		(start 61.158374 -86.813136)
		(end 60.81395 -86.468712)
		(width 0.1016)
		(layer "F.Cu")
		(net "SPI_CPU_NODE1_MISO")
	)
	(segment
		(start 61.187076 -86.813136)
		(end 61.158374 -86.813136)
		(width 0.1016)
		(layer "F.Cu")
		(net "SPI_CPU_NODE1_MISO")
	)
	(segment
		(start 97.20072 -103.683308)
		(end 94.461584 -100.944172)
		(width 0.1016)
		(layer "F.Cu")
		(net "SPI_CPU_NODE1_MISO")
	)
	(via
		(at 97.20072 -103.683308)
		(size 0.508)
		(drill 0.254)
		(layers "F.Cu" "B.Cu")
		(net "SPI_CPU_NODE1_MISO")
	)
	(via
		(at 61.259466 -88.30945)
		(size 0.6604)
		(drill 0.3302)
		(layers "F.Cu" "B.Cu")
		(net "SPI_CPU_NODE1_MISO")
	)
	(via
		(at 60.77966 -86.468712)
		(size 0.508)
		(drill 0.254)
		(layers "F.Cu" "B.Cu")
		(net "SPI_CPU_NODE1_MISO")
	)
	(segment
		(start 75.606402 -101.939852)
		(end 79.670402 -101.939852)
		(width 0.1016)
		(layer "B.Cu")
		(net "SPI_CPU_NODE1_MISO")
	)
	(segment
		(start 80.600042 -102.869492)
		(end 81.74736 -102.869492)
		(width 0.1016)
		(layer "B.Cu")
		(net "SPI_CPU_NODE1_MISO")
	)
	(segment
		(start 79.670402 -101.939852)
		(end 80.600042 -102.869492)
		(width 0.1016)
		(layer "B.Cu")
		(net "SPI_CPU_NODE1_MISO")
	)
	(segment
		(start 59.991244 -100.623878)
		(end 65.35674 -100.623878)
		(width 0.1016)
		(layer "B.Cu")
		(net "SPI_CPU_NODE1_MISO")
	)
	(segment
		(start 61.19368 -93.312996)
		(end 61.19368 -94.310962)
		(width 0.1016)
		(layer "B.Cu")
		(net "SPI_CPU_NODE1_MISO")
	)
	(segment
		(start 85.714586 -106.836718)
		(end 87.049356 -106.836718)
		(width 0.1016)
		(layer "B.Cu")
		(net "SPI_CPU_NODE1_MISO")
	)
	(segment
		(start 61.53912 -92.967556)
		(end 61.19368 -93.312996)
		(width 0.1016)
		(layer "B.Cu")
		(net "SPI_CPU_NODE1_MISO")
	)
	(segment
		(start 61.259466 -88.30945)
		(end 60.584588 -87.634572)
		(width 0.1016)
		(layer "B.Cu")
		(net "SPI_CPU_NODE1_MISO")
	)
	(segment
		(start 94.79534 -106.088688)
		(end 97.20072 -103.683308)
		(width 0.1016)
		(layer "B.Cu")
		(net "SPI_CPU_NODE1_MISO")
	)
	(segment
		(start 60.584588 -86.663784)
		(end 60.77966 -86.468712)
		(width 0.1016)
		(layer "B.Cu")
		(net "SPI_CPU_NODE1_MISO")
	)
	(segment
		(start 81.74736 -102.869492)
		(end 85.714586 -106.836718)
		(width 0.1016)
		(layer "B.Cu")
		(net "SPI_CPU_NODE1_MISO")
	)
	(segment
		(start 61.53912 -88.589104)
		(end 61.53912 -92.967556)
		(width 0.1016)
		(layer "B.Cu")
		(net "SPI_CPU_NODE1_MISO")
	)
	(segment
		(start 65.59042 -100.857558)
		(end 69.63664 -100.857558)
		(width 0.1016)
		(layer "B.Cu")
		(net "SPI_CPU_NODE1_MISO")
	)
	(segment
		(start 87.049356 -106.836718)
		(end 87.797386 -106.088688)
		(width 0.1016)
		(layer "B.Cu")
		(net "SPI_CPU_NODE1_MISO")
	)
	(segment
		(start 60.584588 -87.634572)
		(end 60.584588 -86.663784)
		(width 0.1016)
		(layer "B.Cu")
		(net "SPI_CPU_NODE1_MISO")
	)
	(segment
		(start 70.141846 -101.362764)
		(end 75.029314 -101.362764)
		(width 0.1016)
		(layer "B.Cu")
		(net "SPI_CPU_NODE1_MISO")
	)
	(segment
		(start 87.797386 -106.088688)
		(end 94.79534 -106.088688)
		(width 0.1016)
		(layer "B.Cu")
		(net "SPI_CPU_NODE1_MISO")
	)
	(segment
		(start 69.63664 -100.857558)
		(end 70.141846 -101.362764)
		(width 0.1016)
		(layer "B.Cu")
		(net "SPI_CPU_NODE1_MISO")
	)
	(segment
		(start 59.54522 -95.959422)
		(end 59.54522 -100.177854)
		(width 0.1016)
		(layer "B.Cu")
		(net "SPI_CPU_NODE1_MISO")
	)
	(segment
		(start 65.35674 -100.623878)
		(end 65.59042 -100.857558)
		(width 0.1016)
		(layer "B.Cu")
		(net "SPI_CPU_NODE1_MISO")
	)
	(segment
		(start 59.54522 -100.177854)
		(end 59.991244 -100.623878)
		(width 0.1016)
		(layer "B.Cu")
		(net "SPI_CPU_NODE1_MISO")
	)
	(segment
		(start 75.029314 -101.362764)
		(end 75.606402 -101.939852)
		(width 0.1016)
		(layer "B.Cu")
		(net "SPI_CPU_NODE1_MISO")
	)
	(segment
		(start 61.259466 -88.30945)
		(end 61.53912 -88.589104)
		(width 0.1016)
		(layer "B.Cu")
		(net "SPI_CPU_NODE1_MISO")
	)
	(segment
		(start 61.19368 -94.310962)
		(end 59.54522 -95.959422)
		(width 0.1016)
		(layer "B.Cu")
		(net "SPI_CPU_NODE1_MISO")
	)
	(segment
		(start 88.77046 -16.204438)
		(end 89.242646 -16.204438)
		(width 0.1016)
		(layer "F.Cu")
		(net "LPC_CPU_NODE1_FRAME_L")
	)
	(segment
		(start 119.690134 -50.275236)
		(end 118.986808 -50.275236)
		(width 0.1016)
		(layer "F.Cu")
		(net "LPC_CPU_NODE1_FRAME_L")
	)
	(segment
		(start 65.936622 -97.995486)
		(end 66.430906 -98.48977)
		(width 0.1016)
		(layer "F.Cu")
		(net "LPC_CPU_NODE1_FRAME_L")
	)
	(segment
		(start 89.67724 -15.769844)
		(end 89.67724 -15.622016)
		(width 0.1016)
		(layer "F.Cu")
		(net "LPC_CPU_NODE1_FRAME_L")
	)
	(segment
		(start 65.936622 -97.398586)
		(end 65.936622 -97.995486)
		(width 0.1016)
		(layer "F.Cu")
		(net "LPC_CPU_NODE1_FRAME_L")
	)
	(segment
		(start 87.69858 -114.99723)
		(end 87.947246 -114.99723)
		(width 0.1016)
		(layer "F.Cu")
		(net "LPC_CPU_NODE1_FRAME_L")
	)
	(segment
		(start 87.947246 -114.99723)
		(end 88.866472 -115.916456)
		(width 0.1016)
		(layer "F.Cu")
		(net "LPC_CPU_NODE1_FRAME_L")
	)
	(segment
		(start 88.866472 -115.916456)
		(end 88.866472 -116.591588)
		(width 0.1016)
		(layer "F.Cu")
		(net "LPC_CPU_NODE1_FRAME_L")
	)
	(segment
		(start 66.225166 -97.110042)
		(end 65.936622 -97.398586)
		(width 0.1016)
		(layer "F.Cu")
		(net "LPC_CPU_NODE1_FRAME_L")
	)
	(segment
		(start 89.242646 -16.204438)
		(end 89.67724 -15.769844)
		(width 0.1016)
		(layer "F.Cu")
		(net "LPC_CPU_NODE1_FRAME_L")
	)
	(via
		(at 89.51468 -95.420688)
		(size 0.508)
		(drill 0.254)
		(layers "F.Cu" "B.Cu")
		(net "LPC_CPU_NODE1_FRAME_L")
	)
	(via
		(at 96.44888 -94.553278)
		(size 0.508)
		(drill 0.254)
		(layers "F.Cu" "B.Cu")
		(net "LPC_CPU_NODE1_FRAME_L")
	)
	(via
		(at 87.69858 -114.99723)
		(size 0.508)
		(drill 0.254)
		(layers "F.Cu" "B.Cu")
		(net "LPC_CPU_NODE1_FRAME_L")
	)
	(via
		(at 66.430906 -98.48977)
		(size 0.508)
		(drill 0.254)
		(layers "F.Cu" "B.Cu")
		(net "LPC_CPU_NODE1_FRAME_L")
	)
	(via
		(at 118.986808 -50.275236)
		(size 0.508)
		(drill 0.254)
		(layers "F.Cu" "B.Cu")
		(net "LPC_CPU_NODE1_FRAME_L")
	)
	(via
		(at 89.67724 -15.622016)
		(size 0.508)
		(drill 0.254)
		(layers "F.Cu" "B.Cu")
		(net "LPC_CPU_NODE1_FRAME_L")
	)
	(segment
		(start 87.69858 -114.99723)
		(end 87.69858 -111.74857)
		(width 0.1143)
		(layer "In2.Cu")
		(net "LPC_CPU_NODE1_FRAME_L")
	)
	(segment
		(start 89.51468 -95.510096)
		(end 89.51468 -95.420688)
		(width 0.1143)
		(layer "In2.Cu")
		(net "LPC_CPU_NODE1_FRAME_L")
	)
	(segment
		(start 87.356188 -96.124776)
		(end 88.9 -96.124776)
		(width 0.1143)
		(layer "In2.Cu")
		(net "LPC_CPU_NODE1_FRAME_L")
	)
	(segment
		(start 115.79225 -56.437276)
		(end 115.79225 -64.579246)
		(width 0.1143)
		(layer "In2.Cu")
		(net "LPC_CPU_NODE1_FRAME_L")
	)
	(segment
		(start 77.69098 -109.891068)
		(end 77.69098 -104.565196)
		(width 0.1143)
		(layer "In2.Cu")
		(net "LPC_CPU_NODE1_FRAME_L")
	)
	(segment
		(start 96.44888 -92.238068)
		(end 96.44888 -94.553278)
		(width 0.1143)
		(layer "In2.Cu")
		(net "LPC_CPU_NODE1_FRAME_L")
	)
	(segment
		(start 85.406992 -111.036608)
		(end 81.238598 -111.036608)
		(width 0.1143)
		(layer "In2.Cu")
		(net "LPC_CPU_NODE1_FRAME_L")
	)
	(segment
		(start 116.21516 -67.356482)
		(end 116.21516 -75.912726)
		(width 0.1143)
		(layer "In2.Cu")
		(net "LPC_CPU_NODE1_FRAME_L")
	)
	(segment
		(start 80.50149 -111.773716)
		(end 79.573628 -111.773716)
		(width 0.1143)
		(layer "In2.Cu")
		(net "LPC_CPU_NODE1_FRAME_L")
	)
	(segment
		(start 86.59368 -112.223296)
		(end 85.406992 -111.036608)
		(width 0.1143)
		(layer "In2.Cu")
		(net "LPC_CPU_NODE1_FRAME_L")
	)
	(segment
		(start 91.929458 -16.873982)
		(end 98.403664 -20.035774)
		(width 0.1143)
		(layer "In2.Cu")
		(net "LPC_CPU_NODE1_FRAME_L")
	)
	(segment
		(start 115.52047 -66.661792)
		(end 116.21516 -67.356482)
		(width 0.1143)
		(layer "In2.Cu")
		(net "LPC_CPU_NODE1_FRAME_L")
	)
	(segment
		(start 107.577636 -84.55025)
		(end 104.136698 -84.55025)
		(width 0.1143)
		(layer "In2.Cu")
		(net "LPC_CPU_NODE1_FRAME_L")
	)
	(segment
		(start 81.238598 -111.036608)
		(end 80.50149 -111.773716)
		(width 0.1143)
		(layer "In2.Cu")
		(net "LPC_CPU_NODE1_FRAME_L")
	)
	(segment
		(start 79.573628 -111.773716)
		(end 77.69098 -109.891068)
		(width 0.1143)
		(layer "In2.Cu")
		(net "LPC_CPU_NODE1_FRAME_L")
	)
	(segment
		(start 98.403664 -20.035774)
		(end 103.127556 -20.035774)
		(width 0.1143)
		(layer "In2.Cu")
		(net "LPC_CPU_NODE1_FRAME_L")
	)
	(segment
		(start 90.635074 -16.57985)
		(end 91.514422 -16.57985)
		(width 0.1143)
		(layer "In2.Cu")
		(net "LPC_CPU_NODE1_FRAME_L")
	)
	(segment
		(start 87.69858 -111.74857)
		(end 85.97138 -110.02137)
		(width 0.1143)
		(layer "In2.Cu")
		(net "LPC_CPU_NODE1_FRAME_L")
	)
	(segment
		(start 85.97138 -97.509584)
		(end 87.356188 -96.124776)
		(width 0.1143)
		(layer "In2.Cu")
		(net "LPC_CPU_NODE1_FRAME_L")
	)
	(segment
		(start 108.34878 -25.256998)
		(end 108.34878 -48.993806)
		(width 0.1143)
		(layer "In2.Cu")
		(net "LPC_CPU_NODE1_FRAME_L")
	)
	(segment
		(start 86.59368 -113.89233)
		(end 86.59368 -112.223296)
		(width 0.1143)
		(layer "In2.Cu")
		(net "LPC_CPU_NODE1_FRAME_L")
	)
	(segment
		(start 73.339198 -100.213414)
		(end 71.9074 -100.213414)
		(width 0.1143)
		(layer "In2.Cu")
		(net "LPC_CPU_NODE1_FRAME_L")
	)
	(segment
		(start 89.67724 -15.622016)
		(end 90.635074 -16.57985)
		(width 0.1143)
		(layer "In2.Cu")
		(net "LPC_CPU_NODE1_FRAME_L")
	)
	(segment
		(start 66.309494 -100.212144)
		(end 66.309494 -98.611182)
		(width 0.1143)
		(layer "In2.Cu")
		(net "LPC_CPU_NODE1_FRAME_L")
	)
	(segment
		(start 88.9 -96.124776)
		(end 89.51468 -95.510096)
		(width 0.1143)
		(layer "In2.Cu")
		(net "LPC_CPU_NODE1_FRAME_L")
	)
	(segment
		(start 87.69858 -114.99723)
		(end 86.59368 -113.89233)
		(width 0.1143)
		(layer "In2.Cu")
		(net "LPC_CPU_NODE1_FRAME_L")
	)
	(segment
		(start 66.62674 -100.52939)
		(end 66.309494 -100.212144)
		(width 0.1143)
		(layer "In2.Cu")
		(net "LPC_CPU_NODE1_FRAME_L")
	)
	(segment
		(start 108.34878 -48.993806)
		(end 115.79225 -56.437276)
		(width 0.1143)
		(layer "In2.Cu")
		(net "LPC_CPU_NODE1_FRAME_L")
	)
	(segment
		(start 115.52047 -64.851026)
		(end 115.52047 -66.661792)
		(width 0.1143)
		(layer "In2.Cu")
		(net "LPC_CPU_NODE1_FRAME_L")
	)
	(segment
		(start 66.309494 -98.611182)
		(end 66.430906 -98.48977)
		(width 0.1143)
		(layer "In2.Cu")
		(net "LPC_CPU_NODE1_FRAME_L")
	)
	(segment
		(start 115.79225 -64.579246)
		(end 115.52047 -64.851026)
		(width 0.1143)
		(layer "In2.Cu")
		(net "LPC_CPU_NODE1_FRAME_L")
	)
	(segment
		(start 104.136698 -84.55025)
		(end 96.44888 -92.238068)
		(width 0.1143)
		(layer "In2.Cu")
		(net "LPC_CPU_NODE1_FRAME_L")
	)
	(segment
		(start 77.69098 -104.565196)
		(end 73.339198 -100.213414)
		(width 0.1143)
		(layer "In2.Cu")
		(net "LPC_CPU_NODE1_FRAME_L")
	)
	(segment
		(start 91.514422 -16.57985)
		(end 91.929458 -16.873982)
		(width 0.1143)
		(layer "In2.Cu")
		(net "LPC_CPU_NODE1_FRAME_L")
	)
	(segment
		(start 85.97138 -110.02137)
		(end 85.97138 -97.509584)
		(width 0.1143)
		(layer "In2.Cu")
		(net "LPC_CPU_NODE1_FRAME_L")
	)
	(segment
		(start 116.21516 -75.912726)
		(end 107.577636 -84.55025)
		(width 0.1143)
		(layer "In2.Cu")
		(net "LPC_CPU_NODE1_FRAME_L")
	)
	(segment
		(start 71.9074 -100.213414)
		(end 71.591424 -100.52939)
		(width 0.1143)
		(layer "In2.Cu")
		(net "LPC_CPU_NODE1_FRAME_L")
	)
	(segment
		(start 103.127556 -20.035774)
		(end 108.34878 -25.256998)
		(width 0.1143)
		(layer "In2.Cu")
		(net "LPC_CPU_NODE1_FRAME_L")
	)
	(segment
		(start 71.591424 -100.52939)
		(end 66.62674 -100.52939)
		(width 0.1143)
		(layer "In2.Cu")
		(net "LPC_CPU_NODE1_FRAME_L")
	)
	(segment
		(start 115.31346 -34.744152)
		(end 119.176292 -38.606984)
		(width 0.1143)
		(layer "In7.Cu")
		(net "LPC_CPU_NODE1_FRAME_L")
	)
	(segment
		(start 91.338654 -15.741142)
		(end 92.924376 -17.326864)
		(width 0.1143)
		(layer "In7.Cu")
		(net "LPC_CPU_NODE1_FRAME_L")
	)
	(segment
		(start 98.401124 -17.326864)
		(end 100.771706 -17.326864)
		(width 0.1143)
		(layer "In7.Cu")
		(net "LPC_CPU_NODE1_FRAME_L")
	)
	(segment
		(start 101.315266 -17.24279)
		(end 101.711506 -17.63903)
		(width 0.1143)
		(layer "In7.Cu")
		(net "LPC_CPU_NODE1_FRAME_L")
	)
	(segment
		(start 89.51468 -95.420688)
		(end 90.024712 -94.910656)
		(width 0.1143)
		(layer "In7.Cu")
		(net "LPC_CPU_NODE1_FRAME_L")
	)
	(segment
		(start 104.531922 -17.63903)
		(end 109.9439 -23.051008)
		(width 0.1143)
		(layer "In7.Cu")
		(net "LPC_CPU_NODE1_FRAME_L")
	)
	(segment
		(start 92.924376 -17.326864)
		(end 95.67164 -17.326864)
		(width 0.1143)
		(layer "In7.Cu")
		(net "LPC_CPU_NODE1_FRAME_L")
	)
	(segment
		(start 111.08182 -31.294832)
		(end 114.53114 -34.744152)
		(width 0.1143)
		(layer "In7.Cu")
		(net "LPC_CPU_NODE1_FRAME_L")
	)
	(segment
		(start 119.176292 -38.606984)
		(end 119.176292 -50.085752)
		(width 0.1143)
		(layer "In7.Cu")
		(net "LPC_CPU_NODE1_FRAME_L")
	)
	(segment
		(start 95.67164 -17.326864)
		(end 96.09074 -17.745964)
		(width 0.1143)
		(layer "In7.Cu")
		(net "LPC_CPU_NODE1_FRAME_L")
	)
	(segment
		(start 111.08182 -28.652724)
		(end 111.08182 -31.294832)
		(width 0.1143)
		(layer "In7.Cu")
		(net "LPC_CPU_NODE1_FRAME_L")
	)
	(segment
		(start 119.176292 -50.085752)
		(end 118.986808 -50.275236)
		(width 0.1143)
		(layer "In7.Cu")
		(net "LPC_CPU_NODE1_FRAME_L")
	)
	(segment
		(start 96.09074 -17.745964)
		(end 97.982024 -17.745964)
		(width 0.1143)
		(layer "In7.Cu")
		(net "LPC_CPU_NODE1_FRAME_L")
	)
	(segment
		(start 89.796366 -15.741142)
		(end 91.338654 -15.741142)
		(width 0.1143)
		(layer "In7.Cu")
		(net "LPC_CPU_NODE1_FRAME_L")
	)
	(segment
		(start 109.9439 -27.514804)
		(end 111.08182 -28.652724)
		(width 0.1143)
		(layer "In7.Cu")
		(net "LPC_CPU_NODE1_FRAME_L")
	)
	(segment
		(start 90.024712 -94.910656)
		(end 93.61805 -94.910656)
		(width 0.1143)
		(layer "In7.Cu")
		(net "LPC_CPU_NODE1_FRAME_L")
	)
	(segment
		(start 97.982024 -17.745964)
		(end 98.401124 -17.326864)
		(width 0.1143)
		(layer "In7.Cu")
		(net "LPC_CPU_NODE1_FRAME_L")
	)
	(segment
		(start 101.711506 -17.63903)
		(end 104.531922 -17.63903)
		(width 0.1143)
		(layer "In7.Cu")
		(net "LPC_CPU_NODE1_FRAME_L")
	)
	(segment
		(start 93.975936 -94.553278)
		(end 96.44888 -94.553278)
		(width 0.1143)
		(layer "In7.Cu")
		(net "LPC_CPU_NODE1_FRAME_L")
	)
	(segment
		(start 114.53114 -34.744152)
		(end 115.31346 -34.744152)
		(width 0.1143)
		(layer "In7.Cu")
		(net "LPC_CPU_NODE1_FRAME_L")
	)
	(segment
		(start 89.67724 -15.622016)
		(end 89.796366 -15.741142)
		(width 0.1143)
		(layer "In7.Cu")
		(net "LPC_CPU_NODE1_FRAME_L")
	)
	(segment
		(start 100.771706 -17.326864)
		(end 100.85578 -17.24279)
		(width 0.1143)
		(layer "In7.Cu")
		(net "LPC_CPU_NODE1_FRAME_L")
	)
	(segment
		(start 109.9439 -23.051008)
		(end 109.9439 -27.514804)
		(width 0.1143)
		(layer "In7.Cu")
		(net "LPC_CPU_NODE1_FRAME_L")
	)
	(segment
		(start 93.61805 -94.910656)
		(end 93.975936 -94.553278)
		(width 0.1143)
		(layer "In7.Cu")
		(net "LPC_CPU_NODE1_FRAME_L")
	)
	(segment
		(start 100.85578 -17.24279)
		(end 101.315266 -17.24279)
		(width 0.1143)
		(layer "In7.Cu")
		(net "LPC_CPU_NODE1_FRAME_L")
	)
	(segment
		(start 61.743082 -66.979038)
		(end 61.743082 -67.025774)
		(width 0.3048)
		(layer "F.Cu")
		(net "PV_VDDR_NODE1")
	)
	(segment
		(start 59.286902 -63.552324)
		(end 59.286902 -64.079374)
		(width 0.3048)
		(layer "F.Cu")
		(net "PV_VDDR_NODE1")
	)
	(segment
		(start 64.277494 -64.328548)
		(end 64.49822 -64.549274)
		(width 0.1778)
		(layer "F.Cu")
		(net "PV_VDDR_NODE1")
	)
	(segment
		(start 35.85464 -16.287242)
		(end 35.85464 -14.63802)
		(width 0.254)
		(layer "F.Cu")
		(net "PV_VDDR_NODE1")
	)
	(segment
		(start 59.411616 -64.204088)
		(end 59.563762 -64.204088)
		(width 0.3048)
		(layer "F.Cu")
		(net "PV_VDDR_NODE1")
	)
	(segment
		(start 67.95008 -20.94992)
		(end 67.95008 -19.551904)
		(width 0.381)
		(layer "F.Cu")
		(net "PV_VDDR_NODE1")
	)
	(segment
		(start 59.286902 -64.079374)
		(end 59.411616 -64.204088)
		(width 0.3048)
		(layer "F.Cu")
		(net "PV_VDDR_NODE1")
	)
	(segment
		(start 42.49293 -16.655796)
		(end 36.223194 -16.655796)
		(width 0.254)
		(layer "F.Cu")
		(net "PV_VDDR_NODE1")
	)
	(segment
		(start 77.25029 -30.587442)
		(end 76.1619 -31.675832)
		(width 0.381)
		(layer "F.Cu")
		(net "PV_VDDR_NODE1")
	)
	(segment
		(start 62.281308 -64.079628)
		(end 62.281308 -64.146938)
		(width 0.1778)
		(layer "F.Cu")
		(net "PV_VDDR_NODE1")
	)
	(segment
		(start 62.602618 -64.804544)
		(end 62.602618 -64.882268)
		(width 0.1778)
		(layer "F.Cu")
		(net "PV_VDDR_NODE1")
	)
	(segment
		(start 62.234572 -64.371728)
		(end 62.451742 -64.588898)
		(width 0.1778)
		(layer "F.Cu")
		(net "PV_VDDR_NODE1")
	)
	(segment
		(start 59.732418 -67.360038)
		(end 59.383422 -67.709034)
		(width 0.3048)
		(layer "F.Cu")
		(net "PV_VDDR_NODE1")
	)
	(segment
		(start 63.355982 -65.278762)
		(end 63.355982 -65.455038)
		(width 0.1778)
		(layer "F.Cu")
		(net "PV_VDDR_NODE1")
	)
	(segment
		(start 64.49822 -64.688466)
		(end 63.731648 -65.455038)
		(width 0.1778)
		(layer "F.Cu")
		(net "PV_VDDR_NODE1")
	)
	(segment
		(start 59.383422 -67.709034)
		(end 59.383422 -67.741038)
		(width 0.3048)
		(layer "F.Cu")
		(net "PV_VDDR_NODE1")
	)
	(segment
		(start 61.743082 -67.025774)
		(end 61.408818 -67.360038)
		(width 0.3048)
		(layer "F.Cu")
		(net "PV_VDDR_NODE1")
	)
	(segment
		(start 56.721756 -13.960094)
		(end 55.838598 -14.843252)
		(width 0.254)
		(layer "F.Cu")
		(net "PV_VDDR_NODE1")
	)
	(segment
		(start 64.49822 -64.594994)
		(end 64.49822 -64.688466)
		(width 0.1778)
		(layer "F.Cu")
		(net "PV_VDDR_NODE1")
	)
	(segment
		(start 81.605882 -19.387058)
		(end 81.607914 -19.387058)
		(width 0.381)
		(layer "F.Cu")
		(net "PV_VDDR_NODE1")
	)
	(segment
		(start 64.49822 -64.549274)
		(end 64.49822 -64.594994)
		(width 0.1778)
		(layer "F.Cu")
		(net "PV_VDDR_NODE1")
	)
	(segment
		(start 72.750172 -20.94992)
		(end 72.750172 -19.746468)
		(width 0.381)
		(layer "F.Cu")
		(net "PV_VDDR_NODE1")
	)
	(segment
		(start 44.274994 -18.43786)
		(end 42.49293 -16.655796)
		(width 0.254)
		(layer "F.Cu")
		(net "PV_VDDR_NODE1")
	)
	(segment
		(start 64.185546 -64.328548)
		(end 64.277494 -64.328548)
		(width 0.1778)
		(layer "F.Cu")
		(net "PV_VDDR_NODE1")
	)
	(segment
		(start 59.383422 -65.455038)
		(end 59.366658 -65.455038)
		(width 0.3048)
		(layer "F.Cu")
		(net "PV_VDDR_NODE1")
	)
	(segment
		(start 60.695332 -64.593724)
		(end 60.695332 -64.594994)
		(width 0.254)
		(layer "F.Cu")
		(net "PV_VDDR_NODE1")
	)
	(segment
		(start 67.95008 -19.551904)
		(end 68.09232 -19.409664)
		(width 0.381)
		(layer "F.Cu")
		(net "PV_VDDR_NODE1")
	)
	(segment
		(start 70.6501 -27.739848)
		(end 70.6501 -29.149802)
		(width 0.381)
		(layer "F.Cu")
		(net "PV_VDDR_NODE1")
	)
	(segment
		(start 79.350108 -20.94992)
		(end 79.350108 -19.453098)
		(width 0.381)
		(layer "F.Cu")
		(net "PV_VDDR_NODE1")
	)
	(segment
		(start 75.450192 -30.273752)
		(end 75.983846 -30.807406)
		(width 0.381)
		(layer "F.Cu")
		(net "PV_VDDR_NODE1")
	)
	(segment
		(start 49.956212 -18.43786)
		(end 44.274994 -18.43786)
		(width 0.254)
		(layer "F.Cu")
		(net "PV_VDDR_NODE1")
	)
	(segment
		(start 60.498228 -64.792098)
		(end 60.151772 -64.792098)
		(width 0.3048)
		(layer "F.Cu")
		(net "PV_VDDR_NODE1")
	)
	(segment
		(start 63.547752 -67.597528)
		(end 63.061596 -67.597528)
		(width 0.3048)
		(layer "F.Cu")
		(net "PV_VDDR_NODE1")
	)
	(segment
		(start 75.450192 -29.149802)
		(end 75.450192 -30.273752)
		(width 0.381)
		(layer "F.Cu")
		(net "PV_VDDR_NODE1")
	)
	(segment
		(start 63.11773 -64.736218)
		(end 63.11773 -65.04051)
		(width 0.1778)
		(layer "F.Cu")
		(net "PV_VDDR_NODE1")
	)
	(segment
		(start 63.729362 -67.360038)
		(end 63.729362 -67.415918)
		(width 0.3048)
		(layer "F.Cu")
		(net "PV_VDDR_NODE1")
	)
	(segment
		(start 79.650082 -31.086298)
		(end 79.650082 -29.149802)
		(width 0.3556)
		(layer "F.Cu")
		(net "PV_VDDR_NODE1")
	)
	(segment
		(start 55.838598 -14.843252)
		(end 53.55082 -14.843252)
		(width 0.254)
		(layer "F.Cu")
		(net "PV_VDDR_NODE1")
	)
	(segment
		(start 59.366658 -65.455038)
		(end 58.647838 -64.736218)
		(width 0.3048)
		(layer "F.Cu")
		(net "PV_VDDR_NODE1")
	)
	(segment
		(start 58.470546 -66.979038)
		(end 57.770522 -66.979038)
		(width 0.3048)
		(layer "F.Cu")
		(net "PV_VDDR_NODE1")
	)
	(segment
		(start 82.050128 -29.149802)
		(end 82.050128 -31.048198)
		(width 0.3556)
		(layer "F.Cu")
		(net "PV_VDDR_NODE1")
	)
	(segment
		(start 59.756802 -67.360038)
		(end 59.732418 -67.360038)
		(width 0.3048)
		(layer "F.Cu")
		(net "PV_VDDR_NODE1")
	)
	(segment
		(start 81.607914 -19.387058)
		(end 81.750154 -19.529298)
		(width 0.381)
		(layer "F.Cu")
		(net "PV_VDDR_NODE1")
	)
	(segment
		(start 63.984886 -63.895224)
		(end 63.984886 -64.127888)
		(width 0.1778)
		(layer "F.Cu")
		(net "PV_VDDR_NODE1")
	)
	(segment
		(start 62.443106 -66.979038)
		(end 61.743082 -66.979038)
		(width 0.3048)
		(layer "F.Cu")
		(net "PV_VDDR_NODE1")
	)
	(segment
		(start 65.90157 -63.556642)
		(end 65.917572 -63.54064)
		(width 0.2032)
		(layer "F.Cu")
		(net "PV_VDDR_NODE1")
	)
	(segment
		(start 75.983846 -30.807406)
		(end 76.09586 -30.807406)
		(width 0.381)
		(layer "F.Cu")
		(net "PV_VDDR_NODE1")
	)
	(segment
		(start 60.456826 -67.360038)
		(end 59.756802 -67.360038)
		(width 0.3048)
		(layer "F.Cu")
		(net "PV_VDDR_NODE1")
	)
	(segment
		(start 57.421018 -67.360038)
		(end 57.397142 -67.360038)
		(width 0.3048)
		(layer "F.Cu")
		(net "PV_VDDR_NODE1")
	)
	(segment
		(start 75.150218 -20.94992)
		(end 75.150218 -19.448018)
		(width 0.381)
		(layer "F.Cu")
		(net "PV_VDDR_NODE1")
	)
	(segment
		(start 59.995308 -64.635634)
		(end 59.995308 -64.594994)
		(width 0.3048)
		(layer "F.Cu")
		(net "PV_VDDR_NODE1")
	)
	(segment
		(start 8.072628 -6.576568)
		(end 7.94004 -6.709156)
		(width 0.381)
		(layer "F.Cu")
		(net "PV_VDDR_NODE1")
	)
	(segment
		(start 62.556136 -63.49492)
		(end 62.556136 -63.8048)
		(width 0.1778)
		(layer "F.Cu")
		(net "PV_VDDR_NODE1")
	)
	(segment
		(start 57.770522 -67.010534)
		(end 57.421018 -67.360038)
		(width 0.3048)
		(layer "F.Cu")
		(net "PV_VDDR_NODE1")
	)
	(segment
		(start 68.250308 -29.149802)
		(end 68.250308 -27.413712)
		(width 0.381)
		(layer "F.Cu")
		(net "PV_VDDR_NODE1")
	)
	(segment
		(start 36.223194 -16.655796)
		(end 35.85464 -16.287242)
		(width 0.254)
		(layer "F.Cu")
		(net "PV_VDDR_NODE1")
	)
	(segment
		(start 12.587986 -12.013946)
		(end 12.587986 -12.846558)
		(width 0.508)
		(layer "F.Cu")
		(net "PV_VDDR_NODE1")
	)
	(segment
		(start 76.950062 -20.94992)
		(end 76.950062 -19.346418)
		(width 0.381)
		(layer "F.Cu")
		(net "PV_VDDR_NODE1")
	)
	(segment
		(start 58.104024 -62.55004)
		(end 57.98566 -62.55004)
		(width 0.3048)
		(layer "F.Cu")
		(net "PV_VDDR_NODE1")
	)
	(segment
		(start 61.193172 -63.762128)
		(end 61.193172 -64.095884)
		(width 0.254)
		(layer "F.Cu")
		(net "PV_VDDR_NODE1")
	)
	(segment
		(start 81.750154 -19.529298)
		(end 81.750154 -20.94992)
		(width 0.381)
		(layer "F.Cu")
		(net "PV_VDDR_NODE1")
	)
	(segment
		(start 70.350126 -20.94992)
		(end 70.350126 -19.366738)
		(width 0.381)
		(layer "F.Cu")
		(net "PV_VDDR_NODE1")
	)
	(segment
		(start 53.55082 -14.843252)
		(end 49.956212 -18.43786)
		(width 0.254)
		(layer "F.Cu")
		(net "PV_VDDR_NODE1")
	)
	(segment
		(start 62.451742 -64.653668)
		(end 62.602618 -64.804544)
		(width 0.1778)
		(layer "F.Cu")
		(net "PV_VDDR_NODE1")
	)
	(segment
		(start 115.882928 -25.531826)
		(end 115.882928 -23.855426)
		(width 0.254)
		(layer "F.Cu")
		(net "PV_VDDR_NODE1")
	)
	(segment
		(start 57.98566 -62.55004)
		(end 57.789318 -62.353698)
		(width 0.3048)
		(layer "F.Cu")
		(net "PV_VDDR_NODE1")
	)
	(segment
		(start 70.83552 -27.554428)
		(end 70.6501 -27.739848)
		(width 0.381)
		(layer "F.Cu")
		(net "PV_VDDR_NODE1")
	)
	(segment
		(start 60.695332 -64.594994)
		(end 60.498228 -64.792098)
		(width 0.3048)
		(layer "F.Cu")
		(net "PV_VDDR_NODE1")
	)
	(segment
		(start 8.072628 -5.272278)
		(end 8.072628 -6.576568)
		(width 0.381)
		(layer "F.Cu")
		(net "PV_VDDR_NODE1")
	)
	(segment
		(start 65.917572 -63.54064)
		(end 65.917572 -64.098932)
		(width 0.2032)
		(layer "F.Cu")
		(net "PV_VDDR_NODE1")
	)
	(segment
		(start 63.061596 -67.597528)
		(end 62.443106 -66.979038)
		(width 0.3048)
		(layer "F.Cu")
		(net "PV_VDDR_NODE1")
	)
	(segment
		(start 72.750172 -19.746468)
		(end 72.527922 -19.524218)
		(width 0.381)
		(layer "F.Cu")
		(net "PV_VDDR_NODE1")
	)
	(segment
		(start 62.281308 -64.146938)
		(end 62.234572 -64.193674)
		(width 0.1778)
		(layer "F.Cu")
		(net "PV_VDDR_NODE1")
	)
	(segment
		(start 63.984886 -64.127888)
		(end 64.185546 -64.328548)
		(width 0.1778)
		(layer "F.Cu")
		(net "PV_VDDR_NODE1")
	)
	(segment
		(start 57.789318 -62.353698)
		(end 57.789318 -62.023498)
		(width 0.3048)
		(layer "F.Cu")
		(net "PV_VDDR_NODE1")
	)
	(segment
		(start 62.556136 -63.8048)
		(end 62.281308 -64.079628)
		(width 0.1778)
		(layer "F.Cu")
		(net "PV_VDDR_NODE1")
	)
	(segment
		(start 58.614818 -64.736218)
		(end 57.59323 -64.736218)
		(width 0.3048)
		(layer "F.Cu")
		(net "PV_VDDR_NODE1")
	)
	(segment
		(start 58.647838 -64.736218)
		(end 58.614818 -64.736218)
		(width 0.3048)
		(layer "F.Cu")
		(net "PV_VDDR_NODE1")
	)
	(segment
		(start 73.050146 -29.149802)
		(end 73.050146 -27.643074)
		(width 0.381)
		(layer "F.Cu")
		(net "PV_VDDR_NODE1")
	)
	(segment
		(start 59.563762 -64.204088)
		(end 59.995308 -64.635634)
		(width 0.3048)
		(layer "F.Cu")
		(net "PV_VDDR_NODE1")
	)
	(segment
		(start 57.770522 -66.979038)
		(end 57.770522 -67.010534)
		(width 0.3048)
		(layer "F.Cu")
		(net "PV_VDDR_NODE1")
	)
	(segment
		(start 63.789814 -63.552324)
		(end 63.789814 -63.700152)
		(width 0.1778)
		(layer "F.Cu")
		(net "PV_VDDR_NODE1")
	)
	(segment
		(start 61.398658 -63.556642)
		(end 61.193172 -63.762128)
		(width 0.254)
		(layer "F.Cu")
		(net "PV_VDDR_NODE1")
	)
	(segment
		(start 63.731648 -65.455038)
		(end 63.355982 -65.455038)
		(width 0.1778)
		(layer "F.Cu")
		(net "PV_VDDR_NODE1")
	)
	(segment
		(start 62.451742 -64.588898)
		(end 62.451742 -64.653668)
		(width 0.1778)
		(layer "F.Cu")
		(net "PV_VDDR_NODE1")
	)
	(segment
		(start 63.789814 -63.700152)
		(end 63.984886 -63.895224)
		(width 0.1778)
		(layer "F.Cu")
		(net "PV_VDDR_NODE1")
	)
	(segment
		(start 61.193172 -64.095884)
		(end 60.695332 -64.593724)
		(width 0.254)
		(layer "F.Cu")
		(net "PV_VDDR_NODE1")
	)
	(segment
		(start 63.729362 -67.415918)
		(end 63.547752 -67.597528)
		(width 0.3048)
		(layer "F.Cu")
		(net "PV_VDDR_NODE1")
	)
	(segment
		(start 77.25029 -29.149802)
		(end 77.25029 -30.587442)
		(width 0.381)
		(layer "F.Cu")
		(net "PV_VDDR_NODE1")
	)
	(segment
		(start 62.234572 -64.193674)
		(end 62.234572 -64.371728)
		(width 0.1778)
		(layer "F.Cu")
		(net "PV_VDDR_NODE1")
	)
	(segment
		(start 63.11773 -65.04051)
		(end 63.355982 -65.278762)
		(width 0.1778)
		(layer "F.Cu")
		(net "PV_VDDR_NODE1")
	)
	(segment
		(start 60.151772 -64.792098)
		(end 59.995308 -64.635634)
		(width 0.3048)
		(layer "F.Cu")
		(net "PV_VDDR_NODE1")
	)
	(segment
		(start 61.408818 -67.360038)
		(end 61.369702 -67.360038)
		(width 0.3048)
		(layer "F.Cu")
		(net "PV_VDDR_NODE1")
	)
	(segment
		(start 7.215632 -6.709156)
		(end 7.94004 -6.709156)
		(width 0.508)
		(layer "F.Cu")
		(net "PV_VDDR_NODE1")
	)
	(via
		(at 58.24474 -12.980162)
		(size 0.508)
		(drill 0.254)
		(layers "F.Cu" "B.Cu")
		(net "PV_VDDR_NODE1")
	)
	(via
		(at 57.789318 -62.023498)
		(size 0.508)
		(drill 0.254)
		(layers "F.Cu" "B.Cu")
		(net "PV_VDDR_NODE1")
	)
	(via
		(at 58.4454 -47.596806)
		(size 0.508)
		(drill 0.254)
		(layers "F.Cu" "B.Cu")
		(net "PV_VDDR_NODE1")
	)
	(via
		(at 69.19976 -19.348958)
		(size 0.508)
		(drill 0.254)
		(layers "F.Cu" "B.Cu")
		(net "PV_VDDR_NODE1")
	)
	(via
		(at 81.00314 -18.94713)
		(size 0.508)
		(drill 0.254)
		(layers "F.Cu" "B.Cu")
		(net "PV_VDDR_NODE1")
	)
	(via
		(at 79.650082 -31.086298)
		(size 0.508)
		(drill 0.254)
		(layers "F.Cu" "B.Cu")
		(net "PV_VDDR_NODE1")
	)
	(via
		(at 68.55968 -18.876772)
		(size 0.508)
		(drill 0.254)
		(layers "F.Cu" "B.Cu")
		(net "PV_VDDR_NODE1")
	)
	(via
		(at 61.54166 -11.558016)
		(size 0.508)
		(drill 0.254)
		(layers "F.Cu" "B.Cu")
		(net "PV_VDDR_NODE1")
	)
	(via
		(at 77.69352 -19.395694)
		(size 0.508)
		(drill 0.254)
		(layers "F.Cu" "B.Cu")
		(net "PV_VDDR_NODE1")
	)
	(via
		(at 62.30874 -12.920218)
		(size 0.508)
		(drill 0.254)
		(layers "F.Cu" "B.Cu")
		(net "PV_VDDR_NODE1")
	)
	(via
		(at 116.309648 -26.848816)
		(size 0.508)
		(drill 0.254)
		(layers "F.Cu" "B.Cu")
		(net "PV_VDDR_NODE1")
	)
	(via
		(at 58.610246 -40.844978)
		(size 0.508)
		(drill 0.254)
		(layers "F.Cu" "B.Cu")
		(net "PV_VDDR_NODE1")
	)
	(via
		(at 63.57366 -11.558016)
		(size 0.508)
		(drill 0.254)
		(layers "F.Cu" "B.Cu")
		(net "PV_VDDR_NODE1")
	)
	(via
		(at 62.602618 -64.882268)
		(size 0.508)
		(drill 0.254)
		(layers "F.Cu" "B.Cu")
		(net "PV_VDDR_NODE1")
	)
	(via
		(at 75.150218 -19.448018)
		(size 0.508)
		(drill 0.254)
		(layers "F.Cu" "B.Cu")
		(net "PV_VDDR_NODE1")
	)
	(via
		(at 70.350126 -19.366738)
		(size 0.508)
		(drill 0.254)
		(layers "F.Cu" "B.Cu")
		(net "PV_VDDR_NODE1")
	)
	(via
		(at 78.67142 -19.362928)
		(size 0.508)
		(drill 0.254)
		(layers "F.Cu" "B.Cu")
		(net "PV_VDDR_NODE1")
	)
	(via
		(at 65.917572 -64.098932)
		(size 0.508)
		(drill 0.254)
		(layers "F.Cu" "B.Cu")
		(net "PV_VDDR_NODE1")
	)
	(via
		(at 7.215632 -6.709156)
		(size 0.508)
		(drill 0.254)
		(layers "F.Cu" "B.Cu")
		(net "PV_VDDR_NODE1")
	)
	(via
		(at 63.355982 -65.455038)
		(size 0.508)
		(drill 0.254)
		(layers "F.Cu" "B.Cu")
		(net "PV_VDDR_NODE1")
	)
	(via
		(at 73.593452 -19.347942)
		(size 0.508)
		(drill 0.254)
		(layers "F.Cu" "B.Cu")
		(net "PV_VDDR_NODE1")
	)
	(via
		(at 64.38646 -13.648944)
		(size 0.508)
		(drill 0.254)
		(layers "F.Cu" "B.Cu")
		(net "PV_VDDR_NODE1")
	)
	(via
		(at 62.55766 -11.558016)
		(size 0.508)
		(drill 0.254)
		(layers "F.Cu" "B.Cu")
		(net "PV_VDDR_NODE1")
	)
	(via
		(at 78.16596 -18.862802)
		(size 0.508)
		(drill 0.254)
		(layers "F.Cu" "B.Cu")
		(net "PV_VDDR_NODE1")
	)
	(via
		(at 62.22238 -44.921424)
		(size 0.6604)
		(drill 0.3302)
		(layers "F.Cu" "B.Cu")
		(net "PV_VDDR_NODE1")
	)
	(via
		(at 62.484762 -50.260758)
		(size 0.6604)
		(drill 0.3302)
		(layers "F.Cu" "B.Cu")
		(net "PV_VDDR_NODE1")
	)
	(via
		(at 76.1619 -31.675832)
		(size 0.508)
		(drill 0.254)
		(layers "F.Cu" "B.Cu")
		(net "PV_VDDR_NODE1")
	)
	(via
		(at 59.383422 -67.741038)
		(size 0.508)
		(drill 0.254)
		(layers "F.Cu" "B.Cu")
		(net "PV_VDDR_NODE1")
	)
	(via
		(at 82.20456 -18.895822)
		(size 0.508)
		(drill 0.254)
		(layers "F.Cu" "B.Cu")
		(net "PV_VDDR_NODE1")
	)
	(via
		(at 69.74332 -18.867374)
		(size 0.508)
		(drill 0.254)
		(layers "F.Cu" "B.Cu")
		(net "PV_VDDR_NODE1")
	)
	(via
		(at 61.29274 -12.949682)
		(size 0.508)
		(drill 0.254)
		(layers "F.Cu" "B.Cu")
		(net "PV_VDDR_NODE1")
	)
	(via
		(at 79.83474 -18.93316)
		(size 0.508)
		(drill 0.254)
		(layers "F.Cu" "B.Cu")
		(net "PV_VDDR_NODE1")
	)
	(via
		(at 74.247502 -19.39163)
		(size 0.508)
		(drill 0.254)
		(layers "F.Cu" "B.Cu")
		(net "PV_VDDR_NODE1")
	)
	(via
		(at 57.397142 -67.360038)
		(size 0.508)
		(drill 0.254)
		(layers "F.Cu" "B.Cu")
		(net "PV_VDDR_NODE1")
	)
	(via
		(at 70.8914 -18.909538)
		(size 0.508)
		(drill 0.254)
		(layers "F.Cu" "B.Cu")
		(net "PV_VDDR_NODE1")
	)
	(via
		(at 59.383422 -65.455038)
		(size 0.508)
		(drill 0.254)
		(layers "F.Cu" "B.Cu")
		(net "PV_VDDR_NODE1")
	)
	(via
		(at 67.306698 -52.243228)
		(size 0.6604)
		(drill 0.3302)
		(layers "F.Cu" "B.Cu")
		(net "PV_VDDR_NODE1")
	)
	(via
		(at 71.4756 -19.288252)
		(size 0.508)
		(drill 0.254)
		(layers "F.Cu" "B.Cu")
		(net "PV_VDDR_NODE1")
	)
	(via
		(at 82.050128 -31.048198)
		(size 0.508)
		(drill 0.254)
		(layers "F.Cu" "B.Cu")
		(net "PV_VDDR_NODE1")
	)
	(via
		(at 68.09232 -19.409664)
		(size 0.508)
		(drill 0.254)
		(layers "F.Cu" "B.Cu")
		(net "PV_VDDR_NODE1")
	)
	(via
		(at 56.21274 -12.980162)
		(size 0.508)
		(drill 0.254)
		(layers "F.Cu" "B.Cu")
		(net "PV_VDDR_NODE1")
	)
	(via
		(at 58.45556 -50.09896)
		(size 0.508)
		(drill 0.254)
		(layers "F.Cu" "B.Cu")
		(net "PV_VDDR_NODE1")
	)
	(via
		(at 80.422242 -19.315938)
		(size 0.508)
		(drill 0.254)
		(layers "F.Cu" "B.Cu")
		(net "PV_VDDR_NODE1")
	)
	(via
		(at 73.050146 -27.643074)
		(size 0.508)
		(drill 0.254)
		(layers "F.Cu" "B.Cu")
		(net "PV_VDDR_NODE1")
	)
	(via
		(at 58.5851 -41.799764)
		(size 0.508)
		(drill 0.254)
		(layers "F.Cu" "B.Cu")
		(net "PV_VDDR_NODE1")
	)
	(via
		(at 59.25566 -12.96543)
		(size 0.508)
		(drill 0.254)
		(layers "F.Cu" "B.Cu")
		(net "PV_VDDR_NODE1")
	)
	(via
		(at 56.46166 -11.558016)
		(size 0.508)
		(drill 0.254)
		(layers "F.Cu" "B.Cu")
		(net "PV_VDDR_NODE1")
	)
	(via
		(at 12.587986 -12.846558)
		(size 0.508)
		(drill 0.254)
		(layers "F.Cu" "B.Cu")
		(net "PV_VDDR_NODE1")
	)
	(via
		(at 72.10298 -18.979896)
		(size 0.508)
		(drill 0.254)
		(layers "F.Cu" "B.Cu")
		(net "PV_VDDR_NODE1")
	)
	(via
		(at 72.527922 -19.524218)
		(size 0.508)
		(drill 0.254)
		(layers "F.Cu" "B.Cu")
		(net "PV_VDDR_NODE1")
	)
	(via
		(at 72.289162 -53.475382)
		(size 0.6604)
		(drill 0.3302)
		(layers "F.Cu" "B.Cu")
		(net "PV_VDDR_NODE1")
	)
	(via
		(at 76.09586 -30.807406)
		(size 0.508)
		(drill 0.254)
		(layers "F.Cu" "B.Cu")
		(net "PV_VDDR_NODE1")
	)
	(via
		(at 81.605882 -19.387058)
		(size 0.508)
		(drill 0.254)
		(layers "F.Cu" "B.Cu")
		(net "PV_VDDR_NODE1")
	)
	(via
		(at 117.579648 -26.848816)
		(size 0.508)
		(drill 0.254)
		(layers "F.Cu" "B.Cu")
		(net "PV_VDDR_NODE1")
	)
	(via
		(at 71.979282 -34.58337)
		(size 0.6604)
		(drill 0.3302)
		(layers "F.Cu" "B.Cu")
		(net "PV_VDDR_NODE1")
	)
	(via
		(at 59.411616 -64.204088)
		(size 0.508)
		(drill 0.254)
		(layers "F.Cu" "B.Cu")
		(net "PV_VDDR_NODE1")
	)
	(via
		(at 76.00188 -19.353784)
		(size 0.508)
		(drill 0.254)
		(layers "F.Cu" "B.Cu")
		(net "PV_VDDR_NODE1")
	)
	(via
		(at 57.22874 -12.980162)
		(size 0.508)
		(drill 0.254)
		(layers "F.Cu" "B.Cu")
		(net "PV_VDDR_NODE1")
	)
	(via
		(at 60.27674 -12.949682)
		(size 0.508)
		(drill 0.254)
		(layers "F.Cu" "B.Cu")
		(net "PV_VDDR_NODE1")
	)
	(via
		(at 68.250308 -27.413712)
		(size 0.508)
		(drill 0.254)
		(layers "F.Cu" "B.Cu")
		(net "PV_VDDR_NODE1")
	)
	(via
		(at 82.83956 -19.353784)
		(size 0.508)
		(drill 0.254)
		(layers "F.Cu" "B.Cu")
		(net "PV_VDDR_NODE1")
	)
	(via
		(at 72.96658 -19.054572)
		(size 0.508)
		(drill 0.254)
		(layers "F.Cu" "B.Cu")
		(net "PV_VDDR_NODE1")
	)
	(via
		(at 63.3222 -12.918948)
		(size 0.508)
		(drill 0.254)
		(layers "F.Cu" "B.Cu")
		(net "PV_VDDR_NODE1")
	)
	(via
		(at 70.83552 -27.554428)
		(size 0.508)
		(drill 0.254)
		(layers "F.Cu" "B.Cu")
		(net "PV_VDDR_NODE1")
	)
	(via
		(at 61.369702 -67.360038)
		(size 0.508)
		(drill 0.254)
		(layers "F.Cu" "B.Cu")
		(net "PV_VDDR_NODE1")
	)
	(via
		(at 58.64606 -43.033696)
		(size 0.508)
		(drill 0.254)
		(layers "F.Cu" "B.Cu")
		(net "PV_VDDR_NODE1")
	)
	(via
		(at 58.49366 -11.558016)
		(size 0.508)
		(drill 0.254)
		(layers "F.Cu" "B.Cu")
		(net "PV_VDDR_NODE1")
	)
	(via
		(at 57.47766 -11.558016)
		(size 0.508)
		(drill 0.254)
		(layers "F.Cu" "B.Cu")
		(net "PV_VDDR_NODE1")
	)
	(via
		(at 79.350108 -19.453098)
		(size 0.508)
		(drill 0.254)
		(layers "F.Cu" "B.Cu")
		(net "PV_VDDR_NODE1")
	)
	(via
		(at 76.950062 -19.346418)
		(size 0.508)
		(drill 0.254)
		(layers "F.Cu" "B.Cu")
		(net "PV_VDDR_NODE1")
	)
	(via
		(at 116.944648 -26.848816)
		(size 0.508)
		(drill 0.254)
		(layers "F.Cu" "B.Cu")
		(net "PV_VDDR_NODE1")
	)
	(via
		(at 58.674 -44.038774)
		(size 0.508)
		(drill 0.254)
		(layers "F.Cu" "B.Cu")
		(net "PV_VDDR_NODE1")
	)
	(segment
		(start 72.186546 -27.751786)
		(end 72.941434 -27.751786)
		(width 0.508)
		(layer "B.Cu")
		(net "PV_VDDR_NODE1")
	)
	(segment
		(start 79.702406 -31.033974)
		(end 79.650082 -31.086298)
		(width 0.508)
		(layer "B.Cu")
		(net "PV_VDDR_NODE1")
	)
	(segment
		(start 79.702406 -30.177486)
		(end 79.702406 -31.033974)
		(width 0.508)
		(layer "B.Cu")
		(net "PV_VDDR_NODE1")
	)
	(segment
		(start 68.48475 -26.273506)
		(end 68.48475 -27.17927)
		(width 0.508)
		(layer "B.Cu")
		(net "PV_VDDR_NODE1")
	)
	(segment
		(start 82.285078 -29.82214)
		(end 82.285078 -30.813248)
		(width 0.508)
		(layer "B.Cu")
		(net "PV_VDDR_NODE1")
	)
	(segment
		(start 72.941434 -27.751786)
		(end 73.050146 -27.643074)
		(width 0.508)
		(layer "B.Cu")
		(net "PV_VDDR_NODE1")
	)
	(segment
		(start 68.48475 -27.17927)
		(end 68.250308 -27.413712)
		(width 0.508)
		(layer "B.Cu")
		(net "PV_VDDR_NODE1")
	)
	(segment
		(start 57.529476 -67.492372)
		(end 57.397142 -67.360038)
		(width 0.4572)
		(layer "B.Cu")
		(net "PV_VDDR_NODE1")
	)
	(segment
		(start 58.10123 -67.492372)
		(end 57.529476 -67.492372)
		(width 0.4572)
		(layer "B.Cu")
		(net "PV_VDDR_NODE1")
	)
	(segment
		(start 82.285078 -30.813248)
		(end 82.050128 -31.048198)
		(width 0.508)
		(layer "B.Cu")
		(net "PV_VDDR_NODE1")
	)
	(segment
		(start 58.625994 -65.176654)
		(end 58.108088 -65.69456)
		(width 0.4572)
		(layer "In2.Cu")
		(net "PV_VDDR_NODE1")
	)
	(segment
		(start 59.33567 -67.741038)
		(end 59.383422 -67.741038)
		(width 0.4572)
		(layer "In2.Cu")
		(net "PV_VDDR_NODE1")
	)
	(segment
		(start 57.540144 -67.360038)
		(end 57.510934 -67.360038)
		(width 0.4572)
		(layer "In2.Cu")
		(net "PV_VDDR_NODE1")
	)
	(segment
		(start 59.383422 -65.404746)
		(end 59.15533 -65.176654)
		(width 0.4572)
		(layer "In2.Cu")
		(net "PV_VDDR_NODE1")
	)
	(segment
		(start 58.108088 -66.792094)
		(end 57.540144 -67.360038)
		(width 0.4572)
		(layer "In2.Cu")
		(net "PV_VDDR_NODE1")
	)
	(segment
		(start 58.108088 -65.69456)
		(end 58.108088 -66.792094)
		(width 0.4572)
		(layer "In2.Cu")
		(net "PV_VDDR_NODE1")
	)
	(segment
		(start 59.383422 -65.455038)
		(end 59.383422 -65.404746)
		(width 0.4572)
		(layer "In2.Cu")
		(net "PV_VDDR_NODE1")
	)
	(segment
		(start 57.510934 -67.360038)
		(end 58.161682 -68.010786)
		(width 0.4572)
		(layer "In2.Cu")
		(net "PV_VDDR_NODE1")
	)
	(segment
		(start 59.065922 -68.010786)
		(end 59.33567 -67.741038)
		(width 0.4572)
		(layer "In2.Cu")
		(net "PV_VDDR_NODE1")
	)
	(segment
		(start 59.15533 -65.176654)
		(end 58.625994 -65.176654)
		(width 0.4572)
		(layer "In2.Cu")
		(net "PV_VDDR_NODE1")
	)
	(segment
		(start 58.161682 -68.010786)
		(end 59.065922 -68.010786)
		(width 0.4572)
		(layer "In2.Cu")
		(net "PV_VDDR_NODE1")
	)
	(segment
		(start 57.510934 -67.360038)
		(end 57.397142 -67.360038)
		(width 0.4572)
		(layer "In2.Cu")
		(net "PV_VDDR_NODE1")
	)
	(segment
		(start 101.943662 -158.497778)
		(end 101.917754 -158.523686)
		(width 0.1016)
		(layer "F.Cu")
		(net "FM_CPLD_NODE1_P1V8_STB_EN")
	)
	(segment
		(start 101.026722 -159.571182)
		(end 101.026722 -158.52521)
		(width 0.1016)
		(layer "F.Cu")
		(net "FM_CPLD_NODE1_P1V8_STB_EN")
	)
	(segment
		(start 102.596188 -158.497778)
		(end 101.943662 -158.497778)
		(width 0.1016)
		(layer "F.Cu")
		(net "FM_CPLD_NODE1_P1V8_STB_EN")
	)
	(segment
		(start 101.917754 -158.523686)
		(end 101.028246 -158.523686)
		(width 0.1016)
		(layer "F.Cu")
		(net "FM_CPLD_NODE1_P1V8_STB_EN")
	)
	(segment
		(start 174.567088 -110.677706)
		(end 179.010564 -115.121182)
		(width 0.1016)
		(layer "F.Cu")
		(net "FM_CPLD_NODE1_P1V8_STB_EN")
	)
	(segment
		(start 168.7703 -110.677706)
		(end 174.567088 -110.677706)
		(width 0.1016)
		(layer "F.Cu")
		(net "FM_CPLD_NODE1_P1V8_STB_EN")
	)
	(segment
		(start 179.010564 -115.121182)
		(end 179.010564 -116.365528)
		(width 0.1016)
		(layer "F.Cu")
		(net "FM_CPLD_NODE1_P1V8_STB_EN")
	)
	(segment
		(start 101.026722 -158.52521)
		(end 101.028246 -158.523686)
		(width 0.1016)
		(layer "F.Cu")
		(net "FM_CPLD_NODE1_P1V8_STB_EN")
	)
	(via
		(at 145.1991 -159.003492)
		(size 0.508)
		(drill 0.254)
		(layers "F.Cu" "B.Cu")
		(net "FM_CPLD_NODE1_P1V8_STB_EN")
	)
	(via
		(at 168.7703 -110.677706)
		(size 0.508)
		(drill 0.254)
		(layers "F.Cu" "B.Cu")
		(net "FM_CPLD_NODE1_P1V8_STB_EN")
	)
	(via
		(at 101.943662 -158.497778)
		(size 0.508)
		(drill 0.254)
		(layers "F.Cu" "B.Cu")
		(net "FM_CPLD_NODE1_P1V8_STB_EN")
	)
	(segment
		(start 158.261304 -134.656068)
		(end 156.314902 -134.656068)
		(width 0.1143)
		(layer "In2.Cu")
		(net "FM_CPLD_NODE1_P1V8_STB_EN")
	)
	(segment
		(start 164.69995 -127.712216)
		(end 165.018974 -128.03124)
		(width 0.1143)
		(layer "In2.Cu")
		(net "FM_CPLD_NODE1_P1V8_STB_EN")
	)
	(segment
		(start 168.351962 -119.446802)
		(end 170.109896 -121.204736)
		(width 0.1143)
		(layer "In2.Cu")
		(net "FM_CPLD_NODE1_P1V8_STB_EN")
	)
	(segment
		(start 165.018974 -128.61544)
		(end 164.64661 -128.987804)
		(width 0.1143)
		(layer "In2.Cu")
		(net "FM_CPLD_NODE1_P1V8_STB_EN")
	)
	(segment
		(start 164.06495 -134.1247)
		(end 158.792672 -134.1247)
		(width 0.1143)
		(layer "In2.Cu")
		(net "FM_CPLD_NODE1_P1V8_STB_EN")
	)
	(segment
		(start 151.83485 -141.803882)
		(end 151.44496 -142.193772)
		(width 0.1143)
		(layer "In2.Cu")
		(net "FM_CPLD_NODE1_P1V8_STB_EN")
	)
	(segment
		(start 170.109896 -121.204736)
		(end 170.109896 -121.6152)
		(width 0.1143)
		(layer "In2.Cu")
		(net "FM_CPLD_NODE1_P1V8_STB_EN")
	)
	(segment
		(start 168.17467 -121.905268)
		(end 164.69995 -125.379988)
		(width 0.1143)
		(layer "In2.Cu")
		(net "FM_CPLD_NODE1_P1V8_STB_EN")
	)
	(segment
		(start 150.70074 -149.99208)
		(end 147.7899 -152.90292)
		(width 0.1143)
		(layer "In2.Cu")
		(net "FM_CPLD_NODE1_P1V8_STB_EN")
	)
	(segment
		(start 158.792672 -134.1247)
		(end 158.261304 -134.656068)
		(width 0.1143)
		(layer "In2.Cu")
		(net "FM_CPLD_NODE1_P1V8_STB_EN")
	)
	(segment
		(start 168.7703 -117.11178)
		(end 168.351962 -117.530118)
		(width 0.1143)
		(layer "In2.Cu")
		(net "FM_CPLD_NODE1_P1V8_STB_EN")
	)
	(segment
		(start 145.42262 -157.436312)
		(end 145.42262 -158.779972)
		(width 0.1143)
		(layer "In2.Cu")
		(net "FM_CPLD_NODE1_P1V8_STB_EN")
	)
	(segment
		(start 151.44496 -144.59966)
		(end 150.70074 -145.34388)
		(width 0.1143)
		(layer "In2.Cu")
		(net "FM_CPLD_NODE1_P1V8_STB_EN")
	)
	(segment
		(start 168.351962 -117.530118)
		(end 168.351962 -119.446802)
		(width 0.1143)
		(layer "In2.Cu")
		(net "FM_CPLD_NODE1_P1V8_STB_EN")
	)
	(segment
		(start 147.7899 -155.069032)
		(end 145.42262 -157.436312)
		(width 0.1143)
		(layer "In2.Cu")
		(net "FM_CPLD_NODE1_P1V8_STB_EN")
	)
	(segment
		(start 164.64661 -128.987804)
		(end 164.64661 -133.54304)
		(width 0.1143)
		(layer "In2.Cu")
		(net "FM_CPLD_NODE1_P1V8_STB_EN")
	)
	(segment
		(start 151.44496 -142.193772)
		(end 151.44496 -144.59966)
		(width 0.1143)
		(layer "In2.Cu")
		(net "FM_CPLD_NODE1_P1V8_STB_EN")
	)
	(segment
		(start 156.314902 -134.656068)
		(end 151.83485 -139.13612)
		(width 0.1143)
		(layer "In2.Cu")
		(net "FM_CPLD_NODE1_P1V8_STB_EN")
	)
	(segment
		(start 151.83485 -139.13612)
		(end 151.83485 -141.803882)
		(width 0.1143)
		(layer "In2.Cu")
		(net "FM_CPLD_NODE1_P1V8_STB_EN")
	)
	(segment
		(start 150.70074 -145.34388)
		(end 150.70074 -149.99208)
		(width 0.1143)
		(layer "In2.Cu")
		(net "FM_CPLD_NODE1_P1V8_STB_EN")
	)
	(segment
		(start 168.7703 -110.677706)
		(end 168.7703 -117.11178)
		(width 0.1143)
		(layer "In2.Cu")
		(net "FM_CPLD_NODE1_P1V8_STB_EN")
	)
	(segment
		(start 169.819828 -121.905268)
		(end 168.17467 -121.905268)
		(width 0.1143)
		(layer "In2.Cu")
		(net "FM_CPLD_NODE1_P1V8_STB_EN")
	)
	(segment
		(start 164.69995 -125.379988)
		(end 164.69995 -127.712216)
		(width 0.1143)
		(layer "In2.Cu")
		(net "FM_CPLD_NODE1_P1V8_STB_EN")
	)
	(segment
		(start 147.7899 -152.90292)
		(end 147.7899 -155.069032)
		(width 0.1143)
		(layer "In2.Cu")
		(net "FM_CPLD_NODE1_P1V8_STB_EN")
	)
	(segment
		(start 145.42262 -158.779972)
		(end 145.1991 -159.003492)
		(width 0.1143)
		(layer "In2.Cu")
		(net "FM_CPLD_NODE1_P1V8_STB_EN")
	)
	(segment
		(start 170.109896 -121.6152)
		(end 169.819828 -121.905268)
		(width 0.1143)
		(layer "In2.Cu")
		(net "FM_CPLD_NODE1_P1V8_STB_EN")
	)
	(segment
		(start 165.018974 -128.03124)
		(end 165.018974 -128.61544)
		(width 0.1143)
		(layer "In2.Cu")
		(net "FM_CPLD_NODE1_P1V8_STB_EN")
	)
	(segment
		(start 164.64661 -133.54304)
		(end 164.06495 -134.1247)
		(width 0.1143)
		(layer "In2.Cu")
		(net "FM_CPLD_NODE1_P1V8_STB_EN")
	)
	(segment
		(start 126.05258 -159.31388)
		(end 126.39929 -158.96717)
		(width 0.1143)
		(layer "In6.Cu")
		(net "FM_CPLD_NODE1_P1V8_STB_EN")
	)
	(segment
		(start 130.762248 -157.961584)
		(end 137.465816 -157.961584)
		(width 0.1143)
		(layer "In6.Cu")
		(net "FM_CPLD_NODE1_P1V8_STB_EN")
	)
	(segment
		(start 144.530826 -159.003492)
		(end 145.1991 -159.003492)
		(width 0.1143)
		(layer "In6.Cu")
		(net "FM_CPLD_NODE1_P1V8_STB_EN")
	)
	(segment
		(start 104.939338 -158.497778)
		(end 105.43286 -158.9913)
		(width 0.1143)
		(layer "In6.Cu")
		(net "FM_CPLD_NODE1_P1V8_STB_EN")
	)
	(segment
		(start 111.063024 -160.380426)
		(end 111.38789 -160.705292)
		(width 0.1143)
		(layer "In6.Cu")
		(net "FM_CPLD_NODE1_P1V8_STB_EN")
	)
	(segment
		(start 107.526074 -158.9913)
		(end 108.9152 -160.380426)
		(width 0.1143)
		(layer "In6.Cu")
		(net "FM_CPLD_NODE1_P1V8_STB_EN")
	)
	(segment
		(start 144.423892 -158.896558)
		(end 144.530826 -159.003492)
		(width 0.1143)
		(layer "In6.Cu")
		(net "FM_CPLD_NODE1_P1V8_STB_EN")
	)
	(segment
		(start 129.756662 -158.96717)
		(end 130.762248 -157.961584)
		(width 0.1143)
		(layer "In6.Cu")
		(net "FM_CPLD_NODE1_P1V8_STB_EN")
	)
	(segment
		(start 105.43286 -158.9913)
		(end 107.526074 -158.9913)
		(width 0.1143)
		(layer "In6.Cu")
		(net "FM_CPLD_NODE1_P1V8_STB_EN")
	)
	(segment
		(start 137.48004 -157.975808)
		(end 138.534902 -157.975808)
		(width 0.1143)
		(layer "In6.Cu")
		(net "FM_CPLD_NODE1_P1V8_STB_EN")
	)
	(segment
		(start 111.75238 -160.705292)
		(end 111.975646 -160.48228)
		(width 0.1143)
		(layer "In6.Cu")
		(net "FM_CPLD_NODE1_P1V8_STB_EN")
	)
	(segment
		(start 138.534902 -157.975808)
		(end 138.6586 -157.85211)
		(width 0.1143)
		(layer "In6.Cu")
		(net "FM_CPLD_NODE1_P1V8_STB_EN")
	)
	(segment
		(start 120.87352 -159.31388)
		(end 126.05258 -159.31388)
		(width 0.1143)
		(layer "In6.Cu")
		(net "FM_CPLD_NODE1_P1V8_STB_EN")
	)
	(segment
		(start 108.9152 -160.380426)
		(end 111.063024 -160.380426)
		(width 0.1143)
		(layer "In6.Cu")
		(net "FM_CPLD_NODE1_P1V8_STB_EN")
	)
	(segment
		(start 119.70512 -160.48228)
		(end 120.87352 -159.31388)
		(width 0.1143)
		(layer "In6.Cu")
		(net "FM_CPLD_NODE1_P1V8_STB_EN")
	)
	(segment
		(start 101.943662 -158.497778)
		(end 104.939338 -158.497778)
		(width 0.1143)
		(layer "In6.Cu")
		(net "FM_CPLD_NODE1_P1V8_STB_EN")
	)
	(segment
		(start 111.975646 -160.48228)
		(end 119.70512 -160.48228)
		(width 0.1143)
		(layer "In6.Cu")
		(net "FM_CPLD_NODE1_P1V8_STB_EN")
	)
	(segment
		(start 143.400018 -158.896558)
		(end 144.423892 -158.896558)
		(width 0.1143)
		(layer "In6.Cu")
		(net "FM_CPLD_NODE1_P1V8_STB_EN")
	)
	(segment
		(start 111.38789 -160.705292)
		(end 111.75238 -160.705292)
		(width 0.1143)
		(layer "In6.Cu")
		(net "FM_CPLD_NODE1_P1V8_STB_EN")
	)
	(segment
		(start 142.35557 -157.85211)
		(end 143.400018 -158.896558)
		(width 0.1143)
		(layer "In6.Cu")
		(net "FM_CPLD_NODE1_P1V8_STB_EN")
	)
	(segment
		(start 138.6586 -157.85211)
		(end 142.35557 -157.85211)
		(width 0.1143)
		(layer "In6.Cu")
		(net "FM_CPLD_NODE1_P1V8_STB_EN")
	)
	(segment
		(start 137.465816 -157.961584)
		(end 137.48004 -157.975808)
		(width 0.1143)
		(layer "In6.Cu")
		(net "FM_CPLD_NODE1_P1V8_STB_EN")
	)
	(segment
		(start 126.39929 -158.96717)
		(end 129.756662 -158.96717)
		(width 0.1143)
		(layer "In6.Cu")
		(net "FM_CPLD_NODE1_P1V8_STB_EN")
	)
	(segment
		(start 169.043858 -121.865644)
		(end 168.34612 -121.167906)
		(width 0.1016)
		(layer "F.Cu")
		(net "FM_CPLD_NODE1_CPU_RSMRST_L")
	)
	(segment
		(start 75.456542 -83.606386)
		(end 75.193906 -83.869022)
		(width 0.1016)
		(layer "F.Cu")
		(net "FM_CPLD_NODE1_CPU_RSMRST_L")
	)
	(segment
		(start 75.193906 -83.869022)
		(end 73.612248 -83.869022)
		(width 0.1016)
		(layer "F.Cu")
		(net "FM_CPLD_NODE1_CPU_RSMRST_L")
	)
	(segment
		(start 173.010322 -121.365518)
		(end 172.510196 -121.865644)
		(width 0.1016)
		(layer "F.Cu")
		(net "FM_CPLD_NODE1_CPU_RSMRST_L")
	)
	(segment
		(start 172.510196 -121.865644)
		(end 169.043858 -121.865644)
		(width 0.1016)
		(layer "F.Cu")
		(net "FM_CPLD_NODE1_CPU_RSMRST_L")
	)
	(segment
		(start 73.2409 -84.24037)
		(end 72.795384 -84.24037)
		(width 0.1016)
		(layer "F.Cu")
		(net "FM_CPLD_NODE1_CPU_RSMRST_L")
	)
	(segment
		(start 73.612248 -83.869022)
		(end 73.2409 -84.24037)
		(width 0.1016)
		(layer "F.Cu")
		(net "FM_CPLD_NODE1_CPU_RSMRST_L")
	)
	(via
		(at 168.34612 -121.167906)
		(size 0.508)
		(drill 0.254)
		(layers "F.Cu" "B.Cu")
		(net "FM_CPLD_NODE1_CPU_RSMRST_L")
	)
	(via
		(at 75.456542 -83.606386)
		(size 0.508)
		(drill 0.254)
		(layers "F.Cu" "B.Cu")
		(net "FM_CPLD_NODE1_CPU_RSMRST_L")
	)
	(segment
		(start 81.48193 -88.51646)
		(end 82.122264 -89.156794)
		(width 0.1143)
		(layer "In6.Cu")
		(net "FM_CPLD_NODE1_CPU_RSMRST_L")
	)
	(segment
		(start 168.34612 -112.672876)
		(end 168.34612 -121.167906)
		(width 0.1143)
		(layer "In6.Cu")
		(net "FM_CPLD_NODE1_CPU_RSMRST_L")
	)
	(segment
		(start 94.84995 -87.328756)
		(end 135.941054 -87.328756)
		(width 0.1143)
		(layer "In6.Cu")
		(net "FM_CPLD_NODE1_CPU_RSMRST_L")
	)
	(segment
		(start 148.373592 -99.761294)
		(end 151.123142 -99.761294)
		(width 0.1143)
		(layer "In6.Cu")
		(net "FM_CPLD_NODE1_CPU_RSMRST_L")
	)
	(segment
		(start 86.909148 -89.156794)
		(end 88.616028 -90.863674)
		(width 0.1143)
		(layer "In6.Cu")
		(net "FM_CPLD_NODE1_CPU_RSMRST_L")
	)
	(segment
		(start 91.315032 -90.863674)
		(end 94.84995 -87.328756)
		(width 0.1143)
		(layer "In6.Cu")
		(net "FM_CPLD_NODE1_CPU_RSMRST_L")
	)
	(segment
		(start 75.456542 -84.36483)
		(end 76.7588 -85.667088)
		(width 0.1143)
		(layer "In6.Cu")
		(net "FM_CPLD_NODE1_CPU_RSMRST_L")
	)
	(segment
		(start 75.456542 -83.606386)
		(end 75.456542 -84.36483)
		(width 0.1143)
		(layer "In6.Cu")
		(net "FM_CPLD_NODE1_CPU_RSMRST_L")
	)
	(segment
		(start 156.487876 -110.090966)
		(end 165.76421 -110.090966)
		(width 0.1143)
		(layer "In6.Cu")
		(net "FM_CPLD_NODE1_CPU_RSMRST_L")
	)
	(segment
		(start 135.941054 -87.328756)
		(end 148.373592 -99.761294)
		(width 0.1143)
		(layer "In6.Cu")
		(net "FM_CPLD_NODE1_CPU_RSMRST_L")
	)
	(segment
		(start 151.9555 -100.593652)
		(end 151.9555 -105.55859)
		(width 0.1143)
		(layer "In6.Cu")
		(net "FM_CPLD_NODE1_CPU_RSMRST_L")
	)
	(segment
		(start 77.863954 -85.667088)
		(end 80.713326 -88.51646)
		(width 0.1143)
		(layer "In6.Cu")
		(net "FM_CPLD_NODE1_CPU_RSMRST_L")
	)
	(segment
		(start 151.9555 -105.55859)
		(end 156.487876 -110.090966)
		(width 0.1143)
		(layer "In6.Cu")
		(net "FM_CPLD_NODE1_CPU_RSMRST_L")
	)
	(segment
		(start 82.122264 -89.156794)
		(end 86.909148 -89.156794)
		(width 0.1143)
		(layer "In6.Cu")
		(net "FM_CPLD_NODE1_CPU_RSMRST_L")
	)
	(segment
		(start 165.76421 -110.090966)
		(end 168.34612 -112.672876)
		(width 0.1143)
		(layer "In6.Cu")
		(net "FM_CPLD_NODE1_CPU_RSMRST_L")
	)
	(segment
		(start 88.616028 -90.863674)
		(end 91.315032 -90.863674)
		(width 0.1143)
		(layer "In6.Cu")
		(net "FM_CPLD_NODE1_CPU_RSMRST_L")
	)
	(segment
		(start 151.123142 -99.761294)
		(end 151.9555 -100.593652)
		(width 0.1143)
		(layer "In6.Cu")
		(net "FM_CPLD_NODE1_CPU_RSMRST_L")
	)
	(segment
		(start 80.713326 -88.51646)
		(end 81.48193 -88.51646)
		(width 0.1143)
		(layer "In6.Cu")
		(net "FM_CPLD_NODE1_CPU_RSMRST_L")
	)
	(segment
		(start 76.7588 -85.667088)
		(end 77.863954 -85.667088)
		(width 0.1143)
		(layer "In6.Cu")
		(net "FM_CPLD_NODE1_CPU_RSMRST_L")
	)
	(segment
		(start 83.816444 -122.641614)
		(end 86.234524 -122.641614)
		(width 0.1016)
		(layer "F.Cu")
		(net "LPC_CPU_NODE1_LAD3")
	)
	(segment
		(start 92.71254 -16.204438)
		(end 92.88018 -16.372078)
		(width 0.1016)
		(layer "F.Cu")
		(net "LPC_CPU_NODE1_LAD3")
	)
	(segment
		(start 92.88018 -16.372078)
		(end 92.88018 -16.372332)
		(width 0.1016)
		(layer "F.Cu")
		(net "LPC_CPU_NODE1_LAD3")
	)
	(segment
		(start 91.17076 -16.204438)
		(end 92.71254 -16.204438)
		(width 0.1016)
		(layer "F.Cu")
		(net "LPC_CPU_NODE1_LAD3")
	)
	(via
		(at 96.40824 -95.23857)
		(size 0.508)
		(drill 0.254)
		(layers "F.Cu" "B.Cu")
		(net "LPC_CPU_NODE1_LAD3")
	)
	(via
		(at 92.61983 -95.77451)
		(size 0.508)
		(drill 0.254)
		(layers "F.Cu" "B.Cu")
		(net "LPC_CPU_NODE1_LAD3")
	)
	(via
		(at 58.730642 -99.421696)
		(size 0.508)
		(drill 0.254)
		(layers "F.Cu" "B.Cu")
		(net "LPC_CPU_NODE1_LAD3")
	)
	(via
		(at 92.88018 -16.372332)
		(size 0.508)
		(drill 0.254)
		(layers "F.Cu" "B.Cu")
		(net "LPC_CPU_NODE1_LAD3")
	)
	(via
		(at 86.234524 -122.641614)
		(size 0.508)
		(drill 0.254)
		(layers "F.Cu" "B.Cu")
		(net "LPC_CPU_NODE1_LAD3")
	)
	(via
		(at 120.05818 -42.265092)
		(size 0.508)
		(drill 0.254)
		(layers "F.Cu" "B.Cu")
		(net "LPC_CPU_NODE1_LAD3")
	)
	(segment
		(start 59.102498 -98.017076)
		(end 58.458862 -98.660712)
		(width 0.1016)
		(layer "B.Cu")
		(net "LPC_CPU_NODE1_LAD3")
	)
	(segment
		(start 120.624346 -42.265092)
		(end 121.204736 -41.684702)
		(width 0.1016)
		(layer "B.Cu")
		(net "LPC_CPU_NODE1_LAD3")
	)
	(segment
		(start 59.102498 -96.715834)
		(end 59.102498 -98.017076)
		(width 0.1016)
		(layer "B.Cu")
		(net "LPC_CPU_NODE1_LAD3")
	)
	(segment
		(start 121.204736 -41.684702)
		(end 121.69775 -41.684702)
		(width 0.1016)
		(layer "B.Cu")
		(net "LPC_CPU_NODE1_LAD3")
	)
	(segment
		(start 58.458862 -98.660712)
		(end 58.458862 -99.149916)
		(width 0.1016)
		(layer "B.Cu")
		(net "LPC_CPU_NODE1_LAD3")
	)
	(segment
		(start 120.05818 -42.265092)
		(end 120.624346 -42.265092)
		(width 0.1016)
		(layer "B.Cu")
		(net "LPC_CPU_NODE1_LAD3")
	)
	(segment
		(start 58.458862 -99.149916)
		(end 58.730642 -99.421696)
		(width 0.1016)
		(layer "B.Cu")
		(net "LPC_CPU_NODE1_LAD3")
	)
	(segment
		(start 69.519292 -102.912672)
		(end 66.779648 -102.36835)
		(width 0.1143)
		(layer "In2.Cu")
		(net "LPC_CPU_NODE1_LAD3")
	)
	(segment
		(start 117.051582 -63.300102)
		(end 116.39931 -62.64783)
		(width 0.1143)
		(layer "In2.Cu")
		(net "LPC_CPU_NODE1_LAD3")
	)
	(segment
		(start 116.67998 -66.702686)
		(end 116.7384 -66.644266)
		(width 0.1143)
		(layer "In2.Cu")
		(net "LPC_CPU_NODE1_LAD3")
	)
	(segment
		(start 60.29706 -101.05644)
		(end 58.730642 -99.490022)
		(width 0.1143)
		(layer "In2.Cu")
		(net "LPC_CPU_NODE1_LAD3")
	)
	(segment
		(start 76.43368 -105.824274)
		(end 73.522078 -102.912672)
		(width 0.1143)
		(layer "In2.Cu")
		(net "LPC_CPU_NODE1_LAD3")
	)
	(segment
		(start 84.928202 -115.862354)
		(end 84.928202 -115.263422)
		(width 0.1143)
		(layer "In2.Cu")
		(net "LPC_CPU_NODE1_LAD3")
	)
	(segment
		(start 117.051582 -66.32956)
		(end 117.051582 -63.300102)
		(width 0.1143)
		(layer "In2.Cu")
		(net "LPC_CPU_NODE1_LAD3")
	)
	(segment
		(start 92.61983 -95.77451)
		(end 88.63838 -99.75596)
		(width 0.1143)
		(layer "In2.Cu")
		(net "LPC_CPU_NODE1_LAD3")
	)
	(segment
		(start 103.076248 -19.308318)
		(end 99.95281 -19.308318)
		(width 0.1143)
		(layer "In2.Cu")
		(net "LPC_CPU_NODE1_LAD3")
	)
	(segment
		(start 84.928202 -115.263422)
		(end 85.33638 -114.855244)
		(width 0.1143)
		(layer "In2.Cu")
		(net "LPC_CPU_NODE1_LAD3")
	)
	(segment
		(start 86.234524 -122.641614)
		(end 85.923882 -122.641614)
		(width 0.1143)
		(layer "In2.Cu")
		(net "LPC_CPU_NODE1_LAD3")
	)
	(segment
		(start 85.39734 -118.139718)
		(end 84.928202 -115.862354)
		(width 0.1143)
		(layer "In2.Cu")
		(net "LPC_CPU_NODE1_LAD3")
	)
	(segment
		(start 96.40824 -95.23857)
		(end 96.477582 -95.169228)
		(width 0.1143)
		(layer "In2.Cu")
		(net "LPC_CPU_NODE1_LAD3")
	)
	(segment
		(start 88.63838 -101.170486)
		(end 87.24392 -102.564946)
		(width 0.1143)
		(layer "In2.Cu")
		(net "LPC_CPU_NODE1_LAD3")
	)
	(segment
		(start 89.15273 -110.177834)
		(end 89.15273 -119.723408)
		(width 0.1143)
		(layer "In2.Cu")
		(net "LPC_CPU_NODE1_LAD3")
	)
	(segment
		(start 97.35058 -18.625566)
		(end 94.470474 -17.267174)
		(width 0.1143)
		(layer "In2.Cu")
		(net "LPC_CPU_NODE1_LAD3")
	)
	(segment
		(start 85.923882 -122.641614)
		(end 85.39734 -122.115072)
		(width 0.1143)
		(layer "In2.Cu")
		(net "LPC_CPU_NODE1_LAD3")
	)
	(segment
		(start 81.028794 -113.031016)
		(end 79.05242 -113.031016)
		(width 0.1143)
		(layer "In2.Cu")
		(net "LPC_CPU_NODE1_LAD3")
	)
	(segment
		(start 116.63426 -66.751962)
		(end 116.67998 -66.706242)
		(width 0.1143)
		(layer "In2.Cu")
		(net "LPC_CPU_NODE1_LAD3")
	)
	(segment
		(start 87.24392 -102.564946)
		(end 87.24392 -108.269024)
		(width 0.1143)
		(layer "In2.Cu")
		(net "LPC_CPU_NODE1_LAD3")
	)
	(segment
		(start 65.85712 -101.797866)
		(end 65.115694 -101.05644)
		(width 0.1143)
		(layer "In2.Cu")
		(net "LPC_CPU_NODE1_LAD3")
	)
	(segment
		(start 97.0661 -94.807278)
		(end 97.0661 -92.268802)
		(width 0.1143)
		(layer "In2.Cu")
		(net "LPC_CPU_NODE1_LAD3")
	)
	(segment
		(start 84.182458 -112.293908)
		(end 81.765902 -112.293908)
		(width 0.1143)
		(layer "In2.Cu")
		(net "LPC_CPU_NODE1_LAD3")
	)
	(segment
		(start 87.24392 -108.269024)
		(end 89.15273 -110.177834)
		(width 0.1143)
		(layer "In2.Cu")
		(net "LPC_CPU_NODE1_LAD3")
	)
	(segment
		(start 66.779648 -102.36835)
		(end 66.209164 -101.797866)
		(width 0.1143)
		(layer "In2.Cu")
		(net "LPC_CPU_NODE1_LAD3")
	)
	(segment
		(start 96.70415 -95.169228)
		(end 97.0661 -94.807278)
		(width 0.1143)
		(layer "In2.Cu")
		(net "LPC_CPU_NODE1_LAD3")
	)
	(segment
		(start 93.575378 -16.372078)
		(end 92.88018 -16.372078)
		(width 0.1143)
		(layer "In2.Cu")
		(net "LPC_CPU_NODE1_LAD3")
	)
	(segment
		(start 96.477582 -95.169228)
		(end 96.70415 -95.169228)
		(width 0.1143)
		(layer "In2.Cu")
		(net "LPC_CPU_NODE1_LAD3")
	)
	(segment
		(start 116.63426 -76.086462)
		(end 116.63426 -66.751962)
		(width 0.1143)
		(layer "In2.Cu")
		(net "LPC_CPU_NODE1_LAD3")
	)
	(segment
		(start 103.878634 -85.456268)
		(end 107.264454 -85.456268)
		(width 0.1143)
		(layer "In2.Cu")
		(net "LPC_CPU_NODE1_LAD3")
	)
	(segment
		(start 97.0661 -92.268802)
		(end 103.878634 -85.456268)
		(width 0.1143)
		(layer "In2.Cu")
		(net "LPC_CPU_NODE1_LAD3")
	)
	(segment
		(start 108.769912 -25.001982)
		(end 103.076248 -19.308318)
		(width 0.1143)
		(layer "In2.Cu")
		(net "LPC_CPU_NODE1_LAD3")
	)
	(segment
		(start 73.522078 -102.912672)
		(end 69.519292 -102.912672)
		(width 0.1143)
		(layer "In2.Cu")
		(net "LPC_CPU_NODE1_LAD3")
	)
	(segment
		(start 76.43368 -110.412276)
		(end 76.43368 -105.824274)
		(width 0.1143)
		(layer "In2.Cu")
		(net "LPC_CPU_NODE1_LAD3")
	)
	(segment
		(start 85.33638 -114.855244)
		(end 85.33638 -113.44783)
		(width 0.1143)
		(layer "In2.Cu")
		(net "LPC_CPU_NODE1_LAD3")
	)
	(segment
		(start 108.769912 -48.82007)
		(end 108.769912 -25.001982)
		(width 0.1143)
		(layer "In2.Cu")
		(net "LPC_CPU_NODE1_LAD3")
	)
	(segment
		(start 89.15273 -119.723408)
		(end 86.234524 -122.641614)
		(width 0.1143)
		(layer "In2.Cu")
		(net "LPC_CPU_NODE1_LAD3")
	)
	(segment
		(start 85.39734 -122.115072)
		(end 85.39734 -118.139718)
		(width 0.1143)
		(layer "In2.Cu")
		(net "LPC_CPU_NODE1_LAD3")
	)
	(segment
		(start 88.63838 -99.75596)
		(end 88.63838 -101.170486)
		(width 0.1143)
		(layer "In2.Cu")
		(net "LPC_CPU_NODE1_LAD3")
	)
	(segment
		(start 65.115694 -101.05644)
		(end 60.29706 -101.05644)
		(width 0.1143)
		(layer "In2.Cu")
		(net "LPC_CPU_NODE1_LAD3")
	)
	(segment
		(start 116.7384 -66.642742)
		(end 117.051582 -66.32956)
		(width 0.1143)
		(layer "In2.Cu")
		(net "LPC_CPU_NODE1_LAD3")
	)
	(segment
		(start 66.209164 -101.797866)
		(end 65.85712 -101.797866)
		(width 0.1143)
		(layer "In2.Cu")
		(net "LPC_CPU_NODE1_LAD3")
	)
	(segment
		(start 116.67998 -66.706242)
		(end 116.67998 -66.702686)
		(width 0.1143)
		(layer "In2.Cu")
		(net "LPC_CPU_NODE1_LAD3")
	)
	(segment
		(start 58.730642 -99.490022)
		(end 58.730642 -99.421696)
		(width 0.1143)
		(layer "In2.Cu")
		(net "LPC_CPU_NODE1_LAD3")
	)
	(segment
		(start 99.95281 -19.308318)
		(end 99.270058 -18.625566)
		(width 0.1143)
		(layer "In2.Cu")
		(net "LPC_CPU_NODE1_LAD3")
	)
	(segment
		(start 116.39931 -56.449468)
		(end 108.769912 -48.82007)
		(width 0.1143)
		(layer "In2.Cu")
		(net "LPC_CPU_NODE1_LAD3")
	)
	(segment
		(start 85.33638 -113.44783)
		(end 84.182458 -112.293908)
		(width 0.1143)
		(layer "In2.Cu")
		(net "LPC_CPU_NODE1_LAD3")
	)
	(segment
		(start 92.88018 -16.372078)
		(end 92.88018 -16.372332)
		(width 0.1143)
		(layer "In2.Cu")
		(net "LPC_CPU_NODE1_LAD3")
	)
	(segment
		(start 107.264454 -85.456268)
		(end 116.63426 -76.086462)
		(width 0.1143)
		(layer "In2.Cu")
		(net "LPC_CPU_NODE1_LAD3")
	)
	(segment
		(start 99.270058 -18.625566)
		(end 97.35058 -18.625566)
		(width 0.1143)
		(layer "In2.Cu")
		(net "LPC_CPU_NODE1_LAD3")
	)
	(segment
		(start 116.39931 -62.64783)
		(end 116.39931 -56.449468)
		(width 0.1143)
		(layer "In2.Cu")
		(net "LPC_CPU_NODE1_LAD3")
	)
	(segment
		(start 79.05242 -113.031016)
		(end 76.43368 -110.412276)
		(width 0.1143)
		(layer "In2.Cu")
		(net "LPC_CPU_NODE1_LAD3")
	)
	(segment
		(start 116.7384 -66.644266)
		(end 116.7384 -66.642742)
		(width 0.1143)
		(layer "In2.Cu")
		(net "LPC_CPU_NODE1_LAD3")
	)
	(segment
		(start 81.765902 -112.293908)
		(end 81.028794 -113.031016)
		(width 0.1143)
		(layer "In2.Cu")
		(net "LPC_CPU_NODE1_LAD3")
	)
	(segment
		(start 94.470474 -17.267174)
		(end 93.575378 -16.372078)
		(width 0.1143)
		(layer "In2.Cu")
		(net "LPC_CPU_NODE1_LAD3")
	)
	(segment
		(start 98.1964 -16.907764)
		(end 97.7773 -17.326864)
		(width 0.1143)
		(layer "In7.Cu")
		(net "LPC_CPU_NODE1_LAD3")
	)
	(segment
		(start 119.59844 -38.435534)
		(end 115.487958 -34.325052)
		(width 0.1143)
		(layer "In7.Cu")
		(net "LPC_CPU_NODE1_LAD3")
	)
	(segment
		(start 101.49078 -16.82369)
		(end 100.680774 -16.82369)
		(width 0.1143)
		(layer "In7.Cu")
		(net "LPC_CPU_NODE1_LAD3")
	)
	(segment
		(start 119.59844 -39.772336)
		(end 119.59844 -38.435534)
		(width 0.1143)
		(layer "In7.Cu")
		(net "LPC_CPU_NODE1_LAD3")
	)
	(segment
		(start 111.50092 -28.14447)
		(end 110.363 -27.00655)
		(width 0.1143)
		(layer "In7.Cu")
		(net "LPC_CPU_NODE1_LAD3")
	)
	(segment
		(start 93.84157 -95.77451)
		(end 94.37751 -95.23857)
		(width 0.1143)
		(layer "In7.Cu")
		(net "LPC_CPU_NODE1_LAD3")
	)
	(segment
		(start 97.7773 -17.326864)
		(end 96.537526 -17.326864)
		(width 0.1143)
		(layer "In7.Cu")
		(net "LPC_CPU_NODE1_LAD3")
	)
	(segment
		(start 93.415612 -16.907764)
		(end 92.88018 -16.372332)
		(width 0.1143)
		(layer "In7.Cu")
		(net "LPC_CPU_NODE1_LAD3")
	)
	(segment
		(start 120.05818 -42.265092)
		(end 120.05818 -40.232076)
		(width 0.1143)
		(layer "In7.Cu")
		(net "LPC_CPU_NODE1_LAD3")
	)
	(segment
		(start 110.363 -27.00655)
		(end 110.363 -22.877272)
		(width 0.1143)
		(layer "In7.Cu")
		(net "LPC_CPU_NODE1_LAD3")
	)
	(segment
		(start 101.856794 -17.189704)
		(end 101.49078 -16.82369)
		(width 0.1143)
		(layer "In7.Cu")
		(net "LPC_CPU_NODE1_LAD3")
	)
	(segment
		(start 111.50092 -31.121096)
		(end 111.50092 -28.14447)
		(width 0.1143)
		(layer "In7.Cu")
		(net "LPC_CPU_NODE1_LAD3")
	)
	(segment
		(start 115.487958 -34.325052)
		(end 114.704876 -34.325052)
		(width 0.1143)
		(layer "In7.Cu")
		(net "LPC_CPU_NODE1_LAD3")
	)
	(segment
		(start 120.05818 -40.232076)
		(end 119.59844 -39.772336)
		(width 0.1143)
		(layer "In7.Cu")
		(net "LPC_CPU_NODE1_LAD3")
	)
	(segment
		(start 110.363 -22.877272)
		(end 104.675432 -17.189704)
		(width 0.1143)
		(layer "In7.Cu")
		(net "LPC_CPU_NODE1_LAD3")
	)
	(segment
		(start 100.680774 -16.82369)
		(end 100.5967 -16.907764)
		(width 0.1143)
		(layer "In7.Cu")
		(net "LPC_CPU_NODE1_LAD3")
	)
	(segment
		(start 114.704876 -34.325052)
		(end 111.50092 -31.121096)
		(width 0.1143)
		(layer "In7.Cu")
		(net "LPC_CPU_NODE1_LAD3")
	)
	(segment
		(start 94.37751 -95.23857)
		(end 96.40824 -95.23857)
		(width 0.1143)
		(layer "In7.Cu")
		(net "LPC_CPU_NODE1_LAD3")
	)
	(segment
		(start 100.5967 -16.907764)
		(end 98.1964 -16.907764)
		(width 0.1143)
		(layer "In7.Cu")
		(net "LPC_CPU_NODE1_LAD3")
	)
	(segment
		(start 96.537526 -17.326864)
		(end 96.118426 -16.907764)
		(width 0.1143)
		(layer "In7.Cu")
		(net "LPC_CPU_NODE1_LAD3")
	)
	(segment
		(start 92.61983 -95.77451)
		(end 93.84157 -95.77451)
		(width 0.1143)
		(layer "In7.Cu")
		(net "LPC_CPU_NODE1_LAD3")
	)
	(segment
		(start 104.675432 -17.189704)
		(end 101.856794 -17.189704)
		(width 0.1143)
		(layer "In7.Cu")
		(net "LPC_CPU_NODE1_LAD3")
	)
	(segment
		(start 96.118426 -16.907764)
		(end 93.415612 -16.907764)
		(width 0.1143)
		(layer "In7.Cu")
		(net "LPC_CPU_NODE1_LAD3")
	)
	(segment
		(start 56.065166 -96.309942)
		(end 56.065166 -95.621094)
		(width 0.1016)
		(layer "F.Cu")
		(net "PD_CPU_NODE1_DFX_GPIO_GRP0_0")
	)
	(segment
		(start 55.747412 -88.634062)
		(end 55.640224 -88.74125)
		(width 0.1016)
		(layer "F.Cu")
		(net "PD_CPU_NODE1_DFX_GPIO_GRP0_0")
	)
	(segment
		(start 56.065166 -95.621094)
		(end 55.325772 -94.8817)
		(width 0.1016)
		(layer "F.Cu")
		(net "PD_CPU_NODE1_DFX_GPIO_GRP0_0")
	)
	(segment
		(start 55.640224 -91.280488)
		(end 55.325772 -91.59494)
		(width 0.1016)
		(layer "F.Cu")
		(net "PD_CPU_NODE1_DFX_GPIO_GRP0_0")
	)
	(segment
		(start 55.325772 -94.8817)
		(end 55.325772 -93.64091)
		(width 0.1016)
		(layer "F.Cu")
		(net "PD_CPU_NODE1_DFX_GPIO_GRP0_0")
	)
	(segment
		(start 56.103012 -87.700358)
		(end 55.747412 -88.055958)
		(width 0.1016)
		(layer "F.Cu")
		(net "PD_CPU_NODE1_DFX_GPIO_GRP0_0")
	)
	(segment
		(start 55.640224 -88.74125)
		(end 55.640224 -91.280488)
		(width 0.1016)
		(layer "F.Cu")
		(net "PD_CPU_NODE1_DFX_GPIO_GRP0_0")
	)
	(segment
		(start 55.325772 -91.59494)
		(end 55.325772 -93.64091)
		(width 0.1016)
		(layer "F.Cu")
		(net "PD_CPU_NODE1_DFX_GPIO_GRP0_0")
	)
	(segment
		(start 55.747412 -88.055958)
		(end 55.747412 -88.634062)
		(width 0.1016)
		(layer "F.Cu")
		(net "PD_CPU_NODE1_DFX_GPIO_GRP0_0")
	)
	(via
		(at 55.325772 -93.64091)
		(size 0.762)
		(drill 0.381)
		(layers "F.Cu" "B.Cu")
		(net "PD_CPU_NODE1_DFX_GPIO_GRP0_0")
	)
	(segment
		(start 93.993462 -16.249142)
		(end 94.88424 -16.249142)
		(width 0.1016)
		(layer "F.Cu")
		(net "LPC_CPU_NODE1_LAD2")
	)
	(segment
		(start 85.411056 -122.141488)
		(end 83.816444 -122.141488)
		(width 0.1016)
		(layer "F.Cu")
		(net "LPC_CPU_NODE1_LAD2")
	)
	(segment
		(start 85.725 -121.827544)
		(end 85.411056 -122.141488)
		(width 0.1016)
		(layer "F.Cu")
		(net "LPC_CPU_NODE1_LAD2")
	)
	(segment
		(start 86.045548 -121.827544)
		(end 85.725 -121.827544)
		(width 0.1016)
		(layer "F.Cu")
		(net "LPC_CPU_NODE1_LAD2")
	)
	(via
		(at 96.338644 -96.01581)
		(size 0.508)
		(drill 0.254)
		(layers "F.Cu" "B.Cu")
		(net "LPC_CPU_NODE1_LAD2")
	)
	(via
		(at 94.88424 -16.249142)
		(size 0.508)
		(drill 0.254)
		(layers "F.Cu" "B.Cu")
		(net "LPC_CPU_NODE1_LAD2")
	)
	(via
		(at 90.09126 -95.758)
		(size 0.508)
		(drill 0.254)
		(layers "F.Cu" "B.Cu")
		(net "LPC_CPU_NODE1_LAD2")
	)
	(via
		(at 60.05322 -99.94138)
		(size 0.508)
		(drill 0.254)
		(layers "F.Cu" "B.Cu")
		(net "LPC_CPU_NODE1_LAD2")
	)
	(via
		(at 86.045548 -121.827544)
		(size 0.508)
		(drill 0.254)
		(layers "F.Cu" "B.Cu")
		(net "LPC_CPU_NODE1_LAD2")
	)
	(via
		(at 120.84304 -42.861738)
		(size 0.508)
		(drill 0.254)
		(layers "F.Cu" "B.Cu")
		(net "LPC_CPU_NODE1_LAD2")
	)
	(segment
		(start 121.69775 -42.700702)
		(end 121.004076 -42.700702)
		(width 0.1016)
		(layer "B.Cu")
		(net "LPC_CPU_NODE1_LAD2")
	)
	(segment
		(start 60.05322 -99.94138)
		(end 60.071 -99.9236)
		(width 0.1016)
		(layer "B.Cu")
		(net "LPC_CPU_NODE1_LAD2")
	)
	(segment
		(start 60.071 -99.9236)
		(end 60.071 -99.213416)
		(width 0.1016)
		(layer "B.Cu")
		(net "LPC_CPU_NODE1_LAD2")
	)
	(segment
		(start 60.071 -99.213416)
		(end 60.8965 -98.387916)
		(width 0.1016)
		(layer "B.Cu")
		(net "LPC_CPU_NODE1_LAD2")
	)
	(segment
		(start 60.8965 -98.387916)
		(end 60.8965 -96.286574)
		(width 0.1016)
		(layer "B.Cu")
		(net "LPC_CPU_NODE1_LAD2")
	)
	(segment
		(start 60.8965 -96.286574)
		(end 61.191902 -95.991172)
		(width 0.1016)
		(layer "B.Cu")
		(net "LPC_CPU_NODE1_LAD2")
	)
	(segment
		(start 121.004076 -42.700702)
		(end 120.84304 -42.861738)
		(width 0.1016)
		(layer "B.Cu")
		(net "LPC_CPU_NODE1_LAD2")
	)
	(segment
		(start 61.191902 -95.991172)
		(end 61.191902 -95.7961)
		(width 0.1016)
		(layer "B.Cu")
		(net "LPC_CPU_NODE1_LAD2")
	)
	(segment
		(start 60.05322 -99.94138)
		(end 60.189618 -99.94138)
		(width 0.1143)
		(layer "In2.Cu")
		(net "LPC_CPU_NODE1_LAD2")
	)
	(segment
		(start 85.75548 -114.96929)
		(end 86.04504 -115.25885)
		(width 0.1143)
		(layer "In2.Cu")
		(net "LPC_CPU_NODE1_LAD2")
	)
	(segment
		(start 73.135998 -101.508814)
		(end 76.85278 -105.225596)
		(width 0.1143)
		(layer "In2.Cu")
		(net "LPC_CPU_NODE1_LAD2")
	)
	(segment
		(start 102.101904 -18.209768)
		(end 100.82022 -18.209768)
		(width 0.1143)
		(layer "In2.Cu")
		(net "LPC_CPU_NODE1_LAD2")
	)
	(segment
		(start 102.279958 -18.031714)
		(end 102.101904 -18.209768)
		(width 0.1143)
		(layer "In2.Cu")
		(net "LPC_CPU_NODE1_LAD2")
	)
	(segment
		(start 109.189012 -22.071076)
		(end 105.14965 -18.031714)
		(width 0.1143)
		(layer "In2.Cu")
		(net "LPC_CPU_NODE1_LAD2")
	)
	(segment
		(start 117.16004 -66.81724)
		(end 117.16004 -66.815462)
		(width 0.1143)
		(layer "In2.Cu")
		(net "LPC_CPU_NODE1_LAD2")
	)
	(segment
		(start 88.73363 -110.35157)
		(end 88.73363 -119.54002)
		(width 0.1143)
		(layer "In2.Cu")
		(net "LPC_CPU_NODE1_LAD2")
	)
	(segment
		(start 97.4852 -95.03283)
		(end 97.4852 -92.442538)
		(width 0.1143)
		(layer "In2.Cu")
		(net "LPC_CPU_NODE1_LAD2")
	)
	(segment
		(start 86.04504 -120.445784)
		(end 86.045548 -120.445784)
		(width 0.1143)
		(layer "In2.Cu")
		(net "LPC_CPU_NODE1_LAD2")
	)
	(segment
		(start 97.292922 -17.558512)
		(end 95.983552 -16.249142)
		(width 0.1143)
		(layer "In2.Cu")
		(net "LPC_CPU_NODE1_LAD2")
	)
	(segment
		(start 85.75548 -113.273332)
		(end 85.75548 -114.96929)
		(width 0.1143)
		(layer "In2.Cu")
		(net "LPC_CPU_NODE1_LAD2")
	)
	(segment
		(start 84.356956 -111.874808)
		(end 85.75548 -113.273332)
		(width 0.1143)
		(layer "In2.Cu")
		(net "LPC_CPU_NODE1_LAD2")
	)
	(segment
		(start 60.189618 -99.94138)
		(end 60.803282 -100.555044)
		(width 0.1143)
		(layer "In2.Cu")
		(net "LPC_CPU_NODE1_LAD2")
	)
	(segment
		(start 71.73214 -101.508814)
		(end 73.135998 -101.508814)
		(width 0.1143)
		(layer "In2.Cu")
		(net "LPC_CPU_NODE1_LAD2")
	)
	(segment
		(start 86.045548 -120.445784)
		(end 86.045548 -121.827544)
		(width 0.1143)
		(layer "In2.Cu")
		(net "LPC_CPU_NODE1_LAD2")
	)
	(segment
		(start 79.226156 -112.611916)
		(end 80.85328 -112.611916)
		(width 0.1143)
		(layer "In2.Cu")
		(net "LPC_CPU_NODE1_LAD2")
	)
	(segment
		(start 88.098884 -101.117146)
		(end 86.82482 -102.39121)
		(width 0.1143)
		(layer "In2.Cu")
		(net "LPC_CPU_NODE1_LAD2")
	)
	(segment
		(start 107.43819 -85.875368)
		(end 117.05336 -76.260198)
		(width 0.1143)
		(layer "In2.Cu")
		(net "LPC_CPU_NODE1_LAD2")
	)
	(segment
		(start 117.09908 -66.879978)
		(end 117.09908 -66.8782)
		(width 0.1143)
		(layer "In2.Cu")
		(net "LPC_CPU_NODE1_LAD2")
	)
	(segment
		(start 66.03111 -101.378766)
		(end 71.602092 -101.378766)
		(width 0.1143)
		(layer "In2.Cu")
		(net "LPC_CPU_NODE1_LAD2")
	)
	(segment
		(start 100.82022 -18.209768)
		(end 100.168964 -17.558512)
		(width 0.1143)
		(layer "In2.Cu")
		(net "LPC_CPU_NODE1_LAD2")
	)
	(segment
		(start 80.85328 -112.611916)
		(end 81.590388 -111.874808)
		(width 0.1143)
		(layer "In2.Cu")
		(net "LPC_CPU_NODE1_LAD2")
	)
	(segment
		(start 88.098884 -97.750376)
		(end 88.098884 -101.117146)
		(width 0.1143)
		(layer "In2.Cu")
		(net "LPC_CPU_NODE1_LAD2")
	)
	(segment
		(start 86.82482 -102.39121)
		(end 86.82482 -108.44276)
		(width 0.1143)
		(layer "In2.Cu")
		(net "LPC_CPU_NODE1_LAD2")
	)
	(segment
		(start 90.09126 -95.758)
		(end 88.098884 -97.750376)
		(width 0.1143)
		(layer "In2.Cu")
		(net "LPC_CPU_NODE1_LAD2")
	)
	(segment
		(start 96.66351 -95.85452)
		(end 97.4852 -95.03283)
		(width 0.1143)
		(layer "In2.Cu")
		(net "LPC_CPU_NODE1_LAD2")
	)
	(segment
		(start 88.73363 -119.54002)
		(end 86.446106 -121.827544)
		(width 0.1143)
		(layer "In2.Cu")
		(net "LPC_CPU_NODE1_LAD2")
	)
	(segment
		(start 95.983552 -16.249142)
		(end 94.88424 -16.249142)
		(width 0.1143)
		(layer "In2.Cu")
		(net "LPC_CPU_NODE1_LAD2")
	)
	(segment
		(start 96.499934 -95.85452)
		(end 96.66351 -95.85452)
		(width 0.1143)
		(layer "In2.Cu")
		(net "LPC_CPU_NODE1_LAD2")
	)
	(segment
		(start 117.16004 -66.815462)
		(end 117.470682 -66.50482)
		(width 0.1143)
		(layer "In2.Cu")
		(net "LPC_CPU_NODE1_LAD2")
	)
	(segment
		(start 105.14965 -18.031714)
		(end 102.279958 -18.031714)
		(width 0.1143)
		(layer "In2.Cu")
		(net "LPC_CPU_NODE1_LAD2")
	)
	(segment
		(start 71.602092 -101.378766)
		(end 71.73214 -101.508814)
		(width 0.1143)
		(layer "In2.Cu")
		(net "LPC_CPU_NODE1_LAD2")
	)
	(segment
		(start 86.446106 -121.827544)
		(end 86.045548 -121.827544)
		(width 0.1143)
		(layer "In2.Cu")
		(net "LPC_CPU_NODE1_LAD2")
	)
	(segment
		(start 86.82482 -108.44276)
		(end 88.73363 -110.35157)
		(width 0.1143)
		(layer "In2.Cu")
		(net "LPC_CPU_NODE1_LAD2")
	)
	(segment
		(start 117.470682 -66.50482)
		(end 117.470682 -56.928004)
		(width 0.1143)
		(layer "In2.Cu")
		(net "LPC_CPU_NODE1_LAD2")
	)
	(segment
		(start 86.04504 -115.25885)
		(end 86.04504 -120.445784)
		(width 0.1143)
		(layer "In2.Cu")
		(net "LPC_CPU_NODE1_LAD2")
	)
	(segment
		(start 60.803282 -100.555044)
		(end 65.207388 -100.555044)
		(width 0.1143)
		(layer "In2.Cu")
		(net "LPC_CPU_NODE1_LAD2")
	)
	(segment
		(start 97.4852 -92.442538)
		(end 104.05237 -85.875368)
		(width 0.1143)
		(layer "In2.Cu")
		(net "LPC_CPU_NODE1_LAD2")
	)
	(segment
		(start 81.590388 -111.874808)
		(end 84.356956 -111.874808)
		(width 0.1143)
		(layer "In2.Cu")
		(net "LPC_CPU_NODE1_LAD2")
	)
	(segment
		(start 96.338644 -96.01581)
		(end 96.499934 -95.85452)
		(width 0.1143)
		(layer "In2.Cu")
		(net "LPC_CPU_NODE1_LAD2")
	)
	(segment
		(start 100.168964 -17.558512)
		(end 97.292922 -17.558512)
		(width 0.1143)
		(layer "In2.Cu")
		(net "LPC_CPU_NODE1_LAD2")
	)
	(segment
		(start 76.85278 -110.23854)
		(end 79.226156 -112.611916)
		(width 0.1143)
		(layer "In2.Cu")
		(net "LPC_CPU_NODE1_LAD2")
	)
	(segment
		(start 76.85278 -105.225596)
		(end 76.85278 -110.23854)
		(width 0.1143)
		(layer "In2.Cu")
		(net "LPC_CPU_NODE1_LAD2")
	)
	(segment
		(start 109.189012 -48.646334)
		(end 109.189012 -22.071076)
		(width 0.1143)
		(layer "In2.Cu")
		(net "LPC_CPU_NODE1_LAD2")
	)
	(segment
		(start 117.09908 -66.8782)
		(end 117.16004 -66.81724)
		(width 0.1143)
		(layer "In2.Cu")
		(net "LPC_CPU_NODE1_LAD2")
	)
	(segment
		(start 65.207388 -100.555044)
		(end 66.03111 -101.378766)
		(width 0.1143)
		(layer "In2.Cu")
		(net "LPC_CPU_NODE1_LAD2")
	)
	(segment
		(start 104.05237 -85.875368)
		(end 107.43819 -85.875368)
		(width 0.1143)
		(layer "In2.Cu")
		(net "LPC_CPU_NODE1_LAD2")
	)
	(segment
		(start 117.05336 -76.260198)
		(end 117.05336 -66.925698)
		(width 0.1143)
		(layer "In2.Cu")
		(net "LPC_CPU_NODE1_LAD2")
	)
	(segment
		(start 117.470682 -56.928004)
		(end 109.189012 -48.646334)
		(width 0.1143)
		(layer "In2.Cu")
		(net "LPC_CPU_NODE1_LAD2")
	)
	(segment
		(start 117.05336 -66.925698)
		(end 117.09908 -66.879978)
		(width 0.1143)
		(layer "In2.Cu")
		(net "LPC_CPU_NODE1_LAD2")
	)
	(segment
		(start 104.162098 -16.083534)
		(end 110.7821 -22.703536)
		(width 0.1143)
		(layer "In7.Cu")
		(net "LPC_CPU_NODE1_LAD2")
	)
	(segment
		(start 94.255336 -96.01581)
		(end 93.862652 -96.408494)
		(width 0.1143)
		(layer "In7.Cu")
		(net "LPC_CPU_NODE1_LAD2")
	)
	(segment
		(start 100.42144 -16.48841)
		(end 100.50526 -16.40459)
		(width 0.1143)
		(layer "In7.Cu")
		(net "LPC_CPU_NODE1_LAD2")
	)
	(segment
		(start 96.293432 -16.488156)
		(end 96.71304 -16.907764)
		(width 0.1143)
		(layer "In7.Cu")
		(net "LPC_CPU_NODE1_LAD2")
	)
	(segment
		(start 121.040652 -39.048944)
		(end 121.040652 -42.290746)
		(width 0.1143)
		(layer "In7.Cu")
		(net "LPC_CPU_NODE1_LAD2")
	)
	(segment
		(start 121.040652 -42.290746)
		(end 120.84304 -42.488358)
		(width 0.1143)
		(layer "In7.Cu")
		(net "LPC_CPU_NODE1_LAD2")
	)
	(segment
		(start 93.862652 -96.408494)
		(end 90.901774 -96.408494)
		(width 0.1143)
		(layer "In7.Cu")
		(net "LPC_CPU_NODE1_LAD2")
	)
	(segment
		(start 97.600008 -16.907764)
		(end 98.019362 -16.48841)
		(width 0.1143)
		(layer "In7.Cu")
		(net "LPC_CPU_NODE1_LAD2")
	)
	(segment
		(start 101.005132 -16.40459)
		(end 101.326188 -16.083534)
		(width 0.1143)
		(layer "In7.Cu")
		(net "LPC_CPU_NODE1_LAD2")
	)
	(segment
		(start 113.42624 -31.434532)
		(end 121.040652 -39.048944)
		(width 0.1143)
		(layer "In7.Cu")
		(net "LPC_CPU_NODE1_LAD2")
	)
	(segment
		(start 113.42624 -29.245814)
		(end 113.42624 -31.434532)
		(width 0.1143)
		(layer "In7.Cu")
		(net "LPC_CPU_NODE1_LAD2")
	)
	(segment
		(start 100.50526 -16.40459)
		(end 101.005132 -16.40459)
		(width 0.1143)
		(layer "In7.Cu")
		(net "LPC_CPU_NODE1_LAD2")
	)
	(segment
		(start 98.019362 -16.48841)
		(end 100.42144 -16.48841)
		(width 0.1143)
		(layer "In7.Cu")
		(net "LPC_CPU_NODE1_LAD2")
	)
	(segment
		(start 95.123254 -16.488156)
		(end 96.293432 -16.488156)
		(width 0.1143)
		(layer "In7.Cu")
		(net "LPC_CPU_NODE1_LAD2")
	)
	(segment
		(start 120.84304 -42.488358)
		(end 120.84304 -42.861738)
		(width 0.1143)
		(layer "In7.Cu")
		(net "LPC_CPU_NODE1_LAD2")
	)
	(segment
		(start 110.7821 -22.703536)
		(end 110.7821 -26.601674)
		(width 0.1143)
		(layer "In7.Cu")
		(net "LPC_CPU_NODE1_LAD2")
	)
	(segment
		(start 110.7821 -26.601674)
		(end 113.42624 -29.245814)
		(width 0.1143)
		(layer "In7.Cu")
		(net "LPC_CPU_NODE1_LAD2")
	)
	(segment
		(start 101.326188 -16.083534)
		(end 104.162098 -16.083534)
		(width 0.1143)
		(layer "In7.Cu")
		(net "LPC_CPU_NODE1_LAD2")
	)
	(segment
		(start 96.338644 -96.01581)
		(end 94.255336 -96.01581)
		(width 0.1143)
		(layer "In7.Cu")
		(net "LPC_CPU_NODE1_LAD2")
	)
	(segment
		(start 96.71304 -16.907764)
		(end 97.600008 -16.907764)
		(width 0.1143)
		(layer "In7.Cu")
		(net "LPC_CPU_NODE1_LAD2")
	)
	(segment
		(start 90.901774 -96.408494)
		(end 90.25128 -95.758)
		(width 0.1143)
		(layer "In7.Cu")
		(net "LPC_CPU_NODE1_LAD2")
	)
	(segment
		(start 90.25128 -95.758)
		(end 90.09126 -95.758)
		(width 0.1143)
		(layer "In7.Cu")
		(net "LPC_CPU_NODE1_LAD2")
	)
	(segment
		(start 94.88424 -16.249142)
		(end 95.123254 -16.488156)
		(width 0.1143)
		(layer "In7.Cu")
		(net "LPC_CPU_NODE1_LAD2")
	)
	(segment
		(start 164.566854 -129.85242)
		(end 162.893756 -129.85242)
		(width 0.1016)
		(layer "F.Cu")
		(net "LED_CPU_NODE1_CPLD")
	)
	(segment
		(start 167.704008 -126.715266)
		(end 169.222674 -126.715266)
		(width 0.1016)
		(layer "F.Cu")
		(net "LED_CPU_NODE1_CPLD")
	)
	(segment
		(start 169.222674 -126.715266)
		(end 171.572174 -124.365766)
		(width 0.1016)
		(layer "F.Cu")
		(net "LED_CPU_NODE1_CPLD")
	)
	(segment
		(start 166.0652 -128.354074)
		(end 164.566854 -129.85242)
		(width 0.1016)
		(layer "F.Cu")
		(net "LED_CPU_NODE1_CPLD")
	)
	(segment
		(start 171.572174 -124.365766)
		(end 172.010324 -124.365766)
		(width 0.1016)
		(layer "F.Cu")
		(net "LED_CPU_NODE1_CPLD")
	)
	(segment
		(start 166.0652 -128.354074)
		(end 167.704008 -126.715266)
		(width 0.1016)
		(layer "F.Cu")
		(net "LED_CPU_NODE1_CPLD")
	)
	(via
		(at 166.0652 -128.354074)
		(size 0.508)
		(drill 0.254)
		(layers "F.Cu" "B.Cu")
		(net "LED_CPU_NODE1_CPLD")
	)
	(segment
		(start 65.630044 -77.555598)
		(end 65.630044 -77.531468)
		(width 0.1143)
		(layer "F.Cu")
		(net "PD_CPU_NODE1_SPD_EN_L")
	)
	(segment
		(start 65.630044 -77.531468)
		(end 65.99428 -77.167232)
		(width 0.1143)
		(layer "F.Cu")
		(net "PD_CPU_NODE1_SPD_EN_L")
	)
	(segment
		(start 65.99428 -77.167232)
		(end 65.99428 -77.1652)
		(width 0.1143)
		(layer "F.Cu")
		(net "PD_CPU_NODE1_SPD_EN_L")
	)
	(via
		(at 65.99428 -77.1652)
		(size 0.508)
		(drill 0.254)
		(layers "F.Cu" "B.Cu")
		(net "PD_CPU_NODE1_SPD_EN_L")
	)
	(via
		(at 84.294218 -74.007218)
		(size 0.6604)
		(drill 0.3302)
		(layers "F.Cu" "B.Cu")
		(net "PD_CPU_NODE1_SPD_EN_L")
	)
	(segment
		(start 84.294218 -74.007218)
		(end 84.657946 -74.370946)
		(width 0.1016)
		(layer "B.Cu")
		(net "PD_CPU_NODE1_SPD_EN_L")
	)
	(segment
		(start 79.4766 -74.007218)
		(end 78.725014 -74.758804)
		(width 0.1016)
		(layer "B.Cu")
		(net "PD_CPU_NODE1_SPD_EN_L")
	)
	(segment
		(start 88.7476 -73.253854)
		(end 89.1794 -73.685654)
		(width 0.1016)
		(layer "B.Cu")
		(net "PD_CPU_NODE1_SPD_EN_L")
	)
	(segment
		(start 74.87285 -75.200002)
		(end 74.204068 -75.868784)
		(width 0.1016)
		(layer "B.Cu")
		(net "PD_CPU_NODE1_SPD_EN_L")
	)
	(segment
		(start 84.294218 -74.007218)
		(end 79.4766 -74.007218)
		(width 0.1016)
		(layer "B.Cu")
		(net "PD_CPU_NODE1_SPD_EN_L")
	)
	(segment
		(start 84.657946 -74.370946)
		(end 86.143592 -74.370946)
		(width 0.1016)
		(layer "B.Cu")
		(net "PD_CPU_NODE1_SPD_EN_L")
	)
	(segment
		(start 91.018106 -73.685654)
		(end 89.1794 -73.685654)
		(width 0.1016)
		(layer "B.Cu")
		(net "PD_CPU_NODE1_SPD_EN_L")
	)
	(segment
		(start 65.99428 -76.565506)
		(end 65.99428 -77.1652)
		(width 0.1016)
		(layer "B.Cu")
		(net "PD_CPU_NODE1_SPD_EN_L")
	)
	(segment
		(start 78.725014 -74.758804)
		(end 77.950822 -74.758804)
		(width 0.1016)
		(layer "B.Cu")
		(net "PD_CPU_NODE1_SPD_EN_L")
	)
	(segment
		(start 66.37782 -76.181966)
		(end 65.99428 -76.565506)
		(width 0.1016)
		(layer "B.Cu")
		(net "PD_CPU_NODE1_SPD_EN_L")
	)
	(segment
		(start 91.07297 -73.740518)
		(end 91.018106 -73.685654)
		(width 0.1016)
		(layer "B.Cu")
		(net "PD_CPU_NODE1_SPD_EN_L")
	)
	(segment
		(start 77.950822 -74.758804)
		(end 77.509624 -75.200002)
		(width 0.1016)
		(layer "B.Cu")
		(net "PD_CPU_NODE1_SPD_EN_L")
	)
	(segment
		(start 77.509624 -75.200002)
		(end 74.87285 -75.200002)
		(width 0.1016)
		(layer "B.Cu")
		(net "PD_CPU_NODE1_SPD_EN_L")
	)
	(segment
		(start 68.077842 -75.868784)
		(end 67.76466 -76.181966)
		(width 0.1016)
		(layer "B.Cu")
		(net "PD_CPU_NODE1_SPD_EN_L")
	)
	(segment
		(start 67.76466 -76.181966)
		(end 66.37782 -76.181966)
		(width 0.1016)
		(layer "B.Cu")
		(net "PD_CPU_NODE1_SPD_EN_L")
	)
	(segment
		(start 74.204068 -75.868784)
		(end 68.077842 -75.868784)
		(width 0.1016)
		(layer "B.Cu")
		(net "PD_CPU_NODE1_SPD_EN_L")
	)
	(segment
		(start 86.143592 -74.370946)
		(end 87.260684 -73.253854)
		(width 0.1016)
		(layer "B.Cu")
		(net "PD_CPU_NODE1_SPD_EN_L")
	)
	(segment
		(start 87.260684 -73.253854)
		(end 88.7476 -73.253854)
		(width 0.1016)
		(layer "B.Cu")
		(net "PD_CPU_NODE1_SPD_EN_L")
	)
	(segment
		(start 96.278954 -16.291814)
		(end 97.344738 -16.291814)
		(width 0.1016)
		(layer "F.Cu")
		(net "LPC_CPU_NODE1_LAD1")
	)
	(segment
		(start 88.366346 -116.591588)
		(end 88.366346 -118.209568)
		(width 0.1016)
		(layer "F.Cu")
		(net "LPC_CPU_NODE1_LAD1")
	)
	(segment
		(start 88.366346 -118.209568)
		(end 88.076786 -118.499128)
		(width 0.1016)
		(layer "F.Cu")
		(net "LPC_CPU_NODE1_LAD1")
	)
	(segment
		(start 88.076786 -118.499128)
		(end 88.0745 -118.499128)
		(width 0.1016)
		(layer "F.Cu")
		(net "LPC_CPU_NODE1_LAD1")
	)
	(via
		(at 87.31758 -97.070164)
		(size 0.508)
		(drill 0.254)
		(layers "F.Cu" "B.Cu")
		(net "LPC_CPU_NODE1_LAD1")
	)
	(via
		(at 60.048648 -98.481388)
		(size 0.508)
		(drill 0.254)
		(layers "F.Cu" "B.Cu")
		(net "LPC_CPU_NODE1_LAD1")
	)
	(via
		(at 88.0745 -118.499128)
		(size 0.508)
		(drill 0.254)
		(layers "F.Cu" "B.Cu")
		(net "LPC_CPU_NODE1_LAD1")
	)
	(via
		(at 97.344738 -16.291814)
		(size 0.508)
		(drill 0.254)
		(layers "F.Cu" "B.Cu")
		(net "LPC_CPU_NODE1_LAD1")
	)
	(via
		(at 96.3422 -96.738948)
		(size 0.508)
		(drill 0.254)
		(layers "F.Cu" "B.Cu")
		(net "LPC_CPU_NODE1_LAD1")
	)
	(via
		(at 120.3833 -43.719496)
		(size 0.508)
		(drill 0.254)
		(layers "F.Cu" "B.Cu")
		(net "LPC_CPU_NODE1_LAD1")
	)
	(segment
		(start 60.5663 -97.686368)
		(end 60.5663 -98.01352)
		(width 0.1016)
		(layer "B.Cu")
		(net "LPC_CPU_NODE1_LAD1")
	)
	(segment
		(start 60.098432 -98.481388)
		(end 60.048648 -98.481388)
		(width 0.1016)
		(layer "B.Cu")
		(net "LPC_CPU_NODE1_LAD1")
	)
	(segment
		(start 121.143522 -43.719496)
		(end 121.146316 -43.716702)
		(width 0.1016)
		(layer "B.Cu")
		(net "LPC_CPU_NODE1_LAD1")
	)
	(segment
		(start 120.3833 -43.719496)
		(end 121.143522 -43.719496)
		(width 0.1016)
		(layer "B.Cu")
		(net "LPC_CPU_NODE1_LAD1")
	)
	(segment
		(start 121.146316 -43.716702)
		(end 121.69775 -43.716702)
		(width 0.1016)
		(layer "B.Cu")
		(net "LPC_CPU_NODE1_LAD1")
	)
	(segment
		(start 60.5663 -98.01352)
		(end 60.098432 -98.481388)
		(width 0.1016)
		(layer "B.Cu")
		(net "LPC_CPU_NODE1_LAD1")
	)
	(segment
		(start 60.118498 -97.096834)
		(end 60.118498 -97.238566)
		(width 0.1016)
		(layer "B.Cu")
		(net "LPC_CPU_NODE1_LAD1")
	)
	(segment
		(start 60.118498 -97.238566)
		(end 60.5663 -97.686368)
		(width 0.1016)
		(layer "B.Cu")
		(net "LPC_CPU_NODE1_LAD1")
	)
	(segment
		(start 86.17458 -114.71021)
		(end 86.17458 -113.099596)
		(width 0.1143)
		(layer "In2.Cu")
		(net "LPC_CPU_NODE1_LAD1")
	)
	(segment
		(start 86.40064 -109.262926)
		(end 88.31453 -111.176816)
		(width 0.1143)
		(layer "In2.Cu")
		(net "LPC_CPU_NODE1_LAD1")
	)
	(segment
		(start 117.47246 -76.74229)
		(end 117.47246 -67.099434)
		(width 0.1143)
		(layer "In2.Cu")
		(net "LPC_CPU_NODE1_LAD1")
	)
	(segment
		(start 66.32956 -100.959666)
		(end 64.048386 -98.678492)
		(width 0.1143)
		(layer "In2.Cu")
		(net "LPC_CPU_NODE1_LAD1")
	)
	(segment
		(start 88.31453 -118.259098)
		(end 88.0745 -118.499128)
		(width 0.1143)
		(layer "In2.Cu")
		(net "LPC_CPU_NODE1_LAD1")
	)
	(segment
		(start 88.0745 -118.499128)
		(end 87.798148 -118.499128)
		(width 0.1143)
		(layer "In2.Cu")
		(net "LPC_CPU_NODE1_LAD1")
	)
	(segment
		(start 88.31453 -111.176816)
		(end 88.31453 -118.259098)
		(width 0.1143)
		(layer "In2.Cu")
		(net "LPC_CPU_NODE1_LAD1")
	)
	(segment
		(start 104.86009 -17.006062)
		(end 99.487736 -17.006062)
		(width 0.1143)
		(layer "In2.Cu")
		(net "LPC_CPU_NODE1_LAD1")
	)
	(segment
		(start 96.488758 -96.738948)
		(end 97.9043 -95.323406)
		(width 0.1143)
		(layer "In2.Cu")
		(net "LPC_CPU_NODE1_LAD1")
	)
	(segment
		(start 97.9043 -95.323406)
		(end 97.9043 -92.725494)
		(width 0.1143)
		(layer "In2.Cu")
		(net "LPC_CPU_NODE1_LAD1")
	)
	(segment
		(start 86.17458 -113.099596)
		(end 84.530692 -111.455708)
		(width 0.1143)
		(layer "In2.Cu")
		(net "LPC_CPU_NODE1_LAD1")
	)
	(segment
		(start 87.31758 -97.070164)
		(end 86.40064 -97.987104)
		(width 0.1143)
		(layer "In2.Cu")
		(net "LPC_CPU_NODE1_LAD1")
	)
	(segment
		(start 60.145422 -98.578162)
		(end 60.048648 -98.481388)
		(width 0.1143)
		(layer "In2.Cu")
		(net "LPC_CPU_NODE1_LAD1")
	)
	(segment
		(start 71.777352 -100.959666)
		(end 66.32956 -100.959666)
		(width 0.1143)
		(layer "In2.Cu")
		(net "LPC_CPU_NODE1_LAD1")
	)
	(segment
		(start 86.66988 -117.37086)
		(end 86.66988 -115.20551)
		(width 0.1143)
		(layer "In2.Cu")
		(net "LPC_CPU_NODE1_LAD1")
	)
	(segment
		(start 79.399892 -112.192816)
		(end 77.27188 -110.064804)
		(width 0.1143)
		(layer "In2.Cu")
		(net "LPC_CPU_NODE1_LAD1")
	)
	(segment
		(start 97.95002 -92.669614)
		(end 104.325166 -86.294468)
		(width 0.1143)
		(layer "In2.Cu")
		(net "LPC_CPU_NODE1_LAD1")
	)
	(segment
		(start 77.27188 -110.064804)
		(end 77.27188 -105.05186)
		(width 0.1143)
		(layer "In2.Cu")
		(net "LPC_CPU_NODE1_LAD1")
	)
	(segment
		(start 64.048386 -98.678492)
		(end 61.20257 -98.678492)
		(width 0.1143)
		(layer "In2.Cu")
		(net "LPC_CPU_NODE1_LAD1")
	)
	(segment
		(start 117.51818 -67.051936)
		(end 117.889782 -66.680334)
		(width 0.1143)
		(layer "In2.Cu")
		(net "LPC_CPU_NODE1_LAD1")
	)
	(segment
		(start 109.608112 -21.754084)
		(end 104.86009 -17.006062)
		(width 0.1143)
		(layer "In2.Cu")
		(net "LPC_CPU_NODE1_LAD1")
	)
	(segment
		(start 97.95002 -92.679774)
		(end 97.95002 -92.669614)
		(width 0.1143)
		(layer "In2.Cu")
		(net "LPC_CPU_NODE1_LAD1")
	)
	(segment
		(start 80.677512 -112.192816)
		(end 79.399892 -112.192816)
		(width 0.1143)
		(layer "In2.Cu")
		(net "LPC_CPU_NODE1_LAD1")
	)
	(segment
		(start 117.51818 -67.053714)
		(end 117.51818 -67.051936)
		(width 0.1143)
		(layer "In2.Cu")
		(net "LPC_CPU_NODE1_LAD1")
	)
	(segment
		(start 77.27188 -105.05186)
		(end 73.309734 -101.089714)
		(width 0.1143)
		(layer "In2.Cu")
		(net "LPC_CPU_NODE1_LAD1")
	)
	(segment
		(start 97.9043 -92.725494)
		(end 97.95002 -92.679774)
		(width 0.1143)
		(layer "In2.Cu")
		(net "LPC_CPU_NODE1_LAD1")
	)
	(segment
		(start 61.20257 -98.678492)
		(end 61.10224 -98.578162)
		(width 0.1143)
		(layer "In2.Cu")
		(net "LPC_CPU_NODE1_LAD1")
	)
	(segment
		(start 96.3422 -96.738948)
		(end 96.488758 -96.738948)
		(width 0.1143)
		(layer "In2.Cu")
		(net "LPC_CPU_NODE1_LAD1")
	)
	(segment
		(start 109.608112 -48.472598)
		(end 109.608112 -21.754084)
		(width 0.1143)
		(layer "In2.Cu")
		(net "LPC_CPU_NODE1_LAD1")
	)
	(segment
		(start 107.920282 -86.294468)
		(end 108.165646 -86.049104)
		(width 0.1143)
		(layer "In2.Cu")
		(net "LPC_CPU_NODE1_LAD1")
	)
	(segment
		(start 117.889782 -66.680334)
		(end 117.889782 -56.754268)
		(width 0.1143)
		(layer "In2.Cu")
		(net "LPC_CPU_NODE1_LAD1")
	)
	(segment
		(start 81.41462 -111.455708)
		(end 80.677512 -112.192816)
		(width 0.1143)
		(layer "In2.Cu")
		(net "LPC_CPU_NODE1_LAD1")
	)
	(segment
		(start 117.889782 -56.754268)
		(end 109.608112 -48.472598)
		(width 0.1143)
		(layer "In2.Cu")
		(net "LPC_CPU_NODE1_LAD1")
	)
	(segment
		(start 86.66988 -115.20551)
		(end 86.17458 -114.71021)
		(width 0.1143)
		(layer "In2.Cu")
		(net "LPC_CPU_NODE1_LAD1")
	)
	(segment
		(start 71.9074 -101.089714)
		(end 71.777352 -100.959666)
		(width 0.1143)
		(layer "In2.Cu")
		(net "LPC_CPU_NODE1_LAD1")
	)
	(segment
		(start 84.530692 -111.455708)
		(end 81.41462 -111.455708)
		(width 0.1143)
		(layer "In2.Cu")
		(net "LPC_CPU_NODE1_LAD1")
	)
	(segment
		(start 98.773488 -16.291814)
		(end 97.344738 -16.291814)
		(width 0.1143)
		(layer "In2.Cu")
		(net "LPC_CPU_NODE1_LAD1")
	)
	(segment
		(start 108.1659 -86.049104)
		(end 108.1659 -86.04885)
		(width 0.1143)
		(layer "In2.Cu")
		(net "LPC_CPU_NODE1_LAD1")
	)
	(segment
		(start 86.40064 -97.987104)
		(end 86.40064 -109.262926)
		(width 0.1143)
		(layer "In2.Cu")
		(net "LPC_CPU_NODE1_LAD1")
	)
	(segment
		(start 104.325166 -86.294468)
		(end 107.920282 -86.294468)
		(width 0.1143)
		(layer "In2.Cu")
		(net "LPC_CPU_NODE1_LAD1")
	)
	(segment
		(start 73.309734 -101.089714)
		(end 71.9074 -101.089714)
		(width 0.1143)
		(layer "In2.Cu")
		(net "LPC_CPU_NODE1_LAD1")
	)
	(segment
		(start 61.10224 -98.578162)
		(end 60.145422 -98.578162)
		(width 0.1143)
		(layer "In2.Cu")
		(net "LPC_CPU_NODE1_LAD1")
	)
	(segment
		(start 108.165646 -86.049104)
		(end 108.1659 -86.049104)
		(width 0.1143)
		(layer "In2.Cu")
		(net "LPC_CPU_NODE1_LAD1")
	)
	(segment
		(start 108.1659 -86.04885)
		(end 117.47246 -76.74229)
		(width 0.1143)
		(layer "In2.Cu")
		(net "LPC_CPU_NODE1_LAD1")
	)
	(segment
		(start 87.798148 -118.499128)
		(end 86.66988 -117.37086)
		(width 0.1143)
		(layer "In2.Cu")
		(net "LPC_CPU_NODE1_LAD1")
	)
	(segment
		(start 117.47246 -67.099434)
		(end 117.51818 -67.053714)
		(width 0.1143)
		(layer "In2.Cu")
		(net "LPC_CPU_NODE1_LAD1")
	)
	(segment
		(start 99.487736 -17.006062)
		(end 98.773488 -16.291814)
		(width 0.1143)
		(layer "In2.Cu")
		(net "LPC_CPU_NODE1_LAD1")
	)
	(segment
		(start 121.459752 -43.116246)
		(end 120.856502 -43.719496)
		(width 0.1143)
		(layer "In7.Cu")
		(net "LPC_CPU_NODE1_LAD1")
	)
	(segment
		(start 93.996764 -96.868996)
		(end 87.518748 -96.868996)
		(width 0.1143)
		(layer "In7.Cu")
		(net "LPC_CPU_NODE1_LAD1")
	)
	(segment
		(start 94.126812 -96.738948)
		(end 93.996764 -96.868996)
		(width 0.1143)
		(layer "In7.Cu")
		(net "LPC_CPU_NODE1_LAD1")
	)
	(segment
		(start 111.2012 -22.375368)
		(end 111.2012 -26.371042)
		(width 0.1143)
		(layer "In7.Cu")
		(net "LPC_CPU_NODE1_LAD1")
	)
	(segment
		(start 120.856502 -43.719496)
		(end 120.3833 -43.719496)
		(width 0.1143)
		(layer "In7.Cu")
		(net "LPC_CPU_NODE1_LAD1")
	)
	(segment
		(start 103.95966 -15.133828)
		(end 111.2012 -22.375368)
		(width 0.1143)
		(layer "In7.Cu")
		(net "LPC_CPU_NODE1_LAD1")
	)
	(segment
		(start 121.459752 -38.875208)
		(end 121.459752 -43.116246)
		(width 0.1143)
		(layer "In7.Cu")
		(net "LPC_CPU_NODE1_LAD1")
	)
	(segment
		(start 97.344738 -16.291814)
		(end 97.611692 -16.02486)
		(width 0.1143)
		(layer "In7.Cu")
		(net "LPC_CPU_NODE1_LAD1")
	)
	(segment
		(start 113.84534 -31.260796)
		(end 121.459752 -38.875208)
		(width 0.1143)
		(layer "In7.Cu")
		(net "LPC_CPU_NODE1_LAD1")
	)
	(segment
		(start 87.518748 -96.868996)
		(end 87.31758 -97.070164)
		(width 0.1143)
		(layer "In7.Cu")
		(net "LPC_CPU_NODE1_LAD1")
	)
	(segment
		(start 97.611692 -16.02486)
		(end 99.839526 -16.02486)
		(width 0.1143)
		(layer "In7.Cu")
		(net "LPC_CPU_NODE1_LAD1")
	)
	(segment
		(start 113.84534 -29.015182)
		(end 113.84534 -31.260796)
		(width 0.1143)
		(layer "In7.Cu")
		(net "LPC_CPU_NODE1_LAD1")
	)
	(segment
		(start 99.839526 -16.02486)
		(end 100.730558 -15.133828)
		(width 0.1143)
		(layer "In7.Cu")
		(net "LPC_CPU_NODE1_LAD1")
	)
	(segment
		(start 111.2012 -26.371042)
		(end 113.84534 -29.015182)
		(width 0.1143)
		(layer "In7.Cu")
		(net "LPC_CPU_NODE1_LAD1")
	)
	(segment
		(start 96.3422 -96.738948)
		(end 94.126812 -96.738948)
		(width 0.1143)
		(layer "In7.Cu")
		(net "LPC_CPU_NODE1_LAD1")
	)
	(segment
		(start 100.730558 -15.133828)
		(end 103.95966 -15.133828)
		(width 0.1143)
		(layer "In7.Cu")
		(net "LPC_CPU_NODE1_LAD1")
	)
	(segment
		(start 179.124356 -114.107722)
		(end 179.124356 -113.048034)
		(width 0.1016)
		(layer "F.Cu")
		(net "XDP_CPU_NODE1_PWROK")
	)
	(segment
		(start 180.0098 -114.993166)
		(end 179.124356 -114.107722)
		(width 0.1016)
		(layer "F.Cu")
		(net "XDP_CPU_NODE1_PWROK")
	)
	(segment
		(start 180.0098 -116.364766)
		(end 180.0098 -114.993166)
		(width 0.1016)
		(layer "F.Cu")
		(net "XDP_CPU_NODE1_PWROK")
	)
	(segment
		(start 180.010562 -116.365528)
		(end 180.0098 -116.364766)
		(width 0.1016)
		(layer "F.Cu")
		(net "XDP_CPU_NODE1_PWROK")
	)
	(segment
		(start 179.124356 -113.048034)
		(end 178.9557 -112.879378)
		(width 0.1016)
		(layer "F.Cu")
		(net "XDP_CPU_NODE1_PWROK")
	)
	(via
		(at 115.26774 -73.48855)
		(size 0.508)
		(drill 0.254)
		(layers "F.Cu" "B.Cu")
		(net "XDP_CPU_NODE1_PWROK")
	)
	(via
		(at 178.9557 -112.879378)
		(size 0.508)
		(drill 0.254)
		(layers "F.Cu" "B.Cu")
		(net "XDP_CPU_NODE1_PWROK")
	)
	(segment
		(start 101.477572 -68.568824)
		(end 102.941882 -70.033134)
		(width 0.1016)
		(layer "B.Cu")
		(net "XDP_CPU_NODE1_PWROK")
	)
	(segment
		(start 104.008174 -66.164206)
		(end 104.008174 -66.293492)
		(width 0.1016)
		(layer "B.Cu")
		(net "XDP_CPU_NODE1_PWROK")
	)
	(segment
		(start 102.391972 -66.771774)
		(end 101.477572 -67.686174)
		(width 0.1016)
		(layer "B.Cu")
		(net "XDP_CPU_NODE1_PWROK")
	)
	(segment
		(start 103.529892 -66.771774)
		(end 102.391972 -66.771774)
		(width 0.1016)
		(layer "B.Cu")
		(net "XDP_CPU_NODE1_PWROK")
	)
	(segment
		(start 101.477572 -67.686174)
		(end 101.477572 -68.568824)
		(width 0.1016)
		(layer "B.Cu")
		(net "XDP_CPU_NODE1_PWROK")
	)
	(segment
		(start 111.32312 -72.673464)
		(end 112.450118 -73.800462)
		(width 0.1016)
		(layer "B.Cu")
		(net "XDP_CPU_NODE1_PWROK")
	)
	(segment
		(start 112.450118 -73.800462)
		(end 114.955828 -73.800462)
		(width 0.1016)
		(layer "B.Cu")
		(net "XDP_CPU_NODE1_PWROK")
	)
	(segment
		(start 104.008174 -66.293492)
		(end 103.529892 -66.771774)
		(width 0.1016)
		(layer "B.Cu")
		(net "XDP_CPU_NODE1_PWROK")
	)
	(segment
		(start 110.770924 -72.673464)
		(end 111.32312 -72.673464)
		(width 0.1016)
		(layer "B.Cu")
		(net "XDP_CPU_NODE1_PWROK")
	)
	(segment
		(start 114.955828 -73.800462)
		(end 115.26774 -73.48855)
		(width 0.1016)
		(layer "B.Cu")
		(net "XDP_CPU_NODE1_PWROK")
	)
	(segment
		(start 102.941882 -70.033134)
		(end 108.130594 -70.033134)
		(width 0.1016)
		(layer "B.Cu")
		(net "XDP_CPU_NODE1_PWROK")
	)
	(segment
		(start 108.130594 -70.033134)
		(end 110.770924 -72.673464)
		(width 0.1016)
		(layer "B.Cu")
		(net "XDP_CPU_NODE1_PWROK")
	)
	(segment
		(start 171.293028 -112.27943)
		(end 171.06138 -112.511078)
		(width 0.1143)
		(layer "In7.Cu")
		(net "XDP_CPU_NODE1_PWROK")
	)
	(segment
		(start 178.355752 -112.27943)
		(end 171.293028 -112.27943)
		(width 0.1143)
		(layer "In7.Cu")
		(net "XDP_CPU_NODE1_PWROK")
	)
	(segment
		(start 178.9557 -112.879378)
		(end 178.355752 -112.27943)
		(width 0.1143)
		(layer "In7.Cu")
		(net "XDP_CPU_NODE1_PWROK")
	)
	(segment
		(start 156.83738 -108.475018)
		(end 143.138652 -94.77629)
		(width 0.1143)
		(layer "In7.Cu")
		(net "XDP_CPU_NODE1_PWROK")
	)
	(segment
		(start 143.138652 -94.77629)
		(end 130.690112 -94.77629)
		(width 0.1143)
		(layer "In7.Cu")
		(net "XDP_CPU_NODE1_PWROK")
	)
	(segment
		(start 167.644572 -112.511078)
		(end 165.658546 -110.525052)
		(width 0.1143)
		(layer "In7.Cu")
		(net "XDP_CPU_NODE1_PWROK")
	)
	(segment
		(start 130.690112 -94.77629)
		(end 116.86794 -80.954118)
		(width 0.1143)
		(layer "In7.Cu")
		(net "XDP_CPU_NODE1_PWROK")
	)
	(segment
		(start 156.83738 -108.552742)
		(end 156.83738 -108.475018)
		(width 0.1143)
		(layer "In7.Cu")
		(net "XDP_CPU_NODE1_PWROK")
	)
	(segment
		(start 171.06138 -112.511078)
		(end 167.644572 -112.511078)
		(width 0.1143)
		(layer "In7.Cu")
		(net "XDP_CPU_NODE1_PWROK")
	)
	(segment
		(start 165.658546 -110.525052)
		(end 158.80969 -110.525052)
		(width 0.1143)
		(layer "In7.Cu")
		(net "XDP_CPU_NODE1_PWROK")
	)
	(segment
		(start 116.86794 -75.08875)
		(end 115.26774 -73.48855)
		(width 0.1143)
		(layer "In7.Cu")
		(net "XDP_CPU_NODE1_PWROK")
	)
	(segment
		(start 158.80969 -110.525052)
		(end 156.83738 -108.552742)
		(width 0.1143)
		(layer "In7.Cu")
		(net "XDP_CPU_NODE1_PWROK")
	)
	(segment
		(start 116.86794 -80.954118)
		(end 116.86794 -75.08875)
		(width 0.1143)
		(layer "In7.Cu")
		(net "XDP_CPU_NODE1_PWROK")
	)
	(segment
		(start 67.949318 -90.378026)
		(end 68.262754 -90.691462)
		(width 0.1016)
		(layer "F.Cu")
		(net "PD_CPU_NODE1_BOOTDEVSEL")
	)
	(segment
		(start 67.413886 -86.862666)
		(end 67.413886 -87.284814)
		(width 0.1016)
		(layer "F.Cu")
		(net "PD_CPU_NODE1_BOOTDEVSEL")
	)
	(segment
		(start 67.954652 -89.074498)
		(end 67.949318 -89.079832)
		(width 0.1016)
		(layer "F.Cu")
		(net "PD_CPU_NODE1_BOOTDEVSEL")
	)
	(segment
		(start 67.949318 -89.079832)
		(end 67.949318 -90.378026)
		(width 0.1016)
		(layer "F.Cu")
		(net "PD_CPU_NODE1_BOOTDEVSEL")
	)
	(segment
		(start 68.262754 -90.691462)
		(end 68.749164 -90.691462)
		(width 0.1016)
		(layer "F.Cu")
		(net "PD_CPU_NODE1_BOOTDEVSEL")
	)
	(segment
		(start 74.458068 -93.731842)
		(end 73.442068 -93.731842)
		(width 0.1016)
		(layer "F.Cu")
		(net "PD_CPU_NODE1_BOOTDEVSEL")
	)
	(segment
		(start 72.207882 -91.628214)
		(end 73.150222 -92.570554)
		(width 0.1016)
		(layer "F.Cu")
		(net "PD_CPU_NODE1_BOOTDEVSEL")
	)
	(segment
		(start 67.65798 -88.147652)
		(end 67.687444 -88.147652)
		(width 0.1016)
		(layer "F.Cu")
		(net "PD_CPU_NODE1_BOOTDEVSEL")
	)
	(segment
		(start 73.442068 -93.731842)
		(end 73.442068 -92.8624)
		(width 0.1016)
		(layer "F.Cu")
		(net "PD_CPU_NODE1_BOOTDEVSEL")
	)
	(segment
		(start 67.687444 -88.147652)
		(end 67.954652 -88.41486)
		(width 0.1016)
		(layer "F.Cu")
		(net "PD_CPU_NODE1_BOOTDEVSEL")
	)
	(segment
		(start 67.24142 -87.45728)
		(end 67.24142 -87.731092)
		(width 0.1016)
		(layer "F.Cu")
		(net "PD_CPU_NODE1_BOOTDEVSEL")
	)
	(segment
		(start 68.749164 -90.691462)
		(end 69.685916 -91.628214)
		(width 0.1016)
		(layer "F.Cu")
		(net "PD_CPU_NODE1_BOOTDEVSEL")
	)
	(segment
		(start 67.954652 -88.41486)
		(end 67.954652 -89.074498)
		(width 0.1016)
		(layer "F.Cu")
		(net "PD_CPU_NODE1_BOOTDEVSEL")
	)
	(segment
		(start 69.685916 -91.628214)
		(end 72.207882 -91.628214)
		(width 0.1016)
		(layer "F.Cu")
		(net "PD_CPU_NODE1_BOOTDEVSEL")
	)
	(segment
		(start 73.442068 -92.8624)
		(end 73.150222 -92.570554)
		(width 0.1016)
		(layer "F.Cu")
		(net "PD_CPU_NODE1_BOOTDEVSEL")
	)
	(segment
		(start 67.24142 -87.731092)
		(end 67.65798 -88.147652)
		(width 0.1016)
		(layer "F.Cu")
		(net "PD_CPU_NODE1_BOOTDEVSEL")
	)
	(segment
		(start 67.413886 -87.284814)
		(end 67.24142 -87.45728)
		(width 0.1016)
		(layer "F.Cu")
		(net "PD_CPU_NODE1_BOOTDEVSEL")
	)
	(via
		(at 73.150222 -92.570554)
		(size 0.762)
		(drill 0.381)
		(layers "F.Cu" "B.Cu")
		(net "PD_CPU_NODE1_BOOTDEVSEL")
	)
	(segment
		(start 92.20835 -3.993134)
		(end 92.20835 -3.283204)
		(width 0.1016)
		(layer "F.Cu")
		(net "IRQ_CPU_NODE1_SERIAL")
	)
	(via
		(at 92.20835 -3.283204)
		(size 0.508)
		(drill 0.254)
		(layers "F.Cu" "B.Cu")
		(net "IRQ_CPU_NODE1_SERIAL")
	)
	(via
		(at 111.67618 -17.791176)
		(size 0.508)
		(drill 0.254)
		(layers "F.Cu" "B.Cu")
		(net "IRQ_CPU_NODE1_SERIAL")
	)
	(via
		(at 112.36452 -19.180302)
		(size 0.508)
		(drill 0.254)
		(layers "F.Cu" "B.Cu")
		(net "IRQ_CPU_NODE1_SERIAL")
	)
	(via
		(at 95.6564 -103.64343)
		(size 0.508)
		(drill 0.254)
		(layers "F.Cu" "B.Cu")
		(net "IRQ_CPU_NODE1_SERIAL")
	)
	(via
		(at 120.28932 -45.176186)
		(size 0.508)
		(drill 0.254)
		(layers "F.Cu" "B.Cu")
		(net "IRQ_CPU_NODE1_SERIAL")
	)
	(via
		(at 61.328554 -99.605338)
		(size 0.508)
		(drill 0.254)
		(layers "F.Cu" "B.Cu")
		(net "IRQ_CPU_NODE1_SERIAL")
	)
	(segment
		(start 109.17174 -15.987522)
		(end 109.17174 -11.288268)
		(width 0.1016)
		(layer "B.Cu")
		(net "IRQ_CPU_NODE1_SERIAL")
	)
	(segment
		(start 112.36452 -19.180302)
		(end 109.17174 -15.987522)
		(width 0.1016)
		(layer "B.Cu")
		(net "IRQ_CPU_NODE1_SERIAL")
	)
	(segment
		(start 101.5238 -2.713736)
		(end 109.96676 -11.156696)
		(width 0.1016)
		(layer "B.Cu")
		(net "IRQ_CPU_NODE1_SERIAL")
	)
	(segment
		(start 109.96676 -15.94866)
		(end 111.67618 -17.65808)
		(width 0.1016)
		(layer "B.Cu")
		(net "IRQ_CPU_NODE1_SERIAL")
	)
	(segment
		(start 63.208662 -98.74758)
		(end 63.16726 -98.788982)
		(width 0.1016)
		(layer "B.Cu")
		(net "IRQ_CPU_NODE1_SERIAL")
	)
	(segment
		(start 63.166498 -97.096834)
		(end 63.208662 -97.138998)
		(width 0.1016)
		(layer "B.Cu")
		(net "IRQ_CPU_NODE1_SERIAL")
	)
	(segment
		(start 61.52896 -99.10572)
		(end 61.52896 -99.265232)
		(width 0.1016)
		(layer "B.Cu")
		(net "IRQ_CPU_NODE1_SERIAL")
	)
	(segment
		(start 61.845698 -98.788982)
		(end 61.52896 -99.10572)
		(width 0.1016)
		(layer "B.Cu")
		(net "IRQ_CPU_NODE1_SERIAL")
	)
	(segment
		(start 63.16726 -98.788982)
		(end 61.845698 -98.788982)
		(width 0.1016)
		(layer "B.Cu")
		(net "IRQ_CPU_NODE1_SERIAL")
	)
	(segment
		(start 63.208662 -97.138998)
		(end 63.208662 -98.74758)
		(width 0.1016)
		(layer "B.Cu")
		(net "IRQ_CPU_NODE1_SERIAL")
	)
	(segment
		(start 111.67618 -17.65808)
		(end 111.67618 -17.791176)
		(width 0.1016)
		(layer "B.Cu")
		(net "IRQ_CPU_NODE1_SERIAL")
	)
	(segment
		(start 101.166676 -3.283204)
		(end 92.20835 -3.283204)
		(width 0.1016)
		(layer "B.Cu")
		(net "IRQ_CPU_NODE1_SERIAL")
	)
	(segment
		(start 120.74779 -45.817282)
		(end 120.74779 -45.634656)
		(width 0.1016)
		(layer "B.Cu")
		(net "IRQ_CPU_NODE1_SERIAL")
	)
	(segment
		(start 92.777818 -2.713736)
		(end 101.5238 -2.713736)
		(width 0.1016)
		(layer "B.Cu")
		(net "IRQ_CPU_NODE1_SERIAL")
	)
	(segment
		(start 92.20835 -3.283204)
		(end 92.777818 -2.713736)
		(width 0.1016)
		(layer "B.Cu")
		(net "IRQ_CPU_NODE1_SERIAL")
	)
	(segment
		(start 120.74779 -45.634656)
		(end 120.28932 -45.176186)
		(width 0.1016)
		(layer "B.Cu")
		(net "IRQ_CPU_NODE1_SERIAL")
	)
	(segment
		(start 109.17174 -11.288268)
		(end 101.166676 -3.283204)
		(width 0.1016)
		(layer "B.Cu")
		(net "IRQ_CPU_NODE1_SERIAL")
	)
	(segment
		(start 109.96676 -11.156696)
		(end 109.96676 -15.94866)
		(width 0.1016)
		(layer "B.Cu")
		(net "IRQ_CPU_NODE1_SERIAL")
	)
	(segment
		(start 61.328554 -99.465638)
		(end 61.328554 -99.605338)
		(width 0.1016)
		(layer "B.Cu")
		(net "IRQ_CPU_NODE1_SERIAL")
	)
	(segment
		(start 61.52896 -99.265232)
		(end 61.328554 -99.465638)
		(width 0.1016)
		(layer "B.Cu")
		(net "IRQ_CPU_NODE1_SERIAL")
	)
	(segment
		(start 112.2045 -33.930336)
		(end 112.2045 -47.531528)
		(width 0.1143)
		(layer "In2.Cu")
		(net "IRQ_CPU_NODE1_SERIAL")
	)
	(segment
		(start 95.6564 -103.302054)
		(end 95.6564 -103.64343)
		(width 0.1143)
		(layer "In2.Cu")
		(net "IRQ_CPU_NODE1_SERIAL")
	)
	(segment
		(start 114.707162 -49.982628)
		(end 120.2817 -55.557166)
		(width 0.1143)
		(layer "In2.Cu")
		(net "IRQ_CPU_NODE1_SERIAL")
	)
	(segment
		(start 114.6556 -49.982628)
		(end 114.707162 -49.982628)
		(width 0.1143)
		(layer "In2.Cu")
		(net "IRQ_CPU_NODE1_SERIAL")
	)
	(segment
		(start 105.034334 -87.970868)
		(end 99.68484 -93.320362)
		(width 0.1143)
		(layer "In2.Cu")
		(net "IRQ_CPU_NODE1_SERIAL")
	)
	(segment
		(start 109.849666 -87.970868)
		(end 105.034334 -87.970868)
		(width 0.1143)
		(layer "In2.Cu")
		(net "IRQ_CPU_NODE1_SERIAL")
	)
	(segment
		(start 113.424462 -32.710374)
		(end 112.2045 -33.930336)
		(width 0.1143)
		(layer "In2.Cu")
		(net "IRQ_CPU_NODE1_SERIAL")
	)
	(segment
		(start 97.90176 -98.274886)
		(end 97.90176 -101.056694)
		(width 0.1143)
		(layer "In2.Cu")
		(net "IRQ_CPU_NODE1_SERIAL")
	)
	(segment
		(start 112.61598 -28.532836)
		(end 113.424462 -29.341318)
		(width 0.1143)
		(layer "In2.Cu")
		(net "IRQ_CPU_NODE1_SERIAL")
	)
	(segment
		(start 112.2045 -47.531528)
		(end 114.6556 -49.982628)
		(width 0.1143)
		(layer "In2.Cu")
		(net "IRQ_CPU_NODE1_SERIAL")
	)
	(segment
		(start 113.424462 -29.341318)
		(end 113.424462 -32.710374)
		(width 0.1143)
		(layer "In2.Cu")
		(net "IRQ_CPU_NODE1_SERIAL")
	)
	(segment
		(start 112.61598 -19.431762)
		(end 112.61598 -28.532836)
		(width 0.1143)
		(layer "In2.Cu")
		(net "IRQ_CPU_NODE1_SERIAL")
	)
	(segment
		(start 97.90176 -101.056694)
		(end 95.6564 -103.302054)
		(width 0.1143)
		(layer "In2.Cu")
		(net "IRQ_CPU_NODE1_SERIAL")
	)
	(segment
		(start 120.2817 -77.538834)
		(end 109.849666 -87.970868)
		(width 0.1143)
		(layer "In2.Cu")
		(net "IRQ_CPU_NODE1_SERIAL")
	)
	(segment
		(start 99.68484 -96.491806)
		(end 97.90176 -98.274886)
		(width 0.1143)
		(layer "In2.Cu")
		(net "IRQ_CPU_NODE1_SERIAL")
	)
	(segment
		(start 99.68484 -93.320362)
		(end 99.68484 -96.491806)
		(width 0.1143)
		(layer "In2.Cu")
		(net "IRQ_CPU_NODE1_SERIAL")
	)
	(segment
		(start 120.2817 -55.557166)
		(end 120.2817 -77.538834)
		(width 0.1143)
		(layer "In2.Cu")
		(net "IRQ_CPU_NODE1_SERIAL")
	)
	(segment
		(start 112.36452 -19.180302)
		(end 112.61598 -19.431762)
		(width 0.1143)
		(layer "In2.Cu")
		(net "IRQ_CPU_NODE1_SERIAL")
	)
	(segment
		(start 74.752454 -102.58552)
		(end 73.65619 -101.489256)
		(width 0.1143)
		(layer "In7.Cu")
		(net "IRQ_CPU_NODE1_SERIAL")
	)
	(segment
		(start 122.297952 -43.53941)
		(end 120.661176 -45.176186)
		(width 0.1143)
		(layer "In7.Cu")
		(net "IRQ_CPU_NODE1_SERIAL")
	)
	(segment
		(start 61.592206 -99.86899)
		(end 61.328554 -99.605338)
		(width 0.1143)
		(layer "In7.Cu")
		(net "IRQ_CPU_NODE1_SERIAL")
	)
	(segment
		(start 122.297952 -35.818572)
		(end 122.297952 -43.53941)
		(width 0.1143)
		(layer "In7.Cu")
		(net "IRQ_CPU_NODE1_SERIAL")
	)
	(segment
		(start 111.67618 -17.791176)
		(end 111.67618 -20.523708)
		(width 0.1143)
		(layer "In7.Cu")
		(net "IRQ_CPU_NODE1_SERIAL")
	)
	(segment
		(start 95.42018 -103.64343)
		(end 94.36227 -102.58552)
		(width 0.1143)
		(layer "In7.Cu")
		(net "IRQ_CPU_NODE1_SERIAL")
	)
	(segment
		(start 120.661176 -45.176186)
		(end 120.28932 -45.176186)
		(width 0.1143)
		(layer "In7.Cu")
		(net "IRQ_CPU_NODE1_SERIAL")
	)
	(segment
		(start 64.547496 -99.86899)
		(end 61.592206 -99.86899)
		(width 0.1143)
		(layer "In7.Cu")
		(net "IRQ_CPU_NODE1_SERIAL")
	)
	(segment
		(start 94.36227 -102.58552)
		(end 74.752454 -102.58552)
		(width 0.1143)
		(layer "In7.Cu")
		(net "IRQ_CPU_NODE1_SERIAL")
	)
	(segment
		(start 112.5347 -26.05532)
		(end 122.297952 -35.818572)
		(width 0.1143)
		(layer "In7.Cu")
		(net "IRQ_CPU_NODE1_SERIAL")
	)
	(segment
		(start 112.5347 -21.382228)
		(end 112.5347 -26.05532)
		(width 0.1143)
		(layer "In7.Cu")
		(net "IRQ_CPU_NODE1_SERIAL")
	)
	(segment
		(start 73.65619 -101.489256)
		(end 66.167762 -101.489256)
		(width 0.1143)
		(layer "In7.Cu")
		(net "IRQ_CPU_NODE1_SERIAL")
	)
	(segment
		(start 111.67618 -20.523708)
		(end 112.5347 -21.382228)
		(width 0.1143)
		(layer "In7.Cu")
		(net "IRQ_CPU_NODE1_SERIAL")
	)
	(segment
		(start 66.167762 -101.489256)
		(end 64.547496 -99.86899)
		(width 0.1143)
		(layer "In7.Cu")
		(net "IRQ_CPU_NODE1_SERIAL")
	)
	(segment
		(start 95.6564 -103.64343)
		(end 95.42018 -103.64343)
		(width 0.1143)
		(layer "In7.Cu")
		(net "IRQ_CPU_NODE1_SERIAL")
	)
	(segment
		(start 179.010564 -120.366028)
		(end 179.510436 -120.8659)
		(width 0.1016)
		(layer "F.Cu")
		(net "PWRGD_NODE1_P1V26_BMC_PG")
	)
	(segment
		(start 85.518752 -138.633962)
		(end 85.518752 -137.408412)
		(width 0.1016)
		(layer "F.Cu")
		(net "PWRGD_NODE1_P1V26_BMC_PG")
	)
	(segment
		(start 84.927948 -139.751562)
		(end 84.927948 -139.224766)
		(width 0.1016)
		(layer "F.Cu")
		(net "PWRGD_NODE1_P1V26_BMC_PG")
	)
	(segment
		(start 84.927948 -139.224766)
		(end 85.518752 -138.633962)
		(width 0.1016)
		(layer "F.Cu")
		(net "PWRGD_NODE1_P1V26_BMC_PG")
	)
	(segment
		(start 179.010564 -120.365774)
		(end 179.010564 -120.366028)
		(width 0.1016)
		(layer "F.Cu")
		(net "PWRGD_NODE1_P1V26_BMC_PG")
	)
	(segment
		(start 85.518752 -137.408412)
		(end 86.201758 -137.408412)
		(width 0.1016)
		(layer "F.Cu")
		(net "PWRGD_NODE1_P1V26_BMC_PG")
	)
	(segment
		(start 86.201758 -137.408412)
		(end 86.44382 -137.650474)
		(width 0.1016)
		(layer "F.Cu")
		(net "PWRGD_NODE1_P1V26_BMC_PG")
	)
	(via
		(at 86.44382 -137.650474)
		(size 0.508)
		(drill 0.254)
		(layers "F.Cu" "B.Cu")
		(net "PWRGD_NODE1_P1V26_BMC_PG")
	)
	(via
		(at 164.2364 -117.747034)
		(size 0.508)
		(drill 0.254)
		(layers "F.Cu" "B.Cu")
		(net "PWRGD_NODE1_P1V26_BMC_PG")
	)
	(via
		(at 179.510436 -120.8659)
		(size 0.49022)
		(drill 0.254)
		(layers "F.Cu" "B.Cu")
		(net "PWRGD_NODE1_P1V26_BMC_PG")
	)
	(via
		(at 137.99312 -124.72416)
		(size 0.508)
		(drill 0.254)
		(layers "F.Cu" "B.Cu")
		(net "PWRGD_NODE1_P1V26_BMC_PG")
	)
	(segment
		(start 117.9703 -138.598656)
		(end 117.9703 -142.717012)
		(width 0.1143)
		(layer "In2.Cu")
		(net "PWRGD_NODE1_P1V26_BMC_PG")
	)
	(segment
		(start 135.26897 -125.720856)
		(end 133.555486 -124.007372)
		(width 0.1143)
		(layer "In2.Cu")
		(net "PWRGD_NODE1_P1V26_BMC_PG")
	)
	(segment
		(start 118.66118 -137.289286)
		(end 118.66118 -137.907776)
		(width 0.1143)
		(layer "In2.Cu")
		(net "PWRGD_NODE1_P1V26_BMC_PG")
	)
	(segment
		(start 137.99312 -124.72416)
		(end 137.986262 -124.72416)
		(width 0.1143)
		(layer "In2.Cu")
		(net "PWRGD_NODE1_P1V26_BMC_PG")
	)
	(segment
		(start 133.555486 -124.007372)
		(end 128.92405 -124.007372)
		(width 0.1143)
		(layer "In2.Cu")
		(net "PWRGD_NODE1_P1V26_BMC_PG")
	)
	(segment
		(start 88.200738 -137.650474)
		(end 86.44382 -137.650474)
		(width 0.1143)
		(layer "In2.Cu")
		(net "PWRGD_NODE1_P1V26_BMC_PG")
	)
	(segment
		(start 118.66118 -137.907776)
		(end 117.9703 -138.598656)
		(width 0.1143)
		(layer "In2.Cu")
		(net "PWRGD_NODE1_P1V26_BMC_PG")
	)
	(segment
		(start 127.2667 -128.683766)
		(end 118.66118 -137.289286)
		(width 0.1143)
		(layer "In2.Cu")
		(net "PWRGD_NODE1_P1V26_BMC_PG")
	)
	(segment
		(start 137.986262 -124.72416)
		(end 136.989566 -125.720856)
		(width 0.1143)
		(layer "In2.Cu")
		(net "PWRGD_NODE1_P1V26_BMC_PG")
	)
	(segment
		(start 136.989566 -125.720856)
		(end 135.26897 -125.720856)
		(width 0.1143)
		(layer "In2.Cu")
		(net "PWRGD_NODE1_P1V26_BMC_PG")
	)
	(segment
		(start 115.637056 -145.050256)
		(end 95.60052 -145.050256)
		(width 0.1143)
		(layer "In2.Cu")
		(net "PWRGD_NODE1_P1V26_BMC_PG")
	)
	(segment
		(start 95.60052 -145.050256)
		(end 88.200738 -137.650474)
		(width 0.1143)
		(layer "In2.Cu")
		(net "PWRGD_NODE1_P1V26_BMC_PG")
	)
	(segment
		(start 128.92405 -124.007372)
		(end 127.2667 -125.664722)
		(width 0.1143)
		(layer "In2.Cu")
		(net "PWRGD_NODE1_P1V26_BMC_PG")
	)
	(segment
		(start 127.2667 -125.664722)
		(end 127.2667 -128.683766)
		(width 0.1143)
		(layer "In2.Cu")
		(net "PWRGD_NODE1_P1V26_BMC_PG")
	)
	(segment
		(start 117.9703 -142.717012)
		(end 115.637056 -145.050256)
		(width 0.1143)
		(layer "In2.Cu")
		(net "PWRGD_NODE1_P1V26_BMC_PG")
	)
	(segment
		(start 149.221444 -125.19914)
		(end 138.4681 -125.19914)
		(width 0.1143)
		(layer "In6.Cu")
		(net "PWRGD_NODE1_P1V26_BMC_PG")
	)
	(segment
		(start 153.2255 -121.195084)
		(end 149.221444 -125.19914)
		(width 0.1143)
		(layer "In6.Cu")
		(net "PWRGD_NODE1_P1V26_BMC_PG")
	)
	(segment
		(start 160.78962 -121.195084)
		(end 153.2255 -121.195084)
		(width 0.1143)
		(layer "In6.Cu")
		(net "PWRGD_NODE1_P1V26_BMC_PG")
	)
	(segment
		(start 164.2364 -117.748304)
		(end 160.78962 -121.195084)
		(width 0.1143)
		(layer "In6.Cu")
		(net "PWRGD_NODE1_P1V26_BMC_PG")
	)
	(segment
		(start 164.2364 -117.747034)
		(end 164.2364 -117.748304)
		(width 0.1143)
		(layer "In6.Cu")
		(net "PWRGD_NODE1_P1V26_BMC_PG")
	)
	(segment
		(start 138.4681 -125.19914)
		(end 137.99312 -124.72416)
		(width 0.1143)
		(layer "In6.Cu")
		(net "PWRGD_NODE1_P1V26_BMC_PG")
	)
	(segment
		(start 176.42078 -118.139972)
		(end 175.59274 -117.311932)
		(width 0.1143)
		(layer "In7.Cu")
		(net "PWRGD_NODE1_P1V26_BMC_PG")
	)
	(segment
		(start 175.59274 -117.311932)
		(end 172.22978 -117.311932)
		(width 0.1143)
		(layer "In7.Cu")
		(net "PWRGD_NODE1_P1V26_BMC_PG")
	)
	(segment
		(start 166.146226 -117.273578)
		(end 165.89502 -117.524784)
		(width 0.1143)
		(layer "In7.Cu")
		(net "PWRGD_NODE1_P1V26_BMC_PG")
	)
	(segment
		(start 164.45865 -117.524784)
		(end 164.2364 -117.747034)
		(width 0.1143)
		(layer "In7.Cu")
		(net "PWRGD_NODE1_P1V26_BMC_PG")
	)
	(segment
		(start 177.786284 -120.8659)
		(end 176.42078 -119.500396)
		(width 0.1143)
		(layer "In7.Cu")
		(net "PWRGD_NODE1_P1V26_BMC_PG")
	)
	(segment
		(start 172.191426 -117.273578)
		(end 166.146226 -117.273578)
		(width 0.1143)
		(layer "In7.Cu")
		(net "PWRGD_NODE1_P1V26_BMC_PG")
	)
	(segment
		(start 172.22978 -117.311932)
		(end 172.191426 -117.273578)
		(width 0.1143)
		(layer "In7.Cu")
		(net "PWRGD_NODE1_P1V26_BMC_PG")
	)
	(segment
		(start 165.89502 -117.524784)
		(end 164.45865 -117.524784)
		(width 0.1143)
		(layer "In7.Cu")
		(net "PWRGD_NODE1_P1V26_BMC_PG")
	)
	(segment
		(start 176.42078 -119.500396)
		(end 176.42078 -118.139972)
		(width 0.1143)
		(layer "In7.Cu")
		(net "PWRGD_NODE1_P1V26_BMC_PG")
	)
	(segment
		(start 179.510436 -120.8659)
		(end 177.786284 -120.8659)
		(width 0.1143)
		(layer "In7.Cu")
		(net "PWRGD_NODE1_P1V26_BMC_PG")
	)
	(segment
		(start 76.860146 -86.239604)
		(end 76.860146 -89.186258)
		(width 0.1016)
		(layer "F.Cu")
		(net "VR_CPU_NODE1_INTVRMEN")
	)
	(segment
		(start 75.475084 -85.166454)
		(end 75.786996 -85.166454)
		(width 0.1016)
		(layer "F.Cu")
		(net "VR_CPU_NODE1_INTVRMEN")
	)
	(segment
		(start 73.842372 -84.858098)
		(end 74.070972 -84.629498)
		(width 0.1016)
		(layer "F.Cu")
		(net "VR_CPU_NODE1_INTVRMEN")
	)
	(segment
		(start 75.786996 -85.166454)
		(end 76.860146 -86.239604)
		(width 0.1016)
		(layer "F.Cu")
		(net "VR_CPU_NODE1_INTVRMEN")
	)
	(segment
		(start 76.860146 -89.186258)
		(end 77.685392 -90.011504)
		(width 0.1016)
		(layer "F.Cu")
		(net "VR_CPU_NODE1_INTVRMEN")
	)
	(segment
		(start 73.305162 -84.858098)
		(end 73.842372 -84.858098)
		(width 0.1016)
		(layer "F.Cu")
		(net "VR_CPU_NODE1_INTVRMEN")
	)
	(segment
		(start 74.938128 -84.629498)
		(end 75.475084 -85.166454)
		(width 0.1016)
		(layer "F.Cu")
		(net "VR_CPU_NODE1_INTVRMEN")
	)
	(segment
		(start 79.563468 -91.027504)
		(end 79.563468 -90.011504)
		(width 0.1016)
		(layer "F.Cu")
		(net "VR_CPU_NODE1_INTVRMEN")
	)
	(segment
		(start 74.070972 -84.629498)
		(end 74.938128 -84.629498)
		(width 0.1016)
		(layer "F.Cu")
		(net "VR_CPU_NODE1_INTVRMEN")
	)
	(segment
		(start 77.685392 -90.011504)
		(end 78.08468 -90.011504)
		(width 0.1016)
		(layer "F.Cu")
		(net "VR_CPU_NODE1_INTVRMEN")
	)
	(segment
		(start 79.563468 -90.011504)
		(end 78.08468 -90.011504)
		(width 0.1016)
		(layer "F.Cu")
		(net "VR_CPU_NODE1_INTVRMEN")
	)
	(via
		(at 78.08468 -90.011504)
		(size 0.762)
		(drill 0.381)
		(layers "F.Cu" "B.Cu")
		(net "VR_CPU_NODE1_INTVRMEN")
	)
	(segment
		(start 67.788028 -98.085148)
		(end 67.788028 -98.59391)
		(width 0.1016)
		(layer "F.Cu")
		(net "LPC_CPU_NODE1_CLKOUT1")
	)
	(segment
		(start 68.257166 -97.61601)
		(end 67.788028 -98.085148)
		(width 0.1016)
		(layer "F.Cu")
		(net "LPC_CPU_NODE1_CLKOUT1")
	)
	(segment
		(start 118.139718 -49.14011)
		(end 118.72468 -48.555148)
		(width 0.1016)
		(layer "F.Cu")
		(net "LPC_CPU_NODE1_CLKOUT1")
	)
	(segment
		(start 68.257166 -97.110042)
		(end 68.257166 -97.61601)
		(width 0.1016)
		(layer "F.Cu")
		(net "LPC_CPU_NODE1_CLKOUT1")
	)
	(segment
		(start 117.08638 -49.14011)
		(end 118.139718 -49.14011)
		(width 0.1016)
		(layer "F.Cu")
		(net "LPC_CPU_NODE1_CLKOUT1")
	)
	(segment
		(start 114.4651 -51.76139)
		(end 117.08638 -49.14011)
		(width 0.1016)
		(layer "F.Cu")
		(net "LPC_CPU_NODE1_CLKOUT1")
	)
	(segment
		(start 118.72468 -48.555148)
		(end 118.72468 -41.529762)
		(width 0.1016)
		(layer "F.Cu")
		(net "LPC_CPU_NODE1_CLKOUT1")
	)
	(via
		(at 114.4651 -51.76139)
		(size 0.508)
		(drill 0.254)
		(layers "F.Cu" "B.Cu")
		(net "LPC_CPU_NODE1_CLKOUT1")
	)
	(via
		(at 67.788028 -98.59391)
		(size 0.508)
		(drill 0.254)
		(layers "F.Cu" "B.Cu")
		(net "LPC_CPU_NODE1_CLKOUT1")
	)
	(via
		(at 97.18548 -99.538028)
		(size 0.508)
		(drill 0.254)
		(layers "F.Cu" "B.Cu")
		(net "LPC_CPU_NODE1_CLKOUT1")
	)
	(segment
		(start 114.4651 -52.013104)
		(end 114.4651 -51.76139)
		(width 0.1143)
		(layer "In2.Cu")
		(net "LPC_CPU_NODE1_CLKOUT1")
	)
	(segment
		(start 108.280962 -87.132668)
		(end 118.48338 -76.93025)
		(width 0.1143)
		(layer "In2.Cu")
		(net "LPC_CPU_NODE1_CLKOUT1")
	)
	(segment
		(start 98.84664 -92.969588)
		(end 104.68356 -87.132668)
		(width 0.1143)
		(layer "In2.Cu")
		(net "LPC_CPU_NODE1_CLKOUT1")
	)
	(segment
		(start 98.84664 -96.082612)
		(end 98.84664 -92.969588)
		(width 0.1143)
		(layer "In2.Cu")
		(net "LPC_CPU_NODE1_CLKOUT1")
	)
	(segment
		(start 96.63811 -98.990658)
		(end 96.63811 -98.291142)
		(width 0.1143)
		(layer "In2.Cu")
		(net "LPC_CPU_NODE1_CLKOUT1")
	)
	(segment
		(start 118.48338 -67.496436)
		(end 118.727982 -67.251834)
		(width 0.1143)
		(layer "In2.Cu")
		(net "LPC_CPU_NODE1_CLKOUT1")
	)
	(segment
		(start 118.48338 -76.93025)
		(end 118.48338 -67.496436)
		(width 0.1143)
		(layer "In2.Cu")
		(net "LPC_CPU_NODE1_CLKOUT1")
	)
	(segment
		(start 118.727982 -56.275986)
		(end 114.4651 -52.013104)
		(width 0.1143)
		(layer "In2.Cu")
		(net "LPC_CPU_NODE1_CLKOUT1")
	)
	(segment
		(start 96.63811 -98.291142)
		(end 98.84664 -96.082612)
		(width 0.1143)
		(layer "In2.Cu")
		(net "LPC_CPU_NODE1_CLKOUT1")
	)
	(segment
		(start 118.727982 -67.251834)
		(end 118.727982 -56.275986)
		(width 0.1143)
		(layer "In2.Cu")
		(net "LPC_CPU_NODE1_CLKOUT1")
	)
	(segment
		(start 97.18548 -99.538028)
		(end 96.63811 -98.990658)
		(width 0.1143)
		(layer "In2.Cu")
		(net "LPC_CPU_NODE1_CLKOUT1")
	)
	(segment
		(start 104.68356 -87.132668)
		(end 108.280962 -87.132668)
		(width 0.1143)
		(layer "In2.Cu")
		(net "LPC_CPU_NODE1_CLKOUT1")
	)
	(segment
		(start 76.320142 -99.03841)
		(end 82.262472 -99.03841)
		(width 0.1143)
		(layer "In7.Cu")
		(net "LPC_CPU_NODE1_CLKOUT1")
	)
	(segment
		(start 83.3501 -97.950782)
		(end 85.491574 -97.950782)
		(width 0.1143)
		(layer "In7.Cu")
		(net "LPC_CPU_NODE1_CLKOUT1")
	)
	(segment
		(start 82.262472 -99.03841)
		(end 83.3501 -97.950782)
		(width 0.1143)
		(layer "In7.Cu")
		(net "LPC_CPU_NODE1_CLKOUT1")
	)
	(segment
		(start 85.491574 -97.950782)
		(end 87.4649 -99.924108)
		(width 0.1143)
		(layer "In7.Cu")
		(net "LPC_CPU_NODE1_CLKOUT1")
	)
	(segment
		(start 91.828874 -99.924108)
		(end 92.241116 -100.33635)
		(width 0.1143)
		(layer "In7.Cu")
		(net "LPC_CPU_NODE1_CLKOUT1")
	)
	(segment
		(start 92.241116 -100.33635)
		(end 93.440758 -100.33635)
		(width 0.1143)
		(layer "In7.Cu")
		(net "LPC_CPU_NODE1_CLKOUT1")
	)
	(segment
		(start 87.4649 -99.924108)
		(end 91.828874 -99.924108)
		(width 0.1143)
		(layer "In7.Cu")
		(net "LPC_CPU_NODE1_CLKOUT1")
	)
	(segment
		(start 93.853 -99.924108)
		(end 96.7994 -99.924108)
		(width 0.1143)
		(layer "In7.Cu")
		(net "LPC_CPU_NODE1_CLKOUT1")
	)
	(segment
		(start 96.7994 -99.924108)
		(end 97.18548 -99.538028)
		(width 0.1143)
		(layer "In7.Cu")
		(net "LPC_CPU_NODE1_CLKOUT1")
	)
	(segment
		(start 93.440758 -100.33635)
		(end 93.853 -99.924108)
		(width 0.1143)
		(layer "In7.Cu")
		(net "LPC_CPU_NODE1_CLKOUT1")
	)
	(segment
		(start 75.809602 -98.52787)
		(end 76.320142 -99.03841)
		(width 0.1143)
		(layer "In7.Cu")
		(net "LPC_CPU_NODE1_CLKOUT1")
	)
	(segment
		(start 72.83323 -98.52787)
		(end 75.809602 -98.52787)
		(width 0.1143)
		(layer "In7.Cu")
		(net "LPC_CPU_NODE1_CLKOUT1")
	)
	(segment
		(start 67.788028 -98.59391)
		(end 67.871594 -98.677476)
		(width 0.1143)
		(layer "In7.Cu")
		(net "LPC_CPU_NODE1_CLKOUT1")
	)
	(segment
		(start 72.683624 -98.677476)
		(end 72.83323 -98.52787)
		(width 0.1143)
		(layer "In7.Cu")
		(net "LPC_CPU_NODE1_CLKOUT1")
	)
	(segment
		(start 67.871594 -98.677476)
		(end 72.683624 -98.677476)
		(width 0.1143)
		(layer "In7.Cu")
		(net "LPC_CPU_NODE1_CLKOUT1")
	)
	(segment
		(start 71.741792 -128.059434)
		(end 72.142096 -127.65913)
		(width 0.1016)
		(layer "F.Cu")
		(net "PD_BMC_NODE1_PEREXT")
	)
	(via
		(at 72.142096 -127.65913)
		(size 0.49022)
		(drill 0.254)
		(layers "F.Cu" "B.Cu")
		(net "PD_BMC_NODE1_PEREXT")
	)
	(segment
		(start 73.47204 -128.989074)
		(end 72.142096 -127.65913)
		(width 0.1016)
		(layer "B.Cu")
		(net "PD_BMC_NODE1_PEREXT")
	)
	(segment
		(start 75.415902 -128.989074)
		(end 73.47204 -128.989074)
		(width 0.1016)
		(layer "B.Cu")
		(net "PD_BMC_NODE1_PEREXT")
	)
	(segment
		(start 65.249044 -76.67117)
		(end 65.384172 -76.806298)
		(width 0.1143)
		(layer "F.Cu")
		(net "PD_CPU_NODE1_PUNIT_ST_ADDR0")
	)
	(segment
		(start 65.249044 -76.269342)
		(end 65.249044 -76.67117)
		(width 0.1143)
		(layer "F.Cu")
		(net "PD_CPU_NODE1_PUNIT_ST_ADDR0")
	)
	(segment
		(start 65.384172 -76.806298)
		(end 65.384172 -77.097382)
		(width 0.1143)
		(layer "F.Cu")
		(net "PD_CPU_NODE1_PUNIT_ST_ADDR0")
	)
	(via
		(at 65.384172 -77.097382)
		(size 0.508)
		(drill 0.254)
		(layers "F.Cu" "B.Cu")
		(net "PD_CPU_NODE1_PUNIT_ST_ADDR0")
	)
	(via
		(at 78.574138 -74.15276)
		(size 0.6604)
		(drill 0.3302)
		(layers "F.Cu" "B.Cu")
		(net "PD_CPU_NODE1_PUNIT_ST_ADDR0")
	)
	(segment
		(start 91.07297 -72.216518)
		(end 91.018106 -72.161654)
		(width 0.1016)
		(layer "B.Cu")
		(net "PD_CPU_NODE1_PUNIT_ST_ADDR0")
	)
	(segment
		(start 74.11974 -75.665584)
		(end 67.993514 -75.665584)
		(width 0.1016)
		(layer "B.Cu")
		(net "PD_CPU_NODE1_PUNIT_ST_ADDR0")
	)
	(segment
		(start 78.574138 -74.15276)
		(end 79.481172 -73.245726)
		(width 0.1016)
		(layer "B.Cu")
		(net "PD_CPU_NODE1_PUNIT_ST_ADDR0")
	)
	(segment
		(start 78.574138 -74.15276)
		(end 78.222094 -74.504804)
		(width 0.1016)
		(layer "B.Cu")
		(net "PD_CPU_NODE1_PUNIT_ST_ADDR0")
	)
	(segment
		(start 88.984074 -72.86498)
		(end 89.1794 -72.669654)
		(width 0.1016)
		(layer "B.Cu")
		(net "PD_CPU_NODE1_PUNIT_ST_ADDR0")
	)
	(segment
		(start 67.680332 -75.978766)
		(end 66.278506 -75.978766)
		(width 0.1016)
		(layer "B.Cu")
		(net "PD_CPU_NODE1_PUNIT_ST_ADDR0")
	)
	(segment
		(start 67.993514 -75.665584)
		(end 67.680332 -75.978766)
		(width 0.1016)
		(layer "B.Cu")
		(net "PD_CPU_NODE1_PUNIT_ST_ADDR0")
	)
	(segment
		(start 89.1794 -72.669654)
		(end 89.1794 -72.161654)
		(width 0.1016)
		(layer "B.Cu")
		(net "PD_CPU_NODE1_PUNIT_ST_ADDR0")
	)
	(segment
		(start 79.481172 -73.245726)
		(end 86.909402 -73.245726)
		(width 0.1016)
		(layer "B.Cu")
		(net "PD_CPU_NODE1_PUNIT_ST_ADDR0")
	)
	(segment
		(start 86.909402 -73.245726)
		(end 87.290148 -72.86498)
		(width 0.1016)
		(layer "B.Cu")
		(net "PD_CPU_NODE1_PUNIT_ST_ADDR0")
	)
	(segment
		(start 65.384172 -76.8731)
		(end 65.384172 -77.097382)
		(width 0.1016)
		(layer "B.Cu")
		(net "PD_CPU_NODE1_PUNIT_ST_ADDR0")
	)
	(segment
		(start 77.756004 -74.504804)
		(end 77.264006 -74.996802)
		(width 0.1016)
		(layer "B.Cu")
		(net "PD_CPU_NODE1_PUNIT_ST_ADDR0")
	)
	(segment
		(start 77.264006 -74.996802)
		(end 74.788522 -74.996802)
		(width 0.1016)
		(layer "B.Cu")
		(net "PD_CPU_NODE1_PUNIT_ST_ADDR0")
	)
	(segment
		(start 78.222094 -74.504804)
		(end 77.756004 -74.504804)
		(width 0.1016)
		(layer "B.Cu")
		(net "PD_CPU_NODE1_PUNIT_ST_ADDR0")
	)
	(segment
		(start 91.018106 -72.161654)
		(end 89.1794 -72.161654)
		(width 0.1016)
		(layer "B.Cu")
		(net "PD_CPU_NODE1_PUNIT_ST_ADDR0")
	)
	(segment
		(start 66.278506 -75.978766)
		(end 65.384172 -76.8731)
		(width 0.1016)
		(layer "B.Cu")
		(net "PD_CPU_NODE1_PUNIT_ST_ADDR0")
	)
	(segment
		(start 87.290148 -72.86498)
		(end 88.984074 -72.86498)
		(width 0.1016)
		(layer "B.Cu")
		(net "PD_CPU_NODE1_PUNIT_ST_ADDR0")
	)
	(segment
		(start 74.788522 -74.996802)
		(end 74.11974 -75.665584)
		(width 0.1016)
		(layer "B.Cu")
		(net "PD_CPU_NODE1_PUNIT_ST_ADDR0")
	)
	(segment
		(start 37.18052 -6.950964)
		(end 37.18052 -7.44728)
		(width 0.1016)
		(layer "F.Cu")
		(net "PWRGD_NODE1_PVDDR_STB_PG")
	)
	(segment
		(start 180.010562 -121.365518)
		(end 180.010562 -121.365772)
		(width 0.1016)
		(layer "F.Cu")
		(net "PWRGD_NODE1_PVDDR_STB_PG")
	)
	(segment
		(start 37.446458 -7.713218)
		(end 37.446458 -7.89178)
		(width 0.1016)
		(layer "F.Cu")
		(net "PWRGD_NODE1_PVDDR_STB_PG")
	)
	(segment
		(start 37.18052 -7.44728)
		(end 37.446458 -7.713218)
		(width 0.1016)
		(layer "F.Cu")
		(net "PWRGD_NODE1_PVDDR_STB_PG")
	)
	(segment
		(start 37.682678 -8.128)
		(end 37.682678 -8.738616)
		(width 0.1016)
		(layer "F.Cu")
		(net "PWRGD_NODE1_PVDDR_STB_PG")
	)
	(segment
		(start 180.010562 -121.365772)
		(end 180.510434 -121.865644)
		(width 0.1016)
		(layer "F.Cu")
		(net "PWRGD_NODE1_PVDDR_STB_PG")
	)
	(segment
		(start 37.446458 -7.89178)
		(end 37.682678 -8.128)
		(width 0.1016)
		(layer "F.Cu")
		(net "PWRGD_NODE1_PVDDR_STB_PG")
	)
	(via
		(at 37.446458 -7.713218)
		(size 0.508)
		(drill 0.254)
		(layers "F.Cu" "B.Cu")
		(net "PWRGD_NODE1_PVDDR_STB_PG")
	)
	(via
		(at 41.7957 -15.554706)
		(size 0.508)
		(drill 0.254)
		(layers "F.Cu" "B.Cu")
		(net "PWRGD_NODE1_PVDDR_STB_PG")
	)
	(via
		(at 180.510434 -121.865644)
		(size 0.49022)
		(drill 0.254)
		(layers "F.Cu" "B.Cu")
		(net "PWRGD_NODE1_PVDDR_STB_PG")
	)
	(segment
		(start 36.992814 -8.166862)
		(end 34.42208 -8.166862)
		(width 0.1016)
		(layer "B.Cu")
		(net "PWRGD_NODE1_PVDDR_STB_PG")
	)
	(segment
		(start 34.283142 -16.38935)
		(end 40.961056 -16.38935)
		(width 0.1016)
		(layer "B.Cu")
		(net "PWRGD_NODE1_PVDDR_STB_PG")
	)
	(segment
		(start 32.74314 -9.845802)
		(end 32.74314 -14.849348)
		(width 0.1016)
		(layer "B.Cu")
		(net "PWRGD_NODE1_PVDDR_STB_PG")
	)
	(segment
		(start 40.961056 -16.38935)
		(end 41.7957 -15.554706)
		(width 0.1016)
		(layer "B.Cu")
		(net "PWRGD_NODE1_PVDDR_STB_PG")
	)
	(segment
		(start 37.446458 -7.713218)
		(end 36.992814 -8.166862)
		(width 0.1016)
		(layer "B.Cu")
		(net "PWRGD_NODE1_PVDDR_STB_PG")
	)
	(segment
		(start 34.42208 -8.166862)
		(end 32.74314 -9.845802)
		(width 0.1016)
		(layer "B.Cu")
		(net "PWRGD_NODE1_PVDDR_STB_PG")
	)
	(segment
		(start 32.74314 -14.849348)
		(end 34.283142 -16.38935)
		(width 0.1016)
		(layer "B.Cu")
		(net "PWRGD_NODE1_PVDDR_STB_PG")
	)
	(segment
		(start 183.09717 -121.934732)
		(end 182.473092 -121.934732)
		(width 0.1143)
		(layer "In6.Cu")
		(net "PWRGD_NODE1_PVDDR_STB_PG")
	)
	(segment
		(start 161.82086 -47.383954)
		(end 164.368226 -49.93132)
		(width 0.1143)
		(layer "In6.Cu")
		(net "PWRGD_NODE1_PVDDR_STB_PG")
	)
	(segment
		(start 42.95394 -15.167102)
		(end 43.196764 -15.409926)
		(width 0.1143)
		(layer "In6.Cu")
		(net "PWRGD_NODE1_PVDDR_STB_PG")
	)
	(segment
		(start 183.35371 -85.74151)
		(end 183.35371 -121.678192)
		(width 0.1143)
		(layer "In6.Cu")
		(net "PWRGD_NODE1_PVDDR_STB_PG")
	)
	(segment
		(start 117.304566 -14.65199)
		(end 119.341138 -16.688562)
		(width 0.1143)
		(layer "In6.Cu")
		(net "PWRGD_NODE1_PVDDR_STB_PG")
	)
	(segment
		(start 91.419934 -14.65199)
		(end 117.304566 -14.65199)
		(width 0.1143)
		(layer "In6.Cu")
		(net "PWRGD_NODE1_PVDDR_STB_PG")
	)
	(segment
		(start 182.473092 -121.934732)
		(end 182.248048 -121.709688)
		(width 0.1143)
		(layer "In6.Cu")
		(net "PWRGD_NODE1_PVDDR_STB_PG")
	)
	(segment
		(start 43.196764 -15.409926)
		(end 63.782702 -15.409926)
		(width 0.1143)
		(layer "In6.Cu")
		(net "PWRGD_NODE1_PVDDR_STB_PG")
	)
	(segment
		(start 42.183304 -15.167102)
		(end 42.95394 -15.167102)
		(width 0.1143)
		(layer "In6.Cu")
		(net "PWRGD_NODE1_PVDDR_STB_PG")
	)
	(segment
		(start 164.368226 -49.93132)
		(end 164.368226 -66.756026)
		(width 0.1143)
		(layer "In6.Cu")
		(net "PWRGD_NODE1_PVDDR_STB_PG")
	)
	(segment
		(start 129.8956 -15.9258)
		(end 130.2512 -15.5702)
		(width 0.1143)
		(layer "In6.Cu")
		(net "PWRGD_NODE1_PVDDR_STB_PG")
	)
	(segment
		(start 156.7942 -15.5702)
		(end 161.82086 -20.59686)
		(width 0.1143)
		(layer "In6.Cu")
		(net "PWRGD_NODE1_PVDDR_STB_PG")
	)
	(segment
		(start 123.584716 -16.688562)
		(end 124.346716 -15.9258)
		(width 0.1143)
		(layer "In6.Cu")
		(net "PWRGD_NODE1_PVDDR_STB_PG")
	)
	(segment
		(start 41.7957 -15.554706)
		(end 42.183304 -15.167102)
		(width 0.1143)
		(layer "In6.Cu")
		(net "PWRGD_NODE1_PVDDR_STB_PG")
	)
	(segment
		(start 161.82086 -20.59686)
		(end 161.82086 -47.383954)
		(width 0.1143)
		(layer "In6.Cu")
		(net "PWRGD_NODE1_PVDDR_STB_PG")
	)
	(segment
		(start 130.2512 -15.5702)
		(end 156.7942 -15.5702)
		(width 0.1143)
		(layer "In6.Cu")
		(net "PWRGD_NODE1_PVDDR_STB_PG")
	)
	(segment
		(start 63.782702 -15.409926)
		(end 64.08166 -15.110968)
		(width 0.1143)
		(layer "In6.Cu")
		(net "PWRGD_NODE1_PVDDR_STB_PG")
	)
	(segment
		(start 64.08166 -15.110968)
		(end 90.960956 -15.110968)
		(width 0.1143)
		(layer "In6.Cu")
		(net "PWRGD_NODE1_PVDDR_STB_PG")
	)
	(segment
		(start 119.341138 -16.688562)
		(end 123.584716 -16.688562)
		(width 0.1143)
		(layer "In6.Cu")
		(net "PWRGD_NODE1_PVDDR_STB_PG")
	)
	(segment
		(start 182.248048 -121.709688)
		(end 180.66639 -121.709688)
		(width 0.1143)
		(layer "In6.Cu")
		(net "PWRGD_NODE1_PVDDR_STB_PG")
	)
	(segment
		(start 90.960956 -15.110968)
		(end 91.419934 -14.65199)
		(width 0.1143)
		(layer "In6.Cu")
		(net "PWRGD_NODE1_PVDDR_STB_PG")
	)
	(segment
		(start 164.368226 -66.756026)
		(end 183.35371 -85.74151)
		(width 0.1143)
		(layer "In6.Cu")
		(net "PWRGD_NODE1_PVDDR_STB_PG")
	)
	(segment
		(start 183.35371 -121.678192)
		(end 183.09717 -121.934732)
		(width 0.1143)
		(layer "In6.Cu")
		(net "PWRGD_NODE1_PVDDR_STB_PG")
	)
	(segment
		(start 124.346716 -15.9258)
		(end 129.8956 -15.9258)
		(width 0.1143)
		(layer "In6.Cu")
		(net "PWRGD_NODE1_PVDDR_STB_PG")
	)
	(segment
		(start 180.66639 -121.709688)
		(end 180.510434 -121.865644)
		(width 0.1143)
		(layer "In6.Cu")
		(net "PWRGD_NODE1_PVDDR_STB_PG")
	)
	(segment
		(start 67.7418 -126.459488)
		(end 67.7418 -126.147576)
		(width 0.1016)
		(layer "F.Cu")
		(net "IRQ_LVC3_CPU_NODE1_WAKE_R_L")
	)
	(segment
		(start 68.329048 -121.46915)
		(end 68.329048 -122.822462)
		(width 0.1016)
		(layer "F.Cu")
		(net "IRQ_LVC3_CPU_NODE1_WAKE_R_L")
	)
	(segment
		(start 67.310254 -125.71603)
		(end 67.310254 -125.179074)
		(width 0.1016)
		(layer "F.Cu")
		(net "IRQ_LVC3_CPU_NODE1_WAKE_R_L")
	)
	(segment
		(start 68.329048 -122.822462)
		(end 67.310254 -123.841256)
		(width 0.1016)
		(layer "F.Cu")
		(net "IRQ_LVC3_CPU_NODE1_WAKE_R_L")
	)
	(segment
		(start 67.310254 -124.631958)
		(end 67.036696 -124.905516)
		(width 0.1016)
		(layer "F.Cu")
		(net "IRQ_LVC3_CPU_NODE1_WAKE_R_L")
	)
	(segment
		(start 67.7418 -126.147576)
		(end 67.310254 -125.71603)
		(width 0.1016)
		(layer "F.Cu")
		(net "IRQ_LVC3_CPU_NODE1_WAKE_R_L")
	)
	(segment
		(start 68.353686 -121.444512)
		(end 68.329048 -121.46915)
		(width 0.1016)
		(layer "F.Cu")
		(net "IRQ_LVC3_CPU_NODE1_WAKE_R_L")
	)
	(segment
		(start 67.310254 -123.841256)
		(end 67.310254 -124.631958)
		(width 0.1016)
		(layer "F.Cu")
		(net "IRQ_LVC3_CPU_NODE1_WAKE_R_L")
	)
	(segment
		(start 67.310254 -125.179074)
		(end 67.036696 -124.905516)
		(width 0.1016)
		(layer "F.Cu")
		(net "IRQ_LVC3_CPU_NODE1_WAKE_R_L")
	)
	(via
		(at 67.036696 -124.905516)
		(size 0.508)
		(drill 0.254)
		(layers "F.Cu" "B.Cu")
		(net "IRQ_LVC3_CPU_NODE1_WAKE_R_L")
	)
	(segment
		(start 69.440044 -77.555598)
		(end 69.672962 -77.32268)
		(width 0.1016)
		(layer "F.Cu")
		(net "PU_CPU_NODE1_MEM_SPEED0")
	)
	(segment
		(start 69.672962 -77.32268)
		(end 69.672962 -77.066902)
		(width 0.1016)
		(layer "F.Cu")
		(net "PU_CPU_NODE1_MEM_SPEED0")
	)
	(via
		(at 69.672962 -77.066902)
		(size 0.508)
		(drill 0.254)
		(layers "F.Cu" "B.Cu")
		(net "PU_CPU_NODE1_MEM_SPEED0")
	)
	(via
		(at 84.993988 -76.926694)
		(size 0.6604)
		(drill 0.3302)
		(layers "F.Cu" "B.Cu")
		(net "PU_CPU_NODE1_MEM_SPEED0")
	)
	(segment
		(start 77.302614 -76.317602)
		(end 83.685888 -76.317602)
		(width 0.1016)
		(layer "B.Cu")
		(net "PU_CPU_NODE1_MEM_SPEED0")
	)
	(segment
		(start 83.685888 -76.317602)
		(end 84.29498 -76.926694)
		(width 0.1016)
		(layer "B.Cu")
		(net "PU_CPU_NODE1_MEM_SPEED0")
	)
	(segment
		(start 75.069954 -76.925424)
		(end 75.176126 -77.031596)
		(width 0.1016)
		(layer "B.Cu")
		(net "PU_CPU_NODE1_MEM_SPEED0")
	)
	(segment
		(start 86.364826 -78.527402)
		(end 87.479378 -78.527402)
		(width 0.1016)
		(layer "B.Cu")
		(net "PU_CPU_NODE1_MEM_SPEED0")
	)
	(segment
		(start 85.712808 -77.645514)
		(end 85.712808 -77.875384)
		(width 0.1016)
		(layer "B.Cu")
		(net "PU_CPU_NODE1_MEM_SPEED0")
	)
	(segment
		(start 76.58862 -77.031596)
		(end 77.302614 -76.317602)
		(width 0.1016)
		(layer "B.Cu")
		(net "PU_CPU_NODE1_MEM_SPEED0")
	)
	(segment
		(start 87.479378 -78.527402)
		(end 87.71763 -78.765654)
		(width 0.1016)
		(layer "B.Cu")
		(net "PU_CPU_NODE1_MEM_SPEED0")
	)
	(segment
		(start 88.3793 -78.765654)
		(end 88.3793 -77.749654)
		(width 0.1016)
		(layer "B.Cu")
		(net "PU_CPU_NODE1_MEM_SPEED0")
	)
	(segment
		(start 85.712808 -77.875384)
		(end 86.364826 -78.527402)
		(width 0.1016)
		(layer "B.Cu")
		(net "PU_CPU_NODE1_MEM_SPEED0")
	)
	(segment
		(start 75.176126 -77.031596)
		(end 76.58862 -77.031596)
		(width 0.1016)
		(layer "B.Cu")
		(net "PU_CPU_NODE1_MEM_SPEED0")
	)
	(segment
		(start 71.2851 -77.436726)
		(end 71.796402 -76.925424)
		(width 0.1016)
		(layer "B.Cu")
		(net "PU_CPU_NODE1_MEM_SPEED0")
	)
	(segment
		(start 84.29498 -76.926694)
		(end 84.993988 -76.926694)
		(width 0.1016)
		(layer "B.Cu")
		(net "PU_CPU_NODE1_MEM_SPEED0")
	)
	(segment
		(start 71.796402 -76.925424)
		(end 75.069954 -76.925424)
		(width 0.1016)
		(layer "B.Cu")
		(net "PU_CPU_NODE1_MEM_SPEED0")
	)
	(segment
		(start 87.71763 -78.765654)
		(end 88.3793 -78.765654)
		(width 0.1016)
		(layer "B.Cu")
		(net "PU_CPU_NODE1_MEM_SPEED0")
	)
	(segment
		(start 70.042786 -77.436726)
		(end 71.2851 -77.436726)
		(width 0.1016)
		(layer "B.Cu")
		(net "PU_CPU_NODE1_MEM_SPEED0")
	)
	(segment
		(start 84.993988 -76.926694)
		(end 85.712808 -77.645514)
		(width 0.1016)
		(layer "B.Cu")
		(net "PU_CPU_NODE1_MEM_SPEED0")
	)
	(segment
		(start 69.672962 -77.066902)
		(end 70.042786 -77.436726)
		(width 0.1016)
		(layer "B.Cu")
		(net "PU_CPU_NODE1_MEM_SPEED0")
	)
	(segment
		(start 176.01057 -118.349522)
		(end 175.53178 -117.870732)
		(width 0.1016)
		(layer "F.Cu")
		(net "TP_FM_CPLD_NODE1_SSI_PERST_L")
	)
	(segment
		(start 176.01057 -118.365524)
		(end 176.01057 -118.349522)
		(width 0.1016)
		(layer "F.Cu")
		(net "TP_FM_CPLD_NODE1_SSI_PERST_L")
	)
	(via
		(at 175.53178 -117.870732)
		(size 0.508)
		(drill 0.254)
		(layers "F.Cu" "B.Cu")
		(net "TP_FM_CPLD_NODE1_SSI_PERST_L")
	)
	(via
		(at 176.80178 -116.560854)
		(size 0.6604)
		(drill 0.3302)
		(layers "F.Cu" "B.Cu")
		(net "TP_FM_CPLD_NODE1_SSI_PERST_L")
	)
	(segment
		(start 176.80178 -116.560854)
		(end 175.53178 -117.830854)
		(width 0.1016)
		(layer "B.Cu")
		(net "TP_FM_CPLD_NODE1_SSI_PERST_L")
	)
	(segment
		(start 175.53178 -117.830854)
		(end 175.53178 -117.870732)
		(width 0.1016)
		(layer "B.Cu")
		(net "TP_FM_CPLD_NODE1_SSI_PERST_L")
	)
	(segment
		(start 66.9417 -128.859534)
		(end 66.9417 -128.857502)
		(width 0.1016)
		(layer "F.Cu")
		(net "RST_BMC_NODE1_PERST_L")
	)
	(segment
		(start 66.9417 -128.857502)
		(end 67.340988 -128.458214)
		(width 0.1016)
		(layer "F.Cu")
		(net "RST_BMC_NODE1_PERST_L")
	)
	(via
		(at 69.141086 -123.381262)
		(size 0.6604)
		(drill 0.3302)
		(layers "F.Cu" "B.Cu")
		(net "RST_BMC_NODE1_PERST_L")
	)
	(via
		(at 67.340988 -128.458214)
		(size 0.49022)
		(drill 0.254)
		(layers "F.Cu" "B.Cu")
		(net "RST_BMC_NODE1_PERST_L")
	)
	(segment
		(start 67.738498 -127.409448)
		(end 67.738498 -128.060704)
		(width 0.1016)
		(layer "B.Cu")
		(net "RST_BMC_NODE1_PERST_L")
	)
	(segment
		(start 68.491862 -123.381262)
		(end 67.561206 -124.311918)
		(width 0.1016)
		(layer "B.Cu")
		(net "RST_BMC_NODE1_PERST_L")
	)
	(segment
		(start 67.738498 -128.060704)
		(end 67.340988 -128.458214)
		(width 0.1016)
		(layer "B.Cu")
		(net "RST_BMC_NODE1_PERST_L")
	)
	(segment
		(start 67.561206 -124.311918)
		(end 67.561206 -125.920754)
		(width 0.1016)
		(layer "B.Cu")
		(net "RST_BMC_NODE1_PERST_L")
	)
	(segment
		(start 67.561206 -125.920754)
		(end 67.921886 -126.281434)
		(width 0.1016)
		(layer "B.Cu")
		(net "RST_BMC_NODE1_PERST_L")
	)
	(segment
		(start 67.921886 -126.281434)
		(end 67.921886 -127.22606)
		(width 0.1016)
		(layer "B.Cu")
		(net "RST_BMC_NODE1_PERST_L")
	)
	(segment
		(start 70.690994 -121.463308)
		(end 70.672198 -121.444512)
		(width 0.1016)
		(layer "B.Cu")
		(net "RST_BMC_NODE1_PERST_L")
	)
	(segment
		(start 67.921886 -127.22606)
		(end 67.738498 -127.409448)
		(width 0.1016)
		(layer "B.Cu")
		(net "RST_BMC_NODE1_PERST_L")
	)
	(segment
		(start 69.141086 -123.381262)
		(end 69.395086 -123.127262)
		(width 0.1016)
		(layer "B.Cu")
		(net "RST_BMC_NODE1_PERST_L")
	)
	(segment
		(start 71.721472 -121.459752)
		(end 70.69455 -121.459752)
		(width 0.1016)
		(layer "B.Cu")
		(net "RST_BMC_NODE1_PERST_L")
	)
	(segment
		(start 69.395086 -123.127262)
		(end 69.395086 -121.444512)
		(width 0.1016)
		(layer "B.Cu")
		(net "RST_BMC_NODE1_PERST_L")
	)
	(segment
		(start 70.69455 -121.459752)
		(end 70.690994 -121.463308)
		(width 0.1016)
		(layer "B.Cu")
		(net "RST_BMC_NODE1_PERST_L")
	)
	(segment
		(start 69.141086 -123.381262)
		(end 68.491862 -123.381262)
		(width 0.1016)
		(layer "B.Cu")
		(net "RST_BMC_NODE1_PERST_L")
	)
	(segment
		(start 70.672198 -121.444512)
		(end 69.395086 -121.444512)
		(width 0.1016)
		(layer "B.Cu")
		(net "RST_BMC_NODE1_PERST_L")
	)
	(segment
		(start 80.28305 -82.902044)
		(end 79.320898 -82.902044)
		(width 0.1016)
		(layer "F.Cu")
		(net "LPC_CPU_NODE1_CLK0_DS")
	)
	(segment
		(start 72.901556 -82.200242)
		(end 73.168256 -82.200242)
		(width 0.1016)
		(layer "F.Cu")
		(net "LPC_CPU_NODE1_CLK0_DS")
	)
	(segment
		(start 73.479152 -81.889346)
		(end 73.803764 -81.889346)
		(width 0.1016)
		(layer "F.Cu")
		(net "LPC_CPU_NODE1_CLK0_DS")
	)
	(segment
		(start 79.169768 -82.775298)
		(end 79.18196 -82.763106)
		(width 0.1016)
		(layer "F.Cu")
		(net "LPC_CPU_NODE1_CLK0_DS")
	)
	(segment
		(start 75.1967 -82.124042)
		(end 75.421998 -81.898744)
		(width 0.1016)
		(layer "F.Cu")
		(net "LPC_CPU_NODE1_CLK0_DS")
	)
	(segment
		(start 79.320898 -82.902044)
		(end 79.18196 -82.763106)
		(width 0.1016)
		(layer "F.Cu")
		(net "LPC_CPU_NODE1_CLK0_DS")
	)
	(segment
		(start 73.168256 -82.200242)
		(end 73.479152 -81.889346)
		(width 0.1016)
		(layer "F.Cu")
		(net "LPC_CPU_NODE1_CLK0_DS")
	)
	(segment
		(start 78.722474 -82.775298)
		(end 79.169768 -82.775298)
		(width 0.1016)
		(layer "F.Cu")
		(net "LPC_CPU_NODE1_CLK0_DS")
	)
	(segment
		(start 74.03846 -82.124042)
		(end 75.1967 -82.124042)
		(width 0.1016)
		(layer "F.Cu")
		(net "LPC_CPU_NODE1_CLK0_DS")
	)
	(segment
		(start 75.421998 -81.898744)
		(end 77.84592 -81.898744)
		(width 0.1016)
		(layer "F.Cu")
		(net "LPC_CPU_NODE1_CLK0_DS")
	)
	(segment
		(start 73.803764 -81.889346)
		(end 74.03846 -82.124042)
		(width 0.1016)
		(layer "F.Cu")
		(net "LPC_CPU_NODE1_CLK0_DS")
	)
	(segment
		(start 77.84592 -81.898744)
		(end 78.722474 -82.775298)
		(width 0.1016)
		(layer "F.Cu")
		(net "LPC_CPU_NODE1_CLK0_DS")
	)
	(via
		(at 79.18196 -82.763106)
		(size 0.508)
		(drill 0.254)
		(layers "F.Cu" "B.Cu")
		(net "LPC_CPU_NODE1_CLK0_DS")
	)
	(segment
		(start 79.320898 -82.902044)
		(end 79.18196 -82.763106)
		(width 0.1016)
		(layer "B.Cu")
		(net "LPC_CPU_NODE1_CLK0_DS")
	)
	(segment
		(start 80.28305 -82.902044)
		(end 79.320898 -82.902044)
		(width 0.1016)
		(layer "B.Cu")
		(net "LPC_CPU_NODE1_CLK0_DS")
	)
	(segment
		(start 64.381126 -83.476846)
		(end 64.74587 -83.112102)
		(width 0.1016)
		(layer "F.Cu")
		(net "PD_CPU_NODE1_BRD_ID1")
	)
	(segment
		(start 64.18961 -83.476846)
		(end 64.381126 -83.476846)
		(width 0.1016)
		(layer "F.Cu")
		(net "PD_CPU_NODE1_BRD_ID1")
	)
	(via
		(at 64.74587 -83.112102)
		(size 0.508)
		(drill 0.254)
		(layers "F.Cu" "B.Cu")
		(net "PD_CPU_NODE1_BRD_ID1")
	)
	(via
		(at 65.739772 -88.822022)
		(size 0.6604)
		(drill 0.3302)
		(layers "F.Cu" "B.Cu")
		(net "PD_CPU_NODE1_BRD_ID1")
	)
	(segment
		(start 66.214498 -96.296734)
		(end 66.214498 -96.115632)
		(width 0.1016)
		(layer "B.Cu")
		(net "PD_CPU_NODE1_BRD_ID1")
	)
	(segment
		(start 66.711068 -94.846394)
		(end 66.1289 -94.264226)
		(width 0.1016)
		(layer "B.Cu")
		(net "PD_CPU_NODE1_BRD_ID1")
	)
	(segment
		(start 66.1289 -93.214698)
		(end 65.721992 -93.214698)
		(width 0.1016)
		(layer "B.Cu")
		(net "PD_CPU_NODE1_BRD_ID1")
	)
	(segment
		(start 65.760854 -84.127086)
		(end 65.760854 -88.80094)
		(width 0.1016)
		(layer "B.Cu")
		(net "PD_CPU_NODE1_BRD_ID1")
	)
	(segment
		(start 65.760854 -88.80094)
		(end 65.739772 -88.822022)
		(width 0.1016)
		(layer "B.Cu")
		(net "PD_CPU_NODE1_BRD_ID1")
	)
	(segment
		(start 65.358264 -90.252296)
		(end 65.358264 -89.20353)
		(width 0.1016)
		(layer "B.Cu")
		(net "PD_CPU_NODE1_BRD_ID1")
	)
	(segment
		(start 65.358264 -89.20353)
		(end 65.739772 -88.822022)
		(width 0.1016)
		(layer "B.Cu")
		(net "PD_CPU_NODE1_BRD_ID1")
	)
	(segment
		(start 65.721992 -93.214698)
		(end 65.463674 -92.95638)
		(width 0.1016)
		(layer "B.Cu")
		(net "PD_CPU_NODE1_BRD_ID1")
	)
	(segment
		(start 65.661286 -90.555318)
		(end 65.358264 -90.252296)
		(width 0.1016)
		(layer "B.Cu")
		(net "PD_CPU_NODE1_BRD_ID1")
	)
	(segment
		(start 66.711068 -95.619062)
		(end 66.711068 -94.846394)
		(width 0.1016)
		(layer "B.Cu")
		(net "PD_CPU_NODE1_BRD_ID1")
	)
	(segment
		(start 65.463674 -92.95638)
		(end 65.463674 -91.711272)
		(width 0.1016)
		(layer "B.Cu")
		(net "PD_CPU_NODE1_BRD_ID1")
	)
	(segment
		(start 65.463674 -91.711272)
		(end 65.661286 -91.51366)
		(width 0.1016)
		(layer "B.Cu")
		(net "PD_CPU_NODE1_BRD_ID1")
	)
	(segment
		(start 65.661286 -91.51366)
		(end 65.661286 -90.555318)
		(width 0.1016)
		(layer "B.Cu")
		(net "PD_CPU_NODE1_BRD_ID1")
	)
	(segment
		(start 64.74587 -83.112102)
		(end 65.760854 -84.127086)
		(width 0.1016)
		(layer "B.Cu")
		(net "PD_CPU_NODE1_BRD_ID1")
	)
	(segment
		(start 66.214498 -96.115632)
		(end 66.711068 -95.619062)
		(width 0.1016)
		(layer "B.Cu")
		(net "PD_CPU_NODE1_BRD_ID1")
	)
	(segment
		(start 66.1289 -94.264226)
		(end 66.1289 -93.214698)
		(width 0.1016)
		(layer "B.Cu")
		(net "PD_CPU_NODE1_BRD_ID1")
	)
	(segment
		(start 67.916044 -77.551026)
		(end 67.802506 -77.437488)
		(width 0.1016)
		(layer "F.Cu")
		(net "PD_CPU_NODE1_MEM_SPEED1")
	)
	(segment
		(start 67.916044 -77.555598)
		(end 67.916044 -77.551026)
		(width 0.1016)
		(layer "F.Cu")
		(net "PD_CPU_NODE1_MEM_SPEED1")
	)
	(segment
		(start 67.802506 -77.437488)
		(end 67.802506 -77.033374)
		(width 0.1016)
		(layer "F.Cu")
		(net "PD_CPU_NODE1_MEM_SPEED1")
	)
	(via
		(at 80.014826 -74.996802)
		(size 0.6604)
		(drill 0.3302)
		(layers "F.Cu" "B.Cu")
		(net "PD_CPU_NODE1_MEM_SPEED1")
	)
	(via
		(at 67.802506 -77.033374)
		(size 0.508)
		(drill 0.254)
		(layers "F.Cu" "B.Cu")
		(net "PD_CPU_NODE1_MEM_SPEED1")
	)
	(segment
		(start 78.4225 -75.266804)
		(end 78.082902 -75.606402)
		(width 0.1016)
		(layer "B.Cu")
		(net "PD_CPU_NODE1_MEM_SPEED1")
	)
	(segment
		(start 75.041506 -75.606402)
		(end 74.332084 -76.315824)
		(width 0.1016)
		(layer "B.Cu")
		(net "PD_CPU_NODE1_MEM_SPEED1")
	)
	(segment
		(start 68.321428 -76.315824)
		(end 67.802506 -76.834746)
		(width 0.1016)
		(layer "B.Cu")
		(net "PD_CPU_NODE1_MEM_SPEED1")
	)
	(segment
		(start 74.332084 -76.315824)
		(end 68.321428 -76.315824)
		(width 0.1016)
		(layer "B.Cu")
		(net "PD_CPU_NODE1_MEM_SPEED1")
	)
	(segment
		(start 90.527886 -76.172568)
		(end 89.044018 -76.172568)
		(width 0.1016)
		(layer "B.Cu")
		(net "PD_CPU_NODE1_MEM_SPEED1")
	)
	(segment
		(start 89.044018 -76.172568)
		(end 89.020904 -76.149454)
		(width 0.1016)
		(layer "B.Cu")
		(net "PD_CPU_NODE1_MEM_SPEED1")
	)
	(segment
		(start 67.802506 -76.834746)
		(end 67.802506 -77.033374)
		(width 0.1016)
		(layer "B.Cu")
		(net "PD_CPU_NODE1_MEM_SPEED1")
	)
	(segment
		(start 91.07297 -75.772518)
		(end 90.927936 -75.772518)
		(width 0.1016)
		(layer "B.Cu")
		(net "PD_CPU_NODE1_MEM_SPEED1")
	)
	(segment
		(start 79.744824 -75.266804)
		(end 78.4225 -75.266804)
		(width 0.1016)
		(layer "B.Cu")
		(net "PD_CPU_NODE1_MEM_SPEED1")
	)
	(segment
		(start 88.44534 -75.717654)
		(end 88.3793 -75.717654)
		(width 0.1016)
		(layer "B.Cu")
		(net "PD_CPU_NODE1_MEM_SPEED1")
	)
	(segment
		(start 85.644736 -74.996802)
		(end 86.365588 -75.717654)
		(width 0.1016)
		(layer "B.Cu")
		(net "PD_CPU_NODE1_MEM_SPEED1")
	)
	(segment
		(start 90.927936 -75.772518)
		(end 90.527886 -76.172568)
		(width 0.1016)
		(layer "B.Cu")
		(net "PD_CPU_NODE1_MEM_SPEED1")
	)
	(segment
		(start 78.082902 -75.606402)
		(end 75.041506 -75.606402)
		(width 0.1016)
		(layer "B.Cu")
		(net "PD_CPU_NODE1_MEM_SPEED1")
	)
	(segment
		(start 80.014826 -74.996802)
		(end 85.644736 -74.996802)
		(width 0.1016)
		(layer "B.Cu")
		(net "PD_CPU_NODE1_MEM_SPEED1")
	)
	(segment
		(start 86.365588 -75.717654)
		(end 88.3793 -75.717654)
		(width 0.1016)
		(layer "B.Cu")
		(net "PD_CPU_NODE1_MEM_SPEED1")
	)
	(segment
		(start 89.020904 -76.149454)
		(end 88.87714 -76.149454)
		(width 0.1016)
		(layer "B.Cu")
		(net "PD_CPU_NODE1_MEM_SPEED1")
	)
	(segment
		(start 88.87714 -76.149454)
		(end 88.44534 -75.717654)
		(width 0.1016)
		(layer "B.Cu")
		(net "PD_CPU_NODE1_MEM_SPEED1")
	)
	(segment
		(start 80.014826 -74.996802)
		(end 79.744824 -75.266804)
		(width 0.1016)
		(layer "B.Cu")
		(net "PD_CPU_NODE1_MEM_SPEED1")
	)
	(segment
		(start 77.554074 -92.965524)
		(end 75.980798 -91.392248)
		(width 0.1016)
		(layer "F.Cu")
		(net "PU_CPU_NODE1_BRD_ID0")
	)
	(segment
		(start 69.617844 -88.44026)
		(end 69.461888 -88.596216)
		(width 0.1016)
		(layer "F.Cu")
		(net "PU_CPU_NODE1_BRD_ID0")
	)
	(segment
		(start 78.522068 -93.708982)
		(end 77.77861 -92.965524)
		(width 0.1016)
		(layer "F.Cu")
		(net "PU_CPU_NODE1_BRD_ID0")
	)
	(segment
		(start 69.461888 -89.698576)
		(end 70.773036 -91.009724)
		(width 0.1016)
		(layer "F.Cu")
		(net "PU_CPU_NODE1_BRD_ID0")
	)
	(segment
		(start 75.980798 -91.392248)
		(end 75.063858 -91.392248)
		(width 0.1016)
		(layer "F.Cu")
		(net "PU_CPU_NODE1_BRD_ID0")
	)
	(segment
		(start 69.461888 -88.596216)
		(end 69.461888 -89.698576)
		(width 0.1016)
		(layer "F.Cu")
		(net "PU_CPU_NODE1_BRD_ID0")
	)
	(segment
		(start 74.681334 -91.009724)
		(end 75.063858 -91.392248)
		(width 0.1016)
		(layer "F.Cu")
		(net "PU_CPU_NODE1_BRD_ID0")
	)
	(segment
		(start 77.77861 -92.965524)
		(end 77.554074 -92.965524)
		(width 0.1016)
		(layer "F.Cu")
		(net "PU_CPU_NODE1_BRD_ID0")
	)
	(segment
		(start 78.522068 -93.731842)
		(end 78.522068 -93.708982)
		(width 0.1016)
		(layer "F.Cu")
		(net "PU_CPU_NODE1_BRD_ID0")
	)
	(segment
		(start 77.506068 -93.731842)
		(end 78.522068 -93.731842)
		(width 0.1016)
		(layer "F.Cu")
		(net "PU_CPU_NODE1_BRD_ID0")
	)
	(segment
		(start 70.773036 -91.009724)
		(end 74.681334 -91.009724)
		(width 0.1016)
		(layer "F.Cu")
		(net "PU_CPU_NODE1_BRD_ID0")
	)
	(via
		(at 75.063858 -91.392248)
		(size 0.508)
		(drill 0.254)
		(layers "F.Cu" "B.Cu")
		(net "PU_CPU_NODE1_BRD_ID0")
	)
	(segment
		(start 67.154044 -77.550772)
		(end 67.183254 -77.521562)
		(width 0.1016)
		(layer "F.Cu")
		(net "PD_CPU_NODE1_HVMGEAR_SEL")
	)
	(segment
		(start 67.183254 -77.521562)
		(end 67.183254 -76.989686)
		(width 0.1016)
		(layer "F.Cu")
		(net "PD_CPU_NODE1_HVMGEAR_SEL")
	)
	(segment
		(start 67.154044 -77.555598)
		(end 67.154044 -77.550772)
		(width 0.1016)
		(layer "F.Cu")
		(net "PD_CPU_NODE1_HVMGEAR_SEL")
	)
	(via
		(at 67.183254 -76.989686)
		(size 0.508)
		(drill 0.254)
		(layers "F.Cu" "B.Cu")
		(net "PD_CPU_NODE1_HVMGEAR_SEL")
	)
	(via
		(at 87.059516 -75.012804)
		(size 0.6604)
		(drill 0.3302)
		(layers "F.Cu" "B.Cu")
		(net "PD_CPU_NODE1_HVMGEAR_SEL")
	)
	(segment
		(start 91.07297 -74.756518)
		(end 91.018106 -74.701654)
		(width 0.1016)
		(layer "B.Cu")
		(net "PD_CPU_NODE1_HVMGEAR_SEL")
	)
	(segment
		(start 68.16217 -76.071984)
		(end 67.244468 -76.989686)
		(width 0.1016)
		(layer "B.Cu")
		(net "PD_CPU_NODE1_HVMGEAR_SEL")
	)
	(segment
		(start 88.7857 -75.029314)
		(end 88.7857 -75.012804)
		(width 0.1016)
		(layer "B.Cu")
		(net "PD_CPU_NODE1_HVMGEAR_SEL")
	)
	(segment
		(start 86.739984 -74.693272)
		(end 84.163662 -74.693272)
		(width 0.1016)
		(layer "B.Cu")
		(net "PD_CPU_NODE1_HVMGEAR_SEL")
	)
	(segment
		(start 88.7857 -75.012804)
		(end 88.86825 -75.012804)
		(width 0.1016)
		(layer "B.Cu")
		(net "PD_CPU_NODE1_HVMGEAR_SEL")
	)
	(segment
		(start 79.212948 -75.012804)
		(end 78.164182 -75.012804)
		(width 0.1016)
		(layer "B.Cu")
		(net "PD_CPU_NODE1_HVMGEAR_SEL")
	)
	(segment
		(start 77.773784 -75.403202)
		(end 74.957178 -75.403202)
		(width 0.1016)
		(layer "B.Cu")
		(net "PD_CPU_NODE1_HVMGEAR_SEL")
	)
	(segment
		(start 87.95639 -75.012804)
		(end 88.07704 -75.133454)
		(width 0.1016)
		(layer "B.Cu")
		(net "PD_CPU_NODE1_HVMGEAR_SEL")
	)
	(segment
		(start 78.164182 -75.012804)
		(end 77.773784 -75.403202)
		(width 0.1016)
		(layer "B.Cu")
		(net "PD_CPU_NODE1_HVMGEAR_SEL")
	)
	(segment
		(start 79.760318 -74.465434)
		(end 79.212948 -75.012804)
		(width 0.1016)
		(layer "B.Cu")
		(net "PD_CPU_NODE1_HVMGEAR_SEL")
	)
	(segment
		(start 74.288396 -76.071984)
		(end 68.16217 -76.071984)
		(width 0.1016)
		(layer "B.Cu")
		(net "PD_CPU_NODE1_HVMGEAR_SEL")
	)
	(segment
		(start 83.935824 -74.465434)
		(end 79.760318 -74.465434)
		(width 0.1016)
		(layer "B.Cu")
		(net "PD_CPU_NODE1_HVMGEAR_SEL")
	)
	(segment
		(start 87.059516 -75.012804)
		(end 86.739984 -74.693272)
		(width 0.1016)
		(layer "B.Cu")
		(net "PD_CPU_NODE1_HVMGEAR_SEL")
	)
	(segment
		(start 88.86825 -75.012804)
		(end 89.1794 -74.701654)
		(width 0.1016)
		(layer "B.Cu")
		(net "PD_CPU_NODE1_HVMGEAR_SEL")
	)
	(segment
		(start 88.68156 -75.133454)
		(end 88.7857 -75.029314)
		(width 0.1016)
		(layer "B.Cu")
		(net "PD_CPU_NODE1_HVMGEAR_SEL")
	)
	(segment
		(start 88.07704 -75.133454)
		(end 88.68156 -75.133454)
		(width 0.1016)
		(layer "B.Cu")
		(net "PD_CPU_NODE1_HVMGEAR_SEL")
	)
	(segment
		(start 67.244468 -76.989686)
		(end 67.183254 -76.989686)
		(width 0.1016)
		(layer "B.Cu")
		(net "PD_CPU_NODE1_HVMGEAR_SEL")
	)
	(segment
		(start 87.059516 -75.012804)
		(end 87.95639 -75.012804)
		(width 0.1016)
		(layer "B.Cu")
		(net "PD_CPU_NODE1_HVMGEAR_SEL")
	)
	(segment
		(start 84.163662 -74.693272)
		(end 83.935824 -74.465434)
		(width 0.1016)
		(layer "B.Cu")
		(net "PD_CPU_NODE1_HVMGEAR_SEL")
	)
	(segment
		(start 91.018106 -74.701654)
		(end 89.1794 -74.701654)
		(width 0.1016)
		(layer "B.Cu")
		(net "PD_CPU_NODE1_HVMGEAR_SEL")
	)
	(segment
		(start 74.957178 -75.403202)
		(end 74.288396 -76.071984)
		(width 0.1016)
		(layer "B.Cu")
		(net "PD_CPU_NODE1_HVMGEAR_SEL")
	)
	(segment
		(start 149.811994 -43.664124)
		(end 150.600918 -43.664124)
		(width 0.508)
		(layer "F.Cu")
		(net "P5V_NODE1")
	)
	(segment
		(start 25.10536 -56.183022)
		(end 24.63546 -56.652922)
		(width 0.381)
		(layer "F.Cu")
		(net "P5V_NODE1")
	)
	(segment
		(start 142.705836 -54.529228)
		(end 141.834362 -54.529228)
		(width 0.508)
		(layer "F.Cu")
		(net "P5V_NODE1")
	)
	(segment
		(start 141.834362 -54.529228)
		(end 141.1605 -53.855366)
		(width 0.508)
		(layer "F.Cu")
		(net "P5V_NODE1")
	)
	(segment
		(start 126.261622 -47.199804)
		(end 126.261622 -48.308514)
		(width 0.254)
		(layer "F.Cu")
		(net "P5V_NODE1")
	)
	(segment
		(start 133.289802 -156.308298)
		(end 134.068312 -156.308298)
		(width 0.508)
		(layer "F.Cu")
		(net "P5V_NODE1")
	)
	(segment
		(start 141.761718 -47.199804)
		(end 141.761718 -45.80636)
		(width 0.254)
		(layer "F.Cu")
		(net "P5V_NODE1")
	)
	(segment
		(start 133.223 -51.83505)
		(end 133.223 -52.122324)
		(width 0.508)
		(layer "F.Cu")
		(net "P5V_NODE1")
	)
	(segment
		(start 126.261622 -48.308514)
		(end 126.00432 -48.565816)
		(width 0.254)
		(layer "F.Cu")
		(net "P5V_NODE1")
	)
	(segment
		(start 112.72901 -161.227516)
		(end 112.7379 -161.227516)
		(width 0.508)
		(layer "F.Cu")
		(net "P5V_NODE1")
	)
	(segment
		(start 150.231602 -40.373046)
		(end 150.758398 -40.899842)
		(width 0.508)
		(layer "F.Cu")
		(net "P5V_NODE1")
	)
	(segment
		(start 112.320578 -160.819084)
		(end 112.72901 -161.227516)
		(width 0.508)
		(layer "F.Cu")
		(net "P5V_NODE1")
	)
	(segment
		(start 150.055326 -41.480994)
		(end 150.177246 -41.480994)
		(width 0.508)
		(layer "F.Cu")
		(net "P5V_NODE1")
	)
	(segment
		(start 141.761718 -45.80636)
		(end 141.487144 -45.531786)
		(width 0.254)
		(layer "F.Cu")
		(net "P5V_NODE1")
	)
	(segment
		(start 139.676886 -51.876706)
		(end 139.676886 -52.59324)
		(width 0.508)
		(layer "F.Cu")
		(net "P5V_NODE1")
	)
	(segment
		(start 138.303 -51.83505)
		(end 138.303 -52.578)
		(width 0.508)
		(layer "F.Cu")
		(net "P5V_NODE1")
	)
	(segment
		(start 125.800104 -48.989234)
		(end 125.800104 -49.670462)
		(width 0.508)
		(layer "F.Cu")
		(net "P5V_NODE1")
	)
	(segment
		(start 138.537696 -57.587388)
		(end 137.127234 -57.587388)
		(width 0.508)
		(layer "F.Cu")
		(net "P5V_NODE1")
	)
	(segment
		(start 126.00432 -48.785018)
		(end 125.800104 -48.989234)
		(width 0.508)
		(layer "F.Cu")
		(net "P5V_NODE1")
	)
	(segment
		(start 126.135638 -180.487828)
		(end 126.959868 -180.487828)
		(width 0.508)
		(layer "F.Cu")
		(net "P5V_NODE1")
	)
	(segment
		(start 150.177246 -41.480994)
		(end 150.758398 -40.899842)
		(width 0.508)
		(layer "F.Cu")
		(net "P5V_NODE1")
	)
	(segment
		(start 125.800104 -49.670462)
		(end 126.440946 -49.670462)
		(width 0.508)
		(layer "F.Cu")
		(net "P5V_NODE1")
	)
	(segment
		(start 126.135638 -179.471828)
		(end 127.18034 -179.471828)
		(width 0.508)
		(layer "F.Cu")
		(net "P5V_NODE1")
	)
	(segment
		(start 135.574532 -56.649366)
		(end 135.109966 -56.1848)
		(width 0.508)
		(layer "F.Cu")
		(net "P5V_NODE1")
	)
	(segment
		(start 141.708886 -51.876706)
		(end 141.708886 -52.714398)
		(width 0.508)
		(layer "F.Cu")
		(net "P5V_NODE1")
	)
	(segment
		(start 141.487144 -45.531786)
		(end 141.182344 -45.531786)
		(width 0.254)
		(layer "F.Cu")
		(net "P5V_NODE1")
	)
	(segment
		(start 135.255 -51.83505)
		(end 135.255 -52.451)
		(width 0.508)
		(layer "F.Cu")
		(net "P5V_NODE1")
	)
	(segment
		(start 135.109966 -56.1848)
		(end 135.109966 -55.724552)
		(width 0.508)
		(layer "F.Cu")
		(net "P5V_NODE1")
	)
	(segment
		(start 112.320578 -160.57753)
		(end 112.320578 -160.819084)
		(width 0.508)
		(layer "F.Cu")
		(net "P5V_NODE1")
	)
	(segment
		(start 137.127234 -57.587388)
		(end 136.189212 -56.649366)
		(width 0.508)
		(layer "F.Cu")
		(net "P5V_NODE1")
	)
	(segment
		(start 126.135638 -181.503828)
		(end 126.860808 -181.503828)
		(width 0.508)
		(layer "F.Cu")
		(net "P5V_NODE1")
	)
	(segment
		(start 133.223 -52.122324)
		(end 133.770878 -52.670202)
		(width 0.508)
		(layer "F.Cu")
		(net "P5V_NODE1")
	)
	(segment
		(start 136.189212 -56.649366)
		(end 135.574532 -56.649366)
		(width 0.508)
		(layer "F.Cu")
		(net "P5V_NODE1")
	)
	(segment
		(start 25.10536 -55.558436)
		(end 25.10536 -56.183022)
		(width 0.381)
		(layer "F.Cu")
		(net "P5V_NODE1")
	)
	(segment
		(start 126.440946 -49.670462)
		(end 126.785116 -49.326292)
		(width 0.508)
		(layer "F.Cu")
		(net "P5V_NODE1")
	)
	(segment
		(start 130.0988 -51.25085)
		(end 130.0988 -51.8668)
		(width 0.508)
		(layer "F.Cu")
		(net "P5V_NODE1")
	)
	(segment
		(start 150.073868 -40.373046)
		(end 150.231602 -40.373046)
		(width 0.508)
		(layer "F.Cu")
		(net "P5V_NODE1")
	)
	(segment
		(start 127.993902 -155.853892)
		(end 129.038096 -155.853892)
		(width 0.508)
		(layer "F.Cu")
		(net "P5V_NODE1")
	)
	(segment
		(start 126.00432 -48.565816)
		(end 126.00432 -48.785018)
		(width 0.508)
		(layer "F.Cu")
		(net "P5V_NODE1")
	)
	(segment
		(start 126.135638 -182.519828)
		(end 126.135638 -181.503828)
		(width 0.508)
		(layer "F.Cu")
		(net "P5V_NODE1")
	)
	(via
		(at 141.060678 -175.045624)
		(size 0.508)
		(drill 0.254)
		(layers "F.Cu" "B.Cu")
		(net "P5V_NODE1")
	)
	(via
		(at 141.0081 -177.077624)
		(size 0.508)
		(drill 0.254)
		(layers "F.Cu" "B.Cu")
		(net "P5V_NODE1")
	)
	(via
		(at 94.27972 -4.518406)
		(size 0.508)
		(drill 0.254)
		(layers "F.Cu" "B.Cu")
		(net "P5V_NODE1")
	)
	(via
		(at 20.9804 -72.498204)
		(size 0.508)
		(drill 0.254)
		(layers "F.Cu" "B.Cu")
		(net "P5V_NODE1")
	)
	(via
		(at 189.91834 -25.474422)
		(size 0.508)
		(drill 0.254)
		(layers "F.Cu" "B.Cu")
		(net "P5V_NODE1")
	)
	(via
		(at 124.81052 -176.442624)
		(size 0.508)
		(drill 0.254)
		(layers "F.Cu" "B.Cu")
		(net "P5V_NODE1")
	)
	(via
		(at 137.71372 -23.757636)
		(size 0.508)
		(drill 0.254)
		(layers "F.Cu" "B.Cu")
		(net "P5V_NODE1")
	)
	(via
		(at 130.2004 -45.4406)
		(size 0.508)
		(drill 0.254)
		(layers "F.Cu" "B.Cu")
		(net "P5V_NODE1")
	)
	(via
		(at 171.85386 -47.802292)
		(size 0.508)
		(drill 0.254)
		(layers "F.Cu" "B.Cu")
		(net "P5V_NODE1")
	)
	(via
		(at 145.486628 -49.580546)
		(size 0.508)
		(drill 0.254)
		(layers "F.Cu" "B.Cu")
		(net "P5V_NODE1")
	)
	(via
		(at 69.2531 -176.210468)
		(size 0.508)
		(drill 0.254)
		(layers "F.Cu" "B.Cu")
		(net "P5V_NODE1")
	)
	(via
		(at 77.798676 -171.489624)
		(size 0.508)
		(drill 0.254)
		(layers "F.Cu" "B.Cu")
		(net "P5V_NODE1")
	)
	(via
		(at 130.0988 -51.8668)
		(size 0.508)
		(drill 0.254)
		(layers "F.Cu" "B.Cu")
		(net "P5V_NODE1")
	)
	(via
		(at 134.068312 -156.308298)
		(size 0.508)
		(drill 0.254)
		(layers "F.Cu" "B.Cu")
		(net "P5V_NODE1")
	)
	(via
		(at 149.343872 -35.24631)
		(size 0.508)
		(drill 0.254)
		(layers "F.Cu" "B.Cu")
		(net "P5V_NODE1")
	)
	(via
		(at 190.79972 -27.993086)
		(size 0.508)
		(drill 0.254)
		(layers "F.Cu" "B.Cu")
		(net "P5V_NODE1")
	)
	(via
		(at 91.84132 -178.78044)
		(size 0.508)
		(drill 0.254)
		(layers "F.Cu" "B.Cu")
		(net "P5V_NODE1")
	)
	(via
		(at 139.676886 -52.59324)
		(size 0.508)
		(drill 0.254)
		(layers "F.Cu" "B.Cu")
		(net "P5V_NODE1")
	)
	(via
		(at 141.042136 -174.029624)
		(size 0.508)
		(drill 0.254)
		(layers "F.Cu" "B.Cu")
		(net "P5V_NODE1")
	)
	(via
		(at 155.14574 -173.718982)
		(size 0.508)
		(drill 0.254)
		(layers "F.Cu" "B.Cu")
		(net "P5V_NODE1")
	)
	(via
		(at 138.303 -52.578)
		(size 0.508)
		(drill 0.254)
		(layers "F.Cu" "B.Cu")
		(net "P5V_NODE1")
	)
	(via
		(at 126.785116 -49.326292)
		(size 0.508)
		(drill 0.254)
		(layers "F.Cu" "B.Cu")
		(net "P5V_NODE1")
	)
	(via
		(at 171.09186 -144.194784)
		(size 0.508)
		(drill 0.254)
		(layers "F.Cu" "B.Cu")
		(net "P5V_NODE1")
	)
	(via
		(at 109.407452 -180.633624)
		(size 0.508)
		(drill 0.254)
		(layers "F.Cu" "B.Cu")
		(net "P5V_NODE1")
	)
	(via
		(at 109.376972 -177.585624)
		(size 0.508)
		(drill 0.254)
		(layers "F.Cu" "B.Cu")
		(net "P5V_NODE1")
	)
	(via
		(at 173.26356 -49.43221)
		(size 0.508)
		(drill 0.254)
		(layers "F.Cu" "B.Cu")
		(net "P5V_NODE1")
	)
	(via
		(at 190.00978 -27.993086)
		(size 0.508)
		(drill 0.254)
		(layers "F.Cu" "B.Cu")
		(net "P5V_NODE1")
	)
	(via
		(at 91.86164 -170.511724)
		(size 0.508)
		(drill 0.254)
		(layers "F.Cu" "B.Cu")
		(net "P5V_NODE1")
	)
	(via
		(at 109.426502 -176.569624)
		(size 0.508)
		(drill 0.254)
		(layers "F.Cu" "B.Cu")
		(net "P5V_NODE1")
	)
	(via
		(at 127.18034 -179.471828)
		(size 0.508)
		(drill 0.254)
		(layers "F.Cu" "B.Cu")
		(net "P5V_NODE1")
	)
	(via
		(at 177.2539 -47.356014)
		(size 0.508)
		(drill 0.254)
		(layers "F.Cu" "B.Cu")
		(net "P5V_NODE1")
	)
	(via
		(at 77.718666 -174.537624)
		(size 0.508)
		(drill 0.254)
		(layers "F.Cu" "B.Cu")
		(net "P5V_NODE1")
	)
	(via
		(at 172.30344 -141.586204)
		(size 0.508)
		(drill 0.254)
		(layers "F.Cu" "B.Cu")
		(net "P5V_NODE1")
	)
	(via
		(at 138.537696 -57.587388)
		(size 0.508)
		(drill 0.254)
		(layers "F.Cu" "B.Cu")
		(net "P5V_NODE1")
	)
	(via
		(at 155.08478 -176.569624)
		(size 0.508)
		(drill 0.254)
		(layers "F.Cu" "B.Cu")
		(net "P5V_NODE1")
	)
	(via
		(at 175.12792 -49.43221)
		(size 0.508)
		(drill 0.254)
		(layers "F.Cu" "B.Cu")
		(net "P5V_NODE1")
	)
	(via
		(at 141.048232 -170.981624)
		(size 0.508)
		(drill 0.254)
		(layers "F.Cu" "B.Cu")
		(net "P5V_NODE1")
	)
	(via
		(at 94.22384 -5.226558)
		(size 0.508)
		(drill 0.254)
		(layers "F.Cu" "B.Cu")
		(net "P5V_NODE1")
	)
	(via
		(at 155.0797 -174.40656)
		(size 0.508)
		(drill 0.254)
		(layers "F.Cu" "B.Cu")
		(net "P5V_NODE1")
	)
	(via
		(at 126.959868 -180.487828)
		(size 0.508)
		(drill 0.254)
		(layers "F.Cu" "B.Cu")
		(net "P5V_NODE1")
	)
	(via
		(at 65.405 -14.253718)
		(size 0.508)
		(drill 0.254)
		(layers "F.Cu" "B.Cu")
		(net "P5V_NODE1")
	)
	(via
		(at 133.770878 -52.670202)
		(size 0.508)
		(drill 0.254)
		(layers "F.Cu" "B.Cu")
		(net "P5V_NODE1")
	)
	(via
		(at 62.624462 -161.717736)
		(size 0.508)
		(drill 0.254)
		(layers "F.Cu" "B.Cu")
		(net "P5V_NODE1")
	)
	(via
		(at 171.1198 -142.87881)
		(size 0.508)
		(drill 0.254)
		(layers "F.Cu" "B.Cu")
		(net "P5V_NODE1")
	)
	(via
		(at 77.718666 -175.553624)
		(size 0.508)
		(drill 0.254)
		(layers "F.Cu" "B.Cu")
		(net "P5V_NODE1")
	)
	(via
		(at 172.14342 -144.197324)
		(size 0.508)
		(drill 0.254)
		(layers "F.Cu" "B.Cu")
		(net "P5V_NODE1")
	)
	(via
		(at 64.592962 -161.732976)
		(size 0.508)
		(drill 0.254)
		(layers "F.Cu" "B.Cu")
		(net "P5V_NODE1")
	)
	(via
		(at 69.99224 -177.242216)
		(size 0.508)
		(drill 0.254)
		(layers "F.Cu" "B.Cu")
		(net "P5V_NODE1")
	)
	(via
		(at 65.154302 -163.193476)
		(size 0.508)
		(drill 0.254)
		(layers "F.Cu" "B.Cu")
		(net "P5V_NODE1")
	)
	(via
		(at 20.97024 -73.177146)
		(size 0.508)
		(drill 0.254)
		(layers "F.Cu" "B.Cu")
		(net "P5V_NODE1")
	)
	(via
		(at 150.758398 -40.899842)
		(size 0.508)
		(drill 0.254)
		(layers "F.Cu" "B.Cu")
		(net "P5V_NODE1")
	)
	(via
		(at 112.7379 -161.227516)
		(size 0.508)
		(drill 0.254)
		(layers "F.Cu" "B.Cu")
		(net "P5V_NODE1")
	)
	(via
		(at 189.16904 -26.342594)
		(size 0.508)
		(drill 0.254)
		(layers "F.Cu" "B.Cu")
		(net "P5V_NODE1")
	)
	(via
		(at 77.798676 -170.473624)
		(size 0.508)
		(drill 0.254)
		(layers "F.Cu" "B.Cu")
		(net "P5V_NODE1")
	)
	(via
		(at 141.048232 -171.997624)
		(size 0.508)
		(drill 0.254)
		(layers "F.Cu" "B.Cu")
		(net "P5V_NODE1")
	)
	(via
		(at 155.08478 -175.553624)
		(size 0.508)
		(drill 0.254)
		(layers "F.Cu" "B.Cu")
		(net "P5V_NODE1")
	)
	(via
		(at 141.038834 -176.061624)
		(size 0.508)
		(drill 0.254)
		(layers "F.Cu" "B.Cu")
		(net "P5V_NODE1")
	)
	(via
		(at 61.910722 -161.674556)
		(size 0.508)
		(drill 0.254)
		(layers "F.Cu" "B.Cu")
		(net "P5V_NODE1")
	)
	(via
		(at 144.699228 -49.580546)
		(size 0.508)
		(drill 0.254)
		(layers "F.Cu" "B.Cu")
		(net "P5V_NODE1")
	)
	(via
		(at 32.05988 -21.155914)
		(size 0.508)
		(drill 0.254)
		(layers "F.Cu" "B.Cu")
		(net "P5V_NODE1")
	)
	(via
		(at 175.12792 -48.550576)
		(size 0.508)
		(drill 0.254)
		(layers "F.Cu" "B.Cu")
		(net "P5V_NODE1")
	)
	(via
		(at 63.267082 -161.712656)
		(size 0.508)
		(drill 0.254)
		(layers "F.Cu" "B.Cu")
		(net "P5V_NODE1")
	)
	(via
		(at 141.1605 -53.855366)
		(size 0.508)
		(drill 0.254)
		(layers "F.Cu" "B.Cu")
		(net "P5V_NODE1")
	)
	(via
		(at 32.05988 -20.412456)
		(size 0.508)
		(drill 0.254)
		(layers "F.Cu" "B.Cu")
		(net "P5V_NODE1")
	)
	(via
		(at 64.712342 -163.683696)
		(size 0.508)
		(drill 0.254)
		(layers "F.Cu" "B.Cu")
		(net "P5V_NODE1")
	)
	(via
		(at 91.82354 -172.945044)
		(size 0.508)
		(drill 0.254)
		(layers "F.Cu" "B.Cu")
		(net "P5V_NODE1")
	)
	(via
		(at 189.17666 -27.162252)
		(size 0.508)
		(drill 0.254)
		(layers "F.Cu" "B.Cu")
		(net "P5V_NODE1")
	)
	(via
		(at 64.051942 -163.663376)
		(size 0.508)
		(drill 0.254)
		(layers "F.Cu" "B.Cu")
		(net "P5V_NODE1")
	)
	(via
		(at 176.15408 -47.339504)
		(size 0.508)
		(drill 0.254)
		(layers "F.Cu" "B.Cu")
		(net "P5V_NODE1")
	)
	(via
		(at 109.438948 -175.553624)
		(size 0.508)
		(drill 0.254)
		(layers "F.Cu" "B.Cu")
		(net "P5V_NODE1")
	)
	(via
		(at 141.02969 -173.013624)
		(size 0.508)
		(drill 0.254)
		(layers "F.Cu" "B.Cu")
		(net "P5V_NODE1")
	)
	(via
		(at 138.684 -45.72)
		(size 0.508)
		(drill 0.254)
		(layers "F.Cu" "B.Cu")
		(net "P5V_NODE1")
	)
	(via
		(at 173.26356 -48.568356)
		(size 0.508)
		(drill 0.254)
		(layers "F.Cu" "B.Cu")
		(net "P5V_NODE1")
	)
	(via
		(at 189.24778 -27.986482)
		(size 0.508)
		(drill 0.254)
		(layers "F.Cu" "B.Cu")
		(net "P5V_NODE1")
	)
	(via
		(at 65.558162 -13.636752)
		(size 0.508)
		(drill 0.254)
		(layers "F.Cu" "B.Cu")
		(net "P5V_NODE1")
	)
	(via
		(at 137.668508 -45.7454)
		(size 0.508)
		(drill 0.254)
		(layers "F.Cu" "B.Cu")
		(net "P5V_NODE1")
	)
	(via
		(at 129.038096 -155.853892)
		(size 0.508)
		(drill 0.254)
		(layers "F.Cu" "B.Cu")
		(net "P5V_NODE1")
	)
	(via
		(at 109.389418 -178.601624)
		(size 0.508)
		(drill 0.254)
		(layers "F.Cu" "B.Cu")
		(net "P5V_NODE1")
	)
	(via
		(at 172.1739 -142.87881)
		(size 0.508)
		(drill 0.254)
		(layers "F.Cu" "B.Cu")
		(net "P5V_NODE1")
	)
	(via
		(at 171.1833 -141.557756)
		(size 0.508)
		(drill 0.254)
		(layers "F.Cu" "B.Cu")
		(net "P5V_NODE1")
	)
	(via
		(at 141.182344 -45.531786)
		(size 0.508)
		(drill 0.254)
		(layers "F.Cu" "B.Cu")
		(net "P5V_NODE1")
	)
	(via
		(at 77.76083 -173.521624)
		(size 0.508)
		(drill 0.254)
		(layers "F.Cu" "B.Cu")
		(net "P5V_NODE1")
	)
	(via
		(at 63.957962 -161.722816)
		(size 0.508)
		(drill 0.254)
		(layers "F.Cu" "B.Cu")
		(net "P5V_NODE1")
	)
	(via
		(at 147.104354 -179.795678)
		(size 0.508)
		(drill 0.254)
		(layers "F.Cu" "B.Cu")
		(net "P5V_NODE1")
	)
	(via
		(at 92.35186 -178.390296)
		(size 0.508)
		(drill 0.254)
		(layers "F.Cu" "B.Cu")
		(net "P5V_NODE1")
	)
	(via
		(at 172.7454 -47.798228)
		(size 0.508)
		(drill 0.254)
		(layers "F.Cu" "B.Cu")
		(net "P5V_NODE1")
	)
	(via
		(at 24.63546 -56.652922)
		(size 0.508)
		(drill 0.254)
		(layers "F.Cu" "B.Cu")
		(net "P5V_NODE1")
	)
	(via
		(at 69.20484 -174.723806)
		(size 0.508)
		(drill 0.254)
		(layers "F.Cu" "B.Cu")
		(net "P5V_NODE1")
	)
	(via
		(at 143.748252 -24.59228)
		(size 0.508)
		(drill 0.254)
		(layers "F.Cu" "B.Cu")
		(net "P5V_NODE1")
	)
	(via
		(at 190.77432 -25.474422)
		(size 0.508)
		(drill 0.254)
		(layers "F.Cu" "B.Cu")
		(net "P5V_NODE1")
	)
	(via
		(at 134.435088 -45.290994)
		(size 0.508)
		(drill 0.254)
		(layers "F.Cu" "B.Cu")
		(net "P5V_NODE1")
	)
	(via
		(at 124.731018 -177.712624)
		(size 0.508)
		(drill 0.254)
		(layers "F.Cu" "B.Cu")
		(net "P5V_NODE1")
	)
	(via
		(at 126.860808 -181.503828)
		(size 0.508)
		(drill 0.254)
		(layers "F.Cu" "B.Cu")
		(net "P5V_NODE1")
	)
	(via
		(at 91.95816 -173.95825)
		(size 0.508)
		(drill 0.254)
		(layers "F.Cu" "B.Cu")
		(net "P5V_NODE1")
	)
	(via
		(at 70.88124 -176.099724)
		(size 0.508)
		(drill 0.254)
		(layers "F.Cu" "B.Cu")
		(net "P5V_NODE1")
	)
	(via
		(at 65.141602 -162.398456)
		(size 0.508)
		(drill 0.254)
		(layers "F.Cu" "B.Cu")
		(net "P5V_NODE1")
	)
	(via
		(at 139.05992 -24.544528)
		(size 0.508)
		(drill 0.254)
		(layers "F.Cu" "B.Cu")
		(net "P5V_NODE1")
	)
	(via
		(at 135.255 -52.451)
		(size 0.508)
		(drill 0.254)
		(layers "F.Cu" "B.Cu")
		(net "P5V_NODE1")
	)
	(via
		(at 141.708886 -52.714398)
		(size 0.508)
		(drill 0.254)
		(layers "F.Cu" "B.Cu")
		(net "P5V_NODE1")
	)
	(via
		(at 109.405674 -179.617624)
		(size 0.508)
		(drill 0.254)
		(layers "F.Cu" "B.Cu")
		(net "P5V_NODE1")
	)
	(via
		(at 150.600918 -43.664124)
		(size 0.508)
		(drill 0.254)
		(layers "F.Cu" "B.Cu")
		(net "P5V_NODE1")
	)
	(via
		(at 77.798676 -172.505624)
		(size 0.508)
		(drill 0.254)
		(layers "F.Cu" "B.Cu")
		(net "P5V_NODE1")
	)
	(via
		(at 124.756418 -174.626778)
		(size 0.508)
		(drill 0.254)
		(layers "F.Cu" "B.Cu")
		(net "P5V_NODE1")
	)
	(via
		(at 149.390354 -179.795678)
		(size 0.508)
		(drill 0.254)
		(layers "F.Cu" "B.Cu")
		(net "P5V_NODE1")
	)
	(via
		(at 148.361654 -179.804822)
		(size 0.508)
		(drill 0.254)
		(layers "F.Cu" "B.Cu")
		(net "P5V_NODE1")
	)
	(via
		(at 109.426502 -174.537624)
		(size 0.508)
		(drill 0.254)
		(layers "F.Cu" "B.Cu")
		(net "P5V_NODE1")
	)
	(segment
		(start 141.67231 -174.029624)
		(end 141.042136 -174.029624)
		(width 0.508)
		(layer "B.Cu")
		(net "P5V_NODE1")
	)
	(segment
		(start 109.407452 -180.633624)
		(end 110.04931 -180.633624)
		(width 0.508)
		(layer "B.Cu")
		(net "P5V_NODE1")
	)
	(segment
		(start 134.431024 -46.56455)
		(end 134.435088 -46.560486)
		(width 0.508)
		(layer "B.Cu")
		(net "P5V_NODE1")
	)
	(segment
		(start 148.361654 -179.298854)
		(end 148.361654 -179.804822)
		(width 0.508)
		(layer "B.Cu")
		(net "P5V_NODE1")
	)
	(segment
		(start 110.04931 -180.633624)
		(end 110.04931 -181.649624)
		(width 0.508)
		(layer "B.Cu")
		(net "P5V_NODE1")
	)
	(segment
		(start 78.43139 -177.585624)
		(end 78.43139 -176.569624)
		(width 0.508)
		(layer "B.Cu")
		(net "P5V_NODE1")
	)
	(segment
		(start 110.04931 -179.617624)
		(end 109.405674 -179.617624)
		(width 0.508)
		(layer "B.Cu")
		(net "P5V_NODE1")
	)
	(segment
		(start 141.67231 -177.077624)
		(end 141.0081 -177.077624)
		(width 0.508)
		(layer "B.Cu")
		(net "P5V_NODE1")
	)
	(segment
		(start 124.477018 -177.458624)
		(end 124.731018 -177.712624)
		(width 0.508)
		(layer "B.Cu")
		(net "P5V_NODE1")
	)
	(segment
		(start 141.189202 -46.487842)
		(end 141.168628 -46.467268)
		(width 0.508)
		(layer "B.Cu")
		(net "P5V_NODE1")
	)
	(segment
		(start 124.540264 -174.410624)
		(end 124.756418 -174.626778)
		(width 0.508)
		(layer "B.Cu")
		(net "P5V_NODE1")
	)
	(segment
		(start 154.46121 -174.537624)
		(end 154.95016 -174.537624)
		(width 0.508)
		(layer "B.Cu")
		(net "P5V_NODE1")
	)
	(segment
		(start 141.67231 -175.045624)
		(end 141.060678 -175.045624)
		(width 0.508)
		(layer "B.Cu")
		(net "P5V_NODE1")
	)
	(segment
		(start 130.715258 -155.597098)
		(end 130.458464 -155.853892)
		(width 0.508)
		(layer "B.Cu")
		(net "P5V_NODE1")
	)
	(segment
		(start 110.04931 -177.585624)
		(end 109.376972 -177.585624)
		(width 0.508)
		(layer "B.Cu")
		(net "P5V_NODE1")
	)
	(segment
		(start 154.948382 -173.521624)
		(end 155.14574 -173.718982)
		(width 0.508)
		(layer "B.Cu")
		(net "P5V_NODE1")
	)
	(segment
		(start 78.43139 -170.473624)
		(end 77.798676 -170.473624)
		(width 0.508)
		(layer "B.Cu")
		(net "P5V_NODE1")
	)
	(segment
		(start 124.10821 -176.442624)
		(end 124.81052 -176.442624)
		(width 0.508)
		(layer "B.Cu")
		(net "P5V_NODE1")
	)
	(segment
		(start 110.04931 -178.601624)
		(end 109.389418 -178.601624)
		(width 0.508)
		(layer "B.Cu")
		(net "P5V_NODE1")
	)
	(segment
		(start 130.2004 -46.09465)
		(end 130.2004 -45.4406)
		(width 0.508)
		(layer "B.Cu")
		(net "P5V_NODE1")
	)
	(segment
		(start 124.10821 -177.458624)
		(end 124.477018 -177.458624)
		(width 0.508)
		(layer "B.Cu")
		(net "P5V_NODE1")
	)
	(segment
		(start 148.247354 -179.184554)
		(end 148.361654 -179.298854)
		(width 0.508)
		(layer "B.Cu")
		(net "P5V_NODE1")
	)
	(segment
		(start 110.04931 -175.553624)
		(end 109.438948 -175.553624)
		(width 0.508)
		(layer "B.Cu")
		(net "P5V_NODE1")
	)
	(segment
		(start 78.43139 -171.489624)
		(end 77.798676 -171.489624)
		(width 0.508)
		(layer "B.Cu")
		(net "P5V_NODE1")
	)
	(segment
		(start 128.9558 -51.2572)
		(end 129.4892 -51.2572)
		(width 0.508)
		(layer "B.Cu")
		(net "P5V_NODE1")
	)
	(segment
		(start 132.165344 -155.597098)
		(end 130.715258 -155.597098)
		(width 0.508)
		(layer "B.Cu")
		(net "P5V_NODE1")
	)
	(segment
		(start 133.4516 -46.56455)
		(end 134.431024 -46.56455)
		(width 0.508)
		(layer "B.Cu")
		(net "P5V_NODE1")
	)
	(segment
		(start 141.67231 -171.997624)
		(end 141.048232 -171.997624)
		(width 0.508)
		(layer "B.Cu")
		(net "P5V_NODE1")
	)
	(segment
		(start 134.068312 -156.308298)
		(end 132.876544 -156.308298)
		(width 0.508)
		(layer "B.Cu")
		(net "P5V_NODE1")
	)
	(segment
		(start 154.95016 -174.537624)
		(end 155.0797 -174.408084)
		(width 0.508)
		(layer "B.Cu")
		(net "P5V_NODE1")
	)
	(segment
		(start 154.46121 -172.505624)
		(end 154.46121 -173.521624)
		(width 0.508)
		(layer "B.Cu")
		(net "P5V_NODE1")
	)
	(segment
		(start 77.718666 -175.553624)
		(end 78.43139 -175.553624)
		(width 0.508)
		(layer "B.Cu")
		(net "P5V_NODE1")
	)
	(segment
		(start 154.46121 -176.569624)
		(end 155.08478 -176.569624)
		(width 0.508)
		(layer "B.Cu")
		(net "P5V_NODE1")
	)
	(segment
		(start 130.48615 -46.3804)
		(end 130.2004 -46.09465)
		(width 0.508)
		(layer "B.Cu")
		(net "P5V_NODE1")
	)
	(segment
		(start 110.04931 -176.569624)
		(end 109.426502 -176.569624)
		(width 0.508)
		(layer "B.Cu")
		(net "P5V_NODE1")
	)
	(segment
		(start 78.43139 -173.521624)
		(end 77.76083 -173.521624)
		(width 0.508)
		(layer "B.Cu")
		(net "P5V_NODE1")
	)
	(segment
		(start 130.458464 -155.853892)
		(end 129.038096 -155.853892)
		(width 0.508)
		(layer "B.Cu")
		(net "P5V_NODE1")
	)
	(segment
		(start 78.43139 -172.505624)
		(end 77.798676 -172.505624)
		(width 0.508)
		(layer "B.Cu")
		(net "P5V_NODE1")
	)
	(segment
		(start 154.46121 -175.553624)
		(end 155.08478 -175.553624)
		(width 0.508)
		(layer "B.Cu")
		(net "P5V_NODE1")
	)
	(segment
		(start 141.67231 -173.013624)
		(end 141.02969 -173.013624)
		(width 0.508)
		(layer "B.Cu")
		(net "P5V_NODE1")
	)
	(segment
		(start 137.668508 -46.552104)
		(end 137.668508 -45.7454)
		(width 0.508)
		(layer "B.Cu")
		(net "P5V_NODE1")
	)
	(segment
		(start 141.67231 -176.061624)
		(end 141.038834 -176.061624)
		(width 0.508)
		(layer "B.Cu")
		(net "P5V_NODE1")
	)
	(segment
		(start 134.435088 -46.560486)
		(end 134.435088 -45.290994)
		(width 0.508)
		(layer "B.Cu")
		(net "P5V_NODE1")
	)
	(segment
		(start 124.10821 -174.410624)
		(end 124.540264 -174.410624)
		(width 0.508)
		(layer "B.Cu")
		(net "P5V_NODE1")
	)
	(segment
		(start 154.46121 -173.521624)
		(end 154.948382 -173.521624)
		(width 0.508)
		(layer "B.Cu")
		(net "P5V_NODE1")
	)
	(segment
		(start 141.67231 -170.981624)
		(end 141.048232 -170.981624)
		(width 0.508)
		(layer "B.Cu")
		(net "P5V_NODE1")
	)
	(segment
		(start 78.43139 -175.553624)
		(end 78.43139 -176.569624)
		(width 0.508)
		(layer "B.Cu")
		(net "P5V_NODE1")
	)
	(segment
		(start 110.04931 -174.537624)
		(end 109.426502 -174.537624)
		(width 0.508)
		(layer "B.Cu")
		(net "P5V_NODE1")
	)
	(segment
		(start 147.104354 -179.184554)
		(end 147.104354 -179.795678)
		(width 0.508)
		(layer "B.Cu")
		(net "P5V_NODE1")
	)
	(segment
		(start 141.168628 -46.467268)
		(end 141.168628 -45.545502)
		(width 0.508)
		(layer "B.Cu")
		(net "P5V_NODE1")
	)
	(segment
		(start 141.67231 -178.093624)
		(end 141.67231 -177.077624)
		(width 0.508)
		(layer "B.Cu")
		(net "P5V_NODE1")
	)
	(segment
		(start 129.4892 -51.2572)
		(end 130.0988 -51.8668)
		(width 0.508)
		(layer "B.Cu")
		(net "P5V_NODE1")
	)
	(segment
		(start 138.684 -46.552104)
		(end 138.684 -45.72)
		(width 0.508)
		(layer "B.Cu")
		(net "P5V_NODE1")
	)
	(segment
		(start 149.390354 -179.184554)
		(end 149.390354 -179.795678)
		(width 0.508)
		(layer "B.Cu")
		(net "P5V_NODE1")
	)
	(segment
		(start 78.43139 -174.537624)
		(end 77.718666 -174.537624)
		(width 0.508)
		(layer "B.Cu")
		(net "P5V_NODE1")
	)
	(segment
		(start 132.876544 -156.308298)
		(end 132.165344 -155.597098)
		(width 0.508)
		(layer "B.Cu")
		(net "P5V_NODE1")
	)
	(segment
		(start 141.168628 -45.545502)
		(end 141.182344 -45.531786)
		(width 0.508)
		(layer "B.Cu")
		(net "P5V_NODE1")
	)
	(segment
		(start 124.10821 -174.410624)
		(end 124.10821 -175.426624)
		(width 0.508)
		(layer "B.Cu")
		(net "P5V_NODE1")
	)
	(segment
		(start 155.0797 -174.408084)
		(end 155.0797 -174.40656)
		(width 0.508)
		(layer "B.Cu")
		(net "P5V_NODE1")
	)
	(segment
		(start 52.503578 -17.236948)
		(end 55.477664 -14.262862)
		(width 1.016)
		(layer "In2.Cu")
		(net "P5V_NODE1")
	)
	(segment
		(start 55.477664 -14.262862)
		(end 61.64072 -14.262862)
		(width 1.016)
		(layer "In2.Cu")
		(net "P5V_NODE1")
	)
	(segment
		(start 33.222438 -21.155914)
		(end 37.141404 -17.236948)
		(width 1.016)
		(layer "In2.Cu")
		(net "P5V_NODE1")
	)
	(segment
		(start 37.141404 -17.236948)
		(end 52.503578 -17.236948)
		(width 1.016)
		(layer "In2.Cu")
		(net "P5V_NODE1")
	)
	(segment
		(start 110.076742 -174.135288)
		(end 109.704886 -174.507144)
		(width 0.508)
		(layer "In6.Cu")
		(net "P5V_NODE1")
	)
	(segment
		(start 112.613186 -161.227516)
		(end 111.687102 -162.1536)
		(width 0.508)
		(layer "In6.Cu")
		(net "P5V_NODE1")
	)
	(segment
		(start 109.89056 -166.111174)
		(end 109.89056 -172.05706)
		(width 0.508)
		(layer "In6.Cu")
		(net "P5V_NODE1")
	)
	(segment
		(start 108.50626 -163.531296)
		(end 108.50626 -164.726874)
		(width 0.508)
		(layer "In6.Cu")
		(net "P5V_NODE1")
	)
	(segment
		(start 109.89056 -172.05706)
		(end 110.076742 -172.243242)
		(width 0.508)
		(layer "In6.Cu")
		(net "P5V_NODE1")
	)
	(segment
		(start 109.456982 -174.507144)
		(end 109.426502 -174.537624)
		(width 0.508)
		(layer "In6.Cu")
		(net "P5V_NODE1")
	)
	(segment
		(start 109.704886 -174.507144)
		(end 109.456982 -174.507144)
		(width 0.508)
		(layer "In6.Cu")
		(net "P5V_NODE1")
	)
	(segment
		(start 110.076742 -172.243242)
		(end 110.076742 -174.135288)
		(width 0.508)
		(layer "In6.Cu")
		(net "P5V_NODE1")
	)
	(segment
		(start 111.687102 -162.1536)
		(end 109.883956 -162.1536)
		(width 0.508)
		(layer "In6.Cu")
		(net "P5V_NODE1")
	)
	(segment
		(start 112.7379 -161.227516)
		(end 112.613186 -161.227516)
		(width 0.508)
		(layer "In6.Cu")
		(net "P5V_NODE1")
	)
	(segment
		(start 108.50626 -164.726874)
		(end 109.89056 -166.111174)
		(width 0.508)
		(layer "In6.Cu")
		(net "P5V_NODE1")
	)
	(segment
		(start 109.883956 -162.1536)
		(end 108.50626 -163.531296)
		(width 0.508)
		(layer "In6.Cu")
		(net "P5V_NODE1")
	)
	(segment
		(start 129.038096 -155.853892)
		(end 129.7686 -156.584396)
		(width 0.508)
		(layer "In7.Cu")
		(net "P5V_NODE1")
	)
	(segment
		(start 129.396744 -157.556962)
		(end 125.91669 -157.556962)
		(width 0.508)
		(layer "In7.Cu")
		(net "P5V_NODE1")
	)
	(segment
		(start 129.7686 -156.584396)
		(end 129.7686 -157.185106)
		(width 0.508)
		(layer "In7.Cu")
		(net "P5V_NODE1")
	)
	(segment
		(start 125.91669 -157.556962)
		(end 123.001532 -160.47212)
		(width 0.508)
		(layer "In7.Cu")
		(net "P5V_NODE1")
	)
	(segment
		(start 117.605556 -160.369758)
		(end 116.747798 -161.227516)
		(width 0.508)
		(layer "In7.Cu")
		(net "P5V_NODE1")
	)
	(segment
		(start 116.747798 -161.227516)
		(end 112.7379 -161.227516)
		(width 0.508)
		(layer "In7.Cu")
		(net "P5V_NODE1")
	)
	(segment
		(start 118.13286 -160.369758)
		(end 117.605556 -160.369758)
		(width 0.508)
		(layer "In7.Cu")
		(net "P5V_NODE1")
	)
	(segment
		(start 123.001532 -160.47212)
		(end 118.235222 -160.47212)
		(width 0.508)
		(layer "In7.Cu")
		(net "P5V_NODE1")
	)
	(segment
		(start 118.235222 -160.47212)
		(end 118.13286 -160.369758)
		(width 0.508)
		(layer "In7.Cu")
		(net "P5V_NODE1")
	)
	(segment
		(start 129.7686 -157.185106)
		(end 129.396744 -157.556962)
		(width 0.508)
		(layer "In7.Cu")
		(net "P5V_NODE1")
	)
	(segment
		(start 65.249044 -75.569318)
		(end 65.249044 -75.559412)
		(width 0.1143)
		(layer "F.Cu")
		(net "PD_CPU_NODE1_PUNIT_ST_ADDR1")
	)
	(segment
		(start 65.249044 -75.559412)
		(end 65.62852 -75.179936)
		(width 0.1143)
		(layer "F.Cu")
		(net "PD_CPU_NODE1_PUNIT_ST_ADDR1")
	)
	(via
		(at 87.17788 -71.225664)
		(size 0.6604)
		(drill 0.3302)
		(layers "F.Cu" "B.Cu")
		(net "PD_CPU_NODE1_PUNIT_ST_ADDR1")
	)
	(via
		(at 65.62852 -75.179936)
		(size 0.508)
		(drill 0.254)
		(layers "F.Cu" "B.Cu")
		(net "PD_CPU_NODE1_PUNIT_ST_ADDR1")
	)
	(segment
		(start 86.397338 -72.006206)
		(end 87.17788 -71.225664)
		(width 0.1016)
		(layer "B.Cu")
		(net "PD_CPU_NODE1_PUNIT_ST_ADDR1")
	)
	(segment
		(start 79.104998 -72.006206)
		(end 86.397338 -72.006206)
		(width 0.1016)
		(layer "B.Cu")
		(net "PD_CPU_NODE1_PUNIT_ST_ADDR1")
	)
	(segment
		(start 91.018106 -71.145654)
		(end 89.1794 -71.145654)
		(width 0.1016)
		(layer "B.Cu")
		(net "PD_CPU_NODE1_PUNIT_ST_ADDR1")
	)
	(segment
		(start 68.476368 -73.538334)
		(end 69.298566 -74.360532)
		(width 0.1016)
		(layer "B.Cu")
		(net "PD_CPU_NODE1_PUNIT_ST_ADDR1")
	)
	(segment
		(start 66.524378 -73.927716)
		(end 67.757294 -73.927716)
		(width 0.1016)
		(layer "B.Cu")
		(net "PD_CPU_NODE1_PUNIT_ST_ADDR1")
	)
	(segment
		(start 88.571324 -70.537578)
		(end 87.865966 -70.537578)
		(width 0.1016)
		(layer "B.Cu")
		(net "PD_CPU_NODE1_PUNIT_ST_ADDR1")
	)
	(segment
		(start 87.865966 -70.537578)
		(end 87.17788 -71.225664)
		(width 0.1016)
		(layer "B.Cu")
		(net "PD_CPU_NODE1_PUNIT_ST_ADDR1")
	)
	(segment
		(start 67.757294 -73.927716)
		(end 68.146676 -73.538334)
		(width 0.1016)
		(layer "B.Cu")
		(net "PD_CPU_NODE1_PUNIT_ST_ADDR1")
	)
	(segment
		(start 77.43444 -73.676764)
		(end 79.104998 -72.006206)
		(width 0.1016)
		(layer "B.Cu")
		(net "PD_CPU_NODE1_PUNIT_ST_ADDR1")
	)
	(segment
		(start 69.298566 -74.360532)
		(end 73.889108 -74.360532)
		(width 0.1016)
		(layer "B.Cu")
		(net "PD_CPU_NODE1_PUNIT_ST_ADDR1")
	)
	(segment
		(start 91.07297 -71.200518)
		(end 91.018106 -71.145654)
		(width 0.1016)
		(layer "B.Cu")
		(net "PD_CPU_NODE1_PUNIT_ST_ADDR1")
	)
	(segment
		(start 68.146676 -73.538334)
		(end 68.476368 -73.538334)
		(width 0.1016)
		(layer "B.Cu")
		(net "PD_CPU_NODE1_PUNIT_ST_ADDR1")
	)
	(segment
		(start 74.572876 -73.676764)
		(end 77.43444 -73.676764)
		(width 0.1016)
		(layer "B.Cu")
		(net "PD_CPU_NODE1_PUNIT_ST_ADDR1")
	)
	(segment
		(start 89.1794 -71.145654)
		(end 88.571324 -70.537578)
		(width 0.1016)
		(layer "B.Cu")
		(net "PD_CPU_NODE1_PUNIT_ST_ADDR1")
	)
	(segment
		(start 73.889108 -74.360532)
		(end 74.572876 -73.676764)
		(width 0.1016)
		(layer "B.Cu")
		(net "PD_CPU_NODE1_PUNIT_ST_ADDR1")
	)
	(segment
		(start 65.62852 -74.823574)
		(end 66.524378 -73.927716)
		(width 0.1016)
		(layer "B.Cu")
		(net "PD_CPU_NODE1_PUNIT_ST_ADDR1")
	)
	(segment
		(start 65.62852 -75.179936)
		(end 65.62852 -74.823574)
		(width 0.1016)
		(layer "B.Cu")
		(net "PD_CPU_NODE1_PUNIT_ST_ADDR1")
	)
	(segment
		(start 40.17391 -6.190488)
		(end 40.17391 -5.4102)
		(width 0.1016)
		(layer "F.Cu")
		(net "FM_CPLD_NODE1_PVDDR_STB_EN")
	)
	(segment
		(start 39.619428 -4.036314)
		(end 40.053514 -4.4704)
		(width 0.1016)
		(layer "F.Cu")
		(net "FM_CPLD_NODE1_PVDDR_STB_EN")
	)
	(segment
		(start 40.053514 -4.4704)
		(end 40.177974 -4.4704)
		(width 0.1016)
		(layer "F.Cu")
		(net "FM_CPLD_NODE1_PVDDR_STB_EN")
	)
	(segment
		(start 171.97578 -112.98555)
		(end 171.97578 -112.98428)
		(width 0.1016)
		(layer "F.Cu")
		(net "FM_CPLD_NODE1_PVDDR_STB_EN")
	)
	(segment
		(start 39.099998 -3.086354)
		(end 39.619428 -3.605784)
		(width 0.1016)
		(layer "F.Cu")
		(net "FM_CPLD_NODE1_PVDDR_STB_EN")
	)
	(segment
		(start 172.43044 -113.44021)
		(end 171.97578 -112.98555)
		(width 0.1016)
		(layer "F.Cu")
		(net "FM_CPLD_NODE1_PVDDR_STB_EN")
	)
	(segment
		(start 173.797214 -113.44021)
		(end 172.43044 -113.44021)
		(width 0.1016)
		(layer "F.Cu")
		(net "FM_CPLD_NODE1_PVDDR_STB_EN")
	)
	(segment
		(start 40.177974 -5.406136)
		(end 40.17391 -5.4102)
		(width 0.1016)
		(layer "F.Cu")
		(net "FM_CPLD_NODE1_PVDDR_STB_EN")
	)
	(segment
		(start 39.619428 -3.605784)
		(end 39.619428 -4.036314)
		(width 0.1016)
		(layer "F.Cu")
		(net "FM_CPLD_NODE1_PVDDR_STB_EN")
	)
	(segment
		(start 175.010318 -114.653314)
		(end 173.797214 -113.44021)
		(width 0.1016)
		(layer "F.Cu")
		(net "FM_CPLD_NODE1_PVDDR_STB_EN")
	)
	(segment
		(start 40.177974 -4.4704)
		(end 40.177974 -5.406136)
		(width 0.1016)
		(layer "F.Cu")
		(net "FM_CPLD_NODE1_PVDDR_STB_EN")
	)
	(segment
		(start 175.010318 -116.365528)
		(end 175.010318 -114.653314)
		(width 0.1016)
		(layer "F.Cu")
		(net "FM_CPLD_NODE1_PVDDR_STB_EN")
	)
	(via
		(at 40.17391 -5.4102)
		(size 0.508)
		(drill 0.254)
		(layers "F.Cu" "B.Cu")
		(net "FM_CPLD_NODE1_PVDDR_STB_EN")
	)
	(via
		(at 42.68216 -15.611348)
		(size 0.508)
		(drill 0.254)
		(layers "F.Cu" "B.Cu")
		(net "FM_CPLD_NODE1_PVDDR_STB_EN")
	)
	(via
		(at 171.97578 -112.98428)
		(size 0.508)
		(drill 0.254)
		(layers "F.Cu" "B.Cu")
		(net "FM_CPLD_NODE1_PVDDR_STB_EN")
	)
	(segment
		(start 41.421558 -16.87195)
		(end 34.081212 -16.87195)
		(width 0.1016)
		(layer "B.Cu")
		(net "FM_CPLD_NODE1_PVDDR_STB_EN")
	)
	(segment
		(start 32.26054 -15.051278)
		(end 32.26054 -8.82396)
		(width 0.1016)
		(layer "B.Cu")
		(net "FM_CPLD_NODE1_PVDDR_STB_EN")
	)
	(segment
		(start 32.26054 -8.82396)
		(end 34.141918 -6.942582)
		(width 0.1016)
		(layer "B.Cu")
		(net "FM_CPLD_NODE1_PVDDR_STB_EN")
	)
	(segment
		(start 37.178742 -6.398006)
		(end 39.186104 -6.398006)
		(width 0.1016)
		(layer "B.Cu")
		(net "FM_CPLD_NODE1_PVDDR_STB_EN")
	)
	(segment
		(start 36.634166 -6.942582)
		(end 37.178742 -6.398006)
		(width 0.1016)
		(layer "B.Cu")
		(net "FM_CPLD_NODE1_PVDDR_STB_EN")
	)
	(segment
		(start 39.186104 -6.398006)
		(end 40.17391 -5.4102)
		(width 0.1016)
		(layer "B.Cu")
		(net "FM_CPLD_NODE1_PVDDR_STB_EN")
	)
	(segment
		(start 34.141918 -6.942582)
		(end 36.634166 -6.942582)
		(width 0.1016)
		(layer "B.Cu")
		(net "FM_CPLD_NODE1_PVDDR_STB_EN")
	)
	(segment
		(start 42.68216 -15.611348)
		(end 41.421558 -16.87195)
		(width 0.1016)
		(layer "B.Cu")
		(net "FM_CPLD_NODE1_PVDDR_STB_EN")
	)
	(segment
		(start 34.081212 -16.87195)
		(end 32.26054 -15.051278)
		(width 0.1016)
		(layer "B.Cu")
		(net "FM_CPLD_NODE1_PVDDR_STB_EN")
	)
	(segment
		(start 42.68216 -15.611348)
		(end 42.976038 -15.905226)
		(width 0.1143)
		(layer "In6.Cu")
		(net "FM_CPLD_NODE1_PVDDR_STB_EN")
	)
	(segment
		(start 160.87598 -47.756826)
		(end 163.606226 -50.487072)
		(width 0.1143)
		(layer "In6.Cu")
		(net "FM_CPLD_NODE1_PVDDR_STB_EN")
	)
	(segment
		(start 160.87598 -20.74418)
		(end 160.87598 -47.756826)
		(width 0.1143)
		(layer "In6.Cu")
		(net "FM_CPLD_NODE1_PVDDR_STB_EN")
	)
	(segment
		(start 117.097048 -15.14729)
		(end 119.678958 -17.7292)
		(width 0.1143)
		(layer "In6.Cu")
		(net "FM_CPLD_NODE1_PVDDR_STB_EN")
	)
	(segment
		(start 64.289178 -15.606268)
		(end 87.82939 -15.606268)
		(width 0.1143)
		(layer "In6.Cu")
		(net "FM_CPLD_NODE1_PVDDR_STB_EN")
	)
	(segment
		(start 178.95443 -82.43443)
		(end 178.95443 -106.00563)
		(width 0.1143)
		(layer "In6.Cu")
		(net "FM_CPLD_NODE1_PVDDR_STB_EN")
	)
	(segment
		(start 97.08642 -15.929864)
		(end 97.16262 -15.853664)
		(width 0.1143)
		(layer "In6.Cu")
		(net "FM_CPLD_NODE1_PVDDR_STB_EN")
	)
	(segment
		(start 92.571316 -16.060166)
		(end 92.82049 -15.810992)
		(width 0.1143)
		(layer "In6.Cu")
		(net "FM_CPLD_NODE1_PVDDR_STB_EN")
	)
	(segment
		(start 163.606226 -50.487072)
		(end 163.606226 -67.086226)
		(width 0.1143)
		(layer "In6.Cu")
		(net "FM_CPLD_NODE1_PVDDR_STB_EN")
	)
	(segment
		(start 133.636004 -17.7292)
		(end 135.007604 -16.3576)
		(width 0.1143)
		(layer "In6.Cu")
		(net "FM_CPLD_NODE1_PVDDR_STB_EN")
	)
	(segment
		(start 178.95443 -106.00563)
		(end 171.97578 -112.98428)
		(width 0.1143)
		(layer "In6.Cu")
		(net "FM_CPLD_NODE1_PVDDR_STB_EN")
	)
	(segment
		(start 92.82049 -15.810992)
		(end 95.06712 -15.810992)
		(width 0.1143)
		(layer "In6.Cu")
		(net "FM_CPLD_NODE1_PVDDR_STB_EN")
	)
	(segment
		(start 63.99022 -15.905226)
		(end 64.289178 -15.606268)
		(width 0.1143)
		(layer "In6.Cu")
		(net "FM_CPLD_NODE1_PVDDR_STB_EN")
	)
	(segment
		(start 135.007604 -16.3576)
		(end 156.4894 -16.3576)
		(width 0.1143)
		(layer "In6.Cu")
		(net "FM_CPLD_NODE1_PVDDR_STB_EN")
	)
	(segment
		(start 99.611942 -15.853664)
		(end 100.318316 -15.14729)
		(width 0.1143)
		(layer "In6.Cu")
		(net "FM_CPLD_NODE1_PVDDR_STB_EN")
	)
	(segment
		(start 87.82939 -15.606268)
		(end 88.283288 -16.060166)
		(width 0.1143)
		(layer "In6.Cu")
		(net "FM_CPLD_NODE1_PVDDR_STB_EN")
	)
	(segment
		(start 156.4894 -16.3576)
		(end 160.87598 -20.74418)
		(width 0.1143)
		(layer "In6.Cu")
		(net "FM_CPLD_NODE1_PVDDR_STB_EN")
	)
	(segment
		(start 163.606226 -67.086226)
		(end 178.95443 -82.43443)
		(width 0.1143)
		(layer "In6.Cu")
		(net "FM_CPLD_NODE1_PVDDR_STB_EN")
	)
	(segment
		(start 88.283288 -16.060166)
		(end 92.571316 -16.060166)
		(width 0.1143)
		(layer "In6.Cu")
		(net "FM_CPLD_NODE1_PVDDR_STB_EN")
	)
	(segment
		(start 97.16262 -15.853664)
		(end 99.611942 -15.853664)
		(width 0.1143)
		(layer "In6.Cu")
		(net "FM_CPLD_NODE1_PVDDR_STB_EN")
	)
	(segment
		(start 95.06712 -15.810992)
		(end 95.185992 -15.929864)
		(width 0.1143)
		(layer "In6.Cu")
		(net "FM_CPLD_NODE1_PVDDR_STB_EN")
	)
	(segment
		(start 42.976038 -15.905226)
		(end 63.99022 -15.905226)
		(width 0.1143)
		(layer "In6.Cu")
		(net "FM_CPLD_NODE1_PVDDR_STB_EN")
	)
	(segment
		(start 100.318316 -15.14729)
		(end 117.097048 -15.14729)
		(width 0.1143)
		(layer "In6.Cu")
		(net "FM_CPLD_NODE1_PVDDR_STB_EN")
	)
	(segment
		(start 95.185992 -15.929864)
		(end 97.08642 -15.929864)
		(width 0.1143)
		(layer "In6.Cu")
		(net "FM_CPLD_NODE1_PVDDR_STB_EN")
	)
	(segment
		(start 119.678958 -17.7292)
		(end 133.636004 -17.7292)
		(width 0.1143)
		(layer "In6.Cu")
		(net "FM_CPLD_NODE1_PVDDR_STB_EN")
	)
	(segment
		(start 73.343262 -91.300808)
		(end 74.575924 -92.53347)
		(width 0.1016)
		(layer "F.Cu")
		(net "PD_CPU_NODE1_NODE_ID")
	)
	(segment
		(start 76.490068 -93.731842)
		(end 75.474068 -93.731842)
		(width 0.1016)
		(layer "F.Cu")
		(net "PD_CPU_NODE1_NODE_ID")
	)
	(segment
		(start 69.021452 -89.720166)
		(end 70.602094 -91.300808)
		(width 0.1016)
		(layer "F.Cu")
		(net "PD_CPU_NODE1_NODE_ID")
	)
	(segment
		(start 68.722748 -87.762588)
		(end 69.021452 -88.061292)
		(width 0.1016)
		(layer "F.Cu")
		(net "PD_CPU_NODE1_NODE_ID")
	)
	(segment
		(start 69.021452 -88.061292)
		(end 69.021452 -89.720166)
		(width 0.1016)
		(layer "F.Cu")
		(net "PD_CPU_NODE1_NODE_ID")
	)
	(segment
		(start 75.474068 -93.731842)
		(end 75.474068 -93.431614)
		(width 0.1016)
		(layer "F.Cu")
		(net "PD_CPU_NODE1_NODE_ID")
	)
	(segment
		(start 68.722748 -87.700358)
		(end 68.722748 -87.762588)
		(width 0.1016)
		(layer "F.Cu")
		(net "PD_CPU_NODE1_NODE_ID")
	)
	(segment
		(start 70.602094 -91.300808)
		(end 73.343262 -91.300808)
		(width 0.1016)
		(layer "F.Cu")
		(net "PD_CPU_NODE1_NODE_ID")
	)
	(segment
		(start 75.474068 -93.431614)
		(end 74.575924 -92.53347)
		(width 0.1016)
		(layer "F.Cu")
		(net "PD_CPU_NODE1_NODE_ID")
	)
	(via
		(at 74.575924 -92.53347)
		(size 0.762)
		(drill 0.381)
		(layers "F.Cu" "B.Cu")
		(net "PD_CPU_NODE1_NODE_ID")
	)
	(segment
		(start 161.979356 -102.135686)
		(end 161.782252 -102.33279)
		(width 0.1778)
		(layer "F.Cu")
		(net "P3V3_USB_NODE1")
	)
	(segment
		(start 163.340034 -102.135686)
		(end 161.979356 -102.135686)
		(width 0.1778)
		(layer "F.Cu")
		(net "P3V3_USB_NODE1")
	)
	(segment
		(start 169.643298 -96.219264)
		(end 169.98061 -95.881952)
		(width 0.1778)
		(layer "F.Cu")
		(net "P3V3_USB_NODE1")
	)
	(segment
		(start 169.643298 -97.032572)
		(end 169.643298 -96.219264)
		(width 0.1778)
		(layer "F.Cu")
		(net "P3V3_USB_NODE1")
	)
	(via
		(at 161.782252 -102.33279)
		(size 0.508)
		(drill 0.254)
		(layers "F.Cu" "B.Cu")
		(net "P3V3_USB_NODE1")
	)
	(via
		(at 169.98061 -95.881952)
		(size 0.508)
		(drill 0.254)
		(layers "F.Cu" "B.Cu")
		(net "P3V3_USB_NODE1")
	)
	(segment
		(start 51.999896 -73.399142)
		(end 51.599846 -73.799192)
		(width 0.3048)
		(layer "F.Cu")
		(net "P1V5_NODE1_AM21")
	)
	(via
		(at 50.156872 -73.455022)
		(size 0.6604)
		(drill 0.3302)
		(layers "F.Cu" "B.Cu")
		(net "P1V5_NODE1_AM21")
	)
	(via
		(at 51.599846 -73.799192)
		(size 0.508)
		(drill 0.254)
		(layers "F.Cu" "B.Cu")
		(net "P1V5_NODE1_AM21")
	)
	(segment
		(start 50.456592 -73.155302)
		(end 50.156872 -73.455022)
		(width 0.508)
		(layer "B.Cu")
		(net "P1V5_NODE1_AM21")
	)
	(segment
		(start 50.457862 -72.338184)
		(end 50.456592 -72.338184)
		(width 0.508)
		(layer "B.Cu")
		(net "P1V5_NODE1_AM21")
	)
	(segment
		(start 50.456592 -72.338184)
		(end 50.456592 -73.155302)
		(width 0.508)
		(layer "B.Cu")
		(net "P1V5_NODE1_AM21")
	)
	(segment
		(start 50.501042 -73.799192)
		(end 51.599846 -73.799192)
		(width 0.381)
		(layer "B.Cu")
		(net "P1V5_NODE1_AM21")
	)
	(segment
		(start 50.156872 -73.455022)
		(end 50.501042 -73.799192)
		(width 0.381)
		(layer "B.Cu")
		(net "P1V5_NODE1_AM21")
	)
	(segment
		(start 113.198402 -25.394412)
		(end 113.71961 -24.873204)
		(width 0.254)
		(layer "F.Cu")
		(net "PV_VTT_DDR_NODE1_VOSNS")
	)
	(segment
		(start 114.382804 -24.21001)
		(end 113.71961 -24.873204)
		(width 0.254)
		(layer "F.Cu")
		(net "PV_VTT_DDR_NODE1_VOSNS")
	)
	(segment
		(start 114.382804 -23.855426)
		(end 114.382804 -24.21001)
		(width 0.254)
		(layer "F.Cu")
		(net "PV_VTT_DDR_NODE1_VOSNS")
	)
	(segment
		(start 113.198402 -25.82672)
		(end 113.198402 -25.394412)
		(width 0.254)
		(layer "F.Cu")
		(net "PV_VTT_DDR_NODE1_VOSNS")
	)
	(via
		(at 113.71961 -24.873204)
		(size 0.508)
		(drill 0.254)
		(layers "F.Cu" "B.Cu")
		(net "PV_VTT_DDR_NODE1_VOSNS")
	)
	(via
		(at 181.03596 -150.647654)
		(size 0.508)
		(drill 0.254)
		(layers "F.Cu" "B.Cu")
		(net "LAN2_CTRL_P1V9_R")
	)
	(segment
		(start 51.384962 -75.980544)
		(end 51.44135 -76.036932)
		(width 0.381)
		(layer "F.Cu")
		(net "P1V5_NODE1_AJ21")
	)
	(segment
		(start 37.107622 -74.418698)
		(end 38.029134 -74.418698)
		(width 0.508)
		(layer "F.Cu")
		(net "P1V5_NODE1_AJ21")
	)
	(segment
		(start 51.384962 -75.343512)
		(end 51.384962 -75.980544)
		(width 0.381)
		(layer "F.Cu")
		(net "P1V5_NODE1_AJ21")
	)
	(segment
		(start 51.729132 -74.999342)
		(end 51.384962 -75.343512)
		(width 0.381)
		(layer "F.Cu")
		(net "P1V5_NODE1_AJ21")
	)
	(segment
		(start 51.999896 -74.999342)
		(end 51.729132 -74.999342)
		(width 0.381)
		(layer "F.Cu")
		(net "P1V5_NODE1_AJ21")
	)
	(via
		(at 38.029134 -74.418698)
		(size 0.508)
		(drill 0.254)
		(layers "F.Cu" "B.Cu")
		(net "P1V5_NODE1_AJ21")
	)
	(via
		(at 51.44135 -76.036932)
		(size 0.508)
		(drill 0.254)
		(layers "F.Cu" "B.Cu")
		(net "P1V5_NODE1_AJ21")
	)
	(segment
		(start 50.780188 -74.592688)
		(end 50.780188 -75.687174)
		(width 0.508)
		(layer "In2.Cu")
		(net "P1V5_NODE1_AJ21")
	)
	(segment
		(start 50.202846 -74.015346)
		(end 50.780188 -74.592688)
		(width 0.508)
		(layer "In2.Cu")
		(net "P1V5_NODE1_AJ21")
	)
	(segment
		(start 38.029134 -74.418698)
		(end 38.899592 -75.289156)
		(width 0.381)
		(layer "In2.Cu")
		(net "P1V5_NODE1_AJ21")
	)
	(segment
		(start 44.399962 -74.08545)
		(end 44.678346 -73.807066)
		(width 0.381)
		(layer "In2.Cu")
		(net "P1V5_NODE1_AJ21")
	)
	(segment
		(start 47.194978 -73.807066)
		(end 47.403258 -74.015346)
		(width 0.508)
		(layer "In2.Cu")
		(net "P1V5_NODE1_AJ21")
	)
	(segment
		(start 42.177462 -75.289156)
		(end 43.381168 -74.08545)
		(width 0.381)
		(layer "In2.Cu")
		(net "P1V5_NODE1_AJ21")
	)
	(segment
		(start 45.26915 -73.807066)
		(end 47.194978 -73.807066)
		(width 0.508)
		(layer "In2.Cu")
		(net "P1V5_NODE1_AJ21")
	)
	(segment
		(start 43.381168 -74.08545)
		(end 44.399962 -74.08545)
		(width 0.381)
		(layer "In2.Cu")
		(net "P1V5_NODE1_AJ21")
	)
	(segment
		(start 38.899592 -75.289156)
		(end 42.177462 -75.289156)
		(width 0.381)
		(layer "In2.Cu")
		(net "P1V5_NODE1_AJ21")
	)
	(segment
		(start 51.129946 -76.036932)
		(end 51.44135 -76.036932)
		(width 0.508)
		(layer "In2.Cu")
		(net "P1V5_NODE1_AJ21")
	)
	(segment
		(start 50.780188 -75.687174)
		(end 51.129946 -76.036932)
		(width 0.508)
		(layer "In2.Cu")
		(net "P1V5_NODE1_AJ21")
	)
	(segment
		(start 44.678346 -73.807066)
		(end 45.26915 -73.807066)
		(width 0.381)
		(layer "In2.Cu")
		(net "P1V5_NODE1_AJ21")
	)
	(segment
		(start 47.403258 -74.015346)
		(end 50.202846 -74.015346)
		(width 0.508)
		(layer "In2.Cu")
		(net "P1V5_NODE1_AJ21")
	)
	(via
		(at 113.51768 -19.902932)
		(size 0.508)
		(drill 0.254)
		(layers "F.Cu" "B.Cu")
		(net "PV_VTT_DDR_NODE1_REFOUT")
	)
	(segment
		(start 51.99888 -78.999842)
		(end 51.604164 -79.394558)
		(width 0.3048)
		(layer "F.Cu")
		(net "P1V5_NODE1_AA21")
	)
	(segment
		(start 51.999896 -78.999842)
		(end 51.99888 -78.999842)
		(width 0.3048)
		(layer "F.Cu")
		(net "P1V5_NODE1_AA21")
	)
	(via
		(at 51.604164 -79.394558)
		(size 0.508)
		(drill 0.254)
		(layers "F.Cu" "B.Cu")
		(net "P1V5_NODE1_AA21")
	)
	(via
		(at 48.401478 -82.728054)
		(size 0.508)
		(drill 0.254)
		(layers "F.Cu" "B.Cu")
		(net "P1V5_NODE1_AA21")
	)
	(segment
		(start 48.401478 -83.132422)
		(end 48.401478 -82.728054)
		(width 0.381)
		(layer "B.Cu")
		(net "P1V5_NODE1_AA21")
	)
	(segment
		(start 49.346612 -84.077556)
		(end 48.401478 -83.132422)
		(width 0.381)
		(layer "B.Cu")
		(net "P1V5_NODE1_AA21")
	)
	(segment
		(start 49.873916 -84.077556)
		(end 49.346612 -84.077556)
		(width 0.381)
		(layer "B.Cu")
		(net "P1V5_NODE1_AA21")
	)
	(segment
		(start 49.580038 -81.258918)
		(end 48.401478 -82.437478)
		(width 0.508)
		(layer "In6.Cu")
		(net "P1V5_NODE1_AA21")
	)
	(segment
		(start 50.164492 -81.258918)
		(end 49.580038 -81.258918)
		(width 0.508)
		(layer "In6.Cu")
		(net "P1V5_NODE1_AA21")
	)
	(segment
		(start 51.59883 -79.399892)
		(end 51.33721 -79.399892)
		(width 0.508)
		(layer "In6.Cu")
		(net "P1V5_NODE1_AA21")
	)
	(segment
		(start 48.401478 -82.437478)
		(end 48.401478 -82.728054)
		(width 0.508)
		(layer "In6.Cu")
		(net "P1V5_NODE1_AA21")
	)
	(segment
		(start 50.84064 -79.896462)
		(end 50.84064 -80.58277)
		(width 0.508)
		(layer "In6.Cu")
		(net "P1V5_NODE1_AA21")
	)
	(segment
		(start 50.84064 -80.58277)
		(end 50.164492 -81.258918)
		(width 0.508)
		(layer "In6.Cu")
		(net "P1V5_NODE1_AA21")
	)
	(segment
		(start 51.33721 -79.399892)
		(end 50.84064 -79.896462)
		(width 0.508)
		(layer "In6.Cu")
		(net "P1V5_NODE1_AA21")
	)
	(segment
		(start 51.604164 -79.394558)
		(end 51.59883 -79.399892)
		(width 0.508)
		(layer "In6.Cu")
		(net "P1V5_NODE1_AA21")
	)
	(segment
		(start 131.45262 -131.58724)
		(end 131.45262 -130.12674)
		(width 0.127)
		(layer "F.Cu")
		(net "P2E_CPU_USB_NODE1_RX_DP")
	)
	(segment
		(start 130.137916 -135.825484)
		(end 130.137916 -134.69366)
		(width 0.127)
		(layer "F.Cu")
		(net "P2E_CPU_USB_NODE1_RX_DP")
	)
	(segment
		(start 156.83103 -101.765608)
		(end 156.074618 -101.765608)
		(width 0.127)
		(layer "F.Cu")
		(net "P2E_CPU_USB_NODE1_RX_DP")
	)
	(segment
		(start 130.137916 -134.69366)
		(end 130.1115 -134.667244)
		(width 0.127)
		(layer "F.Cu")
		(net "P2E_CPU_USB_NODE1_RX_DP")
	)
	(segment
		(start 131.581906 -129.997454)
		(end 131.93522 -129.997454)
		(width 0.127)
		(layer "F.Cu")
		(net "P2E_CPU_USB_NODE1_RX_DP")
	)
	(segment
		(start 157.18663 -102.121208)
		(end 156.83103 -101.765608)
		(width 0.127)
		(layer "F.Cu")
		(net "P2E_CPU_USB_NODE1_RX_DP")
	)
	(segment
		(start 130.1115 -132.92836)
		(end 131.45262 -131.58724)
		(width 0.127)
		(layer "F.Cu")
		(net "P2E_CPU_USB_NODE1_RX_DP")
	)
	(segment
		(start 156.074618 -101.765608)
		(end 155.610814 -102.229412)
		(width 0.127)
		(layer "F.Cu")
		(net "P2E_CPU_USB_NODE1_RX_DP")
	)
	(segment
		(start 130.1115 -134.667244)
		(end 130.1115 -132.92836)
		(width 0.127)
		(layer "F.Cu")
		(net "P2E_CPU_USB_NODE1_RX_DP")
	)
	(segment
		(start 131.45262 -130.12674)
		(end 131.581906 -129.997454)
		(width 0.127)
		(layer "F.Cu")
		(net "P2E_CPU_USB_NODE1_RX_DP")
	)
	(via
		(at 131.93522 -129.997454)
		(size 0.508)
		(drill 0.254)
		(layers "F.Cu" "B.Cu")
		(net "P2E_CPU_USB_NODE1_RX_DP")
	)
	(via
		(at 155.610814 -102.229412)
		(size 0.508)
		(drill 0.254)
		(layers "F.Cu" "B.Cu")
		(net "P2E_CPU_USB_NODE1_RX_DP")
	)
	(segment
		(start 138.315446 -128.433068)
		(end 139.293854 -128.433068)
		(width 0.127)
		(layer "B.Cu")
		(net "P2E_CPU_USB_NODE1_RX_DP")
	)
	(segment
		(start 137.157206 -128.565402)
		(end 137.289286 -128.433068)
		(width 0.127)
		(layer "B.Cu")
		(net "P2E_CPU_USB_NODE1_RX_DP")
	)
	(segment
		(start 137.670286 -128.433068)
		(end 137.802366 -128.565402)
		(width 0.127)
		(layer "B.Cu")
		(net "P2E_CPU_USB_NODE1_RX_DP")
	)
	(segment
		(start 136.131046 -128.565402)
		(end 136.263126 -128.433068)
		(width 0.127)
		(layer "B.Cu")
		(net "P2E_CPU_USB_NODE1_RX_DP")
	)
	(segment
		(start 135.150098 -128.433068)
		(end 135.617966 -128.433068)
		(width 0.127)
		(layer "B.Cu")
		(net "P2E_CPU_USB_NODE1_RX_DP")
	)
	(segment
		(start 136.644126 -128.433068)
		(end 136.776206 -128.565402)
		(width 0.127)
		(layer "B.Cu")
		(net "P2E_CPU_USB_NODE1_RX_DP")
	)
	(segment
		(start 131.65201 -129.997454)
		(end 131.45262 -129.798064)
		(width 0.127)
		(layer "B.Cu")
		(net "P2E_CPU_USB_NODE1_RX_DP")
	)
	(segment
		(start 137.802366 -128.565402)
		(end 138.183366 -128.565402)
		(width 0.127)
		(layer "B.Cu")
		(net "P2E_CPU_USB_NODE1_RX_DP")
	)
	(segment
		(start 131.86537 -128.819148)
		(end 132.984494 -128.819148)
		(width 0.127)
		(layer "B.Cu")
		(net "P2E_CPU_USB_NODE1_RX_DP")
	)
	(segment
		(start 131.45262 -129.798064)
		(end 131.45262 -129.231898)
		(width 0.127)
		(layer "B.Cu")
		(net "P2E_CPU_USB_NODE1_RX_DP")
	)
	(segment
		(start 148.974556 -121.661682)
		(end 151.29002 -116.13134)
		(width 0.127)
		(layer "B.Cu")
		(net "P2E_CPU_USB_NODE1_RX_DP")
	)
	(segment
		(start 153.936954 -101.746812)
		(end 155.128214 -101.746812)
		(width 0.127)
		(layer "B.Cu")
		(net "P2E_CPU_USB_NODE1_RX_DP")
	)
	(segment
		(start 135.750046 -128.565402)
		(end 136.131046 -128.565402)
		(width 0.127)
		(layer "B.Cu")
		(net "P2E_CPU_USB_NODE1_RX_DP")
	)
	(segment
		(start 135.617966 -128.433068)
		(end 135.750046 -128.565402)
		(width 0.127)
		(layer "B.Cu")
		(net "P2E_CPU_USB_NODE1_RX_DP")
	)
	(segment
		(start 142.210282 -125.51664)
		(end 145.119598 -125.51664)
		(width 0.127)
		(layer "B.Cu")
		(net "P2E_CPU_USB_NODE1_RX_DP")
	)
	(segment
		(start 131.93522 -129.997454)
		(end 131.65201 -129.997454)
		(width 0.127)
		(layer "B.Cu")
		(net "P2E_CPU_USB_NODE1_RX_DP")
	)
	(segment
		(start 155.128214 -101.746812)
		(end 155.610814 -102.229412)
		(width 0.127)
		(layer "B.Cu")
		(net "P2E_CPU_USB_NODE1_RX_DP")
	)
	(segment
		(start 139.293854 -128.433068)
		(end 142.210282 -125.51664)
		(width 0.127)
		(layer "B.Cu")
		(net "P2E_CPU_USB_NODE1_RX_DP")
	)
	(segment
		(start 136.263126 -128.433068)
		(end 136.644126 -128.433068)
		(width 0.127)
		(layer "B.Cu")
		(net "P2E_CPU_USB_NODE1_RX_DP")
	)
	(segment
		(start 151.29002 -116.13134)
		(end 151.29002 -107.912408)
		(width 0.127)
		(layer "B.Cu")
		(net "P2E_CPU_USB_NODE1_RX_DP")
	)
	(segment
		(start 138.183366 -128.565402)
		(end 138.315446 -128.433068)
		(width 0.127)
		(layer "B.Cu")
		(net "P2E_CPU_USB_NODE1_RX_DP")
	)
	(segment
		(start 133.636766 -128.819148)
		(end 134.764018 -128.819148)
		(width 0.127)
		(layer "B.Cu")
		(net "P2E_CPU_USB_NODE1_RX_DP")
	)
	(segment
		(start 134.764018 -128.819148)
		(end 135.150098 -128.433068)
		(width 0.127)
		(layer "B.Cu")
		(net "P2E_CPU_USB_NODE1_RX_DP")
	)
	(segment
		(start 137.289286 -128.433068)
		(end 137.670286 -128.433068)
		(width 0.127)
		(layer "B.Cu")
		(net "P2E_CPU_USB_NODE1_RX_DP")
	)
	(segment
		(start 136.776206 -128.565402)
		(end 137.157206 -128.565402)
		(width 0.127)
		(layer "B.Cu")
		(net "P2E_CPU_USB_NODE1_RX_DP")
	)
	(segment
		(start 151.29002 -107.912408)
		(end 151.969978 -103.713788)
		(width 0.127)
		(layer "B.Cu")
		(net "P2E_CPU_USB_NODE1_RX_DP")
	)
	(segment
		(start 131.45262 -129.231898)
		(end 131.86537 -128.819148)
		(width 0.127)
		(layer "B.Cu")
		(net "P2E_CPU_USB_NODE1_RX_DP")
	)
	(segment
		(start 145.119598 -125.51664)
		(end 148.974556 -121.661682)
		(width 0.127)
		(layer "B.Cu")
		(net "P2E_CPU_USB_NODE1_RX_DP")
	)
	(segment
		(start 133.12013 -128.954784)
		(end 133.50113 -128.954784)
		(width 0.127)
		(layer "B.Cu")
		(net "P2E_CPU_USB_NODE1_RX_DP")
	)
	(segment
		(start 151.969978 -103.713788)
		(end 153.936954 -101.746812)
		(width 0.127)
		(layer "B.Cu")
		(net "P2E_CPU_USB_NODE1_RX_DP")
	)
	(segment
		(start 133.50113 -128.954784)
		(end 133.636766 -128.819148)
		(width 0.127)
		(layer "B.Cu")
		(net "P2E_CPU_USB_NODE1_RX_DP")
	)
	(segment
		(start 132.984494 -128.819148)
		(end 133.12013 -128.954784)
		(width 0.127)
		(layer "B.Cu")
		(net "P2E_CPU_USB_NODE1_RX_DP")
	)
	(segment
		(start 103.923846 -18.954242)
		(end 104.321102 -19.351498)
		(width 0.508)
		(layer "F.Cu")
		(net "PV_VTT_DDR_NODE1")
	)
	(segment
		(start 103.923846 -18.264124)
		(end 103.923846 -18.954242)
		(width 0.508)
		(layer "F.Cu")
		(net "PV_VTT_DDR_NODE1")
	)
	(segment
		(start 103.650288 -29.149802)
		(end 103.650288 -27.723084)
		(width 0.381)
		(layer "F.Cu")
		(net "PV_VTT_DDR_NODE1")
	)
	(segment
		(start 103.923846 -18.264124)
		(end 103.350314 -18.837656)
		(width 0.381)
		(layer "F.Cu")
		(net "PV_VTT_DDR_NODE1")
	)
	(segment
		(start 103.350314 -18.837656)
		(end 103.350314 -20.94992)
		(width 0.381)
		(layer "F.Cu")
		(net "PV_VTT_DDR_NODE1")
	)
	(segment
		(start 115.30076 -25.040844)
		(end 115.382802 -24.958802)
		(width 0.254)
		(layer "F.Cu")
		(net "PV_VTT_DDR_NODE1")
	)
	(segment
		(start 115.382802 -24.958802)
		(end 115.382802 -23.855426)
		(width 0.254)
		(layer "F.Cu")
		(net "PV_VTT_DDR_NODE1")
	)
	(via
		(at 103.650288 -27.723084)
		(size 0.508)
		(drill 0.254)
		(layers "F.Cu" "B.Cu")
		(net "PV_VTT_DDR_NODE1")
	)
	(via
		(at 115.30076 -25.040844)
		(size 0.508)
		(drill 0.254)
		(layers "F.Cu" "B.Cu")
		(net "PV_VTT_DDR_NODE1")
	)
	(via
		(at 114.182652 -26.706576)
		(size 0.508)
		(drill 0.254)
		(layers "F.Cu" "B.Cu")
		(net "PV_VTT_DDR_NODE1")
	)
	(via
		(at 104.321102 -19.351498)
		(size 0.508)
		(drill 0.254)
		(layers "F.Cu" "B.Cu")
		(net "PV_VTT_DDR_NODE1")
	)
	(via
		(at 115.104672 -26.706576)
		(size 0.508)
		(drill 0.254)
		(layers "F.Cu" "B.Cu")
		(net "PV_VTT_DDR_NODE1")
	)
	(segment
		(start 52.799996 -75.798172)
		(end 52.405026 -75.403202)
		(width 0.1016)
		(layer "F.Cu")
		(net "TP_P1V8_VCCABGTS_NODE1")
	)
	(segment
		(start 52.799996 -75.799442)
		(end 52.799996 -75.798172)
		(width 0.1016)
		(layer "F.Cu")
		(net "TP_P1V8_VCCABGTS_NODE1")
	)
	(via
		(at 48.843692 -72.690482)
		(size 0.508)
		(drill 0.254)
		(layers "F.Cu" "B.Cu")
		(net "TP_P1V8_VCCABGTS_NODE1")
	)
	(via
		(at 52.405026 -75.403202)
		(size 0.508)
		(drill 0.254)
		(layers "F.Cu" "B.Cu")
		(net "TP_P1V8_VCCABGTS_NODE1")
	)
	(segment
		(start 48.843692 -72.690482)
		(end 48.843692 -72.692514)
		(width 0.1143)
		(layer "In2.Cu")
		(net "TP_P1V8_VCCABGTS_NODE1")
	)
	(segment
		(start 49.364392 -73.213214)
		(end 50.586132 -73.213214)
		(width 0.1143)
		(layer "In2.Cu")
		(net "TP_P1V8_VCCABGTS_NODE1")
	)
	(segment
		(start 48.843692 -72.692514)
		(end 49.364392 -73.213214)
		(width 0.1143)
		(layer "In2.Cu")
		(net "TP_P1V8_VCCABGTS_NODE1")
	)
	(segment
		(start 52.405026 -75.310746)
		(end 52.405026 -75.403202)
		(width 0.1143)
		(layer "In2.Cu")
		(net "TP_P1V8_VCCABGTS_NODE1")
	)
	(segment
		(start 51.093116 -73.720198)
		(end 51.093116 -73.998836)
		(width 0.1143)
		(layer "In2.Cu")
		(net "TP_P1V8_VCCABGTS_NODE1")
	)
	(segment
		(start 51.093116 -73.998836)
		(end 52.405026 -75.310746)
		(width 0.1143)
		(layer "In2.Cu")
		(net "TP_P1V8_VCCABGTS_NODE1")
	)
	(segment
		(start 50.586132 -73.213214)
		(end 51.093116 -73.720198)
		(width 0.1143)
		(layer "In2.Cu")
		(net "TP_P1V8_VCCABGTS_NODE1")
	)
	(segment
		(start 115.463828 -18.73504)
		(end 115.92814 -18.270728)
		(width 0.1016)
		(layer "F.Cu")
		(net "PWRGD_NODE1_PVTT_DDR_PG")
	)
	(segment
		(start 115.882928 -20.755102)
		(end 115.882928 -19.411696)
		(width 0.1016)
		(layer "F.Cu")
		(net "PWRGD_NODE1_PVTT_DDR_PG")
	)
	(segment
		(start 127.51181 -14.64818)
		(end 127.7366 -14.64818)
		(width 0.1016)
		(layer "F.Cu")
		(net "PWRGD_NODE1_PVTT_DDR_PG")
	)
	(segment
		(start 115.882928 -19.411696)
		(end 115.463828 -18.992596)
		(width 0.1016)
		(layer "F.Cu")
		(net "PWRGD_NODE1_PVTT_DDR_PG")
	)
	(segment
		(start 181.01056 -123.365768)
		(end 182.874666 -123.365768)
		(width 0.1016)
		(layer "F.Cu")
		(net "PWRGD_NODE1_PVTT_DDR_PG")
	)
	(segment
		(start 115.463828 -18.992596)
		(end 115.463828 -18.73504)
		(width 0.1016)
		(layer "F.Cu")
		(net "PWRGD_NODE1_PVTT_DDR_PG")
	)
	(segment
		(start 115.92814 -18.270728)
		(end 123.889262 -18.270728)
		(width 0.1016)
		(layer "F.Cu")
		(net "PWRGD_NODE1_PVTT_DDR_PG")
	)
	(segment
		(start 123.889262 -18.270728)
		(end 127.51181 -14.64818)
		(width 0.1016)
		(layer "F.Cu")
		(net "PWRGD_NODE1_PVTT_DDR_PG")
	)
	(segment
		(start 182.874666 -123.365768)
		(end 183.20766 -123.032774)
		(width 0.1016)
		(layer "F.Cu")
		(net "PWRGD_NODE1_PVTT_DDR_PG")
	)
	(via
		(at 183.20766 -123.032774)
		(size 0.508)
		(drill 0.254)
		(layers "F.Cu" "B.Cu")
		(net "PWRGD_NODE1_PVTT_DDR_PG")
	)
	(via
		(at 127.7366 -14.64818)
		(size 0.508)
		(drill 0.254)
		(layers "F.Cu" "B.Cu")
		(net "PWRGD_NODE1_PVTT_DDR_PG")
	)
	(segment
		(start 184.434988 -123.032774)
		(end 188.754004 -118.713758)
		(width 0.1143)
		(layer "In6.Cu")
		(net "PWRGD_NODE1_PVTT_DDR_PG")
	)
	(segment
		(start 163.3601 -20.7137)
		(end 156.9974 -14.351)
		(width 0.1143)
		(layer "In6.Cu")
		(net "PWRGD_NODE1_PVTT_DDR_PG")
	)
	(segment
		(start 163.3601 -47.45863)
		(end 163.3601 -20.7137)
		(width 0.1143)
		(layer "In6.Cu")
		(net "PWRGD_NODE1_PVTT_DDR_PG")
	)
	(segment
		(start 165.35908 -66.27368)
		(end 165.35908 -49.45761)
		(width 0.1143)
		(layer "In6.Cu")
		(net "PWRGD_NODE1_PVTT_DDR_PG")
	)
	(segment
		(start 127.7366 -14.6304)
		(end 127.7366 -14.64818)
		(width 0.1143)
		(layer "In6.Cu")
		(net "PWRGD_NODE1_PVTT_DDR_PG")
	)
	(segment
		(start 156.9974 -14.351)
		(end 128.016 -14.351)
		(width 0.1143)
		(layer "In6.Cu")
		(net "PWRGD_NODE1_PVTT_DDR_PG")
	)
	(segment
		(start 128.016 -14.351)
		(end 127.7366 -14.6304)
		(width 0.1143)
		(layer "In6.Cu")
		(net "PWRGD_NODE1_PVTT_DDR_PG")
	)
	(segment
		(start 183.20766 -123.032774)
		(end 184.434988 -123.032774)
		(width 0.1143)
		(layer "In6.Cu")
		(net "PWRGD_NODE1_PVTT_DDR_PG")
	)
	(segment
		(start 188.754004 -118.713758)
		(end 188.754004 -89.668604)
		(width 0.1143)
		(layer "In6.Cu")
		(net "PWRGD_NODE1_PVTT_DDR_PG")
	)
	(segment
		(start 165.35908 -49.45761)
		(end 163.3601 -47.45863)
		(width 0.1143)
		(layer "In6.Cu")
		(net "PWRGD_NODE1_PVTT_DDR_PG")
	)
	(segment
		(start 188.754004 -89.668604)
		(end 165.35908 -66.27368)
		(width 0.1143)
		(layer "In6.Cu")
		(net "PWRGD_NODE1_PVTT_DDR_PG")
	)
	(segment
		(start 62.401196 -78.199742)
		(end 62.801246 -77.799692)
		(width 0.1143)
		(layer "F.Cu")
		(net "TP_CPU_NODE1_VCCCPU0VIDSI0GT1_1")
	)
	(via
		(at 62.801246 -77.799692)
		(size 0.508)
		(drill 0.254)
		(layers "F.Cu" "B.Cu")
		(net "TP_CPU_NODE1_VCCCPU0VIDSI0GT1_1")
	)
	(via
		(at 63.619126 -77.672692)
		(size 0.6604)
		(drill 0.3302)
		(layers "F.Cu" "B.Cu")
		(net "TP_CPU_NODE1_VCCCPU0VIDSI0GT1_1")
	)
	(segment
		(start 63.492126 -77.799692)
		(end 63.619126 -77.672692)
		(width 0.1016)
		(layer "B.Cu")
		(net "TP_CPU_NODE1_VCCCPU0VIDSI0GT1_1")
	)
	(segment
		(start 62.801246 -77.799692)
		(end 63.492126 -77.799692)
		(width 0.1016)
		(layer "B.Cu")
		(net "TP_CPU_NODE1_VCCCPU0VIDSI0GT1_1")
	)
	(segment
		(start 115.42268 -18.059908)
		(end 115.42268 -17.577308)
		(width 0.1016)
		(layer "F.Cu")
		(net "FM_CPLD_NODE1_PVTT_DDR_EN")
	)
	(segment
		(start 114.473228 -19.00936)
		(end 114.473228 -19.480022)
		(width 0.1016)
		(layer "F.Cu")
		(net "FM_CPLD_NODE1_PVTT_DDR_EN")
	)
	(segment
		(start 115.425982 -17.575022)
		(end 115.79352 -17.20723)
		(width 0.1016)
		(layer "F.Cu")
		(net "FM_CPLD_NODE1_PVTT_DDR_EN")
	)
	(segment
		(start 173.703742 -112.987328)
		(end 173.422056 -112.987328)
		(width 0.1016)
		(layer "F.Cu")
		(net "FM_CPLD_NODE1_PVTT_DDR_EN")
	)
	(segment
		(start 176.01057 -117.365526)
		(end 175.470312 -116.825268)
		(width 0.1016)
		(layer "F.Cu")
		(net "FM_CPLD_NODE1_PVTT_DDR_EN")
	)
	(segment
		(start 115.42268 -17.577308)
		(end 115.424712 -17.575276)
		(width 0.1016)
		(layer "F.Cu")
		(net "FM_CPLD_NODE1_PVTT_DDR_EN")
	)
	(segment
		(start 114.473228 -19.480022)
		(end 114.882676 -19.88947)
		(width 0.1016)
		(layer "F.Cu")
		(net "FM_CPLD_NODE1_PVTT_DDR_EN")
	)
	(segment
		(start 118.739666 -16.429736)
		(end 119.60098 -17.29105)
		(width 0.1016)
		(layer "F.Cu")
		(net "FM_CPLD_NODE1_PVTT_DDR_EN")
	)
	(segment
		(start 114.882676 -19.88947)
		(end 114.882676 -20.755102)
		(width 0.1016)
		(layer "F.Cu")
		(net "FM_CPLD_NODE1_PVTT_DDR_EN")
	)
	(segment
		(start 115.425982 -17.575276)
		(end 115.425982 -17.575022)
		(width 0.1016)
		(layer "F.Cu")
		(net "FM_CPLD_NODE1_PVTT_DDR_EN")
	)
	(segment
		(start 115.424712 -17.575276)
		(end 115.425982 -17.575276)
		(width 0.1016)
		(layer "F.Cu")
		(net "FM_CPLD_NODE1_PVTT_DDR_EN")
	)
	(segment
		(start 119.60098 -17.29105)
		(end 123.70562 -17.29105)
		(width 0.1016)
		(layer "F.Cu")
		(net "FM_CPLD_NODE1_PVTT_DDR_EN")
	)
	(segment
		(start 175.470312 -114.753898)
		(end 173.703742 -112.987328)
		(width 0.1016)
		(layer "F.Cu")
		(net "FM_CPLD_NODE1_PVTT_DDR_EN")
	)
	(segment
		(start 175.470312 -116.825268)
		(end 175.470312 -114.753898)
		(width 0.1016)
		(layer "F.Cu")
		(net "FM_CPLD_NODE1_PVTT_DDR_EN")
	)
	(segment
		(start 115.79352 -17.20723)
		(end 115.79352 -16.683228)
		(width 0.1016)
		(layer "F.Cu")
		(net "FM_CPLD_NODE1_PVTT_DDR_EN")
	)
	(segment
		(start 116.047012 -16.429736)
		(end 118.739666 -16.429736)
		(width 0.1016)
		(layer "F.Cu")
		(net "FM_CPLD_NODE1_PVTT_DDR_EN")
	)
	(segment
		(start 114.473228 -19.00936)
		(end 115.42268 -18.059908)
		(width 0.1016)
		(layer "F.Cu")
		(net "FM_CPLD_NODE1_PVTT_DDR_EN")
	)
	(segment
		(start 115.79352 -16.683228)
		(end 116.047012 -16.429736)
		(width 0.1016)
		(layer "F.Cu")
		(net "FM_CPLD_NODE1_PVTT_DDR_EN")
	)
	(via
		(at 173.422056 -112.987328)
		(size 0.508)
		(drill 0.254)
		(layers "F.Cu" "B.Cu")
		(net "FM_CPLD_NODE1_PVTT_DDR_EN")
	)
	(via
		(at 123.70562 -17.29105)
		(size 0.508)
		(drill 0.254)
		(layers "F.Cu" "B.Cu")
		(net "FM_CPLD_NODE1_PVTT_DDR_EN")
	)
	(segment
		(start 133.687566 -17.29105)
		(end 134.900416 -16.0782)
		(width 0.1143)
		(layer "In6.Cu")
		(net "FM_CPLD_NODE1_PVTT_DDR_EN")
	)
	(segment
		(start 134.900416 -16.0782)
		(end 156.591 -16.0782)
		(width 0.1143)
		(layer "In6.Cu")
		(net "FM_CPLD_NODE1_PVTT_DDR_EN")
	)
	(segment
		(start 161.14268 -47.469298)
		(end 163.872926 -50.199544)
		(width 0.1143)
		(layer "In6.Cu")
		(net "FM_CPLD_NODE1_PVTT_DDR_EN")
	)
	(segment
		(start 163.872926 -50.199544)
		(end 163.872926 -66.971926)
		(width 0.1143)
		(layer "In6.Cu")
		(net "FM_CPLD_NODE1_PVTT_DDR_EN")
	)
	(segment
		(start 161.14268 -20.62988)
		(end 161.14268 -47.469298)
		(width 0.1143)
		(layer "In6.Cu")
		(net "FM_CPLD_NODE1_PVTT_DDR_EN")
	)
	(segment
		(start 156.591 -16.0782)
		(end 161.14268 -20.62988)
		(width 0.1143)
		(layer "In6.Cu")
		(net "FM_CPLD_NODE1_PVTT_DDR_EN")
	)
	(segment
		(start 179.22113 -82.32013)
		(end 179.22113 -107.188254)
		(width 0.1143)
		(layer "In6.Cu")
		(net "FM_CPLD_NODE1_PVTT_DDR_EN")
	)
	(segment
		(start 123.70562 -17.29105)
		(end 133.687566 -17.29105)
		(width 0.1143)
		(layer "In6.Cu")
		(net "FM_CPLD_NODE1_PVTT_DDR_EN")
	)
	(segment
		(start 163.872926 -66.971926)
		(end 179.22113 -82.32013)
		(width 0.1143)
		(layer "In6.Cu")
		(net "FM_CPLD_NODE1_PVTT_DDR_EN")
	)
	(segment
		(start 179.22113 -107.188254)
		(end 173.422056 -112.987328)
		(width 0.1143)
		(layer "In6.Cu")
		(net "FM_CPLD_NODE1_PVTT_DDR_EN")
	)
	(segment
		(start 131.14782 -130.191002)
		(end 130.954272 -129.997454)
		(width 0.127)
		(layer "F.Cu")
		(net "P2E_CPU_USB_NODE1_RX_DN")
	)
	(segment
		(start 156.83103 -101.460808)
		(end 156.11221 -101.460808)
		(width 0.127)
		(layer "F.Cu")
		(net "P2E_CPU_USB_NODE1_RX_DN")
	)
	(segment
		(start 129.737866 -135.825484)
		(end 129.737866 -134.69366)
		(width 0.127)
		(layer "F.Cu")
		(net "P2E_CPU_USB_NODE1_RX_DN")
	)
	(segment
		(start 130.954272 -129.997454)
		(end 130.66522 -129.997454)
		(width 0.127)
		(layer "F.Cu")
		(net "P2E_CPU_USB_NODE1_RX_DN")
	)
	(segment
		(start 129.8067 -132.801868)
		(end 131.14782 -131.460748)
		(width 0.127)
		(layer "F.Cu")
		(net "P2E_CPU_USB_NODE1_RX_DN")
	)
	(segment
		(start 156.11221 -101.460808)
		(end 155.610814 -100.959412)
		(width 0.127)
		(layer "F.Cu")
		(net "P2E_CPU_USB_NODE1_RX_DN")
	)
	(segment
		(start 129.737866 -134.69366)
		(end 129.8067 -134.624826)
		(width 0.127)
		(layer "F.Cu")
		(net "P2E_CPU_USB_NODE1_RX_DN")
	)
	(segment
		(start 131.14782 -131.460748)
		(end 131.14782 -130.191002)
		(width 0.127)
		(layer "F.Cu")
		(net "P2E_CPU_USB_NODE1_RX_DN")
	)
	(segment
		(start 129.8067 -134.624826)
		(end 129.8067 -132.801868)
		(width 0.127)
		(layer "F.Cu")
		(net "P2E_CPU_USB_NODE1_RX_DN")
	)
	(segment
		(start 157.18663 -101.105208)
		(end 156.83103 -101.460808)
		(width 0.127)
		(layer "F.Cu")
		(net "P2E_CPU_USB_NODE1_RX_DN")
	)
	(via
		(at 155.610814 -100.959412)
		(size 0.508)
		(drill 0.254)
		(layers "F.Cu" "B.Cu")
		(net "P2E_CPU_USB_NODE1_RX_DN")
	)
	(via
		(at 130.66522 -129.997454)
		(size 0.508)
		(drill 0.254)
		(layers "F.Cu" "B.Cu")
		(net "P2E_CPU_USB_NODE1_RX_DN")
	)
	(segment
		(start 150.98522 -116.069872)
		(end 150.98522 -107.88777)
		(width 0.127)
		(layer "B.Cu")
		(net "P2E_CPU_USB_NODE1_RX_DN")
	)
	(segment
		(start 134.637526 -128.514348)
		(end 135.023606 -128.128268)
		(width 0.127)
		(layer "B.Cu")
		(net "P2E_CPU_USB_NODE1_RX_DN")
	)
	(segment
		(start 131.14782 -129.8194)
		(end 131.14782 -129.105406)
		(width 0.127)
		(layer "B.Cu")
		(net "P2E_CPU_USB_NODE1_RX_DN")
	)
	(segment
		(start 139.167362 -128.128268)
		(end 142.08379 -125.21184)
		(width 0.127)
		(layer "B.Cu")
		(net "P2E_CPU_USB_NODE1_RX_DN")
	)
	(segment
		(start 150.98522 -107.88777)
		(end 151.684736 -103.567738)
		(width 0.127)
		(layer "B.Cu")
		(net "P2E_CPU_USB_NODE1_RX_DN")
	)
	(segment
		(start 153.810462 -101.442012)
		(end 155.128214 -101.442012)
		(width 0.127)
		(layer "B.Cu")
		(net "P2E_CPU_USB_NODE1_RX_DN")
	)
	(segment
		(start 148.716492 -121.488454)
		(end 150.98522 -116.069872)
		(width 0.127)
		(layer "B.Cu")
		(net "P2E_CPU_USB_NODE1_RX_DN")
	)
	(segment
		(start 131.738878 -128.514348)
		(end 134.637526 -128.514348)
		(width 0.127)
		(layer "B.Cu")
		(net "P2E_CPU_USB_NODE1_RX_DN")
	)
	(segment
		(start 155.128214 -101.442012)
		(end 155.610814 -100.959412)
		(width 0.127)
		(layer "B.Cu")
		(net "P2E_CPU_USB_NODE1_RX_DN")
	)
	(segment
		(start 131.14782 -129.105406)
		(end 131.738878 -128.514348)
		(width 0.127)
		(layer "B.Cu")
		(net "P2E_CPU_USB_NODE1_RX_DN")
	)
	(segment
		(start 135.023606 -128.128268)
		(end 139.167362 -128.128268)
		(width 0.127)
		(layer "B.Cu")
		(net "P2E_CPU_USB_NODE1_RX_DN")
	)
	(segment
		(start 151.684736 -103.567738)
		(end 153.810462 -101.442012)
		(width 0.127)
		(layer "B.Cu")
		(net "P2E_CPU_USB_NODE1_RX_DN")
	)
	(segment
		(start 130.969766 -129.997454)
		(end 131.14782 -129.8194)
		(width 0.127)
		(layer "B.Cu")
		(net "P2E_CPU_USB_NODE1_RX_DN")
	)
	(segment
		(start 144.993106 -125.21184)
		(end 148.716492 -121.488454)
		(width 0.127)
		(layer "B.Cu")
		(net "P2E_CPU_USB_NODE1_RX_DN")
	)
	(segment
		(start 142.08379 -125.21184)
		(end 144.993106 -125.21184)
		(width 0.127)
		(layer "B.Cu")
		(net "P2E_CPU_USB_NODE1_RX_DN")
	)
	(segment
		(start 130.66522 -129.997454)
		(end 130.969766 -129.997454)
		(width 0.127)
		(layer "B.Cu")
		(net "P2E_CPU_USB_NODE1_RX_DN")
	)
	(segment
		(start 62.401196 -75.799442)
		(end 62.001146 -76.199492)
		(width 0.1143)
		(layer "F.Cu")
		(net "TP_CPU_NODE1_VCCCPU1VIDSI0GT1_1")
	)
	(via
		(at 65.27292 -76.0222)
		(size 0.6604)
		(drill 0.3302)
		(layers "F.Cu" "B.Cu")
		(net "TP_CPU_NODE1_VCCCPU1VIDSI0GT1_1")
	)
	(via
		(at 62.001146 -76.199492)
		(size 0.508)
		(drill 0.254)
		(layers "F.Cu" "B.Cu")
		(net "TP_CPU_NODE1_VCCCPU1VIDSI0GT1_1")
	)
	(segment
		(start 64.8208 -76.593192)
		(end 65.27292 -76.141072)
		(width 0.1016)
		(layer "B.Cu")
		(net "TP_CPU_NODE1_VCCCPU1VIDSI0GT1_1")
	)
	(segment
		(start 62.001146 -76.199492)
		(end 62.001146 -76.255372)
		(width 0.1016)
		(layer "B.Cu")
		(net "TP_CPU_NODE1_VCCCPU1VIDSI0GT1_1")
	)
	(segment
		(start 65.27292 -76.141072)
		(end 65.27292 -76.0222)
		(width 0.1016)
		(layer "B.Cu")
		(net "TP_CPU_NODE1_VCCCPU1VIDSI0GT1_1")
	)
	(segment
		(start 62.338966 -76.593192)
		(end 64.8208 -76.593192)
		(width 0.1016)
		(layer "B.Cu")
		(net "TP_CPU_NODE1_VCCCPU1VIDSI0GT1_1")
	)
	(segment
		(start 62.001146 -76.255372)
		(end 62.338966 -76.593192)
		(width 0.1016)
		(layer "B.Cu")
		(net "TP_CPU_NODE1_VCCCPU1VIDSI0GT1_1")
	)
	(via
		(at 117.244876 -25.232868)
		(size 0.508)
		(drill 0.254)
		(layers "F.Cu" "B.Cu")
		(net "PV_VTT_DDR_NODE1_REFIN")
	)
	(segment
		(start 171.23537 -97.735898)
		(end 171.562776 -97.735898)
		(width 0.1016)
		(layer "F.Cu")
		(net "TP_U3TXDP1")
	)
	(segment
		(start 174.376334 -97.19056)
		(end 174.781972 -96.784922)
		(width 0.1016)
		(layer "F.Cu")
		(net "TP_U3TXDP1")
	)
	(segment
		(start 171.562776 -97.735898)
		(end 172.108114 -97.19056)
		(width 0.1016)
		(layer "F.Cu")
		(net "TP_U3TXDP1")
	)
	(segment
		(start 172.108114 -97.19056)
		(end 174.376334 -97.19056)
		(width 0.1016)
		(layer "F.Cu")
		(net "TP_U3TXDP1")
	)
	(via
		(at 174.781972 -96.784922)
		(size 0.508)
		(drill 0.254)
		(layers "F.Cu" "B.Cu")
		(net "TP_U3TXDP1")
	)
	(segment
		(start 61.201046 -76.199492)
		(end 61.601096 -75.799442)
		(width 0.1143)
		(layer "F.Cu")
		(net "TP_CPU_NODE1_VCCCPU1VIDSI0GT1P0")
	)
	(via
		(at 61.104018 -74.627994)
		(size 0.6604)
		(drill 0.3302)
		(layers "F.Cu" "B.Cu")
		(net "TP_CPU_NODE1_VCCCPU1VIDSI0GT1P0")
	)
	(via
		(at 61.201046 -76.199492)
		(size 0.508)
		(drill 0.254)
		(layers "F.Cu" "B.Cu")
		(net "TP_CPU_NODE1_VCCCPU1VIDSI0GT1P0")
	)
	(segment
		(start 61.104018 -74.627994)
		(end 60.788296 -74.943716)
		(width 0.1143)
		(layer "B.Cu")
		(net "TP_CPU_NODE1_VCCCPU1VIDSI0GT1P0")
	)
	(segment
		(start 60.788296 -75.786742)
		(end 61.201046 -76.199492)
		(width 0.1143)
		(layer "B.Cu")
		(net "TP_CPU_NODE1_VCCCPU1VIDSI0GT1P0")
	)
	(segment
		(start 60.788296 -74.943716)
		(end 60.788296 -75.786742)
		(width 0.1143)
		(layer "B.Cu")
		(net "TP_CPU_NODE1_VCCCPU1VIDSI0GT1P0")
	)
	(segment
		(start 178.49342 -115.692682)
		(end 178.49342 -116.882672)
		(width 0.1016)
		(layer "F.Cu")
		(net "FM_CPLD_NODE1_P1V0_EN")
	)
	(segment
		(start 178.49342 -116.882672)
		(end 178.010566 -117.365526)
		(width 0.1016)
		(layer "F.Cu")
		(net "FM_CPLD_NODE1_P1V0_EN")
	)
	(segment
		(start 163.322254 -72.313546)
		(end 163.304728 -72.331072)
		(width 0.254)
		(layer "F.Cu")
		(net "FM_CPLD_NODE1_P1V0_EN")
	)
	(segment
		(start 163.990528 -72.313546)
		(end 163.322254 -72.313546)
		(width 0.254)
		(layer "F.Cu")
		(net "FM_CPLD_NODE1_P1V0_EN")
	)
	(via
		(at 172.61586 -89.618566)
		(size 0.508)
		(drill 0.254)
		(layers "F.Cu" "B.Cu")
		(net "FM_CPLD_NODE1_P1V0_EN")
	)
	(via
		(at 178.49342 -115.692682)
		(size 0.508)
		(drill 0.254)
		(layers "F.Cu" "B.Cu")
		(net "FM_CPLD_NODE1_P1V0_EN")
	)
	(via
		(at 163.304728 -72.331072)
		(size 0.508)
		(drill 0.254)
		(layers "F.Cu" "B.Cu")
		(net "FM_CPLD_NODE1_P1V0_EN")
	)
	(segment
		(start 171.46524 -76.510134)
		(end 171.46524 -88.467946)
		(width 0.1016)
		(layer "B.Cu")
		(net "FM_CPLD_NODE1_P1V0_EN")
	)
	(segment
		(start 167.852852 -72.897746)
		(end 171.46524 -76.510134)
		(width 0.1016)
		(layer "B.Cu")
		(net "FM_CPLD_NODE1_P1V0_EN")
	)
	(segment
		(start 163.871402 -72.897746)
		(end 167.852852 -72.897746)
		(width 0.1016)
		(layer "B.Cu")
		(net "FM_CPLD_NODE1_P1V0_EN")
	)
	(segment
		(start 171.46524 -88.467946)
		(end 172.61586 -89.618566)
		(width 0.1016)
		(layer "B.Cu")
		(net "FM_CPLD_NODE1_P1V0_EN")
	)
	(segment
		(start 163.304728 -72.331072)
		(end 163.871402 -72.897746)
		(width 0.1016)
		(layer "B.Cu")
		(net "FM_CPLD_NODE1_P1V0_EN")
	)
	(segment
		(start 172.61586 -89.618566)
		(end 173.064424 -89.170002)
		(width 0.1143)
		(layer "In2.Cu")
		(net "FM_CPLD_NODE1_P1V0_EN")
	)
	(segment
		(start 182.232554 -93.307916)
		(end 182.232554 -108.264706)
		(width 0.1143)
		(layer "In2.Cu")
		(net "FM_CPLD_NODE1_P1V0_EN")
	)
	(segment
		(start 182.232554 -108.264706)
		(end 178.49342 -112.00384)
		(width 0.1143)
		(layer "In2.Cu")
		(net "FM_CPLD_NODE1_P1V0_EN")
	)
	(segment
		(start 173.064424 -89.170002)
		(end 178.09464 -89.170002)
		(width 0.1143)
		(layer "In2.Cu")
		(net "FM_CPLD_NODE1_P1V0_EN")
	)
	(segment
		(start 178.09464 -89.170002)
		(end 182.232554 -93.307916)
		(width 0.1143)
		(layer "In2.Cu")
		(net "FM_CPLD_NODE1_P1V0_EN")
	)
	(segment
		(start 178.49342 -112.00384)
		(end 178.49342 -115.692682)
		(width 0.1143)
		(layer "In2.Cu")
		(net "FM_CPLD_NODE1_P1V0_EN")
	)
	(segment
		(start 174.250096 -97.77349)
		(end 174.718726 -98.24212)
		(width 0.1016)
		(layer "F.Cu")
		(net "TP_U3TXDN1")
	)
	(segment
		(start 171.14647 -98.135694)
		(end 171.77131 -98.135694)
		(width 0.1016)
		(layer "F.Cu")
		(net "TP_U3TXDN1")
	)
	(segment
		(start 172.133514 -97.77349)
		(end 174.250096 -97.77349)
		(width 0.1016)
		(layer "F.Cu")
		(net "TP_U3TXDN1")
	)
	(segment
		(start 171.77131 -98.135694)
		(end 172.133514 -97.77349)
		(width 0.1016)
		(layer "F.Cu")
		(net "TP_U3TXDN1")
	)
	(via
		(at 174.718726 -98.24212)
		(size 0.508)
		(drill 0.254)
		(layers "F.Cu" "B.Cu")
		(net "TP_U3TXDN1")
	)
	(segment
		(start 61.601096 -78.199742)
		(end 61.19495 -77.793596)
		(width 0.1016)
		(layer "F.Cu")
		(net "TP_CPU_NODE1_VCCCPU0VIDSI0GT1P0")
	)
	(segment
		(start 61.19495 -77.793596)
		(end 61.19495 -77.789278)
		(width 0.1016)
		(layer "F.Cu")
		(net "TP_CPU_NODE1_VCCCPU0VIDSI0GT1P0")
	)
	(via
		(at 61.19495 -77.789278)
		(size 0.508)
		(drill 0.254)
		(layers "F.Cu" "B.Cu")
		(net "TP_CPU_NODE1_VCCCPU0VIDSI0GT1P0")
	)
	(segment
		(start 164.443156 -97.032572)
		(end 164.443156 -95.11919)
		(width 0.1016)
		(layer "F.Cu")
		(net "SPI_USB_NODE1_R_SO")
	)
	(segment
		(start 164.443156 -95.11919)
		(end 164.69995 -94.862396)
		(width 0.1016)
		(layer "F.Cu")
		(net "SPI_USB_NODE1_R_SO")
	)
	(segment
		(start 164.905944 -94.656402)
		(end 164.69995 -94.862396)
		(width 0.1016)
		(layer "F.Cu")
		(net "SPI_USB_NODE1_R_SO")
	)
	(segment
		(start 164.905944 -94.240858)
		(end 164.905944 -94.656402)
		(width 0.1016)
		(layer "F.Cu")
		(net "SPI_USB_NODE1_R_SO")
	)
	(via
		(at 164.69995 -94.862396)
		(size 0.508)
		(drill 0.254)
		(layers "F.Cu" "B.Cu")
		(net "SPI_USB_NODE1_R_SO")
	)
	(segment
		(start 41.24071 -85.659214)
		(end 41.166034 -85.584538)
		(width 0.1016)
		(layer "F.Cu")
		(net "TP_CPU_NODE1_HPLL_MONN")
	)
	(segment
		(start 41.88968 -85.659214)
		(end 41.24071 -85.659214)
		(width 0.1016)
		(layer "F.Cu")
		(net "TP_CPU_NODE1_HPLL_MONN")
	)
	(via
		(at 41.166034 -85.584538)
		(size 0.508)
		(drill 0.254)
		(layers "F.Cu" "B.Cu")
		(net "TP_CPU_NODE1_HPLL_MONN")
	)
	(segment
		(start 153.501852 -87.56904)
		(end 154.333702 -87.56904)
		(width 0.1016)
		(layer "F.Cu")
		(net "SPI_USB_NODE1_WP_L")
	)
	(segment
		(start 154.333702 -87.56904)
		(end 154.348434 -87.583772)
		(width 0.1016)
		(layer "F.Cu")
		(net "SPI_USB_NODE1_WP_L")
	)
	(segment
		(start 154.348434 -87.583772)
		(end 155.86456 -87.583772)
		(width 0.1016)
		(layer "F.Cu")
		(net "SPI_USB_NODE1_WP_L")
	)
	(via
		(at 154.348434 -87.583772)
		(size 0.508)
		(drill 0.254)
		(layers "F.Cu" "B.Cu")
		(net "SPI_USB_NODE1_WP_L")
	)
	(segment
		(start 70.89521 -86.862666)
		(end 71.176642 -86.862666)
		(width 0.1016)
		(layer "F.Cu")
		(net "TP_CPU_E59")
	)
	(segment
		(start 71.176642 -86.862666)
		(end 71.42607 -86.613238)
		(width 0.1016)
		(layer "F.Cu")
		(net "TP_CPU_E59")
	)
	(via
		(at 71.42607 -86.613238)
		(size 0.508)
		(drill 0.254)
		(layers "F.Cu" "B.Cu")
		(net "TP_CPU_E59")
	)
	(segment
		(start 157.950662 -99.176078)
		(end 155.188412 -99.176078)
		(width 0.127)
		(layer "F.Cu")
		(net "P2E_CPU_USB_NODE1_TX_DN")
	)
	(segment
		(start 162.353244 -100.141786)
		(end 160.311084 -100.141786)
		(width 0.127)
		(layer "F.Cu")
		(net "P2E_CPU_USB_NODE1_TX_DN")
	)
	(segment
		(start 162.749992 -100.18395)
		(end 162.395408 -100.18395)
		(width 0.127)
		(layer "F.Cu")
		(net "P2E_CPU_USB_NODE1_TX_DN")
	)
	(segment
		(start 136.452102 -129.536698)
		(end 136.721596 -129.806192)
		(width 0.127)
		(layer "F.Cu")
		(net "P2E_CPU_USB_NODE1_TX_DN")
	)
	(segment
		(start 160.311084 -100.141786)
		(end 157.950662 -99.176078)
		(width 0.127)
		(layer "F.Cu")
		(net "P2E_CPU_USB_NODE1_TX_DN")
	)
	(segment
		(start 134.12978 -129.731516)
		(end 134.12978 -129.388362)
		(width 0.127)
		(layer "F.Cu")
		(net "P2E_CPU_USB_NODE1_TX_DN")
	)
	(segment
		(start 136.721596 -129.806192)
		(end 136.91362 -129.806192)
		(width 0.127)
		(layer "F.Cu")
		(net "P2E_CPU_USB_NODE1_TX_DN")
	)
	(segment
		(start 135.40994 -129.194814)
		(end 135.538464 -129.06629)
		(width 0.127)
		(layer "F.Cu")
		(net "P2E_CPU_USB_NODE1_TX_DN")
	)
	(segment
		(start 162.798252 -100.13569)
		(end 162.749992 -100.18395)
		(width 0.127)
		(layer "F.Cu")
		(net "P2E_CPU_USB_NODE1_TX_DN")
	)
	(segment
		(start 162.395408 -100.18395)
		(end 162.353244 -100.141786)
		(width 0.127)
		(layer "F.Cu")
		(net "P2E_CPU_USB_NODE1_TX_DN")
	)
	(segment
		(start 136.173718 -129.06629)
		(end 136.452102 -129.344674)
		(width 0.127)
		(layer "F.Cu")
		(net "P2E_CPU_USB_NODE1_TX_DN")
	)
	(segment
		(start 137.420604 -130.313176)
		(end 138.12774 -130.313176)
		(width 0.127)
		(layer "F.Cu")
		(net "P2E_CPU_USB_NODE1_TX_DN")
	)
	(segment
		(start 155.188412 -99.176078)
		(end 154.705812 -98.693478)
		(width 0.127)
		(layer "F.Cu")
		(net "P2E_CPU_USB_NODE1_TX_DN")
	)
	(segment
		(start 136.452102 -129.344674)
		(end 136.452102 -129.536698)
		(width 0.127)
		(layer "F.Cu")
		(net "P2E_CPU_USB_NODE1_TX_DN")
	)
	(segment
		(start 134.900416 -129.06629)
		(end 135.02894 -129.194814)
		(width 0.127)
		(layer "F.Cu")
		(net "P2E_CPU_USB_NODE1_TX_DN")
	)
	(segment
		(start 135.02894 -129.194814)
		(end 135.40994 -129.194814)
		(width 0.127)
		(layer "F.Cu")
		(net "P2E_CPU_USB_NODE1_TX_DN")
	)
	(segment
		(start 134.12978 -129.388362)
		(end 134.451852 -129.06629)
		(width 0.127)
		(layer "F.Cu")
		(net "P2E_CPU_USB_NODE1_TX_DN")
	)
	(segment
		(start 163.340034 -100.13569)
		(end 162.798252 -100.13569)
		(width 0.127)
		(layer "F.Cu")
		(net "P2E_CPU_USB_NODE1_TX_DN")
	)
	(segment
		(start 138.12774 -130.313176)
		(end 138.26998 -130.455416)
		(width 0.127)
		(layer "F.Cu")
		(net "P2E_CPU_USB_NODE1_TX_DN")
	)
	(segment
		(start 135.538464 -129.06629)
		(end 136.173718 -129.06629)
		(width 0.127)
		(layer "F.Cu")
		(net "P2E_CPU_USB_NODE1_TX_DN")
	)
	(segment
		(start 134.486396 -130.087116)
		(end 134.48538 -130.087116)
		(width 0.127)
		(layer "F.Cu")
		(net "P2E_CPU_USB_NODE1_TX_DN")
	)
	(segment
		(start 138.26998 -130.455416)
		(end 138.26998 -130.877818)
		(width 0.127)
		(layer "F.Cu")
		(net "P2E_CPU_USB_NODE1_TX_DN")
	)
	(segment
		(start 134.451852 -129.06629)
		(end 134.900416 -129.06629)
		(width 0.127)
		(layer "F.Cu")
		(net "P2E_CPU_USB_NODE1_TX_DN")
	)
	(segment
		(start 136.91362 -129.806192)
		(end 137.420604 -130.313176)
		(width 0.127)
		(layer "F.Cu")
		(net "P2E_CPU_USB_NODE1_TX_DN")
	)
	(segment
		(start 134.48538 -130.087116)
		(end 134.12978 -129.731516)
		(width 0.127)
		(layer "F.Cu")
		(net "P2E_CPU_USB_NODE1_TX_DN")
	)
	(via
		(at 138.26998 -130.877818)
		(size 0.508)
		(drill 0.254)
		(layers "F.Cu" "B.Cu")
		(net "P2E_CPU_USB_NODE1_TX_DN")
	)
	(via
		(at 154.705812 -98.693478)
		(size 0.508)
		(drill 0.254)
		(layers "F.Cu" "B.Cu")
		(net "P2E_CPU_USB_NODE1_TX_DN")
	)
	(segment
		(start 146.016218 -126.792482)
		(end 143.035782 -126.792482)
		(width 0.127)
		(layer "B.Cu")
		(net "P2E_CPU_USB_NODE1_TX_DN")
	)
	(segment
		(start 152.80894 -111.79556)
		(end 152.80894 -116.158518)
		(width 0.127)
		(layer "B.Cu")
		(net "P2E_CPU_USB_NODE1_TX_DN")
	)
	(segment
		(start 150.202646 -122.606308)
		(end 146.016218 -126.792482)
		(width 0.127)
		(layer "B.Cu")
		(net "P2E_CPU_USB_NODE1_TX_DN")
	)
	(segment
		(start 157.08884 -102.63505)
		(end 154.071574 -105.652316)
		(width 0.127)
		(layer "B.Cu")
		(net "P2E_CPU_USB_NODE1_TX_DN")
	)
	(segment
		(start 157.08884 -100.131372)
		(end 157.08884 -102.63505)
		(width 0.127)
		(layer "B.Cu")
		(net "P2E_CPU_USB_NODE1_TX_DN")
	)
	(segment
		(start 152.8318 -111.105442)
		(end 152.80894 -111.79556)
		(width 0.127)
		(layer "B.Cu")
		(net "P2E_CPU_USB_NODE1_TX_DN")
	)
	(segment
		(start 138.480546 -130.395218)
		(end 138.26998 -130.605784)
		(width 0.127)
		(layer "B.Cu")
		(net "P2E_CPU_USB_NODE1_TX_DN")
	)
	(segment
		(start 139.433046 -130.395218)
		(end 138.480546 -130.395218)
		(width 0.127)
		(layer "B.Cu")
		(net "P2E_CPU_USB_NODE1_TX_DN")
	)
	(segment
		(start 154.705812 -98.693478)
		(end 155.188412 -99.176078)
		(width 0.127)
		(layer "B.Cu")
		(net "P2E_CPU_USB_NODE1_TX_DN")
	)
	(segment
		(start 155.188412 -99.176078)
		(end 156.133546 -99.176078)
		(width 0.127)
		(layer "B.Cu")
		(net "P2E_CPU_USB_NODE1_TX_DN")
	)
	(segment
		(start 154.071574 -105.652316)
		(end 152.8318 -111.105442)
		(width 0.127)
		(layer "B.Cu")
		(net "P2E_CPU_USB_NODE1_TX_DN")
	)
	(segment
		(start 156.133546 -99.176078)
		(end 157.08884 -100.131372)
		(width 0.127)
		(layer "B.Cu")
		(net "P2E_CPU_USB_NODE1_TX_DN")
	)
	(segment
		(start 152.80894 -116.158518)
		(end 150.202646 -122.606308)
		(width 0.127)
		(layer "B.Cu")
		(net "P2E_CPU_USB_NODE1_TX_DN")
	)
	(segment
		(start 143.035782 -126.792482)
		(end 139.433046 -130.395218)
		(width 0.127)
		(layer "B.Cu")
		(net "P2E_CPU_USB_NODE1_TX_DN")
	)
	(segment
		(start 138.26998 -130.605784)
		(end 138.26998 -130.877818)
		(width 0.127)
		(layer "B.Cu")
		(net "P2E_CPU_USB_NODE1_TX_DN")
	)
	(segment
		(start 41.88968 -86.472014)
		(end 40.70604 -86.472014)
		(width 0.1016)
		(layer "F.Cu")
		(net "TP_CPU_NODE1_HPLL_MONP")
	)
	(segment
		(start 40.70604 -86.472014)
		(end 39.737792 -85.503766)
		(width 0.1016)
		(layer "F.Cu")
		(net "TP_CPU_NODE1_HPLL_MONP")
	)
	(via
		(at 39.737792 -85.503766)
		(size 0.508)
		(drill 0.254)
		(layers "F.Cu" "B.Cu")
		(net "TP_CPU_NODE1_HPLL_MONP")
	)
	(segment
		(start 81.5721 -90.86469)
		(end 81.407 -91.02979)
		(width 0.508)
		(layer "F.Cu")
		(net "P3V3_RTC_NODE1")
	)
	(segment
		(start 81.407 -91.02979)
		(end 80.363568 -91.02979)
		(width 0.508)
		(layer "F.Cu")
		(net "P3V3_RTC_NODE1")
	)
	(segment
		(start 92.556584 -82.238342)
		(end 92.4306 -82.238342)
		(width 0.508)
		(layer "F.Cu")
		(net "P3V3_RTC_NODE1")
	)
	(segment
		(start 102.918006 -81.216246)
		(end 102.081838 -80.380078)
		(width 0.508)
		(layer "F.Cu")
		(net "P3V3_RTC_NODE1")
	)
	(segment
		(start 92.066364 -82.552794)
		(end 88.9889 -82.552794)
		(width 0.508)
		(layer "F.Cu")
		(net "P3V3_RTC_NODE1")
	)
	(segment
		(start 113.80216 -77.454506)
		(end 110.04042 -81.216246)
		(width 0.508)
		(layer "F.Cu")
		(net "P3V3_RTC_NODE1")
	)
	(segment
		(start 113.80216 -72.508618)
		(end 113.80216 -77.454506)
		(width 0.508)
		(layer "F.Cu")
		(net "P3V3_RTC_NODE1")
	)
	(segment
		(start 80.363568 -91.02979)
		(end 80.363568 -91.027504)
		(width 0.508)
		(layer "F.Cu")
		(net "P3V3_RTC_NODE1")
	)
	(segment
		(start 92.3544 -82.314542)
		(end 92.304616 -82.314542)
		(width 0.508)
		(layer "F.Cu")
		(net "P3V3_RTC_NODE1")
	)
	(segment
		(start 102.081838 -80.380078)
		(end 96.409002 -80.380078)
		(width 0.508)
		(layer "F.Cu")
		(net "P3V3_RTC_NODE1")
	)
	(segment
		(start 115.03152 -71.543418)
		(end 115.0366 -71.538338)
		(width 0.508)
		(layer "F.Cu")
		(net "P3V3_RTC_NODE1")
	)
	(segment
		(start 92.304616 -82.314542)
		(end 92.066364 -82.552794)
		(width 0.508)
		(layer "F.Cu")
		(net "P3V3_RTC_NODE1")
	)
	(segment
		(start 93.73616 -80.45069)
		(end 93.73616 -81.058766)
		(width 0.508)
		(layer "F.Cu")
		(net "P3V3_RTC_NODE1")
	)
	(segment
		(start 113.67516 -71.543418)
		(end 115.03152 -71.543418)
		(width 0.508)
		(layer "F.Cu")
		(net "P3V3_RTC_NODE1")
	)
	(segment
		(start 88.9889 -82.552794)
		(end 88.803988 -82.737706)
		(width 0.508)
		(layer "F.Cu")
		(net "P3V3_RTC_NODE1")
	)
	(segment
		(start 92.4306 -82.238342)
		(end 92.3544 -82.314542)
		(width 0.508)
		(layer "F.Cu")
		(net "P3V3_RTC_NODE1")
	)
	(segment
		(start 93.73616 -81.058766)
		(end 92.556584 -82.238342)
		(width 0.508)
		(layer "F.Cu")
		(net "P3V3_RTC_NODE1")
	)
	(segment
		(start 113.527586 -37.320728)
		(end 113.416588 -37.320728)
		(width 0.508)
		(layer "F.Cu")
		(net "P3V3_RTC_NODE1")
	)
	(segment
		(start 161.765488 -116.303552)
		(end 161.32048 -115.858544)
		(width 0.508)
		(layer "F.Cu")
		(net "P3V3_RTC_NODE1")
	)
	(segment
		(start 120.85193 -71.543418)
		(end 115.04168 -71.543418)
		(width 0.508)
		(layer "F.Cu")
		(net "P3V3_RTC_NODE1")
	)
	(segment
		(start 96.33839 -80.45069)
		(end 93.73616 -80.45069)
		(width 0.508)
		(layer "F.Cu")
		(net "P3V3_RTC_NODE1")
	)
	(segment
		(start 113.25606 -71.962518)
		(end 113.67516 -71.543418)
		(width 0.508)
		(layer "F.Cu")
		(net "P3V3_RTC_NODE1")
	)
	(segment
		(start 113.25606 -71.962518)
		(end 113.80216 -72.508618)
		(width 0.508)
		(layer "F.Cu")
		(net "P3V3_RTC_NODE1")
	)
	(segment
		(start 88.803988 -82.737706)
		(end 87.55888 -82.737706)
		(width 0.508)
		(layer "F.Cu")
		(net "P3V3_RTC_NODE1")
	)
	(segment
		(start 110.04042 -81.216246)
		(end 102.918006 -81.216246)
		(width 0.508)
		(layer "F.Cu")
		(net "P3V3_RTC_NODE1")
	)
	(segment
		(start 81.5721 -90.86342)
		(end 81.5721 -90.86469)
		(width 0.508)
		(layer "F.Cu")
		(net "P3V3_RTC_NODE1")
	)
	(segment
		(start 162.296856 -116.303552)
		(end 161.765488 -116.303552)
		(width 0.508)
		(layer "F.Cu")
		(net "P3V3_RTC_NODE1")
	)
	(segment
		(start 96.409002 -80.380078)
		(end 96.33839 -80.45069)
		(width 0.508)
		(layer "F.Cu")
		(net "P3V3_RTC_NODE1")
	)
	(segment
		(start 115.04168 -71.543418)
		(end 115.0366 -71.538338)
		(width 0.508)
		(layer "F.Cu")
		(net "P3V3_RTC_NODE1")
	)
	(segment
		(start 121.50598 -28.71978)
		(end 121.50598 -29.342334)
		(width 0.508)
		(layer "F.Cu")
		(net "P3V3_RTC_NODE1")
	)
	(segment
		(start 121.50598 -29.342334)
		(end 113.527586 -37.320728)
		(width 0.508)
		(layer "F.Cu")
		(net "P3V3_RTC_NODE1")
	)
	(via
		(at 78.53426 -85.587586)
		(size 0.508)
		(drill 0.254)
		(layers "F.Cu" "B.Cu")
		(net "P3V3_RTC_NODE1")
	)
	(via
		(at 93.73616 -80.45069)
		(size 0.508)
		(drill 0.254)
		(layers "F.Cu" "B.Cu")
		(net "P3V3_RTC_NODE1")
	)
	(via
		(at 62.938406 -82.01914)
		(size 0.508)
		(drill 0.254)
		(layers "F.Cu" "B.Cu")
		(net "P3V3_RTC_NODE1")
	)
	(via
		(at 113.416588 -37.320728)
		(size 0.508)
		(drill 0.254)
		(layers "F.Cu" "B.Cu")
		(net "P3V3_RTC_NODE1")
	)
	(via
		(at 112.40008 -56.800242)
		(size 0.508)
		(drill 0.254)
		(layers "F.Cu" "B.Cu")
		(net "P3V3_RTC_NODE1")
	)
	(via
		(at 113.25606 -71.962518)
		(size 0.508)
		(drill 0.254)
		(layers "F.Cu" "B.Cu")
		(net "P3V3_RTC_NODE1")
	)
	(via
		(at 81.5721 -90.86342)
		(size 0.508)
		(drill 0.254)
		(layers "F.Cu" "B.Cu")
		(net "P3V3_RTC_NODE1")
	)
	(via
		(at 161.32048 -115.858544)
		(size 0.508)
		(drill 0.254)
		(layers "F.Cu" "B.Cu")
		(net "P3V3_RTC_NODE1")
	)
	(via
		(at 86.84514 -82.737706)
		(size 0.508)
		(drill 0.254)
		(layers "F.Cu" "B.Cu")
		(net "P3V3_RTC_NODE1")
	)
	(via
		(at 87.55888 -82.737706)
		(size 0.508)
		(drill 0.254)
		(layers "F.Cu" "B.Cu")
		(net "P3V3_RTC_NODE1")
	)
	(via
		(at 115.0366 -71.538338)
		(size 0.508)
		(drill 0.254)
		(layers "F.Cu" "B.Cu")
		(net "P3V3_RTC_NODE1")
	)
	(segment
		(start 78.26248 -85.315806)
		(end 78.53426 -85.587586)
		(width 0.508)
		(layer "B.Cu")
		(net "P3V3_RTC_NODE1")
	)
	(segment
		(start 79.104236 -86.157562)
		(end 78.53426 -85.587586)
		(width 0.508)
		(layer "B.Cu")
		(net "P3V3_RTC_NODE1")
	)
	(segment
		(start 78.26248 -84.93252)
		(end 78.26248 -85.315806)
		(width 0.508)
		(layer "B.Cu")
		(net "P3V3_RTC_NODE1")
	)
	(segment
		(start 79.55026 -86.157562)
		(end 79.104236 -86.157562)
		(width 0.508)
		(layer "B.Cu")
		(net "P3V3_RTC_NODE1")
	)
	(segment
		(start 112.91824 -68.406518)
		(end 112.94491 -68.433188)
		(width 0.508)
		(layer "In2.Cu")
		(net "P3V3_RTC_NODE1")
	)
	(segment
		(start 113.39322 -60.429902)
		(end 113.39322 -66.8147)
		(width 0.508)
		(layer "In2.Cu")
		(net "P3V3_RTC_NODE1")
	)
	(segment
		(start 112.40008 -56.800242)
		(end 113.09858 -57.498742)
		(width 0.508)
		(layer "In2.Cu")
		(net "P3V3_RTC_NODE1")
	)
	(segment
		(start 112.91824 -67.28968)
		(end 112.91824 -68.406518)
		(width 0.508)
		(layer "In2.Cu")
		(net "P3V3_RTC_NODE1")
	)
	(segment
		(start 112.94491 -71.651368)
		(end 113.25606 -71.962518)
		(width 0.508)
		(layer "In2.Cu")
		(net "P3V3_RTC_NODE1")
	)
	(segment
		(start 113.09858 -60.135262)
		(end 113.39322 -60.429902)
		(width 0.508)
		(layer "In2.Cu")
		(net "P3V3_RTC_NODE1")
	)
	(segment
		(start 113.39322 -66.8147)
		(end 112.91824 -67.28968)
		(width 0.508)
		(layer "In2.Cu")
		(net "P3V3_RTC_NODE1")
	)
	(segment
		(start 112.94491 -68.433188)
		(end 112.94491 -71.651368)
		(width 0.508)
		(layer "In2.Cu")
		(net "P3V3_RTC_NODE1")
	)
	(segment
		(start 113.09858 -57.498742)
		(end 113.09858 -60.135262)
		(width 0.508)
		(layer "In2.Cu")
		(net "P3V3_RTC_NODE1")
	)
	(segment
		(start 65.123822 -80.539336)
		(end 73.510648 -80.539336)
		(width 0.508)
		(layer "In6.Cu")
		(net "P3V3_RTC_NODE1")
	)
	(segment
		(start 84.010754 -81.016602)
		(end 84.204556 -81.210404)
		(width 0.508)
		(layer "In6.Cu")
		(net "P3V3_RTC_NODE1")
	)
	(segment
		(start 86.84514 -82.737706)
		(end 87.55888 -82.737706)
		(width 0.508)
		(layer "In6.Cu")
		(net "P3V3_RTC_NODE1")
	)
	(segment
		(start 63.652146 -81.303622)
		(end 64.359536 -81.303622)
		(width 0.508)
		(layer "In6.Cu")
		(net "P3V3_RTC_NODE1")
	)
	(segment
		(start 62.938406 -82.01914)
		(end 62.938406 -82.017362)
		(width 0.508)
		(layer "In6.Cu")
		(net "P3V3_RTC_NODE1")
	)
	(segment
		(start 86.42858 -81.210404)
		(end 87.55888 -82.340704)
		(width 0.508)
		(layer "In6.Cu")
		(net "P3V3_RTC_NODE1")
	)
	(segment
		(start 73.987914 -81.016602)
		(end 84.010754 -81.016602)
		(width 0.508)
		(layer "In6.Cu")
		(net "P3V3_RTC_NODE1")
	)
	(segment
		(start 64.359536 -81.303622)
		(end 65.123822 -80.539336)
		(width 0.508)
		(layer "In6.Cu")
		(net "P3V3_RTC_NODE1")
	)
	(segment
		(start 73.510648 -80.539336)
		(end 73.987914 -81.016602)
		(width 0.508)
		(layer "In6.Cu")
		(net "P3V3_RTC_NODE1")
	)
	(segment
		(start 62.938406 -82.017362)
		(end 63.652146 -81.303622)
		(width 0.508)
		(layer "In6.Cu")
		(net "P3V3_RTC_NODE1")
	)
	(segment
		(start 87.55888 -82.340704)
		(end 87.55888 -82.737706)
		(width 0.508)
		(layer "In6.Cu")
		(net "P3V3_RTC_NODE1")
	)
	(segment
		(start 84.204556 -81.210404)
		(end 86.42858 -81.210404)
		(width 0.508)
		(layer "In6.Cu")
		(net "P3V3_RTC_NODE1")
	)
	(segment
		(start 132.93344 -96.05264)
		(end 133.612636 -96.731836)
		(width 0.508)
		(layer "In7.Cu")
		(net "P3V3_RTC_NODE1")
	)
	(segment
		(start 141.717014 -96.731836)
		(end 157.19298 -112.207802)
		(width 0.508)
		(layer "In7.Cu")
		(net "P3V3_RTC_NODE1")
	)
	(segment
		(start 114.996976 -74.907394)
		(end 115.108736 -74.907394)
		(width 0.508)
		(layer "In7.Cu")
		(net "P3V3_RTC_NODE1")
	)
	(segment
		(start 115.94592 -75.744578)
		(end 115.94592 -82.255106)
		(width 0.508)
		(layer "In7.Cu")
		(net "P3V3_RTC_NODE1")
	)
	(segment
		(start 159.664908 -115.858544)
		(end 161.32048 -115.858544)
		(width 0.508)
		(layer "In7.Cu")
		(net "P3V3_RTC_NODE1")
	)
	(segment
		(start 115.108736 -74.907394)
		(end 115.94592 -75.744578)
		(width 0.508)
		(layer "In7.Cu")
		(net "P3V3_RTC_NODE1")
	)
	(segment
		(start 133.612636 -96.731836)
		(end 141.717014 -96.731836)
		(width 0.508)
		(layer "In7.Cu")
		(net "P3V3_RTC_NODE1")
	)
	(segment
		(start 157.19298 -113.386616)
		(end 159.664908 -115.858544)
		(width 0.508)
		(layer "In7.Cu")
		(net "P3V3_RTC_NODE1")
	)
	(segment
		(start 114.62512 -74.535538)
		(end 114.996976 -74.907394)
		(width 0.508)
		(layer "In7.Cu")
		(net "P3V3_RTC_NODE1")
	)
	(segment
		(start 157.19298 -112.207802)
		(end 157.19298 -113.386616)
		(width 0.508)
		(layer "In7.Cu")
		(net "P3V3_RTC_NODE1")
	)
	(segment
		(start 111.7219 -47.903638)
		(end 112.40008 -48.581818)
		(width 0.508)
		(layer "In7.Cu")
		(net "P3V3_RTC_NODE1")
	)
	(segment
		(start 111.7219 -37.904166)
		(end 111.7219 -47.903638)
		(width 0.508)
		(layer "In7.Cu")
		(net "P3V3_RTC_NODE1")
	)
	(segment
		(start 129.743454 -96.05264)
		(end 132.93344 -96.05264)
		(width 0.508)
		(layer "In7.Cu")
		(net "P3V3_RTC_NODE1")
	)
	(segment
		(start 114.62512 -72.894698)
		(end 114.62512 -74.535538)
		(width 0.508)
		(layer "In7.Cu")
		(net "P3V3_RTC_NODE1")
	)
	(segment
		(start 115.94592 -82.255106)
		(end 129.743454 -96.05264)
		(width 0.508)
		(layer "In7.Cu")
		(net "P3V3_RTC_NODE1")
	)
	(segment
		(start 113.416588 -37.320728)
		(end 112.305338 -37.320728)
		(width 0.508)
		(layer "In7.Cu")
		(net "P3V3_RTC_NODE1")
	)
	(segment
		(start 115.0366 -71.538338)
		(end 115.00358 -71.571358)
		(width 0.508)
		(layer "In7.Cu")
		(net "P3V3_RTC_NODE1")
	)
	(segment
		(start 115.00358 -72.516238)
		(end 114.62512 -72.894698)
		(width 0.508)
		(layer "In7.Cu")
		(net "P3V3_RTC_NODE1")
	)
	(segment
		(start 112.40008 -48.581818)
		(end 112.40008 -56.800242)
		(width 0.508)
		(layer "In7.Cu")
		(net "P3V3_RTC_NODE1")
	)
	(segment
		(start 112.305338 -37.320728)
		(end 111.7219 -37.904166)
		(width 0.508)
		(layer "In7.Cu")
		(net "P3V3_RTC_NODE1")
	)
	(segment
		(start 115.00358 -71.571358)
		(end 115.00358 -72.516238)
		(width 0.508)
		(layer "In7.Cu")
		(net "P3V3_RTC_NODE1")
	)
	(segment
		(start 60.61202 -88.96731)
		(end 60.047378 -89.531952)
		(width 0.1016)
		(layer "F.Cu")
		(net "TP_CPU_NODE1_RSVD_MVT0")
	)
	(segment
		(start 60.047378 -89.531952)
		(end 60.047378 -91.893644)
		(width 0.1016)
		(layer "F.Cu")
		(net "TP_CPU_NODE1_RSVD_MVT0")
	)
	(segment
		(start 60.61202 -88.44026)
		(end 60.61202 -88.96731)
		(width 0.1016)
		(layer "F.Cu")
		(net "TP_CPU_NODE1_RSVD_MVT0")
	)
	(segment
		(start 60.047378 -91.893644)
		(end 60.221876 -92.068142)
		(width 0.1016)
		(layer "F.Cu")
		(net "TP_CPU_NODE1_RSVD_MVT0")
	)
	(segment
		(start 60.221876 -92.068142)
		(end 60.221876 -92.48013)
		(width 0.1016)
		(layer "F.Cu")
		(net "TP_CPU_NODE1_RSVD_MVT0")
	)
	(segment
		(start 60.221876 -92.48013)
		(end 60.217304 -92.484702)
		(width 0.1016)
		(layer "F.Cu")
		(net "TP_CPU_NODE1_RSVD_MVT0")
	)
	(via
		(at 60.217304 -92.484702)
		(size 0.762)
		(drill 0.381)
		(layers "F.Cu" "B.Cu")
		(net "TP_CPU_NODE1_RSVD_MVT0")
	)
	(segment
		(start 70.583044 -72.296782)
		(end 70.583044 -72.308212)
		(width 0.1016)
		(layer "F.Cu")
		(net "XDP_CPU_NODE1_VISA11")
	)
	(segment
		(start 109.24286 -73.906126)
		(end 108.908088 -74.240898)
		(width 0.1016)
		(layer "F.Cu")
		(net "XDP_CPU_NODE1_VISA11")
	)
	(segment
		(start 70.255892 -72.635618)
		(end 70.216776 -72.67448)
		(width 0.1016)
		(layer "F.Cu")
		(net "XDP_CPU_NODE1_VISA11")
	)
	(segment
		(start 108.908088 -74.240898)
		(end 108.576872 -74.240898)
		(width 0.1016)
		(layer "F.Cu")
		(net "XDP_CPU_NODE1_VISA11")
	)
	(segment
		(start 70.583044 -72.308212)
		(end 70.255892 -72.635618)
		(width 0.1016)
		(layer "F.Cu")
		(net "XDP_CPU_NODE1_VISA11")
	)
	(segment
		(start 110.460028 -73.906126)
		(end 109.24286 -73.906126)
		(width 0.1016)
		(layer "F.Cu")
		(net "XDP_CPU_NODE1_VISA11")
	)
	(segment
		(start 70.216776 -72.67448)
		(end 70.216776 -72.690482)
		(width 0.1016)
		(layer "F.Cu")
		(net "XDP_CPU_NODE1_VISA11")
	)
	(via
		(at 70.216776 -72.690482)
		(size 0.508)
		(drill 0.254)
		(layers "F.Cu" "B.Cu")
		(net "XDP_CPU_NODE1_VISA11")
	)
	(via
		(at 108.576872 -74.240898)
		(size 0.508)
		(drill 0.254)
		(layers "F.Cu" "B.Cu")
		(net "XDP_CPU_NODE1_VISA11")
	)
	(segment
		(start 76.047854 -71.733156)
		(end 74.099928 -71.733156)
		(width 0.1143)
		(layer "In2.Cu")
		(net "XDP_CPU_NODE1_VISA11")
	)
	(segment
		(start 92.969588 -65.363598)
		(end 92.969588 -65.888108)
		(width 0.1143)
		(layer "In2.Cu")
		(net "XDP_CPU_NODE1_VISA11")
	)
	(segment
		(start 107.482132 -69.522594)
		(end 107.637072 -69.367654)
		(width 0.1143)
		(layer "In2.Cu")
		(net "XDP_CPU_NODE1_VISA11")
	)
	(segment
		(start 108.134912 -71.986394)
		(end 107.784392 -71.635874)
		(width 0.1143)
		(layer "In2.Cu")
		(net "XDP_CPU_NODE1_VISA11")
	)
	(segment
		(start 92.787216 -66.07048)
		(end 92.52966 -66.07048)
		(width 0.1143)
		(layer "In2.Cu")
		(net "XDP_CPU_NODE1_VISA11")
	)
	(segment
		(start 92.347288 -65.888108)
		(end 92.347288 -65.363598)
		(width 0.1143)
		(layer "In2.Cu")
		(net "XDP_CPU_NODE1_VISA11")
	)
	(segment
		(start 108.058712 -74.053954)
		(end 108.058712 -72.593454)
		(width 0.1143)
		(layer "In2.Cu")
		(net "XDP_CPU_NODE1_VISA11")
	)
	(segment
		(start 93.591888 -65.888108)
		(end 93.591888 -65.363598)
		(width 0.1143)
		(layer "In2.Cu")
		(net "XDP_CPU_NODE1_VISA11")
	)
	(segment
		(start 108.245656 -74.240898)
		(end 108.058712 -74.053954)
		(width 0.1143)
		(layer "In2.Cu")
		(net "XDP_CPU_NODE1_VISA11")
	)
	(segment
		(start 108.576872 -74.240898)
		(end 108.245656 -74.240898)
		(width 0.1143)
		(layer "In2.Cu")
		(net "XDP_CPU_NODE1_VISA11")
	)
	(segment
		(start 92.164916 -65.181226)
		(end 91.742006 -65.181226)
		(width 0.1143)
		(layer "In2.Cu")
		(net "XDP_CPU_NODE1_VISA11")
	)
	(segment
		(start 74.099928 -71.733156)
		(end 73.339452 -72.493632)
		(width 0.1143)
		(layer "In2.Cu")
		(net "XDP_CPU_NODE1_VISA11")
	)
	(segment
		(start 91.217496 -65.705736)
		(end 85.864446 -65.705736)
		(width 0.1143)
		(layer "In2.Cu")
		(net "XDP_CPU_NODE1_VISA11")
	)
	(segment
		(start 107.070906 -69.522594)
		(end 107.482132 -69.522594)
		(width 0.1143)
		(layer "In2.Cu")
		(net "XDP_CPU_NODE1_VISA11")
	)
	(segment
		(start 106.407204 -68.828158)
		(end 104.84866 -67.269614)
		(width 0.1143)
		(layer "In2.Cu")
		(net "XDP_CPU_NODE1_VISA11")
	)
	(segment
		(start 96.26346 -66.07048)
		(end 96.081088 -65.888108)
		(width 0.1143)
		(layer "In2.Cu")
		(net "XDP_CPU_NODE1_VISA11")
	)
	(segment
		(start 107.637072 -69.055234)
		(end 107.409996 -68.828158)
		(width 0.1143)
		(layer "In2.Cu")
		(net "XDP_CPU_NODE1_VISA11")
	)
	(segment
		(start 95.276416 -66.07048)
		(end 95.01886 -66.07048)
		(width 0.1143)
		(layer "In2.Cu")
		(net "XDP_CPU_NODE1_VISA11")
	)
	(segment
		(start 106.90352 -69.68998)
		(end 107.070906 -69.522594)
		(width 0.1143)
		(layer "In2.Cu")
		(net "XDP_CPU_NODE1_VISA11")
	)
	(segment
		(start 92.969588 -65.888108)
		(end 92.787216 -66.07048)
		(width 0.1143)
		(layer "In2.Cu")
		(net "XDP_CPU_NODE1_VISA11")
	)
	(segment
		(start 94.654116 -65.181226)
		(end 94.39656 -65.181226)
		(width 0.1143)
		(layer "In2.Cu")
		(net "XDP_CPU_NODE1_VISA11")
	)
	(segment
		(start 76.415646 -71.365872)
		(end 76.047854 -71.733156)
		(width 0.1143)
		(layer "In2.Cu")
		(net "XDP_CPU_NODE1_VISA11")
	)
	(segment
		(start 95.01886 -66.07048)
		(end 94.836488 -65.888108)
		(width 0.1143)
		(layer "In2.Cu")
		(net "XDP_CPU_NODE1_VISA11")
	)
	(segment
		(start 94.836488 -65.363598)
		(end 94.654116 -65.181226)
		(width 0.1143)
		(layer "In2.Cu")
		(net "XDP_CPU_NODE1_VISA11")
	)
	(segment
		(start 107.784392 -71.635874)
		(end 107.784392 -70.368414)
		(width 0.1143)
		(layer "In2.Cu")
		(net "XDP_CPU_NODE1_VISA11")
	)
	(segment
		(start 94.39656 -65.181226)
		(end 94.214188 -65.363598)
		(width 0.1143)
		(layer "In2.Cu")
		(net "XDP_CPU_NODE1_VISA11")
	)
	(segment
		(start 99.772216 -67.269614)
		(end 97.683828 -65.181226)
		(width 0.1143)
		(layer "In2.Cu")
		(net "XDP_CPU_NODE1_VISA11")
	)
	(segment
		(start 70.216776 -72.949816)
		(end 70.216776 -72.690482)
		(width 0.1143)
		(layer "In2.Cu")
		(net "XDP_CPU_NODE1_VISA11")
	)
	(segment
		(start 107.070906 -70.094094)
		(end 106.90352 -69.926708)
		(width 0.1143)
		(layer "In2.Cu")
		(net "XDP_CPU_NODE1_VISA11")
	)
	(segment
		(start 73.339452 -72.493632)
		(end 73.339452 -72.859646)
		(width 0.1143)
		(layer "In2.Cu")
		(net "XDP_CPU_NODE1_VISA11")
	)
	(segment
		(start 92.347288 -65.363598)
		(end 92.164916 -65.181226)
		(width 0.1143)
		(layer "In2.Cu")
		(net "XDP_CPU_NODE1_VISA11")
	)
	(segment
		(start 93.409516 -65.181226)
		(end 93.15196 -65.181226)
		(width 0.1143)
		(layer "In2.Cu")
		(net "XDP_CPU_NODE1_VISA11")
	)
	(segment
		(start 94.836488 -65.888108)
		(end 94.836488 -65.363598)
		(width 0.1143)
		(layer "In2.Cu")
		(net "XDP_CPU_NODE1_VISA11")
	)
	(segment
		(start 95.458788 -65.363598)
		(end 95.458788 -65.888108)
		(width 0.1143)
		(layer "In2.Cu")
		(net "XDP_CPU_NODE1_VISA11")
	)
	(segment
		(start 96.521016 -66.07048)
		(end 96.26346 -66.07048)
		(width 0.1143)
		(layer "In2.Cu")
		(net "XDP_CPU_NODE1_VISA11")
	)
	(segment
		(start 76.805282 -71.365872)
		(end 76.415646 -71.365872)
		(width 0.1143)
		(layer "In2.Cu")
		(net "XDP_CPU_NODE1_VISA11")
	)
	(segment
		(start 107.784392 -70.368414)
		(end 107.510072 -70.094094)
		(width 0.1143)
		(layer "In2.Cu")
		(net "XDP_CPU_NODE1_VISA11")
	)
	(segment
		(start 94.031816 -66.07048)
		(end 93.77426 -66.07048)
		(width 0.1143)
		(layer "In2.Cu")
		(net "XDP_CPU_NODE1_VISA11")
	)
	(segment
		(start 70.714108 -73.447148)
		(end 70.216776 -72.949816)
		(width 0.1143)
		(layer "In2.Cu")
		(net "XDP_CPU_NODE1_VISA11")
	)
	(segment
		(start 85.864446 -65.705736)
		(end 80.750156 -70.820026)
		(width 0.1143)
		(layer "In2.Cu")
		(net "XDP_CPU_NODE1_VISA11")
	)
	(segment
		(start 96.081088 -65.888108)
		(end 96.081088 -65.363598)
		(width 0.1143)
		(layer "In2.Cu")
		(net "XDP_CPU_NODE1_VISA11")
	)
	(segment
		(start 104.84866 -67.269614)
		(end 99.772216 -67.269614)
		(width 0.1143)
		(layer "In2.Cu")
		(net "XDP_CPU_NODE1_VISA11")
	)
	(segment
		(start 96.081088 -65.363598)
		(end 95.898716 -65.181226)
		(width 0.1143)
		(layer "In2.Cu")
		(net "XDP_CPU_NODE1_VISA11")
	)
	(segment
		(start 96.88576 -65.181226)
		(end 96.703388 -65.363598)
		(width 0.1143)
		(layer "In2.Cu")
		(net "XDP_CPU_NODE1_VISA11")
	)
	(segment
		(start 94.214188 -65.888108)
		(end 94.031816 -66.07048)
		(width 0.1143)
		(layer "In2.Cu")
		(net "XDP_CPU_NODE1_VISA11")
	)
	(segment
		(start 95.458788 -65.888108)
		(end 95.276416 -66.07048)
		(width 0.1143)
		(layer "In2.Cu")
		(net "XDP_CPU_NODE1_VISA11")
	)
	(segment
		(start 96.703388 -65.363598)
		(end 96.703388 -65.888108)
		(width 0.1143)
		(layer "In2.Cu")
		(net "XDP_CPU_NODE1_VISA11")
	)
	(segment
		(start 77.351128 -70.820026)
		(end 76.805282 -71.365872)
		(width 0.1143)
		(layer "In2.Cu")
		(net "XDP_CPU_NODE1_VISA11")
	)
	(segment
		(start 93.15196 -65.181226)
		(end 92.969588 -65.363598)
		(width 0.1143)
		(layer "In2.Cu")
		(net "XDP_CPU_NODE1_VISA11")
	)
	(segment
		(start 91.742006 -65.181226)
		(end 91.217496 -65.705736)
		(width 0.1143)
		(layer "In2.Cu")
		(net "XDP_CPU_NODE1_VISA11")
	)
	(segment
		(start 96.703388 -65.888108)
		(end 96.521016 -66.07048)
		(width 0.1143)
		(layer "In2.Cu")
		(net "XDP_CPU_NODE1_VISA11")
	)
	(segment
		(start 108.134912 -72.517254)
		(end 108.134912 -71.986394)
		(width 0.1143)
		(layer "In2.Cu")
		(net "XDP_CPU_NODE1_VISA11")
	)
	(segment
		(start 94.214188 -65.363598)
		(end 94.214188 -65.888108)
		(width 0.1143)
		(layer "In2.Cu")
		(net "XDP_CPU_NODE1_VISA11")
	)
	(segment
		(start 108.058712 -72.593454)
		(end 108.134912 -72.517254)
		(width 0.1143)
		(layer "In2.Cu")
		(net "XDP_CPU_NODE1_VISA11")
	)
	(segment
		(start 73.339452 -72.859646)
		(end 72.75195 -73.447148)
		(width 0.1143)
		(layer "In2.Cu")
		(net "XDP_CPU_NODE1_VISA11")
	)
	(segment
		(start 95.64116 -65.181226)
		(end 95.458788 -65.363598)
		(width 0.1143)
		(layer "In2.Cu")
		(net "XDP_CPU_NODE1_VISA11")
	)
	(segment
		(start 106.90352 -69.926708)
		(end 106.90352 -69.68998)
		(width 0.1143)
		(layer "In2.Cu")
		(net "XDP_CPU_NODE1_VISA11")
	)
	(segment
		(start 97.683828 -65.181226)
		(end 96.88576 -65.181226)
		(width 0.1143)
		(layer "In2.Cu")
		(net "XDP_CPU_NODE1_VISA11")
	)
	(segment
		(start 93.591888 -65.363598)
		(end 93.409516 -65.181226)
		(width 0.1143)
		(layer "In2.Cu")
		(net "XDP_CPU_NODE1_VISA11")
	)
	(segment
		(start 72.75195 -73.447148)
		(end 70.714108 -73.447148)
		(width 0.1143)
		(layer "In2.Cu")
		(net "XDP_CPU_NODE1_VISA11")
	)
	(segment
		(start 107.510072 -70.094094)
		(end 107.070906 -70.094094)
		(width 0.1143)
		(layer "In2.Cu")
		(net "XDP_CPU_NODE1_VISA11")
	)
	(segment
		(start 107.409996 -68.828158)
		(end 106.407204 -68.828158)
		(width 0.1143)
		(layer "In2.Cu")
		(net "XDP_CPU_NODE1_VISA11")
	)
	(segment
		(start 95.898716 -65.181226)
		(end 95.64116 -65.181226)
		(width 0.1143)
		(layer "In2.Cu")
		(net "XDP_CPU_NODE1_VISA11")
	)
	(segment
		(start 107.637072 -69.367654)
		(end 107.637072 -69.055234)
		(width 0.1143)
		(layer "In2.Cu")
		(net "XDP_CPU_NODE1_VISA11")
	)
	(segment
		(start 92.52966 -66.07048)
		(end 92.347288 -65.888108)
		(width 0.1143)
		(layer "In2.Cu")
		(net "XDP_CPU_NODE1_VISA11")
	)
	(segment
		(start 80.750156 -70.820026)
		(end 77.351128 -70.820026)
		(width 0.1143)
		(layer "In2.Cu")
		(net "XDP_CPU_NODE1_VISA11")
	)
	(segment
		(start 93.77426 -66.07048)
		(end 93.591888 -65.888108)
		(width 0.1143)
		(layer "In2.Cu")
		(net "XDP_CPU_NODE1_VISA11")
	)
	(segment
		(start 72.014334 -86.122002)
		(end 72.591676 -86.122002)
		(width 0.1016)
		(layer "F.Cu")
		(net "USB_NODE1_SMI_L")
	)
	(segment
		(start 163.251134 -104.135682)
		(end 163.251134 -104.896158)
		(width 0.1016)
		(layer "F.Cu")
		(net "USB_NODE1_SMI_L")
	)
	(segment
		(start 161.778696 -106.368596)
		(end 159.945832 -106.368596)
		(width 0.1016)
		(layer "F.Cu")
		(net "USB_NODE1_SMI_L")
	)
	(segment
		(start 159.037528 -108.08843)
		(end 159.945832 -107.180126)
		(width 0.1016)
		(layer "F.Cu")
		(net "USB_NODE1_SMI_L")
	)
	(segment
		(start 149.62378 -107.57535)
		(end 150.13686 -108.08843)
		(width 0.1016)
		(layer "F.Cu")
		(net "USB_NODE1_SMI_L")
	)
	(segment
		(start 159.945832 -107.180126)
		(end 159.945832 -106.368596)
		(width 0.1016)
		(layer "F.Cu")
		(net "USB_NODE1_SMI_L")
	)
	(segment
		(start 150.13686 -108.08843)
		(end 159.037528 -108.08843)
		(width 0.1016)
		(layer "F.Cu")
		(net "USB_NODE1_SMI_L")
	)
	(segment
		(start 163.251134 -104.896158)
		(end 161.778696 -106.368596)
		(width 0.1016)
		(layer "F.Cu")
		(net "USB_NODE1_SMI_L")
	)
	(via
		(at 149.62378 -107.57535)
		(size 0.508)
		(drill 0.254)
		(layers "F.Cu" "B.Cu")
		(net "USB_NODE1_SMI_L")
	)
	(via
		(at 72.591676 -86.122002)
		(size 0.508)
		(drill 0.254)
		(layers "F.Cu" "B.Cu")
		(net "USB_NODE1_SMI_L")
	)
	(segment
		(start 79.389986 -92.388182)
		(end 85.976206 -92.388182)
		(width 0.1143)
		(layer "In6.Cu")
		(net "USB_NODE1_SMI_L")
	)
	(segment
		(start 74.172826 -88.00465)
		(end 75.006454 -88.00465)
		(width 0.1143)
		(layer "In6.Cu")
		(net "USB_NODE1_SMI_L")
	)
	(segment
		(start 72.591676 -86.4235)
		(end 74.172826 -88.00465)
		(width 0.1143)
		(layer "In6.Cu")
		(net "USB_NODE1_SMI_L")
	)
	(segment
		(start 88.15324 -93.744288)
		(end 88.15324 -93.74505)
		(width 0.1143)
		(layer "In6.Cu")
		(net "USB_NODE1_SMI_L")
	)
	(segment
		(start 135.046466 -89.928446)
		(end 149.62378 -104.50576)
		(width 0.1143)
		(layer "In6.Cu")
		(net "USB_NODE1_SMI_L")
	)
	(segment
		(start 88.845898 -94.437708)
		(end 93.174312 -94.437708)
		(width 0.1143)
		(layer "In6.Cu")
		(net "USB_NODE1_SMI_L")
	)
	(segment
		(start 75.006454 -88.00465)
		(end 79.389986 -92.388182)
		(width 0.1143)
		(layer "In6.Cu")
		(net "USB_NODE1_SMI_L")
	)
	(segment
		(start 149.62378 -104.50576)
		(end 149.62378 -107.57535)
		(width 0.1143)
		(layer "In6.Cu")
		(net "USB_NODE1_SMI_L")
	)
	(segment
		(start 93.174312 -94.437708)
		(end 97.683574 -89.928446)
		(width 0.1143)
		(layer "In6.Cu")
		(net "USB_NODE1_SMI_L")
	)
	(segment
		(start 88.15324 -93.74505)
		(end 88.845898 -94.437708)
		(width 0.1143)
		(layer "In6.Cu")
		(net "USB_NODE1_SMI_L")
	)
	(segment
		(start 87.332312 -93.744288)
		(end 88.15324 -93.744288)
		(width 0.1143)
		(layer "In6.Cu")
		(net "USB_NODE1_SMI_L")
	)
	(segment
		(start 85.976206 -92.388182)
		(end 87.332312 -93.744288)
		(width 0.1143)
		(layer "In6.Cu")
		(net "USB_NODE1_SMI_L")
	)
	(segment
		(start 97.683574 -89.928446)
		(end 135.046466 -89.928446)
		(width 0.1143)
		(layer "In6.Cu")
		(net "USB_NODE1_SMI_L")
	)
	(segment
		(start 72.591676 -86.122002)
		(end 72.591676 -86.4235)
		(width 0.1143)
		(layer "In6.Cu")
		(net "USB_NODE1_SMI_L")
	)
	(segment
		(start 113.539778 -60.239148)
		(end 112.575848 -61.203078)
		(width 0.1016)
		(layer "F.Cu")
		(net "XDP_NODE1_P60")
	)
	(segment
		(start 111.872776 -61.90615)
		(end 112.575848 -61.203078)
		(width 0.1016)
		(layer "F.Cu")
		(net "XDP_NODE1_P60")
	)
	(segment
		(start 113.646204 -60.239148)
		(end 113.539778 -60.239148)
		(width 0.1016)
		(layer "F.Cu")
		(net "XDP_NODE1_P60")
	)
	(segment
		(start 110.460028 -61.90615)
		(end 111.872776 -61.90615)
		(width 0.1016)
		(layer "F.Cu")
		(net "XDP_NODE1_P60")
	)
	(via
		(at 112.575848 -61.203078)
		(size 0.508)
		(drill 0.254)
		(layers "F.Cu" "B.Cu")
		(net "XDP_NODE1_P60")
	)
	(via
		(at 33.757108 -100.293678)
		(size 0.6604)
		(drill 0.3302)
		(layers "F.Cu" "B.Cu")
		(net "P1V5_SUS_NODE1")
	)
	(via
		(at 35.162998 -110.72622)
		(size 0.508)
		(drill 0.254)
		(layers "F.Cu" "B.Cu")
		(net "P1V5_SUS_NODE1")
	)
	(via
		(at 33.615376 -101.924612)
		(size 0.6604)
		(drill 0.3302)
		(layers "F.Cu" "B.Cu")
		(net "P1V5_SUS_NODE1")
	)
	(via
		(at 32.161988 -101.964744)
		(size 0.6604)
		(drill 0.3302)
		(layers "F.Cu" "B.Cu")
		(net "P1V5_SUS_NODE1")
	)
	(via
		(at 36.90493 -102.714552)
		(size 0.508)
		(drill 0.254)
		(layers "F.Cu" "B.Cu")
		(net "P1V5_SUS_NODE1")
	)
	(via
		(at 35.343084 -101.804216)
		(size 0.6604)
		(drill 0.3302)
		(layers "F.Cu" "B.Cu")
		(net "P1V5_SUS_NODE1")
	)
	(via
		(at 34.335974 -102.138734)
		(size 0.508)
		(drill 0.254)
		(layers "F.Cu" "B.Cu")
		(net "P1V5_SUS_NODE1")
	)
	(via
		(at 36.029138 -102.06228)
		(size 0.508)
		(drill 0.254)
		(layers "F.Cu" "B.Cu")
		(net "P1V5_SUS_NODE1")
	)
	(via
		(at 36.902136 -101.982778)
		(size 0.508)
		(drill 0.254)
		(layers "F.Cu" "B.Cu")
		(net "P1V5_SUS_NODE1")
	)
	(via
		(at 35.162998 -111.36122)
		(size 0.508)
		(drill 0.254)
		(layers "F.Cu" "B.Cu")
		(net "P1V5_SUS_NODE1")
	)
	(via
		(at 35.023806 -102.450392)
		(size 0.508)
		(drill 0.254)
		(layers "F.Cu" "B.Cu")
		(net "P1V5_SUS_NODE1")
	)
	(via
		(at 35.162998 -111.99622)
		(size 0.508)
		(drill 0.254)
		(layers "F.Cu" "B.Cu")
		(net "P1V5_SUS_NODE1")
	)
	(via
		(at 54.137052 -69.643498)
		(size 0.508)
		(drill 0.254)
		(layers "F.Cu" "B.Cu")
		(net "P1V5_SUS_NODE1")
	)
	(via
		(at 36.0172 -102.738174)
		(size 0.508)
		(drill 0.254)
		(layers "F.Cu" "B.Cu")
		(net "P1V5_SUS_NODE1")
	)
	(via
		(at 34.312352 -102.88524)
		(size 0.508)
		(drill 0.254)
		(layers "F.Cu" "B.Cu")
		(net "P1V5_SUS_NODE1")
	)
	(segment
		(start 54.16931 -69.61124)
		(end 54.137052 -69.643498)
		(width 0.4572)
		(layer "B.Cu")
		(net "P1V5_SUS_NODE1")
	)
	(segment
		(start 54.336188 -70.502018)
		(end 54.087522 -69.693028)
		(width 0.381)
		(layer "B.Cu")
		(net "P1V5_SUS_NODE1")
	)
	(segment
		(start 54.087522 -69.693028)
		(end 54.137052 -69.643498)
		(width 0.381)
		(layer "B.Cu")
		(net "P1V5_SUS_NODE1")
	)
	(segment
		(start 54.16931 -68.90512)
		(end 54.16931 -69.61124)
		(width 0.4572)
		(layer "B.Cu")
		(net "P1V5_SUS_NODE1")
	)
	(segment
		(start 59.517026 -85.762846)
		(end 59.505088 -85.762846)
		(width 0.1143)
		(layer "F.Cu")
		(net "TP_CPU_NODE1_RSVD_MVT1")
	)
	(segment
		(start 59.505088 -85.762846)
		(end 59.132216 -85.389974)
		(width 0.1143)
		(layer "F.Cu")
		(net "TP_CPU_NODE1_RSVD_MVT1")
	)
	(via
		(at 59.149742 -87.108284)
		(size 0.6604)
		(drill 0.3302)
		(layers "F.Cu" "B.Cu")
		(net "TP_CPU_NODE1_RSVD_MVT1")
	)
	(via
		(at 59.132216 -85.389974)
		(size 0.508)
		(drill 0.254)
		(layers "F.Cu" "B.Cu")
		(net "TP_CPU_NODE1_RSVD_MVT1")
	)
	(segment
		(start 59.22518 -87.032846)
		(end 59.289442 -87.032846)
		(width 0.1016)
		(layer "B.Cu")
		(net "TP_CPU_NODE1_RSVD_MVT1")
	)
	(segment
		(start 59.289442 -87.032846)
		(end 59.60237 -86.719918)
		(width 0.1016)
		(layer "B.Cu")
		(net "TP_CPU_NODE1_RSVD_MVT1")
	)
	(segment
		(start 59.149742 -87.108284)
		(end 59.22518 -87.032846)
		(width 0.1016)
		(layer "B.Cu")
		(net "TP_CPU_NODE1_RSVD_MVT1")
	)
	(segment
		(start 59.60237 -86.719918)
		(end 59.60237 -85.85073)
		(width 0.1016)
		(layer "B.Cu")
		(net "TP_CPU_NODE1_RSVD_MVT1")
	)
	(segment
		(start 59.60237 -85.85073)
		(end 59.141614 -85.389974)
		(width 0.1016)
		(layer "B.Cu")
		(net "TP_CPU_NODE1_RSVD_MVT1")
	)
	(segment
		(start 59.141614 -85.389974)
		(end 59.132216 -85.389974)
		(width 0.1016)
		(layer "B.Cu")
		(net "TP_CPU_NODE1_RSVD_MVT1")
	)
	(via
		(at 38.238938 -116.678202)
		(size 0.508)
		(drill 0.254)
		(layers "F.Cu" "B.Cu")
		(net "FM_CPLD_NODE1_P1V5_EN_LV")
	)
	(segment
		(start 161.221928 -91.276678)
		(end 161.221928 -95.409512)
		(width 0.1016)
		(layer "F.Cu")
		(net "SPI_USB_NODE1_CSB_N")
	)
	(segment
		(start 161.831528 -91.276678)
		(end 161.652966 -91.098116)
		(width 0.1016)
		(layer "F.Cu")
		(net "SPI_USB_NODE1_CSB_N")
	)
	(segment
		(start 160.433766 -91.11615)
		(end 160.18129 -91.11615)
		(width 0.1016)
		(layer "F.Cu")
		(net "SPI_USB_NODE1_CSB_N")
	)
	(segment
		(start 158.523432 -95.520002)
		(end 158.259018 -95.520002)
		(width 0.1016)
		(layer "F.Cu")
		(net "SPI_USB_NODE1_CSB_N")
	)
	(segment
		(start 162.01009 -93.440758)
		(end 161.831528 -93.262196)
		(width 0.1016)
		(layer "F.Cu")
		(net "SPI_USB_NODE1_CSB_N")
	)
	(segment
		(start 160.79089 -95.588074)
		(end 160.612328 -95.409512)
		(width 0.1016)
		(layer "F.Cu")
		(net "SPI_USB_NODE1_CSB_N")
	)
	(segment
		(start 160.002728 -95.409512)
		(end 159.824166 -95.588074)
		(width 0.1016)
		(layer "F.Cu")
		(net "SPI_USB_NODE1_CSB_N")
	)
	(segment
		(start 158.040832 -90.522806)
		(end 157.641798 -90.123772)
		(width 0.1016)
		(layer "F.Cu")
		(net "SPI_USB_NODE1_CSB_N")
	)
	(segment
		(start 160.612328 -91.294712)
		(end 160.433766 -91.11615)
		(width 0.1016)
		(layer "F.Cu")
		(net "SPI_USB_NODE1_CSB_N")
	)
	(segment
		(start 161.221928 -95.409512)
		(end 161.043366 -95.588074)
		(width 0.1016)
		(layer "F.Cu")
		(net "SPI_USB_NODE1_CSB_N")
	)
	(segment
		(start 161.043366 -95.588074)
		(end 160.79089 -95.588074)
		(width 0.1016)
		(layer "F.Cu")
		(net "SPI_USB_NODE1_CSB_N")
	)
	(segment
		(start 158.783528 -95.259906)
		(end 158.523432 -95.520002)
		(width 0.1016)
		(layer "F.Cu")
		(net "SPI_USB_NODE1_CSB_N")
	)
	(segment
		(start 162.873944 -93.440758)
		(end 162.01009 -93.440758)
		(width 0.1016)
		(layer "F.Cu")
		(net "SPI_USB_NODE1_CSB_N")
	)
	(segment
		(start 158.783528 -91.640406)
		(end 158.783528 -95.259906)
		(width 0.1016)
		(layer "F.Cu")
		(net "SPI_USB_NODE1_CSB_N")
	)
	(segment
		(start 157.641798 -90.123772)
		(end 157.119574 -90.123772)
		(width 0.1016)
		(layer "F.Cu")
		(net "SPI_USB_NODE1_CSB_N")
	)
	(segment
		(start 160.002728 -91.294712)
		(end 160.002728 -95.409512)
		(width 0.1016)
		(layer "F.Cu")
		(net "SPI_USB_NODE1_CSB_N")
	)
	(segment
		(start 160.18129 -91.11615)
		(end 160.002728 -91.294712)
		(width 0.1016)
		(layer "F.Cu")
		(net "SPI_USB_NODE1_CSB_N")
	)
	(segment
		(start 160.612328 -95.409512)
		(end 160.612328 -91.294712)
		(width 0.1016)
		(layer "F.Cu")
		(net "SPI_USB_NODE1_CSB_N")
	)
	(segment
		(start 158.040832 -95.301816)
		(end 158.040832 -90.522806)
		(width 0.1016)
		(layer "F.Cu")
		(net "SPI_USB_NODE1_CSB_N")
	)
	(segment
		(start 159.393128 -91.640406)
		(end 159.214566 -91.461844)
		(width 0.1016)
		(layer "F.Cu")
		(net "SPI_USB_NODE1_CSB_N")
	)
	(segment
		(start 161.40049 -91.098116)
		(end 161.221928 -91.276678)
		(width 0.1016)
		(layer "F.Cu")
		(net "SPI_USB_NODE1_CSB_N")
	)
	(segment
		(start 159.57169 -95.588074)
		(end 159.393128 -95.409512)
		(width 0.1016)
		(layer "F.Cu")
		(net "SPI_USB_NODE1_CSB_N")
	)
	(segment
		(start 159.393128 -95.409512)
		(end 159.393128 -91.640406)
		(width 0.1016)
		(layer "F.Cu")
		(net "SPI_USB_NODE1_CSB_N")
	)
	(segment
		(start 159.214566 -91.461844)
		(end 158.96209 -91.461844)
		(width 0.1016)
		(layer "F.Cu")
		(net "SPI_USB_NODE1_CSB_N")
	)
	(segment
		(start 155.86456 -90.123772)
		(end 157.119574 -90.123772)
		(width 0.1016)
		(layer "F.Cu")
		(net "SPI_USB_NODE1_CSB_N")
	)
	(segment
		(start 158.259018 -95.520002)
		(end 158.040832 -95.301816)
		(width 0.1016)
		(layer "F.Cu")
		(net "SPI_USB_NODE1_CSB_N")
	)
	(segment
		(start 159.824166 -95.588074)
		(end 159.57169 -95.588074)
		(width 0.1016)
		(layer "F.Cu")
		(net "SPI_USB_NODE1_CSB_N")
	)
	(segment
		(start 161.831528 -93.262196)
		(end 161.831528 -91.276678)
		(width 0.1016)
		(layer "F.Cu")
		(net "SPI_USB_NODE1_CSB_N")
	)
	(segment
		(start 158.96209 -91.461844)
		(end 158.783528 -91.640406)
		(width 0.1016)
		(layer "F.Cu")
		(net "SPI_USB_NODE1_CSB_N")
	)
	(segment
		(start 161.652966 -91.098116)
		(end 161.40049 -91.098116)
		(width 0.1016)
		(layer "F.Cu")
		(net "SPI_USB_NODE1_CSB_N")
	)
	(via
		(at 157.119574 -90.123772)
		(size 0.508)
		(drill 0.254)
		(layers "F.Cu" "B.Cu")
		(net "SPI_USB_NODE1_CSB_N")
	)
	(segment
		(start 108.757974 -72.905874)
		(end 108.688886 -72.836786)
		(width 0.1016)
		(layer "F.Cu")
		(net "XDP_CPU_NODE1_VISA12")
	)
	(segment
		(start 110.460028 -72.905874)
		(end 108.757974 -72.905874)
		(width 0.1016)
		(layer "F.Cu")
		(net "XDP_CPU_NODE1_VISA12")
	)
	(segment
		(start 70.202044 -73.583038)
		(end 70.202044 -73.512426)
		(width 0.1016)
		(layer "F.Cu")
		(net "XDP_CPU_NODE1_VISA12")
	)
	(segment
		(start 110.460028 -72.906128)
		(end 110.460028 -72.905874)
		(width 0.1016)
		(layer "F.Cu")
		(net "XDP_CPU_NODE1_VISA12")
	)
	(segment
		(start 70.202044 -73.512426)
		(end 70.845172 -72.869298)
		(width 0.1016)
		(layer "F.Cu")
		(net "XDP_CPU_NODE1_VISA12")
	)
	(via
		(at 70.845172 -72.869298)
		(size 0.508)
		(drill 0.254)
		(layers "F.Cu" "B.Cu")
		(net "XDP_CPU_NODE1_VISA12")
	)
	(via
		(at 108.688886 -72.836786)
		(size 0.508)
		(drill 0.254)
		(layers "F.Cu" "B.Cu")
		(net "XDP_CPU_NODE1_VISA12")
	)
	(segment
		(start 72.330818 -72.869298)
		(end 72.506332 -73.044812)
		(width 0.1143)
		(layer "In2.Cu")
		(net "XDP_CPU_NODE1_VISA12")
	)
	(segment
		(start 106.581702 -68.406264)
		(end 107.717082 -68.406264)
		(width 0.1143)
		(layer "In2.Cu")
		(net "XDP_CPU_NODE1_VISA12")
	)
	(segment
		(start 108.523532 -69.342254)
		(end 108.208572 -69.657214)
		(width 0.1143)
		(layer "In2.Cu")
		(net "XDP_CPU_NODE1_VISA12")
	)
	(segment
		(start 109.239812 -73.451974)
		(end 109.146086 -73.5457)
		(width 0.1143)
		(layer "In2.Cu")
		(net "XDP_CPU_NODE1_VISA12")
	)
	(segment
		(start 103.210614 -66.850514)
		(end 103.46436 -66.596768)
		(width 0.1143)
		(layer "In2.Cu")
		(net "XDP_CPU_NODE1_VISA12")
	)
	(segment
		(start 108.493052 -73.380854)
		(end 108.493052 -73.03262)
		(width 0.1143)
		(layer "In2.Cu")
		(net "XDP_CPU_NODE1_VISA12")
	)
	(segment
		(start 108.971334 -70.683374)
		(end 109.239812 -70.951852)
		(width 0.1143)
		(layer "In2.Cu")
		(net "XDP_CPU_NODE1_VISA12")
	)
	(segment
		(start 105.24363 -66.850514)
		(end 106.35488 -67.961764)
		(width 0.1143)
		(layer "In2.Cu")
		(net "XDP_CPU_NODE1_VISA12")
	)
	(segment
		(start 99.949508 -66.850514)
		(end 103.210614 -66.850514)
		(width 0.1143)
		(layer "In2.Cu")
		(net "XDP_CPU_NODE1_VISA12")
	)
	(segment
		(start 91.041474 -65.286128)
		(end 91.567508 -64.760094)
		(width 0.1143)
		(layer "In2.Cu")
		(net "XDP_CPU_NODE1_VISA12")
	)
	(segment
		(start 91.567508 -64.760094)
		(end 98.412046 -64.760094)
		(width 0.1143)
		(layer "In2.Cu")
		(net "XDP_CPU_NODE1_VISA12")
	)
	(segment
		(start 109.097826 -73.594214)
		(end 108.706412 -73.594214)
		(width 0.1143)
		(layer "In2.Cu")
		(net "XDP_CPU_NODE1_VISA12")
	)
	(segment
		(start 105.24363 -66.045842)
		(end 105.061258 -66.228214)
		(width 0.1143)
		(layer "In2.Cu")
		(net "XDP_CPU_NODE1_VISA12")
	)
	(segment
		(start 106.35488 -67.961764)
		(end 106.35488 -68.179442)
		(width 0.1143)
		(layer "In2.Cu")
		(net "XDP_CPU_NODE1_VISA12")
	)
	(segment
		(start 104.1654 -66.668142)
		(end 104.347772 -66.850514)
		(width 0.1143)
		(layer "In2.Cu")
		(net "XDP_CPU_NODE1_VISA12")
	)
	(segment
		(start 108.493052 -73.03262)
		(end 108.688886 -72.836786)
		(width 0.1143)
		(layer "In2.Cu")
		(net "XDP_CPU_NODE1_VISA12")
	)
	(segment
		(start 98.412046 -64.760094)
		(end 98.95078 -65.298828)
		(width 0.1143)
		(layer "In2.Cu")
		(net "XDP_CPU_NODE1_VISA12")
	)
	(segment
		(start 70.845172 -72.869298)
		(end 72.330818 -72.869298)
		(width 0.1143)
		(layer "In2.Cu")
		(net "XDP_CPU_NODE1_VISA12")
	)
	(segment
		(start 108.208572 -69.657214)
		(end 108.208572 -70.383654)
		(width 0.1143)
		(layer "In2.Cu")
		(net "XDP_CPU_NODE1_VISA12")
	)
	(segment
		(start 78.987904 -70.396862)
		(end 78.989682 -70.395084)
		(width 0.1143)
		(layer "In2.Cu")
		(net "XDP_CPU_NODE1_VISA12")
	)
	(segment
		(start 74.35215 -70.753224)
		(end 75.81138 -70.753224)
		(width 0.1143)
		(layer "In2.Cu")
		(net "XDP_CPU_NODE1_VISA12")
	)
	(segment
		(start 104.347772 -66.850514)
		(end 105.24363 -66.850514)
		(width 0.1143)
		(layer "In2.Cu")
		(net "XDP_CPU_NODE1_VISA12")
	)
	(segment
		(start 98.95078 -65.298828)
		(end 98.95078 -65.851786)
		(width 0.1143)
		(layer "In2.Cu")
		(net "XDP_CPU_NODE1_VISA12")
	)
	(segment
		(start 104.1654 -66.410586)
		(end 104.1654 -66.668142)
		(width 0.1143)
		(layer "In2.Cu")
		(net "XDP_CPU_NODE1_VISA12")
	)
	(segment
		(start 105.24363 -65.788286)
		(end 105.24363 -66.045842)
		(width 0.1143)
		(layer "In2.Cu")
		(net "XDP_CPU_NODE1_VISA12")
	)
	(segment
		(start 109.239812 -71.945754)
		(end 109.074712 -72.110854)
		(width 0.1143)
		(layer "In2.Cu")
		(net "XDP_CPU_NODE1_VISA12")
	)
	(segment
		(start 72.506332 -73.044812)
		(end 72.848724 -73.044812)
		(width 0.1143)
		(layer "In2.Cu")
		(net "XDP_CPU_NODE1_VISA12")
	)
	(segment
		(start 108.523532 -68.737734)
		(end 108.523532 -69.342254)
		(width 0.1143)
		(layer "In2.Cu")
		(net "XDP_CPU_NODE1_VISA12")
	)
	(segment
		(start 72.848724 -73.044812)
		(end 73.090278 -72.803258)
		(width 0.1143)
		(layer "In2.Cu")
		(net "XDP_CPU_NODE1_VISA12")
	)
	(segment
		(start 109.074712 -72.110854)
		(end 109.074712 -72.377554)
		(width 0.1143)
		(layer "In2.Cu")
		(net "XDP_CPU_NODE1_VISA12")
	)
	(segment
		(start 107.717082 -68.406264)
		(end 107.896152 -68.585334)
		(width 0.1143)
		(layer "In2.Cu")
		(net "XDP_CPU_NODE1_VISA12")
	)
	(segment
		(start 107.896152 -68.585334)
		(end 108.371132 -68.585334)
		(width 0.1143)
		(layer "In2.Cu")
		(net "XDP_CPU_NODE1_VISA12")
	)
	(segment
		(start 109.239812 -72.542654)
		(end 109.239812 -73.451974)
		(width 0.1143)
		(layer "In2.Cu")
		(net "XDP_CPU_NODE1_VISA12")
	)
	(segment
		(start 109.074712 -72.377554)
		(end 109.239812 -72.542654)
		(width 0.1143)
		(layer "In2.Cu")
		(net "XDP_CPU_NODE1_VISA12")
	)
	(segment
		(start 73.090278 -72.015096)
		(end 74.35215 -70.753224)
		(width 0.1143)
		(layer "In2.Cu")
		(net "XDP_CPU_NODE1_VISA12")
	)
	(segment
		(start 98.95078 -65.851786)
		(end 99.949508 -66.850514)
		(width 0.1143)
		(layer "In2.Cu")
		(net "XDP_CPU_NODE1_VISA12")
	)
	(segment
		(start 105.061258 -65.605914)
		(end 105.24363 -65.788286)
		(width 0.1143)
		(layer "In2.Cu")
		(net "XDP_CPU_NODE1_VISA12")
	)
	(segment
		(start 109.146086 -73.545954)
		(end 109.097826 -73.594214)
		(width 0.1143)
		(layer "In2.Cu")
		(net "XDP_CPU_NODE1_VISA12")
	)
	(segment
		(start 75.81138 -70.753224)
		(end 76.167742 -70.396862)
		(width 0.1143)
		(layer "In2.Cu")
		(net "XDP_CPU_NODE1_VISA12")
	)
	(segment
		(start 78.989682 -70.395084)
		(end 80.580484 -70.395084)
		(width 0.1143)
		(layer "In2.Cu")
		(net "XDP_CPU_NODE1_VISA12")
	)
	(segment
		(start 76.167742 -70.396862)
		(end 78.987904 -70.396862)
		(width 0.1143)
		(layer "In2.Cu")
		(net "XDP_CPU_NODE1_VISA12")
	)
	(segment
		(start 109.146086 -73.5457)
		(end 109.146086 -73.545954)
		(width 0.1143)
		(layer "In2.Cu")
		(net "XDP_CPU_NODE1_VISA12")
	)
	(segment
		(start 108.371132 -68.585334)
		(end 108.523532 -68.737734)
		(width 0.1143)
		(layer "In2.Cu")
		(net "XDP_CPU_NODE1_VISA12")
	)
	(segment
		(start 105.061258 -66.228214)
		(end 104.347772 -66.228214)
		(width 0.1143)
		(layer "In2.Cu")
		(net "XDP_CPU_NODE1_VISA12")
	)
	(segment
		(start 108.706412 -73.594214)
		(end 108.493052 -73.380854)
		(width 0.1143)
		(layer "In2.Cu")
		(net "XDP_CPU_NODE1_VISA12")
	)
	(segment
		(start 103.575358 -65.605914)
		(end 105.061258 -65.605914)
		(width 0.1143)
		(layer "In2.Cu")
		(net "XDP_CPU_NODE1_VISA12")
	)
	(segment
		(start 108.208572 -70.383654)
		(end 108.508292 -70.683374)
		(width 0.1143)
		(layer "In2.Cu")
		(net "XDP_CPU_NODE1_VISA12")
	)
	(segment
		(start 109.239812 -70.951852)
		(end 109.239812 -71.945754)
		(width 0.1143)
		(layer "In2.Cu")
		(net "XDP_CPU_NODE1_VISA12")
	)
	(segment
		(start 103.46436 -65.716912)
		(end 103.575358 -65.605914)
		(width 0.1143)
		(layer "In2.Cu")
		(net "XDP_CPU_NODE1_VISA12")
	)
	(segment
		(start 104.347772 -66.228214)
		(end 104.1654 -66.410586)
		(width 0.1143)
		(layer "In2.Cu")
		(net "XDP_CPU_NODE1_VISA12")
	)
	(segment
		(start 103.46436 -66.596768)
		(end 103.46436 -65.716912)
		(width 0.1143)
		(layer "In2.Cu")
		(net "XDP_CPU_NODE1_VISA12")
	)
	(segment
		(start 108.508292 -70.683374)
		(end 108.971334 -70.683374)
		(width 0.1143)
		(layer "In2.Cu")
		(net "XDP_CPU_NODE1_VISA12")
	)
	(segment
		(start 85.68944 -65.286128)
		(end 91.041474 -65.286128)
		(width 0.1143)
		(layer "In2.Cu")
		(net "XDP_CPU_NODE1_VISA12")
	)
	(segment
		(start 73.090278 -72.803258)
		(end 73.090278 -72.015096)
		(width 0.1143)
		(layer "In2.Cu")
		(net "XDP_CPU_NODE1_VISA12")
	)
	(segment
		(start 80.580484 -70.395084)
		(end 85.68944 -65.286128)
		(width 0.1143)
		(layer "In2.Cu")
		(net "XDP_CPU_NODE1_VISA12")
	)
	(segment
		(start 106.35488 -68.179442)
		(end 106.581702 -68.406264)
		(width 0.1143)
		(layer "In2.Cu")
		(net "XDP_CPU_NODE1_VISA12")
	)
	(segment
		(start 179.433474 -116.942616)
		(end 179.433474 -115.184682)
		(width 0.1016)
		(layer "F.Cu")
		(net "FM_CPLD_NODE1_P1V5_EN")
	)
	(segment
		(start 33.744154 -117.535452)
		(end 33.744154 -116.518182)
		(width 0.1016)
		(layer "F.Cu")
		(net "FM_CPLD_NODE1_P1V5_EN")
	)
	(segment
		(start 34.3662 -118.984776)
		(end 34.407856 -118.94312)
		(width 0.1016)
		(layer "F.Cu")
		(net "FM_CPLD_NODE1_P1V5_EN")
	)
	(segment
		(start 33.932876 -118.551452)
		(end 34.3662 -118.984776)
		(width 0.1016)
		(layer "F.Cu")
		(net "FM_CPLD_NODE1_P1V5_EN")
	)
	(segment
		(start 33.744154 -118.551452)
		(end 33.932876 -118.551452)
		(width 0.1016)
		(layer "F.Cu")
		(net "FM_CPLD_NODE1_P1V5_EN")
	)
	(segment
		(start 33.744154 -118.551452)
		(end 33.744154 -117.535452)
		(width 0.1016)
		(layer "F.Cu")
		(net "FM_CPLD_NODE1_P1V5_EN")
	)
	(segment
		(start 179.010564 -117.365526)
		(end 179.433474 -116.942616)
		(width 0.1016)
		(layer "F.Cu")
		(net "FM_CPLD_NODE1_P1V5_EN")
	)
	(segment
		(start 179.433474 -115.184682)
		(end 174.494698 -110.245906)
		(width 0.1016)
		(layer "F.Cu")
		(net "FM_CPLD_NODE1_P1V5_EN")
	)
	(segment
		(start 174.494698 -110.245906)
		(end 159.58947 -110.245906)
		(width 0.1016)
		(layer "F.Cu")
		(net "FM_CPLD_NODE1_P1V5_EN")
	)
	(segment
		(start 34.407856 -118.94312)
		(end 35.24504 -118.94312)
		(width 0.1016)
		(layer "F.Cu")
		(net "FM_CPLD_NODE1_P1V5_EN")
	)
	(segment
		(start 159.58947 -110.245906)
		(end 154.77998 -115.055396)
		(width 0.1016)
		(layer "F.Cu")
		(net "FM_CPLD_NODE1_P1V5_EN")
	)
	(via
		(at 154.77998 -115.055396)
		(size 0.508)
		(drill 0.254)
		(layers "F.Cu" "B.Cu")
		(net "FM_CPLD_NODE1_P1V5_EN")
	)
	(via
		(at 34.3662 -118.984776)
		(size 0.508)
		(drill 0.254)
		(layers "F.Cu" "B.Cu")
		(net "FM_CPLD_NODE1_P1V5_EN")
	)
	(segment
		(start 133.23824 -112.013492)
		(end 132.87248 -112.013492)
		(width 0.1143)
		(layer "In6.Cu")
		(net "FM_CPLD_NODE1_P1V5_EN")
	)
	(segment
		(start 84.127594 -115.34267)
		(end 82.920586 -115.34267)
		(width 0.1143)
		(layer "In6.Cu")
		(net "FM_CPLD_NODE1_P1V5_EN")
	)
	(segment
		(start 94.770448 -116.392198)
		(end 85.177122 -116.392198)
		(width 0.1143)
		(layer "In6.Cu")
		(net "FM_CPLD_NODE1_P1V5_EN")
	)
	(segment
		(start 146.183604 -112.082326)
		(end 136.38276 -112.082326)
		(width 0.1143)
		(layer "In6.Cu")
		(net "FM_CPLD_NODE1_P1V5_EN")
	)
	(segment
		(start 153.679906 -115.055396)
		(end 153.46934 -115.265962)
		(width 0.1143)
		(layer "In6.Cu")
		(net "FM_CPLD_NODE1_P1V5_EN")
	)
	(segment
		(start 125.339602 -112.26546)
		(end 122.66549 -109.591348)
		(width 0.1143)
		(layer "In6.Cu")
		(net "FM_CPLD_NODE1_P1V5_EN")
	)
	(segment
		(start 153.46934 -115.265962)
		(end 149.36724 -115.265962)
		(width 0.1143)
		(layer "In6.Cu")
		(net "FM_CPLD_NODE1_P1V5_EN")
	)
	(segment
		(start 53.269388 -114.740944)
		(end 51.806094 -113.27765)
		(width 0.1143)
		(layer "In6.Cu")
		(net "FM_CPLD_NODE1_P1V5_EN")
	)
	(segment
		(start 154.77998 -115.055396)
		(end 153.679906 -115.055396)
		(width 0.1143)
		(layer "In6.Cu")
		(net "FM_CPLD_NODE1_P1V5_EN")
	)
	(segment
		(start 134.869428 -111.376714)
		(end 133.875018 -111.376714)
		(width 0.1143)
		(layer "In6.Cu")
		(net "FM_CPLD_NODE1_P1V5_EN")
	)
	(segment
		(start 101.571298 -109.591348)
		(end 94.770448 -116.392198)
		(width 0.1143)
		(layer "In6.Cu")
		(net "FM_CPLD_NODE1_P1V5_EN")
	)
	(segment
		(start 50.517806 -113.27765)
		(end 48.99406 -114.801396)
		(width 0.1143)
		(layer "In6.Cu")
		(net "FM_CPLD_NODE1_P1V5_EN")
	)
	(segment
		(start 40.113966 -119.679974)
		(end 37.90569 -119.679974)
		(width 0.1143)
		(layer "In6.Cu")
		(net "FM_CPLD_NODE1_P1V5_EN")
	)
	(segment
		(start 44.8818 -118.339108)
		(end 43.823128 -119.39778)
		(width 0.1143)
		(layer "In6.Cu")
		(net "FM_CPLD_NODE1_P1V5_EN")
	)
	(segment
		(start 37.43706 -119.211344)
		(end 34.592768 -119.211344)
		(width 0.1143)
		(layer "In6.Cu")
		(net "FM_CPLD_NODE1_P1V5_EN")
	)
	(segment
		(start 132.723128 -112.162844)
		(end 126.731776 -112.162844)
		(width 0.1143)
		(layer "In6.Cu")
		(net "FM_CPLD_NODE1_P1V5_EN")
	)
	(segment
		(start 85.177122 -116.392198)
		(end 84.127594 -115.34267)
		(width 0.1143)
		(layer "In6.Cu")
		(net "FM_CPLD_NODE1_P1V5_EN")
	)
	(segment
		(start 82.920586 -115.34267)
		(end 82.31886 -114.740944)
		(width 0.1143)
		(layer "In6.Cu")
		(net "FM_CPLD_NODE1_P1V5_EN")
	)
	(segment
		(start 40.39616 -119.39778)
		(end 40.113966 -119.679974)
		(width 0.1143)
		(layer "In6.Cu")
		(net "FM_CPLD_NODE1_P1V5_EN")
	)
	(segment
		(start 136.16178 -112.303306)
		(end 135.79602 -112.303306)
		(width 0.1143)
		(layer "In6.Cu")
		(net "FM_CPLD_NODE1_P1V5_EN")
	)
	(segment
		(start 126.62916 -112.26546)
		(end 125.339602 -112.26546)
		(width 0.1143)
		(layer "In6.Cu")
		(net "FM_CPLD_NODE1_P1V5_EN")
	)
	(segment
		(start 34.592768 -119.211344)
		(end 34.3662 -118.984776)
		(width 0.1143)
		(layer "In6.Cu")
		(net "FM_CPLD_NODE1_P1V5_EN")
	)
	(segment
		(start 149.36724 -115.265962)
		(end 146.183604 -112.082326)
		(width 0.1143)
		(layer "In6.Cu")
		(net "FM_CPLD_NODE1_P1V5_EN")
	)
	(segment
		(start 37.90569 -119.679974)
		(end 37.43706 -119.211344)
		(width 0.1143)
		(layer "In6.Cu")
		(net "FM_CPLD_NODE1_P1V5_EN")
	)
	(segment
		(start 82.31886 -114.740944)
		(end 53.269388 -114.740944)
		(width 0.1143)
		(layer "In6.Cu")
		(net "FM_CPLD_NODE1_P1V5_EN")
	)
	(segment
		(start 46.111922 -118.339108)
		(end 44.8818 -118.339108)
		(width 0.1143)
		(layer "In6.Cu")
		(net "FM_CPLD_NODE1_P1V5_EN")
	)
	(segment
		(start 135.79602 -112.303306)
		(end 134.869428 -111.376714)
		(width 0.1143)
		(layer "In6.Cu")
		(net "FM_CPLD_NODE1_P1V5_EN")
	)
	(segment
		(start 132.87248 -112.013492)
		(end 132.723128 -112.162844)
		(width 0.1143)
		(layer "In6.Cu")
		(net "FM_CPLD_NODE1_P1V5_EN")
	)
	(segment
		(start 136.38276 -112.082326)
		(end 136.16178 -112.303306)
		(width 0.1143)
		(layer "In6.Cu")
		(net "FM_CPLD_NODE1_P1V5_EN")
	)
	(segment
		(start 133.875018 -111.376714)
		(end 133.23824 -112.013492)
		(width 0.1143)
		(layer "In6.Cu")
		(net "FM_CPLD_NODE1_P1V5_EN")
	)
	(segment
		(start 122.66549 -109.591348)
		(end 101.571298 -109.591348)
		(width 0.1143)
		(layer "In6.Cu")
		(net "FM_CPLD_NODE1_P1V5_EN")
	)
	(segment
		(start 43.823128 -119.39778)
		(end 40.39616 -119.39778)
		(width 0.1143)
		(layer "In6.Cu")
		(net "FM_CPLD_NODE1_P1V5_EN")
	)
	(segment
		(start 48.99406 -114.801396)
		(end 48.99406 -115.45697)
		(width 0.1143)
		(layer "In6.Cu")
		(net "FM_CPLD_NODE1_P1V5_EN")
	)
	(segment
		(start 126.731776 -112.162844)
		(end 126.62916 -112.26546)
		(width 0.1143)
		(layer "In6.Cu")
		(net "FM_CPLD_NODE1_P1V5_EN")
	)
	(segment
		(start 48.99406 -115.45697)
		(end 46.111922 -118.339108)
		(width 0.1143)
		(layer "In6.Cu")
		(net "FM_CPLD_NODE1_P1V5_EN")
	)
	(segment
		(start 51.806094 -113.27765)
		(end 50.517806 -113.27765)
		(width 0.1143)
		(layer "In6.Cu")
		(net "FM_CPLD_NODE1_P1V5_EN")
	)
	(segment
		(start 69.770244 -74.757026)
		(end 69.498972 -75.028298)
		(width 0.1016)
		(layer "F.Cu")
		(net "XDP_CPU_NODE1_VISA13")
	)
	(segment
		(start 107.487212 -72.288654)
		(end 108.896912 -72.288654)
		(width 0.1016)
		(layer "F.Cu")
		(net "XDP_CPU_NODE1_VISA13")
	)
	(segment
		(start 69.440044 -73.583038)
		(end 69.770244 -73.913238)
		(width 0.1016)
		(layer "F.Cu")
		(net "XDP_CPU_NODE1_VISA13")
	)
	(segment
		(start 108.896912 -72.288654)
		(end 109.013752 -72.405494)
		(width 0.1016)
		(layer "F.Cu")
		(net "XDP_CPU_NODE1_VISA13")
	)
	(segment
		(start 110.460028 -72.405494)
		(end 110.460028 -72.406256)
		(width 0.1016)
		(layer "F.Cu")
		(net "XDP_CPU_NODE1_VISA13")
	)
	(segment
		(start 109.013752 -72.405494)
		(end 110.460028 -72.405494)
		(width 0.1016)
		(layer "F.Cu")
		(net "XDP_CPU_NODE1_VISA13")
	)
	(segment
		(start 69.770244 -73.913238)
		(end 69.770244 -74.757026)
		(width 0.1016)
		(layer "F.Cu")
		(net "XDP_CPU_NODE1_VISA13")
	)
	(via
		(at 107.487212 -72.288654)
		(size 0.508)
		(drill 0.254)
		(layers "F.Cu" "B.Cu")
		(net "XDP_CPU_NODE1_VISA13")
	)
	(via
		(at 69.498972 -75.028298)
		(size 0.508)
		(drill 0.254)
		(layers "F.Cu" "B.Cu")
		(net "XDP_CPU_NODE1_VISA13")
	)
	(segment
		(start 98.374454 -73.287636)
		(end 99.26066 -72.40143)
		(width 0.1143)
		(layer "In2.Cu")
		(net "XDP_CPU_NODE1_VISA13")
	)
	(segment
		(start 94.958662 -73.287636)
		(end 96.626172 -73.287636)
		(width 0.1143)
		(layer "In2.Cu")
		(net "XDP_CPU_NODE1_VISA13")
	)
	(segment
		(start 81.310988 -74.094086)
		(end 84.957666 -70.447408)
		(width 0.1143)
		(layer "In2.Cu")
		(net "XDP_CPU_NODE1_VISA13")
	)
	(segment
		(start 92.99067 -71.319644)
		(end 94.958662 -73.287636)
		(width 0.1143)
		(layer "In2.Cu")
		(net "XDP_CPU_NODE1_VISA13")
	)
	(segment
		(start 103.989124 -72.317102)
		(end 104.171496 -72.499474)
		(width 0.1143)
		(layer "In2.Cu")
		(net "XDP_CPU_NODE1_VISA13")
	)
	(segment
		(start 105.233724 -70.926706)
		(end 105.233724 -71.841868)
		(width 0.1143)
		(layer "In2.Cu")
		(net "XDP_CPU_NODE1_VISA13")
	)
	(segment
		(start 101.226112 -71.597774)
		(end 101.226112 -71.978012)
		(width 0.1143)
		(layer "In2.Cu")
		(net "XDP_CPU_NODE1_VISA13")
	)
	(segment
		(start 76.994004 -74.972926)
		(end 77.872844 -74.094086)
		(width 0.1143)
		(layer "In2.Cu")
		(net "XDP_CPU_NODE1_VISA13")
	)
	(segment
		(start 99.26066 -72.40143)
		(end 99.26066 -71.66864)
		(width 0.1143)
		(layer "In2.Cu")
		(net "XDP_CPU_NODE1_VISA13")
	)
	(segment
		(start 104.611424 -72.317102)
		(end 104.611424 -70.926706)
		(width 0.1143)
		(layer "In2.Cu")
		(net "XDP_CPU_NODE1_VISA13")
	)
	(segment
		(start 100.875846 -71.247508)
		(end 101.226112 -71.597774)
		(width 0.1143)
		(layer "In2.Cu")
		(net "XDP_CPU_NODE1_VISA13")
	)
	(segment
		(start 104.611424 -70.926706)
		(end 104.793796 -70.744334)
		(width 0.1143)
		(layer "In2.Cu")
		(net "XDP_CPU_NODE1_VISA13")
	)
	(segment
		(start 101.226112 -71.978012)
		(end 101.564694 -72.316594)
		(width 0.1143)
		(layer "In2.Cu")
		(net "XDP_CPU_NODE1_VISA13")
	)
	(segment
		(start 70.403974 -75.550014)
		(end 70.482968 -75.47102)
		(width 0.1143)
		(layer "In2.Cu")
		(net "XDP_CPU_NODE1_VISA13")
	)
	(segment
		(start 74.513186 -74.972926)
		(end 76.994004 -74.972926)
		(width 0.1143)
		(layer "In2.Cu")
		(net "XDP_CPU_NODE1_VISA13")
	)
	(segment
		(start 99.681792 -71.247508)
		(end 100.875846 -71.247508)
		(width 0.1143)
		(layer "In2.Cu")
		(net "XDP_CPU_NODE1_VISA13")
	)
	(segment
		(start 96.808544 -73.919588)
		(end 96.990916 -74.10196)
		(width 0.1143)
		(layer "In2.Cu")
		(net "XDP_CPU_NODE1_VISA13")
	)
	(segment
		(start 101.564694 -72.316594)
		(end 103.253032 -72.316594)
		(width 0.1143)
		(layer "In2.Cu")
		(net "XDP_CPU_NODE1_VISA13")
	)
	(segment
		(start 70.482968 -75.47102)
		(end 74.015092 -75.47102)
		(width 0.1143)
		(layer "In2.Cu")
		(net "XDP_CPU_NODE1_VISA13")
	)
	(segment
		(start 107.487212 -72.288146)
		(end 107.487212 -72.288654)
		(width 0.1143)
		(layer "In2.Cu")
		(net "XDP_CPU_NODE1_VISA13")
	)
	(segment
		(start 89.453466 -71.319644)
		(end 92.99067 -71.319644)
		(width 0.1143)
		(layer "In2.Cu")
		(net "XDP_CPU_NODE1_VISA13")
	)
	(segment
		(start 97.430844 -73.470008)
		(end 97.613216 -73.287636)
		(width 0.1143)
		(layer "In2.Cu")
		(net "XDP_CPU_NODE1_VISA13")
	)
	(segment
		(start 107.278932 -72.079866)
		(end 107.487212 -72.288146)
		(width 0.1143)
		(layer "In2.Cu")
		(net "XDP_CPU_NODE1_VISA13")
	)
	(segment
		(start 105.471722 -72.079866)
		(end 107.278932 -72.079866)
		(width 0.1143)
		(layer "In2.Cu")
		(net "XDP_CPU_NODE1_VISA13")
	)
	(segment
		(start 103.549196 -70.744334)
		(end 103.806752 -70.744334)
		(width 0.1143)
		(layer "In2.Cu")
		(net "XDP_CPU_NODE1_VISA13")
	)
	(segment
		(start 103.366824 -72.202802)
		(end 103.366824 -70.926706)
		(width 0.1143)
		(layer "In2.Cu")
		(net "XDP_CPU_NODE1_VISA13")
	)
	(segment
		(start 96.808544 -73.470008)
		(end 96.808544 -73.919588)
		(width 0.1143)
		(layer "In2.Cu")
		(net "XDP_CPU_NODE1_VISA13")
	)
	(segment
		(start 96.626172 -73.287636)
		(end 96.808544 -73.470008)
		(width 0.1143)
		(layer "In2.Cu")
		(net "XDP_CPU_NODE1_VISA13")
	)
	(segment
		(start 69.875654 -75.550014)
		(end 70.403974 -75.550014)
		(width 0.1143)
		(layer "In2.Cu")
		(net "XDP_CPU_NODE1_VISA13")
	)
	(segment
		(start 103.253032 -72.316594)
		(end 103.366824 -72.202802)
		(width 0.1143)
		(layer "In2.Cu")
		(net "XDP_CPU_NODE1_VISA13")
	)
	(segment
		(start 104.429052 -72.499474)
		(end 104.611424 -72.317102)
		(width 0.1143)
		(layer "In2.Cu")
		(net "XDP_CPU_NODE1_VISA13")
	)
	(segment
		(start 104.793796 -70.744334)
		(end 105.051352 -70.744334)
		(width 0.1143)
		(layer "In2.Cu")
		(net "XDP_CPU_NODE1_VISA13")
	)
	(segment
		(start 99.26066 -71.66864)
		(end 99.681792 -71.247508)
		(width 0.1143)
		(layer "In2.Cu")
		(net "XDP_CPU_NODE1_VISA13")
	)
	(segment
		(start 97.248472 -74.10196)
		(end 97.430844 -73.919588)
		(width 0.1143)
		(layer "In2.Cu")
		(net "XDP_CPU_NODE1_VISA13")
	)
	(segment
		(start 97.613216 -73.287636)
		(end 98.374454 -73.287636)
		(width 0.1143)
		(layer "In2.Cu")
		(net "XDP_CPU_NODE1_VISA13")
	)
	(segment
		(start 103.366824 -70.926706)
		(end 103.549196 -70.744334)
		(width 0.1143)
		(layer "In2.Cu")
		(net "XDP_CPU_NODE1_VISA13")
	)
	(segment
		(start 105.051352 -70.744334)
		(end 105.233724 -70.926706)
		(width 0.1143)
		(layer "In2.Cu")
		(net "XDP_CPU_NODE1_VISA13")
	)
	(segment
		(start 88.58123 -70.447408)
		(end 89.453466 -71.319644)
		(width 0.1143)
		(layer "In2.Cu")
		(net "XDP_CPU_NODE1_VISA13")
	)
	(segment
		(start 96.990916 -74.10196)
		(end 97.248472 -74.10196)
		(width 0.1143)
		(layer "In2.Cu")
		(net "XDP_CPU_NODE1_VISA13")
	)
	(segment
		(start 104.171496 -72.499474)
		(end 104.429052 -72.499474)
		(width 0.1143)
		(layer "In2.Cu")
		(net "XDP_CPU_NODE1_VISA13")
	)
	(segment
		(start 103.806752 -70.744334)
		(end 103.989124 -70.926706)
		(width 0.1143)
		(layer "In2.Cu")
		(net "XDP_CPU_NODE1_VISA13")
	)
	(segment
		(start 69.498972 -75.173332)
		(end 69.875654 -75.550014)
		(width 0.1143)
		(layer "In2.Cu")
		(net "XDP_CPU_NODE1_VISA13")
	)
	(segment
		(start 84.957666 -70.447408)
		(end 88.58123 -70.447408)
		(width 0.1143)
		(layer "In2.Cu")
		(net "XDP_CPU_NODE1_VISA13")
	)
	(segment
		(start 77.872844 -74.094086)
		(end 81.310988 -74.094086)
		(width 0.1143)
		(layer "In2.Cu")
		(net "XDP_CPU_NODE1_VISA13")
	)
	(segment
		(start 69.498972 -75.028298)
		(end 69.498972 -75.173332)
		(width 0.1143)
		(layer "In2.Cu")
		(net "XDP_CPU_NODE1_VISA13")
	)
	(segment
		(start 97.430844 -73.919588)
		(end 97.430844 -73.470008)
		(width 0.1143)
		(layer "In2.Cu")
		(net "XDP_CPU_NODE1_VISA13")
	)
	(segment
		(start 105.233724 -71.841868)
		(end 105.471722 -72.079866)
		(width 0.1143)
		(layer "In2.Cu")
		(net "XDP_CPU_NODE1_VISA13")
	)
	(segment
		(start 74.015092 -75.47102)
		(end 74.513186 -74.972926)
		(width 0.1143)
		(layer "In2.Cu")
		(net "XDP_CPU_NODE1_VISA13")
	)
	(segment
		(start 103.989124 -70.926706)
		(end 103.989124 -72.317102)
		(width 0.1143)
		(layer "In2.Cu")
		(net "XDP_CPU_NODE1_VISA13")
	)
	(segment
		(start 37.14496 -119.916194)
		(end 37.14496 -118.94312)
		(width 0.1016)
		(layer "F.Cu")
		(net "FM_CPLD_NODE1_P1V5_EN_G")
	)
	(segment
		(start 34.154872 -119.567452)
		(end 34.61766 -120.03024)
		(width 0.1016)
		(layer "F.Cu")
		(net "FM_CPLD_NODE1_P1V5_EN_G")
	)
	(segment
		(start 33.744154 -119.567452)
		(end 34.154872 -119.567452)
		(width 0.1016)
		(layer "F.Cu")
		(net "FM_CPLD_NODE1_P1V5_EN_G")
	)
	(segment
		(start 37.030914 -120.03024)
		(end 37.14496 -119.916194)
		(width 0.1016)
		(layer "F.Cu")
		(net "FM_CPLD_NODE1_P1V5_EN_G")
	)
	(segment
		(start 34.61766 -120.03024)
		(end 37.030914 -120.03024)
		(width 0.1016)
		(layer "F.Cu")
		(net "FM_CPLD_NODE1_P1V5_EN_G")
	)
	(via
		(at 37.14496 -119.916194)
		(size 0.508)
		(drill 0.254)
		(layers "F.Cu" "B.Cu")
		(net "FM_CPLD_NODE1_P1V5_EN_G")
	)
	(segment
		(start 71.403972 -70.711314)
		(end 71.568818 -70.546468)
		(width 0.1016)
		(layer "F.Cu")
		(net "XDP_CPU_NODE1_VISA5")
	)
	(segment
		(start 102.574852 -70.137274)
		(end 101.139752 -68.702174)
		(width 0.1016)
		(layer "F.Cu")
		(net "XDP_CPU_NODE1_VISA5")
	)
	(segment
		(start 104.73182 -69.906388)
		(end 103.555038 -69.906388)
		(width 0.1016)
		(layer "F.Cu")
		(net "XDP_CPU_NODE1_VISA5")
	)
	(segment
		(start 102.237032 -64.437514)
		(end 102.348792 -64.325754)
		(width 0.1016)
		(layer "F.Cu")
		(net "XDP_CPU_NODE1_VISA5")
	)
	(segment
		(start 102.237032 -66.408554)
		(end 102.237032 -64.437514)
		(width 0.1016)
		(layer "F.Cu")
		(net "XDP_CPU_NODE1_VISA5")
	)
	(segment
		(start 103.555038 -69.906388)
		(end 103.324152 -70.137274)
		(width 0.1016)
		(layer "F.Cu")
		(net "XDP_CPU_NODE1_VISA5")
	)
	(segment
		(start 71.345044 -71.596758)
		(end 71.403972 -71.53783)
		(width 0.1016)
		(layer "F.Cu")
		(net "XDP_CPU_NODE1_VISA5")
	)
	(segment
		(start 101.139752 -67.505834)
		(end 102.237032 -66.408554)
		(width 0.1016)
		(layer "F.Cu")
		(net "XDP_CPU_NODE1_VISA5")
	)
	(segment
		(start 103.324152 -70.137274)
		(end 102.574852 -70.137274)
		(width 0.1016)
		(layer "F.Cu")
		(net "XDP_CPU_NODE1_VISA5")
	)
	(segment
		(start 101.139752 -68.702174)
		(end 101.139752 -67.505834)
		(width 0.1016)
		(layer "F.Cu")
		(net "XDP_CPU_NODE1_VISA5")
	)
	(segment
		(start 71.403972 -71.53783)
		(end 71.403972 -70.711314)
		(width 0.1016)
		(layer "F.Cu")
		(net "XDP_CPU_NODE1_VISA5")
	)
	(via
		(at 102.348792 -64.325754)
		(size 0.508)
		(drill 0.254)
		(layers "F.Cu" "B.Cu")
		(net "XDP_CPU_NODE1_VISA5")
	)
	(via
		(at 71.568818 -70.546468)
		(size 0.508)
		(drill 0.254)
		(layers "F.Cu" "B.Cu")
		(net "XDP_CPU_NODE1_VISA5")
	)
	(segment
		(start 101.124004 -59.933332)
		(end 101.382068 -59.933332)
		(width 0.1143)
		(layer "In2.Cu")
		(net "XDP_CPU_NODE1_VISA5")
	)
	(segment
		(start 101.564186 -60.373514)
		(end 101.49205 -60.44565)
		(width 0.1143)
		(layer "In2.Cu")
		(net "XDP_CPU_NODE1_VISA5")
	)
	(segment
		(start 88.668098 -59.234578)
		(end 91.37396 -59.234578)
		(width 0.1143)
		(layer "In2.Cu")
		(net "XDP_CPU_NODE1_VISA5")
	)
	(segment
		(start 102.004368 -60.813696)
		(end 102.262432 -60.813696)
		(width 0.1143)
		(layer "In2.Cu")
		(net "XDP_CPU_NODE1_VISA5")
	)
	(segment
		(start 99.68738 -60.659772)
		(end 102.181152 -63.153544)
		(width 0.1143)
		(layer "In2.Cu")
		(net "XDP_CPU_NODE1_VISA5")
	)
	(segment
		(start 73.448418 -68.66001)
		(end 76.69784 -68.66001)
		(width 0.1143)
		(layer "In2.Cu")
		(net "XDP_CPU_NODE1_VISA5")
	)
	(segment
		(start 101.382068 -59.933332)
		(end 101.564186 -60.11545)
		(width 0.1143)
		(layer "In2.Cu")
		(net "XDP_CPU_NODE1_VISA5")
	)
	(segment
		(start 102.44455 -60.995814)
		(end 102.44455 -61.253878)
		(width 0.1143)
		(layer "In2.Cu")
		(net "XDP_CPU_NODE1_VISA5")
	)
	(segment
		(start 100.793804 -60.005468)
		(end 101.051868 -60.005468)
		(width 0.1143)
		(layer "In2.Cu")
		(net "XDP_CPU_NODE1_VISA5")
	)
	(segment
		(start 76.837286 -68.520564)
		(end 77.889608 -68.520564)
		(width 0.1143)
		(layer "In2.Cu")
		(net "XDP_CPU_NODE1_VISA5")
	)
	(segment
		(start 103.32593 -62.79515)
		(end 103.143304 -62.977522)
		(width 0.1143)
		(layer "In2.Cu")
		(net "XDP_CPU_NODE1_VISA5")
	)
	(segment
		(start 99.869498 -60.21959)
		(end 99.68738 -60.401708)
		(width 0.1143)
		(layer "In2.Cu")
		(net "XDP_CPU_NODE1_VISA5")
	)
	(segment
		(start 71.568818 -70.546468)
		(end 71.568818 -70.53961)
		(width 0.1143)
		(layer "In2.Cu")
		(net "XDP_CPU_NODE1_VISA5")
	)
	(segment
		(start 102.885494 -62.977522)
		(end 100.127562 -60.21959)
		(width 0.1143)
		(layer "In2.Cu")
		(net "XDP_CPU_NODE1_VISA5")
	)
	(segment
		(start 103.143304 -62.977522)
		(end 102.885494 -62.977522)
		(width 0.1143)
		(layer "In2.Cu")
		(net "XDP_CPU_NODE1_VISA5")
	)
	(segment
		(start 101.932232 -60.885832)
		(end 102.004368 -60.813696)
		(width 0.1143)
		(layer "In2.Cu")
		(net "XDP_CPU_NODE1_VISA5")
	)
	(segment
		(start 103.32593 -62.537594)
		(end 103.32593 -62.79515)
		(width 0.1143)
		(layer "In2.Cu")
		(net "XDP_CPU_NODE1_VISA5")
	)
	(segment
		(start 100.430584 -59.642248)
		(end 100.793804 -60.005468)
		(width 0.1143)
		(layer "In2.Cu")
		(net "XDP_CPU_NODE1_VISA5")
	)
	(segment
		(start 77.889608 -68.520564)
		(end 78.781656 -67.628516)
		(width 0.1143)
		(layer "In2.Cu")
		(net "XDP_CPU_NODE1_VISA5")
	)
	(segment
		(start 101.49205 -60.44565)
		(end 101.49205 -60.703714)
		(width 0.1143)
		(layer "In2.Cu")
		(net "XDP_CPU_NODE1_VISA5")
	)
	(segment
		(start 71.568818 -70.53961)
		(end 73.448418 -68.66001)
		(width 0.1143)
		(layer "In2.Cu")
		(net "XDP_CPU_NODE1_VISA5")
	)
	(segment
		(start 102.372414 -61.326014)
		(end 102.372414 -61.584078)
		(width 0.1143)
		(layer "In2.Cu")
		(net "XDP_CPU_NODE1_VISA5")
	)
	(segment
		(start 80.27416 -67.628516)
		(end 88.668098 -59.234578)
		(width 0.1143)
		(layer "In2.Cu")
		(net "XDP_CPU_NODE1_VISA5")
	)
	(segment
		(start 102.181152 -63.153544)
		(end 102.181152 -64.158114)
		(width 0.1143)
		(layer "In2.Cu")
		(net "XDP_CPU_NODE1_VISA5")
	)
	(segment
		(start 91.37396 -59.234578)
		(end 91.78163 -59.642248)
		(width 0.1143)
		(layer "In2.Cu")
		(net "XDP_CPU_NODE1_VISA5")
	)
	(segment
		(start 102.181152 -64.158114)
		(end 102.348792 -64.325754)
		(width 0.1143)
		(layer "In2.Cu")
		(net "XDP_CPU_NODE1_VISA5")
	)
	(segment
		(start 101.674168 -60.885832)
		(end 101.932232 -60.885832)
		(width 0.1143)
		(layer "In2.Cu")
		(net "XDP_CPU_NODE1_VISA5")
	)
	(segment
		(start 91.78163 -59.642248)
		(end 100.430584 -59.642248)
		(width 0.1143)
		(layer "In2.Cu")
		(net "XDP_CPU_NODE1_VISA5")
	)
	(segment
		(start 101.051868 -60.005468)
		(end 101.124004 -59.933332)
		(width 0.1143)
		(layer "In2.Cu")
		(net "XDP_CPU_NODE1_VISA5")
	)
	(segment
		(start 100.127562 -60.21959)
		(end 99.869498 -60.21959)
		(width 0.1143)
		(layer "In2.Cu")
		(net "XDP_CPU_NODE1_VISA5")
	)
	(segment
		(start 99.68738 -60.401708)
		(end 99.68738 -60.659772)
		(width 0.1143)
		(layer "In2.Cu")
		(net "XDP_CPU_NODE1_VISA5")
	)
	(segment
		(start 102.372414 -61.584078)
		(end 103.32593 -62.537594)
		(width 0.1143)
		(layer "In2.Cu")
		(net "XDP_CPU_NODE1_VISA5")
	)
	(segment
		(start 78.781656 -67.628516)
		(end 80.27416 -67.628516)
		(width 0.1143)
		(layer "In2.Cu")
		(net "XDP_CPU_NODE1_VISA5")
	)
	(segment
		(start 101.564186 -60.11545)
		(end 101.564186 -60.373514)
		(width 0.1143)
		(layer "In2.Cu")
		(net "XDP_CPU_NODE1_VISA5")
	)
	(segment
		(start 102.262432 -60.813696)
		(end 102.44455 -60.995814)
		(width 0.1143)
		(layer "In2.Cu")
		(net "XDP_CPU_NODE1_VISA5")
	)
	(segment
		(start 102.44455 -61.253878)
		(end 102.372414 -61.326014)
		(width 0.1143)
		(layer "In2.Cu")
		(net "XDP_CPU_NODE1_VISA5")
	)
	(segment
		(start 76.69784 -68.66001)
		(end 76.837286 -68.520564)
		(width 0.1143)
		(layer "In2.Cu")
		(net "XDP_CPU_NODE1_VISA5")
	)
	(segment
		(start 101.49205 -60.703714)
		(end 101.674168 -60.885832)
		(width 0.1143)
		(layer "In2.Cu")
		(net "XDP_CPU_NODE1_VISA5")
	)
	(segment
		(start 68.297044 -76.269342)
		(end 68.297044 -76.769468)
		(width 0.1016)
		(layer "F.Cu")
		(net "TP_CPU_NODE1_IERR_LV")
	)
	(segment
		(start 68.297044 -76.769468)
		(end 68.42252 -76.894944)
		(width 0.1016)
		(layer "F.Cu")
		(net "TP_CPU_NODE1_IERR_LV")
	)
	(via
		(at 68.42252 -76.894944)
		(size 0.508)
		(drill 0.254)
		(layers "F.Cu" "B.Cu")
		(net "TP_CPU_NODE1_IERR_LV")
	)
	(via
		(at 93.27388 -77.013308)
		(size 0.508)
		(drill 0.254)
		(layers "F.Cu" "B.Cu")
		(net "TP_CPU_NODE1_IERR_LV")
	)
	(segment
		(start 77.892148 -79.442818)
		(end 79.364332 -77.970634)
		(width 0.1143)
		(layer "In7.Cu")
		(net "TP_CPU_NODE1_IERR_LV")
	)
	(segment
		(start 87.092028 -77.53604)
		(end 89.348564 -75.279504)
		(width 0.1143)
		(layer "In7.Cu")
		(net "TP_CPU_NODE1_IERR_LV")
	)
	(segment
		(start 85.869526 -77.970634)
		(end 86.30412 -77.53604)
		(width 0.1143)
		(layer "In7.Cu")
		(net "TP_CPU_NODE1_IERR_LV")
	)
	(segment
		(start 69.035422 -77.620876)
		(end 72.036686 -77.620876)
		(width 0.1143)
		(layer "In7.Cu")
		(net "TP_CPU_NODE1_IERR_LV")
	)
	(segment
		(start 86.30412 -77.53604)
		(end 87.092028 -77.53604)
		(width 0.1143)
		(layer "In7.Cu")
		(net "TP_CPU_NODE1_IERR_LV")
	)
	(segment
		(start 73.858628 -79.442818)
		(end 77.892148 -79.442818)
		(width 0.1143)
		(layer "In7.Cu")
		(net "TP_CPU_NODE1_IERR_LV")
	)
	(segment
		(start 89.348564 -75.279504)
		(end 91.276424 -75.279504)
		(width 0.1143)
		(layer "In7.Cu")
		(net "TP_CPU_NODE1_IERR_LV")
	)
	(segment
		(start 91.276424 -75.279504)
		(end 93.010228 -77.013308)
		(width 0.1143)
		(layer "In7.Cu")
		(net "TP_CPU_NODE1_IERR_LV")
	)
	(segment
		(start 72.036686 -77.620876)
		(end 73.858628 -79.442818)
		(width 0.1143)
		(layer "In7.Cu")
		(net "TP_CPU_NODE1_IERR_LV")
	)
	(segment
		(start 93.010228 -77.013308)
		(end 93.27388 -77.013308)
		(width 0.1143)
		(layer "In7.Cu")
		(net "TP_CPU_NODE1_IERR_LV")
	)
	(segment
		(start 79.364332 -77.970634)
		(end 85.869526 -77.970634)
		(width 0.1143)
		(layer "In7.Cu")
		(net "TP_CPU_NODE1_IERR_LV")
	)
	(segment
		(start 68.42252 -77.007974)
		(end 69.035422 -77.620876)
		(width 0.1143)
		(layer "In7.Cu")
		(net "TP_CPU_NODE1_IERR_LV")
	)
	(segment
		(start 68.42252 -76.894944)
		(end 68.42252 -77.007974)
		(width 0.1143)
		(layer "In7.Cu")
		(net "TP_CPU_NODE1_IERR_LV")
	)
	(segment
		(start 59.489594 -85.000846)
		(end 59.123326 -84.634578)
		(width 0.1016)
		(layer "F.Cu")
		(net "H_CPU_NODE1_THRM_LS_L")
	)
	(segment
		(start 59.517026 -85.000846)
		(end 59.489594 -85.000846)
		(width 0.1016)
		(layer "F.Cu")
		(net "H_CPU_NODE1_THRM_LS_L")
	)
	(via
		(at 59.123326 -84.634578)
		(size 0.508)
		(drill 0.254)
		(layers "F.Cu" "B.Cu")
		(net "H_CPU_NODE1_THRM_LS_L")
	)
	(via
		(at 57.088786 -95.02775)
		(size 0.6604)
		(drill 0.3302)
		(layers "F.Cu" "B.Cu")
		(net "H_CPU_NODE1_THRM_LS_L")
	)
	(segment
		(start 56.988456 -95.12808)
		(end 57.088786 -95.02775)
		(width 0.1016)
		(layer "B.Cu")
		(net "H_CPU_NODE1_THRM_LS_L")
	)
	(segment
		(start 56.988456 -96.214692)
		(end 56.988456 -95.12808)
		(width 0.1016)
		(layer "B.Cu")
		(net "H_CPU_NODE1_THRM_LS_L")
	)
	(segment
		(start 59.80557 -85.485986)
		(end 59.80557 -87.278718)
		(width 0.1016)
		(layer "B.Cu")
		(net "H_CPU_NODE1_THRM_LS_L")
	)
	(segment
		(start 59.2328 -87.851488)
		(end 59.2328 -89.205054)
		(width 0.1016)
		(layer "B.Cu")
		(net "H_CPU_NODE1_THRM_LS_L")
	)
	(segment
		(start 58.510932 -93.605604)
		(end 57.088786 -95.02775)
		(width 0.1016)
		(layer "B.Cu")
		(net "H_CPU_NODE1_THRM_LS_L")
	)
	(segment
		(start 59.2328 -89.205054)
		(end 59.908948 -89.881202)
		(width 0.1016)
		(layer "B.Cu")
		(net "H_CPU_NODE1_THRM_LS_L")
	)
	(segment
		(start 59.80557 -87.278718)
		(end 59.2328 -87.851488)
		(width 0.1016)
		(layer "B.Cu")
		(net "H_CPU_NODE1_THRM_LS_L")
	)
	(segment
		(start 59.123326 -84.634578)
		(end 59.123326 -84.803742)
		(width 0.1016)
		(layer "B.Cu")
		(net "H_CPU_NODE1_THRM_LS_L")
	)
	(segment
		(start 59.123326 -84.803742)
		(end 59.80557 -85.485986)
		(width 0.1016)
		(layer "B.Cu")
		(net "H_CPU_NODE1_THRM_LS_L")
	)
	(segment
		(start 57.070498 -96.296734)
		(end 56.988456 -96.214692)
		(width 0.1016)
		(layer "B.Cu")
		(net "H_CPU_NODE1_THRM_LS_L")
	)
	(segment
		(start 59.908948 -89.881202)
		(end 59.908948 -91.567)
		(width 0.1016)
		(layer "B.Cu")
		(net "H_CPU_NODE1_THRM_LS_L")
	)
	(segment
		(start 59.908948 -91.567)
		(end 58.510932 -92.965016)
		(width 0.1016)
		(layer "B.Cu")
		(net "H_CPU_NODE1_THRM_LS_L")
	)
	(segment
		(start 58.510932 -92.965016)
		(end 58.510932 -93.605604)
		(width 0.1016)
		(layer "B.Cu")
		(net "H_CPU_NODE1_THRM_LS_L")
	)
	(segment
		(start 69.520054 -71.677276)
		(end 69.520054 -71.87438)
		(width 0.1016)
		(layer "F.Cu")
		(net "XDP_CPU_NODE1_VISA6")
	)
	(segment
		(start 69.821044 -71.596758)
		(end 69.600572 -71.596758)
		(width 0.1016)
		(layer "F.Cu")
		(net "XDP_CPU_NODE1_VISA6")
	)
	(segment
		(start 104.73182 -69.406262)
		(end 103.562404 -69.406262)
		(width 0.1016)
		(layer "F.Cu")
		(net "XDP_CPU_NODE1_VISA6")
	)
	(segment
		(start 69.520054 -71.87438)
		(end 69.637656 -71.991982)
		(width 0.1016)
		(layer "F.Cu")
		(net "XDP_CPU_NODE1_VISA6")
	)
	(segment
		(start 102.712012 -69.807074)
		(end 101.469952 -68.565014)
		(width 0.1016)
		(layer "F.Cu")
		(net "XDP_CPU_NODE1_VISA6")
	)
	(segment
		(start 70.278244 -71.299578)
		(end 70.202044 -71.223378)
		(width 0.1016)
		(layer "F.Cu")
		(net "XDP_CPU_NODE1_VISA6")
	)
	(segment
		(start 69.600572 -71.596758)
		(end 69.520054 -71.677276)
		(width 0.1016)
		(layer "F.Cu")
		(net "XDP_CPU_NODE1_VISA6")
	)
	(segment
		(start 69.637656 -71.991982)
		(end 70.173088 -71.991982)
		(width 0.1016)
		(layer "F.Cu")
		(net "XDP_CPU_NODE1_VISA6")
	)
	(segment
		(start 70.278244 -71.886826)
		(end 70.278244 -71.299578)
		(width 0.1016)
		(layer "F.Cu")
		(net "XDP_CPU_NODE1_VISA6")
	)
	(segment
		(start 101.469952 -68.565014)
		(end 101.469952 -67.693794)
		(width 0.1016)
		(layer "F.Cu")
		(net "XDP_CPU_NODE1_VISA6")
	)
	(segment
		(start 103.161592 -69.807074)
		(end 102.712012 -69.807074)
		(width 0.1016)
		(layer "F.Cu")
		(net "XDP_CPU_NODE1_VISA6")
	)
	(segment
		(start 102.803452 -66.360294)
		(end 102.803452 -66.146934)
		(width 0.1016)
		(layer "F.Cu")
		(net "XDP_CPU_NODE1_VISA6")
	)
	(segment
		(start 101.469952 -67.693794)
		(end 102.803452 -66.360294)
		(width 0.1016)
		(layer "F.Cu")
		(net "XDP_CPU_NODE1_VISA6")
	)
	(segment
		(start 103.562404 -69.406262)
		(end 103.161592 -69.807074)
		(width 0.1016)
		(layer "F.Cu")
		(net "XDP_CPU_NODE1_VISA6")
	)
	(segment
		(start 70.173088 -71.991982)
		(end 70.278244 -71.886826)
		(width 0.1016)
		(layer "F.Cu")
		(net "XDP_CPU_NODE1_VISA6")
	)
	(via
		(at 70.202044 -71.223378)
		(size 0.508)
		(drill 0.254)
		(layers "F.Cu" "B.Cu")
		(net "XDP_CPU_NODE1_VISA6")
	)
	(via
		(at 102.803452 -66.146934)
		(size 0.508)
		(drill 0.254)
		(layers "F.Cu" "B.Cu")
		(net "XDP_CPU_NODE1_VISA6")
	)
	(segment
		(start 100.794312 -64.719454)
		(end 101.805232 -64.719454)
		(width 0.1143)
		(layer "In2.Cu")
		(net "XDP_CPU_NODE1_VISA6")
	)
	(segment
		(start 91.93784 -61.009276)
		(end 98.019108 -61.009276)
		(width 0.1143)
		(layer "In2.Cu")
		(net "XDP_CPU_NODE1_VISA6")
	)
	(segment
		(start 93.585792 -61.631576)
		(end 93.40342 -61.813948)
		(width 0.1143)
		(layer "In2.Cu")
		(net "XDP_CPU_NODE1_VISA6")
	)
	(segment
		(start 93.585792 -62.253876)
		(end 98.328734 -62.253876)
		(width 0.1143)
		(layer "In2.Cu")
		(net "XDP_CPU_NODE1_VISA6")
	)
	(segment
		(start 98.20148 -61.191648)
		(end 98.20148 -61.449204)
		(width 0.1143)
		(layer "In2.Cu")
		(net "XDP_CPU_NODE1_VISA6")
	)
	(segment
		(start 98.328734 -62.253876)
		(end 100.794312 -64.719454)
		(width 0.1143)
		(layer "In2.Cu")
		(net "XDP_CPU_NODE1_VISA6")
	)
	(segment
		(start 102.803452 -65.717674)
		(end 102.803452 -66.146934)
		(width 0.1143)
		(layer "In2.Cu")
		(net "XDP_CPU_NODE1_VISA6")
	)
	(segment
		(start 98.20148 -61.449204)
		(end 98.019108 -61.631576)
		(width 0.1143)
		(layer "In2.Cu")
		(net "XDP_CPU_NODE1_VISA6")
	)
	(segment
		(start 70.202044 -71.223378)
		(end 70.614794 -71.636128)
		(width 0.1143)
		(layer "In2.Cu")
		(net "XDP_CPU_NODE1_VISA6")
	)
	(segment
		(start 70.614794 -71.636128)
		(end 71.490332 -71.636128)
		(width 0.1143)
		(layer "In2.Cu")
		(net "XDP_CPU_NODE1_VISA6")
	)
	(segment
		(start 91.00312 -60.074556)
		(end 91.93784 -61.009276)
		(width 0.1143)
		(layer "In2.Cu")
		(net "XDP_CPU_NODE1_VISA6")
	)
	(segment
		(start 71.677022 -71.822818)
		(end 72.026526 -71.822818)
		(width 0.1143)
		(layer "In2.Cu")
		(net "XDP_CPU_NODE1_VISA6")
	)
	(segment
		(start 72.026526 -71.822818)
		(end 74.710544 -69.1388)
		(width 0.1143)
		(layer "In2.Cu")
		(net "XDP_CPU_NODE1_VISA6")
	)
	(segment
		(start 89.015316 -60.074556)
		(end 91.00312 -60.074556)
		(width 0.1143)
		(layer "In2.Cu")
		(net "XDP_CPU_NODE1_VISA6")
	)
	(segment
		(start 93.40342 -62.071504)
		(end 93.585792 -62.253876)
		(width 0.1143)
		(layer "In2.Cu")
		(net "XDP_CPU_NODE1_VISA6")
	)
	(segment
		(start 71.490332 -71.636128)
		(end 71.677022 -71.822818)
		(width 0.1143)
		(layer "In2.Cu")
		(net "XDP_CPU_NODE1_VISA6")
	)
	(segment
		(start 80.319626 -68.770246)
		(end 89.015316 -60.074556)
		(width 0.1143)
		(layer "In2.Cu")
		(net "XDP_CPU_NODE1_VISA6")
	)
	(segment
		(start 101.805232 -64.719454)
		(end 102.803452 -65.717674)
		(width 0.1143)
		(layer "In2.Cu")
		(net "XDP_CPU_NODE1_VISA6")
	)
	(segment
		(start 78.921356 -68.770246)
		(end 80.319626 -68.770246)
		(width 0.1143)
		(layer "In2.Cu")
		(net "XDP_CPU_NODE1_VISA6")
	)
	(segment
		(start 74.710544 -69.1388)
		(end 78.552802 -69.1388)
		(width 0.1143)
		(layer "In2.Cu")
		(net "XDP_CPU_NODE1_VISA6")
	)
	(segment
		(start 93.40342 -61.813948)
		(end 93.40342 -62.071504)
		(width 0.1143)
		(layer "In2.Cu")
		(net "XDP_CPU_NODE1_VISA6")
	)
	(segment
		(start 98.019108 -61.009276)
		(end 98.20148 -61.191648)
		(width 0.1143)
		(layer "In2.Cu")
		(net "XDP_CPU_NODE1_VISA6")
	)
	(segment
		(start 98.019108 -61.631576)
		(end 93.585792 -61.631576)
		(width 0.1143)
		(layer "In2.Cu")
		(net "XDP_CPU_NODE1_VISA6")
	)
	(segment
		(start 78.552802 -69.1388)
		(end 78.921356 -68.770246)
		(width 0.1143)
		(layer "In2.Cu")
		(net "XDP_CPU_NODE1_VISA6")
	)
	(segment
		(start 35.762692 -74.418698)
		(end 35.5473 -74.63409)
		(width 0.508)
		(layer "F.Cu")
		(net "P1V5_NODE1")
	)
	(segment
		(start 54.800246 -71.398892)
		(end 55.200296 -71.798942)
		(width 0.3556)
		(layer "F.Cu")
		(net "P1V5_NODE1")
	)
	(segment
		(start 51.599846 -71.455026)
		(end 51.599846 -71.398892)
		(width 0.3048)
		(layer "F.Cu")
		(net "P1V5_NODE1")
	)
	(segment
		(start 149.3901 -118.202202)
		(end 146.877278 -120.715024)
		(width 0.508)
		(layer "F.Cu")
		(net "P1V5_NODE1")
	)
	(segment
		(start 149.390862 -116.738146)
		(end 149.3901 -116.738908)
		(width 0.508)
		(layer "F.Cu")
		(net "P1V5_NODE1")
	)
	(segment
		(start 146.877278 -120.715024)
		(end 142.83436 -120.715024)
		(width 0.508)
		(layer "F.Cu")
		(net "P1V5_NODE1")
	)
	(segment
		(start 51.943762 -71.798942)
		(end 51.599846 -71.455026)
		(width 0.3048)
		(layer "F.Cu")
		(net "P1V5_NODE1")
	)
	(segment
		(start 149.3901 -116.738908)
		(end 149.3901 -118.202202)
		(width 0.508)
		(layer "F.Cu")
		(net "P1V5_NODE1")
	)
	(segment
		(start 55.200296 -76.599542)
		(end 55.600346 -76.999592)
		(width 0.3048)
		(layer "F.Cu")
		(net "P1V5_NODE1")
	)
	(segment
		(start 54.800246 -72.999092)
		(end 55.200296 -73.399142)
		(width 0.3048)
		(layer "F.Cu")
		(net "P1V5_NODE1")
	)
	(segment
		(start 55.200296 -78.999842)
		(end 55.207662 -78.999842)
		(width 0.254)
		(layer "F.Cu")
		(net "P1V5_NODE1")
	)
	(segment
		(start 55.207662 -78.999842)
		(end 55.612538 -79.404718)
		(width 0.254)
		(layer "F.Cu")
		(net "P1V5_NODE1")
	)
	(segment
		(start 36.307522 -74.418698)
		(end 35.762692 -74.418698)
		(width 0.508)
		(layer "F.Cu")
		(net "P1V5_NODE1")
	)
	(segment
		(start 51.999896 -71.798942)
		(end 51.943762 -71.798942)
		(width 0.3048)
		(layer "F.Cu")
		(net "P1V5_NODE1")
	)
	(segment
		(start 54.800246 -74.599292)
		(end 55.200296 -74.999342)
		(width 0.3048)
		(layer "F.Cu")
		(net "P1V5_NODE1")
	)
	(via
		(at 54.800246 -72.999092)
		(size 0.508)
		(drill 0.254)
		(layers "F.Cu" "B.Cu")
		(net "P1V5_NODE1")
	)
	(via
		(at 37.484304 -113.100866)
		(size 0.508)
		(drill 0.254)
		(layers "F.Cu" "B.Cu")
		(net "P1V5_NODE1")
	)
	(via
		(at 39.20998 -114.28222)
		(size 0.508)
		(drill 0.254)
		(layers "F.Cu" "B.Cu")
		(net "P1V5_NODE1")
	)
	(via
		(at 51.599846 -71.398892)
		(size 0.508)
		(drill 0.254)
		(layers "F.Cu" "B.Cu")
		(net "P1V5_NODE1")
	)
	(via
		(at 35.5473 -74.63409)
		(size 0.508)
		(drill 0.254)
		(layers "F.Cu" "B.Cu")
		(net "P1V5_NODE1")
	)
	(via
		(at 37.484304 -114.370866)
		(size 0.508)
		(drill 0.254)
		(layers "F.Cu" "B.Cu")
		(net "P1V5_NODE1")
	)
	(via
		(at 149.390862 -116.738146)
		(size 0.508)
		(drill 0.254)
		(layers "F.Cu" "B.Cu")
		(net "P1V5_NODE1")
	)
	(via
		(at 55.612538 -79.404718)
		(size 0.508)
		(drill 0.254)
		(layers "F.Cu" "B.Cu")
		(net "P1V5_NODE1")
	)
	(via
		(at 50.94986 -83.21421)
		(size 0.508)
		(drill 0.254)
		(layers "F.Cu" "B.Cu")
		(net "P1V5_NODE1")
	)
	(via
		(at 37.484304 -113.735866)
		(size 0.508)
		(drill 0.254)
		(layers "F.Cu" "B.Cu")
		(net "P1V5_NODE1")
	)
	(via
		(at 54.800246 -74.599292)
		(size 0.508)
		(drill 0.254)
		(layers "F.Cu" "B.Cu")
		(net "P1V5_NODE1")
	)
	(via
		(at 55.600346 -76.999592)
		(size 0.508)
		(drill 0.254)
		(layers "F.Cu" "B.Cu")
		(net "P1V5_NODE1")
	)
	(via
		(at 54.800246 -71.398892)
		(size 0.508)
		(drill 0.254)
		(layers "F.Cu" "B.Cu")
		(net "P1V5_NODE1")
	)
	(segment
		(start 50.457862 -71.538084)
		(end 51.460654 -71.538084)
		(width 0.381)
		(layer "B.Cu")
		(net "P1V5_NODE1")
	)
	(segment
		(start 51.449732 -71.248778)
		(end 51.599846 -71.398892)
		(width 0.4572)
		(layer "B.Cu")
		(net "P1V5_NODE1")
	)
	(segment
		(start 50.674016 -84.077556)
		(end 50.674016 -83.490054)
		(width 0.381)
		(layer "B.Cu")
		(net "P1V5_NODE1")
	)
	(segment
		(start 51.449732 -70.512686)
		(end 51.449732 -71.248778)
		(width 0.4572)
		(layer "B.Cu")
		(net "P1V5_NODE1")
	)
	(segment
		(start 51.460654 -71.538084)
		(end 51.599846 -71.398892)
		(width 0.381)
		(layer "B.Cu")
		(net "P1V5_NODE1")
	)
	(segment
		(start 50.674016 -83.490054)
		(end 50.94986 -83.21421)
		(width 0.381)
		(layer "B.Cu")
		(net "P1V5_NODE1")
	)
	(segment
		(start 102.622604 -85.83422)
		(end 99.078288 -82.289904)
		(width 0.508)
		(layer "In7.Cu")
		(net "P1V5_NODE1")
	)
	(segment
		(start 92.25915 -79.717646)
		(end 91.63558 -79.094076)
		(width 0.508)
		(layer "In7.Cu")
		(net "P1V5_NODE1")
	)
	(segment
		(start 85.175598 -79.647034)
		(end 85.053424 -79.52486)
		(width 0.508)
		(layer "In7.Cu")
		(net "P1V5_NODE1")
	)
	(segment
		(start 149.390862 -116.738146)
		(end 150.046182 -116.738146)
		(width 0.508)
		(layer "In7.Cu")
		(net "P1V5_NODE1")
	)
	(segment
		(start 94.951804 -79.717646)
		(end 92.25915 -79.717646)
		(width 0.508)
		(layer "In7.Cu")
		(net "P1V5_NODE1")
	)
	(segment
		(start 87.759286 -79.647034)
		(end 85.175598 -79.647034)
		(width 0.508)
		(layer "In7.Cu")
		(net "P1V5_NODE1")
	)
	(segment
		(start 60.19927 -80.928464)
		(end 57.066688 -80.928464)
		(width 0.508)
		(layer "In7.Cu")
		(net "P1V5_NODE1")
	)
	(segment
		(start 88.272874 -79.133446)
		(end 87.759286 -79.647034)
		(width 0.508)
		(layer "In7.Cu")
		(net "P1V5_NODE1")
	)
	(segment
		(start 57.066688 -80.928464)
		(end 55.612538 -79.474314)
		(width 0.508)
		(layer "In7.Cu")
		(net "P1V5_NODE1")
	)
	(segment
		(start 142.923768 -104.946958)
		(end 140.342874 -102.366064)
		(width 0.508)
		(layer "In7.Cu")
		(net "P1V5_NODE1")
	)
	(segment
		(start 91.63558 -79.094076)
		(end 90.37066 -79.094076)
		(width 0.508)
		(layer "In7.Cu")
		(net "P1V5_NODE1")
	)
	(segment
		(start 90.37066 -79.094076)
		(end 90.33129 -79.133446)
		(width 0.508)
		(layer "In7.Cu")
		(net "P1V5_NODE1")
	)
	(segment
		(start 54.800246 -71.398892)
		(end 54.800246 -72.036686)
		(width 0.508)
		(layer "In7.Cu")
		(net "P1V5_NODE1")
	)
	(segment
		(start 151.0411 -115.743228)
		(end 151.0411 -113.68151)
		(width 0.508)
		(layer "In7.Cu")
		(net "P1V5_NODE1")
	)
	(segment
		(start 97.524062 -82.289904)
		(end 94.951804 -79.717646)
		(width 0.508)
		(layer "In7.Cu")
		(net "P1V5_NODE1")
	)
	(segment
		(start 65.706244 -81.948782)
		(end 65.706244 -86.247224)
		(width 0.508)
		(layer "In7.Cu")
		(net "P1V5_NODE1")
	)
	(segment
		(start 109.428534 -85.83422)
		(end 102.622604 -85.83422)
		(width 0.508)
		(layer "In7.Cu")
		(net "P1V5_NODE1")
	)
	(segment
		(start 125.960378 -102.366064)
		(end 109.428534 -85.83422)
		(width 0.508)
		(layer "In7.Cu")
		(net "P1V5_NODE1")
	)
	(segment
		(start 83.247484 -80.534256)
		(end 67.12077 -80.534256)
		(width 0.508)
		(layer "In7.Cu")
		(net "P1V5_NODE1")
	)
	(segment
		(start 142.923768 -105.564178)
		(end 142.923768 -104.946958)
		(width 0.508)
		(layer "In7.Cu")
		(net "P1V5_NODE1")
	)
	(segment
		(start 99.078288 -82.289904)
		(end 97.524062 -82.289904)
		(width 0.508)
		(layer "In7.Cu")
		(net "P1V5_NODE1")
	)
	(segment
		(start 150.046182 -116.738146)
		(end 151.0411 -115.743228)
		(width 0.508)
		(layer "In7.Cu")
		(net "P1V5_NODE1")
	)
	(segment
		(start 84.25688 -79.52486)
		(end 83.247484 -80.534256)
		(width 0.508)
		(layer "In7.Cu")
		(net "P1V5_NODE1")
	)
	(segment
		(start 62.956948 -88.082374)
		(end 61.795914 -86.92134)
		(width 0.508)
		(layer "In7.Cu")
		(net "P1V5_NODE1")
	)
	(segment
		(start 65.706244 -86.247224)
		(end 63.871094 -88.082374)
		(width 0.508)
		(layer "In7.Cu")
		(net "P1V5_NODE1")
	)
	(segment
		(start 63.871094 -88.082374)
		(end 62.956948 -88.082374)
		(width 0.508)
		(layer "In7.Cu")
		(net "P1V5_NODE1")
	)
	(segment
		(start 61.795914 -82.525108)
		(end 60.19927 -80.928464)
		(width 0.508)
		(layer "In7.Cu")
		(net "P1V5_NODE1")
	)
	(segment
		(start 67.12077 -80.534256)
		(end 65.706244 -81.948782)
		(width 0.508)
		(layer "In7.Cu")
		(net "P1V5_NODE1")
	)
	(segment
		(start 61.795914 -86.92134)
		(end 61.795914 -82.525108)
		(width 0.508)
		(layer "In7.Cu")
		(net "P1V5_NODE1")
	)
	(segment
		(start 90.33129 -79.133446)
		(end 88.272874 -79.133446)
		(width 0.508)
		(layer "In7.Cu")
		(net "P1V5_NODE1")
	)
	(segment
		(start 85.053424 -79.52486)
		(end 84.25688 -79.52486)
		(width 0.508)
		(layer "In7.Cu")
		(net "P1V5_NODE1")
	)
	(segment
		(start 151.0411 -113.68151)
		(end 142.923768 -105.564178)
		(width 0.508)
		(layer "In7.Cu")
		(net "P1V5_NODE1")
	)
	(segment
		(start 140.342874 -102.366064)
		(end 125.960378 -102.366064)
		(width 0.508)
		(layer "In7.Cu")
		(net "P1V5_NODE1")
	)
	(segment
		(start 55.612538 -79.404718)
		(end 55.612538 -79.474314)
		(width 0.508)
		(layer "In7.Cu")
		(net "P1V5_NODE1")
	)
	(via
		(at 16.37792 -127.405384)
		(size 0.508)
		(drill 0.254)
		(layers "F.Cu" "B.Cu")
		(net "SW_P1V05_NODE1_DRVH")
	)
	(segment
		(start 65.821052 -81.449418)
		(end 66.051684 -81.218786)
		(width 0.1016)
		(layer "F.Cu")
		(net "CLK_33K_CPU_NODE1_SUSCLK_RR")
	)
	(segment
		(start 66.599054 -83.436714)
		(end 66.598546 -83.437222)
		(width 0.1016)
		(layer "F.Cu")
		(net "CLK_33K_CPU_NODE1_SUSCLK_RR")
	)
	(segment
		(start 66.504058 -81.218786)
		(end 66.81343 -81.528158)
		(width 0.1016)
		(layer "F.Cu")
		(net "CLK_33K_CPU_NODE1_SUSCLK_RR")
	)
	(segment
		(start 66.598546 -83.437222)
		(end 66.024252 -83.437222)
		(width 0.1016)
		(layer "F.Cu")
		(net "CLK_33K_CPU_NODE1_SUSCLK_RR")
	)
	(segment
		(start 66.024252 -83.437222)
		(end 65.821052 -83.234022)
		(width 0.1016)
		(layer "F.Cu")
		(net "CLK_33K_CPU_NODE1_SUSCLK_RR")
	)
	(segment
		(start 66.051684 -81.218786)
		(end 66.504058 -81.218786)
		(width 0.1016)
		(layer "F.Cu")
		(net "CLK_33K_CPU_NODE1_SUSCLK_RR")
	)
	(segment
		(start 66.81343 -81.528158)
		(end 67.154044 -81.528158)
		(width 0.1016)
		(layer "F.Cu")
		(net "CLK_33K_CPU_NODE1_SUSCLK_RR")
	)
	(segment
		(start 65.821052 -83.234022)
		(end 65.821052 -81.449418)
		(width 0.1016)
		(layer "F.Cu")
		(net "CLK_33K_CPU_NODE1_SUSCLK_RR")
	)
	(via
		(at 66.599054 -83.436714)
		(size 0.508)
		(drill 0.254)
		(layers "F.Cu" "B.Cu")
		(net "CLK_33K_CPU_NODE1_SUSCLK_RR")
	)
	(via
		(at 66.28638 -87.265002)
		(size 0.6604)
		(drill 0.3302)
		(layers "F.Cu" "B.Cu")
		(net "CLK_33K_CPU_NODE1_SUSCLK_RR")
	)
	(segment
		(start 84.53628 -104.114854)
		(end 84.53628 -101.19106)
		(width 0.1016)
		(layer "B.Cu")
		(net "CLK_33K_CPU_NODE1_SUSCLK_RR")
	)
	(segment
		(start 91.279218 -102.699058)
		(end 91.45778 -102.87762)
		(width 0.1016)
		(layer "B.Cu")
		(net "CLK_33K_CPU_NODE1_SUSCLK_RR")
	)
	(segment
		(start 91.86672 -101.937058)
		(end 91.71432 -102.089458)
		(width 0.1016)
		(layer "B.Cu")
		(net "CLK_33K_CPU_NODE1_SUSCLK_RR")
	)
	(segment
		(start 86.58352 -100.082096)
		(end 86.762082 -100.260658)
		(width 0.1016)
		(layer "B.Cu")
		(net "CLK_33K_CPU_NODE1_SUSCLK_RR")
	)
	(segment
		(start 86.58352 -101.301296)
		(end 86.762082 -101.479858)
		(width 0.1016)
		(layer "B.Cu")
		(net "CLK_33K_CPU_NODE1_SUSCLK_RR")
	)
	(segment
		(start 78.9559 -94.315534)
		(end 78.9559 -96.71812)
		(width 0.1016)
		(layer "B.Cu")
		(net "CLK_33K_CPU_NODE1_SUSCLK_RR")
	)
	(segment
		(start 84.33308 -100.98786)
		(end 75.957684 -100.98786)
		(width 0.1016)
		(layer "B.Cu")
		(net "CLK_33K_CPU_NODE1_SUSCLK_RR")
	)
	(segment
		(start 82.073496 -100.145342)
		(end 82.276696 -100.348542)
		(width 0.1016)
		(layer "B.Cu")
		(net "CLK_33K_CPU_NODE1_SUSCLK_RR")
	)
	(segment
		(start 70.975474 -99.516438)
		(end 70.62343 -99.868482)
		(width 0.1016)
		(layer "B.Cu")
		(net "CLK_33K_CPU_NODE1_SUSCLK_RR")
	)
	(segment
		(start 66.88836 -89.506806)
		(end 66.28638 -87.265002)
		(width 0.1016)
		(layer "B.Cu")
		(net "CLK_33K_CPU_NODE1_SUSCLK_RR")
	)
	(segment
		(start 86.762082 -100.260658)
		(end 90.171778 -100.260658)
		(width 0.1016)
		(layer "B.Cu")
		(net "CLK_33K_CPU_NODE1_SUSCLK_RR")
	)
	(segment
		(start 91.279218 -103.308658)
		(end 86.34222 -103.308658)
		(width 0.1016)
		(layer "B.Cu")
		(net "CLK_33K_CPU_NODE1_SUSCLK_RR")
	)
	(segment
		(start 80.348074 -96.258634)
		(end 80.348074 -94.281498)
		(width 0.1016)
		(layer "B.Cu")
		(net "CLK_33K_CPU_NODE1_SUSCLK_RR")
	)
	(segment
		(start 84.229956 -95.225616)
		(end 84.433156 -95.022416)
		(width 0.1016)
		(layer "B.Cu")
		(net "CLK_33K_CPU_NODE1_SUSCLK_RR")
	)
	(segment
		(start 67.293744 -94.596458)
		(end 66.88836 -94.191074)
		(width 0.1016)
		(layer "B.Cu")
		(net "CLK_33K_CPU_NODE1_SUSCLK_RR")
	)
	(segment
		(start 74.838306 -99.868482)
		(end 72.26173 -99.868482)
		(width 0.1016)
		(layer "B.Cu")
		(net "CLK_33K_CPU_NODE1_SUSCLK_RR")
	)
	(segment
		(start 67.346068 -98.24212)
		(end 67.664838 -97.92335)
		(width 0.1016)
		(layer "B.Cu")
		(net "CLK_33K_CPU_NODE1_SUSCLK_RR")
	)
	(segment
		(start 82.944716 -95.81261)
		(end 83.358736 -95.81261)
		(width 0.1016)
		(layer "B.Cu")
		(net "CLK_33K_CPU_NODE1_SUSCLK_RR")
	)
	(segment
		(start 84.53628 -101.19106)
		(end 84.33308 -100.98786)
		(width 0.1016)
		(layer "B.Cu")
		(net "CLK_33K_CPU_NODE1_SUSCLK_RR")
	)
	(segment
		(start 90.35034 -100.691696)
		(end 90.171778 -100.870258)
		(width 0.1016)
		(layer "B.Cu")
		(net "CLK_33K_CPU_NODE1_SUSCLK_RR")
	)
	(segment
		(start 84.433156 -95.022416)
		(end 84.745576 -95.022416)
		(width 0.1016)
		(layer "B.Cu")
		(net "CLK_33K_CPU_NODE1_SUSCLK_RR")
	)
	(segment
		(start 90.35034 -100.43922)
		(end 90.35034 -100.691696)
		(width 0.1016)
		(layer "B.Cu")
		(net "CLK_33K_CPU_NODE1_SUSCLK_RR")
	)
	(segment
		(start 79.38135 -93.890084)
		(end 78.9559 -94.315534)
		(width 0.1016)
		(layer "B.Cu")
		(net "CLK_33K_CPU_NODE1_SUSCLK_RR")
	)
	(segment
		(start 84.026756 -100.348542)
		(end 84.229956 -100.145342)
		(width 0.1016)
		(layer "B.Cu")
		(net "CLK_33K_CPU_NODE1_SUSCLK_RR")
	)
	(segment
		(start 83.511136 -100.145342)
		(end 83.714336 -100.348542)
		(width 0.1016)
		(layer "B.Cu")
		(net "CLK_33K_CPU_NODE1_SUSCLK_RR")
	)
	(segment
		(start 84.229956 -100.145342)
		(end 84.229956 -95.225616)
		(width 0.1016)
		(layer "B.Cu")
		(net "CLK_33K_CPU_NODE1_SUSCLK_RR")
	)
	(segment
		(start 91.71432 -102.089458)
		(end 86.533482 -102.089458)
		(width 0.1016)
		(layer "B.Cu")
		(net "CLK_33K_CPU_NODE1_SUSCLK_RR")
	)
	(segment
		(start 79.182214 -99.942142)
		(end 80.432656 -99.942142)
		(width 0.1016)
		(layer "B.Cu")
		(net "CLK_33K_CPU_NODE1_SUSCLK_RR")
	)
	(segment
		(start 86.13902 -103.511858)
		(end 86.13902 -103.842058)
		(width 0.1016)
		(layer "B.Cu")
		(net "CLK_33K_CPU_NODE1_SUSCLK_RR")
	)
	(segment
		(start 81.921096 -96.228408)
		(end 82.073496 -96.380808)
		(width 0.1016)
		(layer "B.Cu")
		(net "CLK_33K_CPU_NODE1_SUSCLK_RR")
	)
	(segment
		(start 86.35492 -102.520496)
		(end 86.533482 -102.699058)
		(width 0.1016)
		(layer "B.Cu")
		(net "CLK_33K_CPU_NODE1_SUSCLK_RR")
	)
	(segment
		(start 86.34222 -104.045258)
		(end 91.71432 -104.045258)
		(width 0.1016)
		(layer "B.Cu")
		(net "CLK_33K_CPU_NODE1_SUSCLK_RR")
	)
	(segment
		(start 86.34222 -103.308658)
		(end 86.13902 -103.511858)
		(width 0.1016)
		(layer "B.Cu")
		(net "CLK_33K_CPU_NODE1_SUSCLK_RR")
	)
	(segment
		(start 66.599054 -83.436714)
		(end 66.30797 -83.727798)
		(width 0.1016)
		(layer "B.Cu")
		(net "CLK_33K_CPU_NODE1_SUSCLK_RR")
	)
	(segment
		(start 89.93886 -99.024694)
		(end 89.93886 -99.382326)
		(width 0.1016)
		(layer "B.Cu")
		(net "CLK_33K_CPU_NODE1_SUSCLK_RR")
	)
	(segment
		(start 82.792316 -100.145342)
		(end 82.792316 -95.96501)
		(width 0.1016)
		(layer "B.Cu")
		(net "CLK_33K_CPU_NODE1_SUSCLK_RR")
	)
	(segment
		(start 81.151476 -100.348542)
		(end 81.354676 -100.145342)
		(width 0.1016)
		(layer "B.Cu")
		(net "CLK_33K_CPU_NODE1_SUSCLK_RR")
	)
	(segment
		(start 91.91752 -104.248458)
		(end 91.91752 -104.578658)
		(width 0.1016)
		(layer "B.Cu")
		(net "CLK_33K_CPU_NODE1_SUSCLK_RR")
	)
	(segment
		(start 67.664838 -97.12325)
		(end 67.293744 -96.752156)
		(width 0.1016)
		(layer "B.Cu")
		(net "CLK_33K_CPU_NODE1_SUSCLK_RR")
	)
	(segment
		(start 66.88836 -94.191074)
		(end 66.88836 -89.506806)
		(width 0.1016)
		(layer "B.Cu")
		(net "CLK_33K_CPU_NODE1_SUSCLK_RR")
	)
	(segment
		(start 84.745576 -95.022416)
		(end 84.948776 -95.225616)
		(width 0.1016)
		(layer "B.Cu")
		(net "CLK_33K_CPU_NODE1_SUSCLK_RR")
	)
	(segment
		(start 67.346068 -99.187)
		(end 67.346068 -98.24212)
		(width 0.1016)
		(layer "B.Cu")
		(net "CLK_33K_CPU_NODE1_SUSCLK_RR")
	)
	(segment
		(start 91.45778 -103.130096)
		(end 91.279218 -103.308658)
		(width 0.1016)
		(layer "B.Cu")
		(net "CLK_33K_CPU_NODE1_SUSCLK_RR")
	)
	(segment
		(start 66.045842 -87.024464)
		(end 66.28638 -87.265002)
		(width 0.1016)
		(layer "B.Cu")
		(net "CLK_33K_CPU_NODE1_SUSCLK_RR")
	)
	(segment
		(start 91.71432 -101.479858)
		(end 91.86672 -101.632258)
		(width 0.1016)
		(layer "B.Cu")
		(net "CLK_33K_CPU_NODE1_SUSCLK_RR")
	)
	(segment
		(start 86.58352 -101.04882)
		(end 86.58352 -101.301296)
		(width 0.1016)
		(layer "B.Cu")
		(net "CLK_33K_CPU_NODE1_SUSCLK_RR")
	)
	(segment
		(start 83.358736 -95.81261)
		(end 83.511136 -95.96501)
		(width 0.1016)
		(layer "B.Cu")
		(net "CLK_33K_CPU_NODE1_SUSCLK_RR")
	)
	(segment
		(start 80.839056 -100.348542)
		(end 81.151476 -100.348542)
		(width 0.1016)
		(layer "B.Cu")
		(net "CLK_33K_CPU_NODE1_SUSCLK_RR")
	)
	(segment
		(start 86.533482 -102.089458)
		(end 86.35492 -102.26802)
		(width 0.1016)
		(layer "B.Cu")
		(net "CLK_33K_CPU_NODE1_SUSCLK_RR")
	)
	(segment
		(start 71.909686 -99.516438)
		(end 70.975474 -99.516438)
		(width 0.1016)
		(layer "B.Cu")
		(net "CLK_33K_CPU_NODE1_SUSCLK_RR")
	)
	(segment
		(start 70.62343 -99.868482)
		(end 68.02755 -99.868482)
		(width 0.1016)
		(layer "B.Cu")
		(net "CLK_33K_CPU_NODE1_SUSCLK_RR")
	)
	(segment
		(start 82.792316 -95.96501)
		(end 82.944716 -95.81261)
		(width 0.1016)
		(layer "B.Cu")
		(net "CLK_33K_CPU_NODE1_SUSCLK_RR")
	)
	(segment
		(start 82.276696 -100.348542)
		(end 82.589116 -100.348542)
		(width 0.1016)
		(layer "B.Cu")
		(net "CLK_33K_CPU_NODE1_SUSCLK_RR")
	)
	(segment
		(start 86.13902 -103.842058)
		(end 86.34222 -104.045258)
		(width 0.1016)
		(layer "B.Cu")
		(net "CLK_33K_CPU_NODE1_SUSCLK_RR")
	)
	(segment
		(start 75.957684 -100.98786)
		(end 74.838306 -99.868482)
		(width 0.1016)
		(layer "B.Cu")
		(net "CLK_33K_CPU_NODE1_SUSCLK_RR")
	)
	(segment
		(start 89.701624 -98.787458)
		(end 89.93886 -99.024694)
		(width 0.1016)
		(layer "B.Cu")
		(net "CLK_33K_CPU_NODE1_SUSCLK_RR")
	)
	(segment
		(start 82.073496 -96.380808)
		(end 82.073496 -100.145342)
		(width 0.1016)
		(layer "B.Cu")
		(net "CLK_33K_CPU_NODE1_SUSCLK_RR")
	)
	(segment
		(start 67.664838 -97.92335)
		(end 67.664838 -97.12325)
		(width 0.1016)
		(layer "B.Cu")
		(net "CLK_33K_CPU_NODE1_SUSCLK_RR")
	)
	(segment
		(start 85.203284 -104.781858)
		(end 84.53628 -104.114854)
		(width 0.1016)
		(layer "B.Cu")
		(net "CLK_33K_CPU_NODE1_SUSCLK_RR")
	)
	(segment
		(start 91.71432 -104.781858)
		(end 85.203284 -104.781858)
		(width 0.1016)
		(layer "B.Cu")
		(net "CLK_33K_CPU_NODE1_SUSCLK_RR")
	)
	(segment
		(start 78.979014 -99.281742)
		(end 78.979014 -99.738942)
		(width 0.1016)
		(layer "B.Cu")
		(net "CLK_33K_CPU_NODE1_SUSCLK_RR")
	)
	(segment
		(start 80.207358 -97.028254)
		(end 80.635856 -97.456752)
		(width 0.1016)
		(layer "B.Cu")
		(net "CLK_33K_CPU_NODE1_SUSCLK_RR")
	)
	(segment
		(start 80.348074 -94.281498)
		(end 79.95666 -93.890084)
		(width 0.1016)
		(layer "B.Cu")
		(net "CLK_33K_CPU_NODE1_SUSCLK_RR")
	)
	(segment
		(start 80.432656 -99.942142)
		(end 80.839056 -100.348542)
		(width 0.1016)
		(layer "B.Cu")
		(net "CLK_33K_CPU_NODE1_SUSCLK_RR")
	)
	(segment
		(start 80.432656 -99.078542)
		(end 79.182214 -99.078542)
		(width 0.1016)
		(layer "B.Cu")
		(net "CLK_33K_CPU_NODE1_SUSCLK_RR")
	)
	(segment
		(start 80.635856 -97.456752)
		(end 80.635856 -98.875342)
		(width 0.1016)
		(layer "B.Cu")
		(net "CLK_33K_CPU_NODE1_SUSCLK_RR")
	)
	(segment
		(start 80.635856 -98.875342)
		(end 80.432656 -99.078542)
		(width 0.1016)
		(layer "B.Cu")
		(net "CLK_33K_CPU_NODE1_SUSCLK_RR")
	)
	(segment
		(start 66.30797 -83.833208)
		(end 66.045842 -85.110574)
		(width 0.1016)
		(layer "B.Cu")
		(net "CLK_33K_CPU_NODE1_SUSCLK_RR")
	)
	(segment
		(start 82.589116 -100.348542)
		(end 82.792316 -100.145342)
		(width 0.1016)
		(layer "B.Cu")
		(net "CLK_33K_CPU_NODE1_SUSCLK_RR")
	)
	(segment
		(start 91.71432 -104.045258)
		(end 91.91752 -104.248458)
		(width 0.1016)
		(layer "B.Cu")
		(net "CLK_33K_CPU_NODE1_SUSCLK_RR")
	)
	(segment
		(start 83.714336 -100.348542)
		(end 84.026756 -100.348542)
		(width 0.1016)
		(layer "B.Cu")
		(net "CLK_33K_CPU_NODE1_SUSCLK_RR")
	)
	(segment
		(start 78.9559 -96.71812)
		(end 79.266034 -97.028254)
		(width 0.1016)
		(layer "B.Cu")
		(net "CLK_33K_CPU_NODE1_SUSCLK_RR")
	)
	(segment
		(start 86.762082 -99.651058)
		(end 86.58352 -99.82962)
		(width 0.1016)
		(layer "B.Cu")
		(net "CLK_33K_CPU_NODE1_SUSCLK_RR")
	)
	(segment
		(start 91.86672 -101.632258)
		(end 91.86672 -101.937058)
		(width 0.1016)
		(layer "B.Cu")
		(net "CLK_33K_CPU_NODE1_SUSCLK_RR")
	)
	(segment
		(start 81.354676 -96.380808)
		(end 81.507076 -96.228408)
		(width 0.1016)
		(layer "B.Cu")
		(net "CLK_33K_CPU_NODE1_SUSCLK_RR")
	)
	(segment
		(start 91.45778 -102.87762)
		(end 91.45778 -103.130096)
		(width 0.1016)
		(layer "B.Cu")
		(net "CLK_33K_CPU_NODE1_SUSCLK_RR")
	)
	(segment
		(start 83.511136 -95.96501)
		(end 83.511136 -100.145342)
		(width 0.1016)
		(layer "B.Cu")
		(net "CLK_33K_CPU_NODE1_SUSCLK_RR")
	)
	(segment
		(start 86.58352 -99.82962)
		(end 86.58352 -100.082096)
		(width 0.1016)
		(layer "B.Cu")
		(net "CLK_33K_CPU_NODE1_SUSCLK_RR")
	)
	(segment
		(start 90.171778 -100.260658)
		(end 90.35034 -100.43922)
		(width 0.1016)
		(layer "B.Cu")
		(net "CLK_33K_CPU_NODE1_SUSCLK_RR")
	)
	(segment
		(start 67.293744 -96.752156)
		(end 67.293744 -94.596458)
		(width 0.1016)
		(layer "B.Cu")
		(net "CLK_33K_CPU_NODE1_SUSCLK_RR")
	)
	(segment
		(start 86.35492 -102.26802)
		(end 86.35492 -102.520496)
		(width 0.1016)
		(layer "B.Cu")
		(net "CLK_33K_CPU_NODE1_SUSCLK_RR")
	)
	(segment
		(start 86.503764 -98.787458)
		(end 89.701624 -98.787458)
		(width 0.1016)
		(layer "B.Cu")
		(net "CLK_33K_CPU_NODE1_SUSCLK_RR")
	)
	(segment
		(start 66.045842 -85.110574)
		(end 66.045842 -87.024464)
		(width 0.1016)
		(layer "B.Cu")
		(net "CLK_33K_CPU_NODE1_SUSCLK_RR")
	)
	(segment
		(start 66.30797 -83.727798)
		(end 66.30797 -83.833208)
		(width 0.1016)
		(layer "B.Cu")
		(net "CLK_33K_CPU_NODE1_SUSCLK_RR")
	)
	(segment
		(start 89.670128 -99.651058)
		(end 86.762082 -99.651058)
		(width 0.1016)
		(layer "B.Cu")
		(net "CLK_33K_CPU_NODE1_SUSCLK_RR")
	)
	(segment
		(start 72.26173 -99.868482)
		(end 71.909686 -99.516438)
		(width 0.1016)
		(layer "B.Cu")
		(net "CLK_33K_CPU_NODE1_SUSCLK_RR")
	)
	(segment
		(start 86.762082 -100.870258)
		(end 86.58352 -101.04882)
		(width 0.1016)
		(layer "B.Cu")
		(net "CLK_33K_CPU_NODE1_SUSCLK_RR")
	)
	(segment
		(start 89.93886 -99.382326)
		(end 89.670128 -99.651058)
		(width 0.1016)
		(layer "B.Cu")
		(net "CLK_33K_CPU_NODE1_SUSCLK_RR")
	)
	(segment
		(start 81.354676 -100.145342)
		(end 81.354676 -96.380808)
		(width 0.1016)
		(layer "B.Cu")
		(net "CLK_33K_CPU_NODE1_SUSCLK_RR")
	)
	(segment
		(start 90.171778 -100.870258)
		(end 86.762082 -100.870258)
		(width 0.1016)
		(layer "B.Cu")
		(net "CLK_33K_CPU_NODE1_SUSCLK_RR")
	)
	(segment
		(start 81.507076 -96.228408)
		(end 81.921096 -96.228408)
		(width 0.1016)
		(layer "B.Cu")
		(net "CLK_33K_CPU_NODE1_SUSCLK_RR")
	)
	(segment
		(start 78.979014 -99.738942)
		(end 79.182214 -99.942142)
		(width 0.1016)
		(layer "B.Cu")
		(net "CLK_33K_CPU_NODE1_SUSCLK_RR")
	)
	(segment
		(start 79.266034 -97.028254)
		(end 80.207358 -97.028254)
		(width 0.1016)
		(layer "B.Cu")
		(net "CLK_33K_CPU_NODE1_SUSCLK_RR")
	)
	(segment
		(start 86.762082 -101.479858)
		(end 91.71432 -101.479858)
		(width 0.1016)
		(layer "B.Cu")
		(net "CLK_33K_CPU_NODE1_SUSCLK_RR")
	)
	(segment
		(start 84.948776 -95.225616)
		(end 84.948776 -97.23247)
		(width 0.1016)
		(layer "B.Cu")
		(net "CLK_33K_CPU_NODE1_SUSCLK_RR")
	)
	(segment
		(start 91.91752 -104.578658)
		(end 91.71432 -104.781858)
		(width 0.1016)
		(layer "B.Cu")
		(net "CLK_33K_CPU_NODE1_SUSCLK_RR")
	)
	(segment
		(start 86.533482 -102.699058)
		(end 91.279218 -102.699058)
		(width 0.1016)
		(layer "B.Cu")
		(net "CLK_33K_CPU_NODE1_SUSCLK_RR")
	)
	(segment
		(start 79.95666 -93.890084)
		(end 79.38135 -93.890084)
		(width 0.1016)
		(layer "B.Cu")
		(net "CLK_33K_CPU_NODE1_SUSCLK_RR")
	)
	(segment
		(start 68.02755 -99.868482)
		(end 67.346068 -99.187)
		(width 0.1016)
		(layer "B.Cu")
		(net "CLK_33K_CPU_NODE1_SUSCLK_RR")
	)
	(segment
		(start 79.182214 -99.078542)
		(end 78.979014 -99.281742)
		(width 0.1016)
		(layer "B.Cu")
		(net "CLK_33K_CPU_NODE1_SUSCLK_RR")
	)
	(segment
		(start 84.948776 -97.23247)
		(end 86.503764 -98.787458)
		(width 0.1016)
		(layer "B.Cu")
		(net "CLK_33K_CPU_NODE1_SUSCLK_RR")
	)
	(segment
		(start 103.270812 -68.585334)
		(end 102.442772 -68.585334)
		(width 0.1016)
		(layer "F.Cu")
		(net "XDP_CPU_NODE1_VISA7")
	)
	(segment
		(start 69.821044 -72.308212)
		(end 69.454776 -72.67448)
		(width 0.1016)
		(layer "F.Cu")
		(net "XDP_CPU_NODE1_VISA7")
	)
	(segment
		(start 69.821044 -72.296782)
		(end 69.821044 -72.308212)
		(width 0.1016)
		(layer "F.Cu")
		(net "XDP_CPU_NODE1_VISA7")
	)
	(segment
		(start 104.73182 -68.406264)
		(end 103.449882 -68.406264)
		(width 0.1016)
		(layer "F.Cu")
		(net "XDP_CPU_NODE1_VISA7")
	)
	(segment
		(start 102.442772 -68.585334)
		(end 102.399592 -68.628514)
		(width 0.1016)
		(layer "F.Cu")
		(net "XDP_CPU_NODE1_VISA7")
	)
	(segment
		(start 69.454776 -72.67448)
		(end 69.454776 -72.690482)
		(width 0.1016)
		(layer "F.Cu")
		(net "XDP_CPU_NODE1_VISA7")
	)
	(segment
		(start 103.449882 -68.406264)
		(end 103.270812 -68.585334)
		(width 0.1016)
		(layer "F.Cu")
		(net "XDP_CPU_NODE1_VISA7")
	)
	(via
		(at 69.454776 -72.690482)
		(size 0.508)
		(drill 0.254)
		(layers "F.Cu" "B.Cu")
		(net "XDP_CPU_NODE1_VISA7")
	)
	(via
		(at 102.399592 -68.628514)
		(size 0.508)
		(drill 0.254)
		(layers "F.Cu" "B.Cu")
		(net "XDP_CPU_NODE1_VISA7")
	)
	(segment
		(start 98.257868 -69.18071)
		(end 98.44024 -68.998338)
		(width 0.1143)
		(layer "In2.Cu")
		(net "XDP_CPU_NODE1_VISA7")
	)
	(segment
		(start 71.147432 -74.311002)
		(end 73.026524 -74.311002)
		(width 0.1143)
		(layer "In2.Cu")
		(net "XDP_CPU_NODE1_VISA7")
	)
	(segment
		(start 75.658726 -72.451468)
		(end 77.377798 -72.451468)
		(width 0.1143)
		(layer "In2.Cu")
		(net "XDP_CPU_NODE1_VISA7")
	)
	(segment
		(start 92.54109 -68.118482)
		(end 92.54109 -68.70446)
		(width 0.1143)
		(layer "In2.Cu")
		(net "XDP_CPU_NODE1_VISA7")
	)
	(segment
		(start 102.435152 -68.592954)
		(end 102.399592 -68.628514)
		(width 0.1143)
		(layer "In2.Cu")
		(net "XDP_CPU_NODE1_VISA7")
	)
	(segment
		(start 103.664512 -67.813174)
		(end 103.567992 -67.909694)
		(width 0.1143)
		(layer "In2.Cu")
		(net "XDP_CPU_NODE1_VISA7")
	)
	(segment
		(start 104.228392 -67.813174)
		(end 103.664512 -67.813174)
		(width 0.1143)
		(layer "In2.Cu")
		(net "XDP_CPU_NODE1_VISA7")
	)
	(segment
		(start 104.373172 -69.644514)
		(end 104.373172 -67.957954)
		(width 0.1143)
		(layer "In2.Cu")
		(net "XDP_CPU_NODE1_VISA7")
	)
	(segment
		(start 93.01734 -69.18071)
		(end 98.257868 -69.18071)
		(width 0.1143)
		(layer "In2.Cu")
		(net "XDP_CPU_NODE1_VISA7")
	)
	(segment
		(start 74.772774 -72.402192)
		(end 75.60945 -72.402192)
		(width 0.1143)
		(layer "In2.Cu")
		(net "XDP_CPU_NODE1_VISA7")
	)
	(segment
		(start 102.163372 -69.448934)
		(end 102.163372 -69.674994)
		(width 0.1143)
		(layer "In2.Cu")
		(net "XDP_CPU_NODE1_VISA7")
	)
	(segment
		(start 81.292446 -71.711058)
		(end 85.067394 -67.93611)
		(width 0.1143)
		(layer "In2.Cu")
		(net "XDP_CPU_NODE1_VISA7")
	)
	(segment
		(start 98.942144 -68.110354)
		(end 100.45065 -68.110354)
		(width 0.1143)
		(layer "In2.Cu")
		(net "XDP_CPU_NODE1_VISA7")
	)
	(segment
		(start 100.773992 -68.433696)
		(end 100.773992 -68.776596)
		(width 0.1143)
		(layer "In2.Cu")
		(net "XDP_CPU_NODE1_VISA7")
	)
	(segment
		(start 92.54109 -68.70446)
		(end 93.01734 -69.18071)
		(width 0.1143)
		(layer "In2.Cu")
		(net "XDP_CPU_NODE1_VISA7")
	)
	(segment
		(start 93.16339 -68.118482)
		(end 93.345762 -67.93611)
		(width 0.1143)
		(layer "In2.Cu")
		(net "XDP_CPU_NODE1_VISA7")
	)
	(segment
		(start 77.377798 -72.451468)
		(end 78.118208 -71.711058)
		(width 0.1143)
		(layer "In2.Cu")
		(net "XDP_CPU_NODE1_VISA7")
	)
	(segment
		(start 93.345762 -67.93611)
		(end 98.7679 -67.93611)
		(width 0.1143)
		(layer "In2.Cu")
		(net "XDP_CPU_NODE1_VISA7")
	)
	(segment
		(start 98.44024 -68.740782)
		(end 98.257868 -68.55841)
		(width 0.1143)
		(layer "In2.Cu")
		(net "XDP_CPU_NODE1_VISA7")
	)
	(segment
		(start 102.163372 -69.674994)
		(end 102.379272 -69.890894)
		(width 0.1143)
		(layer "In2.Cu")
		(net "XDP_CPU_NODE1_VISA7")
	)
	(segment
		(start 92.358718 -67.93611)
		(end 92.54109 -68.118482)
		(width 0.1143)
		(layer "In2.Cu")
		(net "XDP_CPU_NODE1_VISA7")
	)
	(segment
		(start 78.118208 -71.711058)
		(end 81.292446 -71.711058)
		(width 0.1143)
		(layer "In2.Cu")
		(net "XDP_CPU_NODE1_VISA7")
	)
	(segment
		(start 100.45065 -68.110354)
		(end 100.773992 -68.433696)
		(width 0.1143)
		(layer "In2.Cu")
		(net "XDP_CPU_NODE1_VISA7")
	)
	(segment
		(start 101.28377 -69.286374)
		(end 102.000812 -69.286374)
		(width 0.1143)
		(layer "In2.Cu")
		(net "XDP_CPU_NODE1_VISA7")
	)
	(segment
		(start 103.567992 -67.909694)
		(end 103.567992 -68.542154)
		(width 0.1143)
		(layer "In2.Cu")
		(net "XDP_CPU_NODE1_VISA7")
	)
	(segment
		(start 74.445114 -72.729852)
		(end 74.772774 -72.402192)
		(width 0.1143)
		(layer "In2.Cu")
		(net "XDP_CPU_NODE1_VISA7")
	)
	(segment
		(start 93.345762 -68.55841)
		(end 93.16339 -68.376038)
		(width 0.1143)
		(layer "In2.Cu")
		(net "XDP_CPU_NODE1_VISA7")
	)
	(segment
		(start 69.526912 -72.690482)
		(end 71.147432 -74.311002)
		(width 0.1143)
		(layer "In2.Cu")
		(net "XDP_CPU_NODE1_VISA7")
	)
	(segment
		(start 98.44024 -68.998338)
		(end 98.44024 -68.740782)
		(width 0.1143)
		(layer "In2.Cu")
		(net "XDP_CPU_NODE1_VISA7")
	)
	(segment
		(start 102.000812 -69.286374)
		(end 102.163372 -69.448934)
		(width 0.1143)
		(layer "In2.Cu")
		(net "XDP_CPU_NODE1_VISA7")
	)
	(segment
		(start 93.16339 -68.376038)
		(end 93.16339 -68.118482)
		(width 0.1143)
		(layer "In2.Cu")
		(net "XDP_CPU_NODE1_VISA7")
	)
	(segment
		(start 103.517192 -68.592954)
		(end 102.435152 -68.592954)
		(width 0.1143)
		(layer "In2.Cu")
		(net "XDP_CPU_NODE1_VISA7")
	)
	(segment
		(start 98.7679 -67.93611)
		(end 98.942144 -68.110354)
		(width 0.1143)
		(layer "In2.Cu")
		(net "XDP_CPU_NODE1_VISA7")
	)
	(segment
		(start 103.567992 -68.542154)
		(end 103.517192 -68.592954)
		(width 0.1143)
		(layer "In2.Cu")
		(net "XDP_CPU_NODE1_VISA7")
	)
	(segment
		(start 100.773992 -68.776596)
		(end 101.28377 -69.286374)
		(width 0.1143)
		(layer "In2.Cu")
		(net "XDP_CPU_NODE1_VISA7")
	)
	(segment
		(start 75.60945 -72.402192)
		(end 75.658726 -72.451468)
		(width 0.1143)
		(layer "In2.Cu")
		(net "XDP_CPU_NODE1_VISA7")
	)
	(segment
		(start 98.257868 -68.55841)
		(end 93.345762 -68.55841)
		(width 0.1143)
		(layer "In2.Cu")
		(net "XDP_CPU_NODE1_VISA7")
	)
	(segment
		(start 104.126792 -69.890894)
		(end 104.373172 -69.644514)
		(width 0.1143)
		(layer "In2.Cu")
		(net "XDP_CPU_NODE1_VISA7")
	)
	(segment
		(start 74.445114 -72.892412)
		(end 74.445114 -72.729852)
		(width 0.1143)
		(layer "In2.Cu")
		(net "XDP_CPU_NODE1_VISA7")
	)
	(segment
		(start 69.454776 -72.690482)
		(end 69.526912 -72.690482)
		(width 0.1143)
		(layer "In2.Cu")
		(net "XDP_CPU_NODE1_VISA7")
	)
	(segment
		(start 104.373172 -67.957954)
		(end 104.228392 -67.813174)
		(width 0.1143)
		(layer "In2.Cu")
		(net "XDP_CPU_NODE1_VISA7")
	)
	(segment
		(start 102.379272 -69.890894)
		(end 104.126792 -69.890894)
		(width 0.1143)
		(layer "In2.Cu")
		(net "XDP_CPU_NODE1_VISA7")
	)
	(segment
		(start 85.067394 -67.93611)
		(end 92.358718 -67.93611)
		(width 0.1143)
		(layer "In2.Cu")
		(net "XDP_CPU_NODE1_VISA7")
	)
	(segment
		(start 73.026524 -74.311002)
		(end 74.445114 -72.892412)
		(width 0.1143)
		(layer "In2.Cu")
		(net "XDP_CPU_NODE1_VISA7")
	)
	(via
		(at 18.44929 -129.283714)
		(size 0.508)
		(drill 0.254)
		(layers "F.Cu" "B.Cu")
		(net "SW_P1V05_NODE1_BT")
	)
	(segment
		(start 171.623228 -95.63735)
		(end 171.979082 -95.281496)
		(width 0.1016)
		(layer "F.Cu")
		(net "USB_NODE1_RREF")
	)
	(segment
		(start 170.043348 -96.491806)
		(end 170.897804 -95.63735)
		(width 0.1016)
		(layer "F.Cu")
		(net "USB_NODE1_RREF")
	)
	(segment
		(start 171.478956 -93.877892)
		(end 171.478956 -94.44101)
		(width 0.1016)
		(layer "F.Cu")
		(net "USB_NODE1_RREF")
	)
	(segment
		(start 171.979082 -94.941136)
		(end 171.979082 -95.281496)
		(width 0.1016)
		(layer "F.Cu")
		(net "USB_NODE1_RREF")
	)
	(segment
		(start 171.478956 -94.44101)
		(end 171.979082 -94.941136)
		(width 0.1016)
		(layer "F.Cu")
		(net "USB_NODE1_RREF")
	)
	(segment
		(start 170.043348 -97.032572)
		(end 170.043348 -96.491806)
		(width 0.1016)
		(layer "F.Cu")
		(net "USB_NODE1_RREF")
	)
	(segment
		(start 170.897804 -95.63735)
		(end 171.623228 -95.63735)
		(width 0.1016)
		(layer "F.Cu")
		(net "USB_NODE1_RREF")
	)
	(via
		(at 171.979082 -95.281496)
		(size 0.508)
		(drill 0.254)
		(layers "F.Cu" "B.Cu")
		(net "USB_NODE1_RREF")
	)
	(segment
		(start 67.624452 -88.551766)
		(end 67.681348 -88.608662)
		(width 0.1016)
		(layer "F.Cu")
		(net "TP_CPU_NODE1_ADR_COMPLETE")
	)
	(segment
		(start 67.681348 -90.46972)
		(end 68.33489 -91.123262)
		(width 0.1016)
		(layer "F.Cu")
		(net "TP_CPU_NODE1_ADR_COMPLETE")
	)
	(segment
		(start 67.681348 -88.608662)
		(end 67.681348 -90.46972)
		(width 0.1016)
		(layer "F.Cu")
		(net "TP_CPU_NODE1_ADR_COMPLETE")
	)
	(segment
		(start 68.33489 -91.123262)
		(end 68.551044 -91.123262)
		(width 0.1016)
		(layer "F.Cu")
		(net "TP_CPU_NODE1_ADR_COMPLETE")
	)
	(via
		(at 68.551044 -91.123262)
		(size 0.508)
		(drill 0.254)
		(layers "F.Cu" "B.Cu")
		(net "TP_CPU_NODE1_ADR_COMPLETE")
	)
	(segment
		(start 102.501192 -67.416934)
		(end 102.010972 -67.907154)
		(width 0.1016)
		(layer "F.Cu")
		(net "XDP_CPU_NODE1_VISA8")
	)
	(segment
		(start 71.454772 -73.732898)
		(end 71.581772 -73.859898)
		(width 0.1016)
		(layer "F.Cu")
		(net "XDP_CPU_NODE1_VISA8")
	)
	(segment
		(start 71.345044 -73.115424)
		(end 71.454772 -73.225152)
		(width 0.1016)
		(layer "F.Cu")
		(net "XDP_CPU_NODE1_VISA8")
	)
	(segment
		(start 103.640636 -67.906138)
		(end 103.151432 -67.416934)
		(width 0.1016)
		(layer "F.Cu")
		(net "XDP_CPU_NODE1_VISA8")
	)
	(segment
		(start 71.454772 -73.225152)
		(end 71.454772 -73.732898)
		(width 0.1016)
		(layer "F.Cu")
		(net "XDP_CPU_NODE1_VISA8")
	)
	(segment
		(start 71.345044 -72.296782)
		(end 71.345044 -73.115424)
		(width 0.1016)
		(layer "F.Cu")
		(net "XDP_CPU_NODE1_VISA8")
	)
	(segment
		(start 103.151432 -67.416934)
		(end 102.501192 -67.416934)
		(width 0.1016)
		(layer "F.Cu")
		(net "XDP_CPU_NODE1_VISA8")
	)
	(segment
		(start 104.73182 -67.906138)
		(end 103.640636 -67.906138)
		(width 0.1016)
		(layer "F.Cu")
		(net "XDP_CPU_NODE1_VISA8")
	)
	(via
		(at 71.581772 -73.859898)
		(size 0.508)
		(drill 0.254)
		(layers "F.Cu" "B.Cu")
		(net "XDP_CPU_NODE1_VISA8")
	)
	(via
		(at 102.010972 -67.907154)
		(size 0.508)
		(drill 0.254)
		(layers "F.Cu" "B.Cu")
		(net "XDP_CPU_NODE1_VISA8")
	)
	(segment
		(start 96.233742 -67.333876)
		(end 96.233742 -66.67246)
		(width 0.1143)
		(layer "In2.Cu")
		(net "XDP_CPU_NODE1_VISA8")
	)
	(segment
		(start 71.581772 -73.859898)
		(end 73.141078 -73.859898)
		(width 0.1143)
		(layer "In2.Cu")
		(net "XDP_CPU_NODE1_VISA8")
	)
	(segment
		(start 96.856042 -66.67246)
		(end 96.856042 -67.333876)
		(width 0.1143)
		(layer "In2.Cu")
		(net "XDP_CPU_NODE1_VISA8")
	)
	(segment
		(start 94.549214 -67.516248)
		(end 94.80677 -67.516248)
		(width 0.1143)
		(layer "In2.Cu")
		(net "XDP_CPU_NODE1_VISA8")
	)
	(segment
		(start 96.05137 -67.516248)
		(end 96.233742 -67.333876)
		(width 0.1143)
		(layer "In2.Cu")
		(net "XDP_CPU_NODE1_VISA8")
	)
	(segment
		(start 94.989142 -66.67246)
		(end 95.171514 -66.490088)
		(width 0.1143)
		(layer "In2.Cu")
		(net "XDP_CPU_NODE1_VISA8")
	)
	(segment
		(start 96.856042 -67.333876)
		(end 97.038414 -67.516248)
		(width 0.1143)
		(layer "In2.Cu")
		(net "XDP_CPU_NODE1_VISA8")
	)
	(segment
		(start 101.794818 -67.691)
		(end 102.010972 -67.907154)
		(width 0.1143)
		(layer "In2.Cu")
		(net "XDP_CPU_NODE1_VISA8")
	)
	(segment
		(start 75.90917 -72.211946)
		(end 76.805536 -72.211946)
		(width 0.1143)
		(layer "In2.Cu")
		(net "XDP_CPU_NODE1_VISA8")
	)
	(segment
		(start 94.366842 -67.333876)
		(end 94.549214 -67.516248)
		(width 0.1143)
		(layer "In2.Cu")
		(net "XDP_CPU_NODE1_VISA8")
	)
	(segment
		(start 93.56217 -67.516248)
		(end 93.744542 -67.333876)
		(width 0.1143)
		(layer "In2.Cu")
		(net "XDP_CPU_NODE1_VISA8")
	)
	(segment
		(start 73.141078 -73.859898)
		(end 74.164952 -72.836024)
		(width 0.1143)
		(layer "In2.Cu")
		(net "XDP_CPU_NODE1_VISA8")
	)
	(segment
		(start 85.85708 -66.565526)
		(end 85.85708 -66.30797)
		(width 0.1143)
		(layer "In2.Cu")
		(net "XDP_CPU_NODE1_VISA8")
	)
	(segment
		(start 74.164952 -72.836024)
		(end 74.164952 -72.490838)
		(width 0.1143)
		(layer "In2.Cu")
		(net "XDP_CPU_NODE1_VISA8")
	)
	(segment
		(start 95.611442 -67.333876)
		(end 95.793814 -67.516248)
		(width 0.1143)
		(layer "In2.Cu")
		(net "XDP_CPU_NODE1_VISA8")
	)
	(segment
		(start 93.744542 -67.333876)
		(end 93.744542 -66.67246)
		(width 0.1143)
		(layer "In2.Cu")
		(net "XDP_CPU_NODE1_VISA8")
	)
	(segment
		(start 91.800426 -66.747898)
		(end 86.039452 -66.747898)
		(width 0.1143)
		(layer "In2.Cu")
		(net "XDP_CPU_NODE1_VISA8")
	)
	(segment
		(start 97.29597 -67.516248)
		(end 97.478342 -67.333876)
		(width 0.1143)
		(layer "In2.Cu")
		(net "XDP_CPU_NODE1_VISA8")
	)
	(segment
		(start 96.233742 -66.67246)
		(end 96.416114 -66.490088)
		(width 0.1143)
		(layer "In2.Cu")
		(net "XDP_CPU_NODE1_VISA8")
	)
	(segment
		(start 94.80677 -67.516248)
		(end 94.989142 -67.333876)
		(width 0.1143)
		(layer "In2.Cu")
		(net "XDP_CPU_NODE1_VISA8")
	)
	(segment
		(start 76.805536 -72.211946)
		(end 77.763116 -71.254366)
		(width 0.1143)
		(layer "In2.Cu")
		(net "XDP_CPU_NODE1_VISA8")
	)
	(segment
		(start 99.598988 -67.691)
		(end 101.794818 -67.691)
		(width 0.1143)
		(layer "In2.Cu")
		(net "XDP_CPU_NODE1_VISA8")
	)
	(segment
		(start 95.171514 -66.490088)
		(end 95.42907 -66.490088)
		(width 0.1143)
		(layer "In2.Cu")
		(net "XDP_CPU_NODE1_VISA8")
	)
	(segment
		(start 91.982798 -67.187826)
		(end 91.982798 -66.93027)
		(width 0.1143)
		(layer "In2.Cu")
		(net "XDP_CPU_NODE1_VISA8")
	)
	(segment
		(start 80.91551 -71.254366)
		(end 84.799678 -67.370198)
		(width 0.1143)
		(layer "In2.Cu")
		(net "XDP_CPU_NODE1_VISA8")
	)
	(segment
		(start 86.039452 -66.125598)
		(end 91.982798 -66.125598)
		(width 0.1143)
		(layer "In2.Cu")
		(net "XDP_CPU_NODE1_VISA8")
	)
	(segment
		(start 95.42907 -66.490088)
		(end 95.611442 -66.67246)
		(width 0.1143)
		(layer "In2.Cu")
		(net "XDP_CPU_NODE1_VISA8")
	)
	(segment
		(start 93.122242 -67.333876)
		(end 93.304614 -67.516248)
		(width 0.1143)
		(layer "In2.Cu")
		(net "XDP_CPU_NODE1_VISA8")
	)
	(segment
		(start 91.800426 -67.370198)
		(end 91.982798 -67.187826)
		(width 0.1143)
		(layer "In2.Cu")
		(net "XDP_CPU_NODE1_VISA8")
	)
	(segment
		(start 94.989142 -67.333876)
		(end 94.989142 -66.67246)
		(width 0.1143)
		(layer "In2.Cu")
		(net "XDP_CPU_NODE1_VISA8")
	)
	(segment
		(start 91.982798 -66.93027)
		(end 91.800426 -66.747898)
		(width 0.1143)
		(layer "In2.Cu")
		(net "XDP_CPU_NODE1_VISA8")
	)
	(segment
		(start 92.93987 -66.490088)
		(end 93.122242 -66.67246)
		(width 0.1143)
		(layer "In2.Cu")
		(net "XDP_CPU_NODE1_VISA8")
	)
	(segment
		(start 97.478342 -67.333876)
		(end 97.478342 -66.67246)
		(width 0.1143)
		(layer "In2.Cu")
		(net "XDP_CPU_NODE1_VISA8")
	)
	(segment
		(start 86.039452 -66.747898)
		(end 85.85708 -66.565526)
		(width 0.1143)
		(layer "In2.Cu")
		(net "XDP_CPU_NODE1_VISA8")
	)
	(segment
		(start 97.478342 -66.67246)
		(end 97.660714 -66.490088)
		(width 0.1143)
		(layer "In2.Cu")
		(net "XDP_CPU_NODE1_VISA8")
	)
	(segment
		(start 96.67367 -66.490088)
		(end 96.856042 -66.67246)
		(width 0.1143)
		(layer "In2.Cu")
		(net "XDP_CPU_NODE1_VISA8")
	)
	(segment
		(start 93.744542 -66.67246)
		(end 93.926914 -66.490088)
		(width 0.1143)
		(layer "In2.Cu")
		(net "XDP_CPU_NODE1_VISA8")
	)
	(segment
		(start 74.164952 -72.490838)
		(end 74.593958 -72.061832)
		(width 0.1143)
		(layer "In2.Cu")
		(net "XDP_CPU_NODE1_VISA8")
	)
	(segment
		(start 93.122242 -66.67246)
		(end 93.122242 -67.333876)
		(width 0.1143)
		(layer "In2.Cu")
		(net "XDP_CPU_NODE1_VISA8")
	)
	(segment
		(start 94.366842 -66.67246)
		(end 94.366842 -67.333876)
		(width 0.1143)
		(layer "In2.Cu")
		(net "XDP_CPU_NODE1_VISA8")
	)
	(segment
		(start 93.926914 -66.490088)
		(end 94.18447 -66.490088)
		(width 0.1143)
		(layer "In2.Cu")
		(net "XDP_CPU_NODE1_VISA8")
	)
	(segment
		(start 95.611442 -66.67246)
		(end 95.611442 -67.333876)
		(width 0.1143)
		(layer "In2.Cu")
		(net "XDP_CPU_NODE1_VISA8")
	)
	(segment
		(start 84.799678 -67.370198)
		(end 91.800426 -67.370198)
		(width 0.1143)
		(layer "In2.Cu")
		(net "XDP_CPU_NODE1_VISA8")
	)
	(segment
		(start 77.763116 -71.254366)
		(end 80.91551 -71.254366)
		(width 0.1143)
		(layer "In2.Cu")
		(net "XDP_CPU_NODE1_VISA8")
	)
	(segment
		(start 75.759056 -72.061832)
		(end 75.90917 -72.211946)
		(width 0.1143)
		(layer "In2.Cu")
		(net "XDP_CPU_NODE1_VISA8")
	)
	(segment
		(start 93.304614 -67.516248)
		(end 93.56217 -67.516248)
		(width 0.1143)
		(layer "In2.Cu")
		(net "XDP_CPU_NODE1_VISA8")
	)
	(segment
		(start 85.85708 -66.30797)
		(end 86.039452 -66.125598)
		(width 0.1143)
		(layer "In2.Cu")
		(net "XDP_CPU_NODE1_VISA8")
	)
	(segment
		(start 92.347288 -66.490088)
		(end 92.93987 -66.490088)
		(width 0.1143)
		(layer "In2.Cu")
		(net "XDP_CPU_NODE1_VISA8")
	)
	(segment
		(start 97.660714 -66.490088)
		(end 98.398076 -66.490088)
		(width 0.1143)
		(layer "In2.Cu")
		(net "XDP_CPU_NODE1_VISA8")
	)
	(segment
		(start 96.416114 -66.490088)
		(end 96.67367 -66.490088)
		(width 0.1143)
		(layer "In2.Cu")
		(net "XDP_CPU_NODE1_VISA8")
	)
	(segment
		(start 91.982798 -66.125598)
		(end 92.347288 -66.490088)
		(width 0.1143)
		(layer "In2.Cu")
		(net "XDP_CPU_NODE1_VISA8")
	)
	(segment
		(start 94.18447 -66.490088)
		(end 94.366842 -66.67246)
		(width 0.1143)
		(layer "In2.Cu")
		(net "XDP_CPU_NODE1_VISA8")
	)
	(segment
		(start 97.038414 -67.516248)
		(end 97.29597 -67.516248)
		(width 0.1143)
		(layer "In2.Cu")
		(net "XDP_CPU_NODE1_VISA8")
	)
	(segment
		(start 95.793814 -67.516248)
		(end 96.05137 -67.516248)
		(width 0.1143)
		(layer "In2.Cu")
		(net "XDP_CPU_NODE1_VISA8")
	)
	(segment
		(start 74.593958 -72.061832)
		(end 75.759056 -72.061832)
		(width 0.1143)
		(layer "In2.Cu")
		(net "XDP_CPU_NODE1_VISA8")
	)
	(segment
		(start 98.398076 -66.490088)
		(end 99.598988 -67.691)
		(width 0.1143)
		(layer "In2.Cu")
		(net "XDP_CPU_NODE1_VISA8")
	)
	(segment
		(start 19.32559 -131.344416)
		(end 19.01825 -131.344416)
		(width 0.254)
		(layer "F.Cu")
		(net "P1V05_NODE1_MODE")
	)
	(segment
		(start 19.01825 -131.344416)
		(end 18.556478 -130.882644)
		(width 0.254)
		(layer "F.Cu")
		(net "P1V05_NODE1_MODE")
	)
	(segment
		(start 18.196052 -130.522218)
		(end 18.556478 -130.882644)
		(width 0.254)
		(layer "F.Cu")
		(net "P1V05_NODE1_MODE")
	)
	(segment
		(start 17.612106 -130.522218)
		(end 18.196052 -130.522218)
		(width 0.254)
		(layer "F.Cu")
		(net "P1V05_NODE1_MODE")
	)
	(via
		(at 18.556478 -130.882644)
		(size 0.508)
		(drill 0.254)
		(layers "F.Cu" "B.Cu")
		(net "P1V05_NODE1_MODE")
	)
	(segment
		(start 165.922452 -87.803228)
		(end 165.922452 -87.550752)
		(width 0.1016)
		(layer "F.Cu")
		(net "SPI_USB_NODE1_SO")
	)
	(segment
		(start 165.922452 -88.769952)
		(end 166.101014 -88.59139)
		(width 0.1016)
		(layer "F.Cu")
		(net "SPI_USB_NODE1_SO")
	)
	(segment
		(start 172.22089 -87.193628)
		(end 172.22089 -86.941152)
		(width 0.1016)
		(layer "F.Cu")
		(net "SPI_USB_NODE1_SO")
	)
	(segment
		(start 172.22089 -86.941152)
		(end 172.042328 -86.76259)
		(width 0.1016)
		(layer "F.Cu")
		(net "SPI_USB_NODE1_SO")
	)
	(segment
		(start 172.042328 -86.76259)
		(end 163.440618 -86.76259)
		(width 0.1016)
		(layer "F.Cu")
		(net "SPI_USB_NODE1_SO")
	)
	(segment
		(start 166.101014 -88.59139)
		(end 172.042328 -88.59139)
		(width 0.1016)
		(layer "F.Cu")
		(net "SPI_USB_NODE1_SO")
	)
	(segment
		(start 162.733482 -86.313772)
		(end 162.724338 -86.322916)
		(width 0.1016)
		(layer "F.Cu")
		(net "SPI_USB_NODE1_SO")
	)
	(segment
		(start 172.22089 -88.160352)
		(end 172.042328 -87.98179)
		(width 0.1016)
		(layer "F.Cu")
		(net "SPI_USB_NODE1_SO")
	)
	(segment
		(start 166.101014 -87.98179)
		(end 165.922452 -87.803228)
		(width 0.1016)
		(layer "F.Cu")
		(net "SPI_USB_NODE1_SO")
	)
	(segment
		(start 163.440618 -86.76259)
		(end 163.000944 -86.322916)
		(width 0.1016)
		(layer "F.Cu")
		(net "SPI_USB_NODE1_SO")
	)
	(segment
		(start 172.042328 -87.37219)
		(end 172.22089 -87.193628)
		(width 0.1016)
		(layer "F.Cu")
		(net "SPI_USB_NODE1_SO")
	)
	(segment
		(start 161.14776 -86.313772)
		(end 162.733482 -86.313772)
		(width 0.1016)
		(layer "F.Cu")
		(net "SPI_USB_NODE1_SO")
	)
	(segment
		(start 172.22089 -88.412828)
		(end 172.22089 -88.160352)
		(width 0.1016)
		(layer "F.Cu")
		(net "SPI_USB_NODE1_SO")
	)
	(segment
		(start 165.922452 -87.550752)
		(end 166.101014 -87.37219)
		(width 0.1016)
		(layer "F.Cu")
		(net "SPI_USB_NODE1_SO")
	)
	(segment
		(start 164.905944 -93.440758)
		(end 164.905944 -91.85148)
		(width 0.1016)
		(layer "F.Cu")
		(net "SPI_USB_NODE1_SO")
	)
	(segment
		(start 164.905944 -91.85148)
		(end 165.922452 -90.834972)
		(width 0.1016)
		(layer "F.Cu")
		(net "SPI_USB_NODE1_SO")
	)
	(segment
		(start 163.000944 -86.322916)
		(end 162.724338 -86.322916)
		(width 0.1016)
		(layer "F.Cu")
		(net "SPI_USB_NODE1_SO")
	)
	(segment
		(start 165.922452 -90.834972)
		(end 165.922452 -88.769952)
		(width 0.1016)
		(layer "F.Cu")
		(net "SPI_USB_NODE1_SO")
	)
	(segment
		(start 166.101014 -87.37219)
		(end 172.042328 -87.37219)
		(width 0.1016)
		(layer "F.Cu")
		(net "SPI_USB_NODE1_SO")
	)
	(segment
		(start 172.042328 -88.59139)
		(end 172.22089 -88.412828)
		(width 0.1016)
		(layer "F.Cu")
		(net "SPI_USB_NODE1_SO")
	)
	(segment
		(start 172.042328 -87.98179)
		(end 166.101014 -87.98179)
		(width 0.1016)
		(layer "F.Cu")
		(net "SPI_USB_NODE1_SO")
	)
	(via
		(at 162.724338 -86.322916)
		(size 0.508)
		(drill 0.254)
		(layers "F.Cu" "B.Cu")
		(net "SPI_USB_NODE1_SO")
	)
	(segment
		(start 67.150488 -90.707464)
		(end 68.654422 -92.211398)
		(width 0.1016)
		(layer "F.Cu")
		(net "TP_CPU_NODE1_C2F_LP_MODE")
	)
	(segment
		(start 66.903092 -89.048844)
		(end 67.150488 -89.29624)
		(width 0.1016)
		(layer "F.Cu")
		(net "TP_CPU_NODE1_C2F_LP_MODE")
	)
	(segment
		(start 67.150488 -89.29624)
		(end 67.150488 -90.707464)
		(width 0.1016)
		(layer "F.Cu")
		(net "TP_CPU_NODE1_C2F_LP_MODE")
	)
	(segment
		(start 68.654422 -92.211398)
		(end 68.654422 -92.448888)
		(width 0.1016)
		(layer "F.Cu")
		(net "TP_CPU_NODE1_C2F_LP_MODE")
	)
	(via
		(at 68.654422 -92.448888)
		(size 0.508)
		(drill 0.254)
		(layers "F.Cu" "B.Cu")
		(net "TP_CPU_NODE1_C2F_LP_MODE")
	)
	(segment
		(start 103.057452 -77.521054)
		(end 99.122992 -73.586594)
		(width 0.1016)
		(layer "F.Cu")
		(net "XDP_CPU_NODE1_VISA0")
	)
	(segment
		(start 99.122992 -73.586594)
		(end 99.122992 -67.896994)
		(width 0.1016)
		(layer "F.Cu")
		(net "XDP_CPU_NODE1_VISA0")
	)
	(segment
		(start 110.460028 -75.906122)
		(end 108.477304 -75.906122)
		(width 0.1016)
		(layer "F.Cu")
		(net "XDP_CPU_NODE1_VISA0")
	)
	(segment
		(start 100.172012 -66.847974)
		(end 100.172012 -66.167254)
		(width 0.1016)
		(layer "F.Cu")
		(net "XDP_CPU_NODE1_VISA0")
	)
	(segment
		(start 108.477304 -75.906122)
		(end 106.862372 -77.521054)
		(width 0.1016)
		(layer "F.Cu")
		(net "XDP_CPU_NODE1_VISA0")
	)
	(segment
		(start 99.122992 -67.896994)
		(end 100.172012 -66.847974)
		(width 0.1016)
		(layer "F.Cu")
		(net "XDP_CPU_NODE1_VISA0")
	)
	(segment
		(start 67.535044 -71.596758)
		(end 67.542664 -71.596758)
		(width 0.1016)
		(layer "F.Cu")
		(net "XDP_CPU_NODE1_VISA0")
	)
	(segment
		(start 106.862372 -77.521054)
		(end 103.057452 -77.521054)
		(width 0.1016)
		(layer "F.Cu")
		(net "XDP_CPU_NODE1_VISA0")
	)
	(segment
		(start 67.542664 -71.596758)
		(end 67.916044 -71.223378)
		(width 0.1016)
		(layer "F.Cu")
		(net "XDP_CPU_NODE1_VISA0")
	)
	(via
		(at 67.916044 -71.223378)
		(size 0.508)
		(drill 0.254)
		(layers "F.Cu" "B.Cu")
		(net "XDP_CPU_NODE1_VISA0")
	)
	(via
		(at 100.172012 -66.167254)
		(size 0.508)
		(drill 0.254)
		(layers "F.Cu" "B.Cu")
		(net "XDP_CPU_NODE1_VISA0")
	)
	(segment
		(start 72.22998 -72.254618)
		(end 74.065638 -70.419468)
		(width 0.1143)
		(layer "In2.Cu")
		(net "XDP_CPU_NODE1_VISA0")
	)
	(segment
		(start 67.916044 -71.223378)
		(end 67.916044 -71.37273)
		(width 0.1143)
		(layer "In2.Cu")
		(net "XDP_CPU_NODE1_VISA0")
	)
	(segment
		(start 85.514688 -64.865504)
		(end 90.852244 -64.865504)
		(width 0.1143)
		(layer "In2.Cu")
		(net "XDP_CPU_NODE1_VISA0")
	)
	(segment
		(start 80.439514 -69.940678)
		(end 85.514688 -64.865504)
		(width 0.1143)
		(layer "In2.Cu")
		(net "XDP_CPU_NODE1_VISA0")
	)
	(segment
		(start 91.37904 -64.338708)
		(end 99.199446 -64.338708)
		(width 0.1143)
		(layer "In2.Cu")
		(net "XDP_CPU_NODE1_VISA0")
	)
	(segment
		(start 100.33508 -65.474342)
		(end 100.33508 -66.004694)
		(width 0.1143)
		(layer "In2.Cu")
		(net "XDP_CPU_NODE1_VISA0")
	)
	(segment
		(start 75.864974 -69.940678)
		(end 80.439514 -69.940678)
		(width 0.1143)
		(layer "In2.Cu")
		(net "XDP_CPU_NODE1_VISA0")
	)
	(segment
		(start 100.17252 -66.167254)
		(end 100.172012 -66.167254)
		(width 0.1143)
		(layer "In2.Cu")
		(net "XDP_CPU_NODE1_VISA0")
	)
	(segment
		(start 67.916044 -71.37273)
		(end 68.797932 -72.254618)
		(width 0.1143)
		(layer "In2.Cu")
		(net "XDP_CPU_NODE1_VISA0")
	)
	(segment
		(start 90.852244 -64.865504)
		(end 91.37904 -64.338708)
		(width 0.1143)
		(layer "In2.Cu")
		(net "XDP_CPU_NODE1_VISA0")
	)
	(segment
		(start 68.797932 -72.254618)
		(end 72.22998 -72.254618)
		(width 0.1143)
		(layer "In2.Cu")
		(net "XDP_CPU_NODE1_VISA0")
	)
	(segment
		(start 99.199446 -64.338708)
		(end 100.33508 -65.474342)
		(width 0.1143)
		(layer "In2.Cu")
		(net "XDP_CPU_NODE1_VISA0")
	)
	(segment
		(start 75.386184 -70.419468)
		(end 75.864974 -69.940678)
		(width 0.1143)
		(layer "In2.Cu")
		(net "XDP_CPU_NODE1_VISA0")
	)
	(segment
		(start 100.33508 -66.004694)
		(end 100.17252 -66.167254)
		(width 0.1143)
		(layer "In2.Cu")
		(net "XDP_CPU_NODE1_VISA0")
	)
	(segment
		(start 74.065638 -70.419468)
		(end 75.386184 -70.419468)
		(width 0.1143)
		(layer "In2.Cu")
		(net "XDP_CPU_NODE1_VISA0")
	)
	(segment
		(start 16.81226 -131.82219)
		(end 16.81226 -132.12953)
		(width 0.254)
		(layer "F.Cu")
		(net "P1V05_NODE1_VREF")
	)
	(segment
		(start 17.956784 -132.66928)
		(end 17.956784 -133.918198)
		(width 0.254)
		(layer "F.Cu")
		(net "P1V05_NODE1_VREF")
	)
	(segment
		(start 16.81226 -132.12953)
		(end 16.993362 -132.310632)
		(width 0.254)
		(layer "F.Cu")
		(net "P1V05_NODE1_VREF")
	)
	(segment
		(start 17.107662 -133.918198)
		(end 17.956784 -133.918198)
		(width 0.254)
		(layer "F.Cu")
		(net "P1V05_NODE1_VREF")
	)
	(segment
		(start 17.598136 -132.310632)
		(end 17.956784 -132.66928)
		(width 0.254)
		(layer "F.Cu")
		(net "P1V05_NODE1_VREF")
	)
	(segment
		(start 16.899382 -133.709918)
		(end 17.107662 -133.918198)
		(width 0.254)
		(layer "F.Cu")
		(net "P1V05_NODE1_VREF")
	)
	(segment
		(start 16.993362 -132.310632)
		(end 17.598136 -132.310632)
		(width 0.254)
		(layer "F.Cu")
		(net "P1V05_NODE1_VREF")
	)
	(via
		(at 17.956784 -133.918198)
		(size 0.508)
		(drill 0.254)
		(layers "F.Cu" "B.Cu")
		(net "P1V05_NODE1_VREF")
	)
	(segment
		(start 100.895912 -73.660254)
		(end 100.717096 -73.481438)
		(width 0.1016)
		(layer "F.Cu")
		(net "XDP_CPU_NODE1_VISA1")
	)
	(segment
		(start 101.46919 -72.224392)
		(end 99.989132 -70.744334)
		(width 0.1016)
		(layer "F.Cu")
		(net "XDP_CPU_NODE1_VISA1")
	)
	(segment
		(start 100.717096 -73.228962)
		(end 101.46919 -72.476868)
		(width 0.1016)
		(layer "F.Cu")
		(net "XDP_CPU_NODE1_VISA1")
	)
	(segment
		(start 102.152958 -72.90816)
		(end 101.900482 -72.90816)
		(width 0.1016)
		(layer "F.Cu")
		(net "XDP_CPU_NODE1_VISA1")
	)
	(segment
		(start 101.900482 -72.90816)
		(end 101.148388 -73.660254)
		(width 0.1016)
		(layer "F.Cu")
		(net "XDP_CPU_NODE1_VISA1")
	)
	(segment
		(start 104.73182 -74.406252)
		(end 103.65105 -74.406252)
		(width 0.1016)
		(layer "F.Cu")
		(net "XDP_CPU_NODE1_VISA1")
	)
	(segment
		(start 67.535044 -72.296782)
		(end 67.535044 -73.006712)
		(width 0.1016)
		(layer "F.Cu")
		(net "XDP_CPU_NODE1_VISA1")
	)
	(segment
		(start 101.148388 -73.660254)
		(end 100.895912 -73.660254)
		(width 0.1016)
		(layer "F.Cu")
		(net "XDP_CPU_NODE1_VISA1")
	)
	(segment
		(start 67.535044 -73.006712)
		(end 67.505072 -73.036684)
		(width 0.1016)
		(layer "F.Cu")
		(net "XDP_CPU_NODE1_VISA1")
	)
	(segment
		(start 100.717096 -73.481438)
		(end 100.717096 -73.228962)
		(width 0.1016)
		(layer "F.Cu")
		(net "XDP_CPU_NODE1_VISA1")
	)
	(segment
		(start 103.65105 -74.406252)
		(end 102.152958 -72.90816)
		(width 0.1016)
		(layer "F.Cu")
		(net "XDP_CPU_NODE1_VISA1")
	)
	(segment
		(start 101.46919 -72.476868)
		(end 101.46919 -72.224392)
		(width 0.1016)
		(layer "F.Cu")
		(net "XDP_CPU_NODE1_VISA1")
	)
	(segment
		(start 99.989132 -70.744334)
		(end 99.989132 -70.289674)
		(width 0.1016)
		(layer "F.Cu")
		(net "XDP_CPU_NODE1_VISA1")
	)
	(segment
		(start 99.989132 -70.289674)
		(end 99.697032 -69.997574)
		(width 0.1016)
		(layer "F.Cu")
		(net "XDP_CPU_NODE1_VISA1")
	)
	(via
		(at 67.505072 -73.036684)
		(size 0.508)
		(drill 0.254)
		(layers "F.Cu" "B.Cu")
		(net "XDP_CPU_NODE1_VISA1")
	)
	(via
		(at 99.697032 -69.997574)
		(size 0.508)
		(drill 0.254)
		(layers "F.Cu" "B.Cu")
		(net "XDP_CPU_NODE1_VISA1")
	)
	(segment
		(start 70.918578 -74.839068)
		(end 73.29424 -74.839068)
		(width 0.1143)
		(layer "In2.Cu")
		(net "XDP_CPU_NODE1_VISA1")
	)
	(segment
		(start 90.647774 -70.020942)
		(end 90.90533 -70.020942)
		(width 0.1143)
		(layer "In2.Cu")
		(net "XDP_CPU_NODE1_VISA1")
	)
	(segment
		(start 91.087702 -70.285356)
		(end 91.270074 -70.467728)
		(width 0.1143)
		(layer "In2.Cu")
		(net "XDP_CPU_NODE1_VISA1")
	)
	(segment
		(start 91.710002 -70.285356)
		(end 91.710002 -70.203314)
		(width 0.1143)
		(layer "In2.Cu")
		(net "XDP_CPU_NODE1_VISA1")
	)
	(segment
		(start 90.465402 -70.285356)
		(end 90.465402 -70.203314)
		(width 0.1143)
		(layer "In2.Cu")
		(net "XDP_CPU_NODE1_VISA1")
	)
	(segment
		(start 92.332302 -70.285356)
		(end 92.514674 -70.467728)
		(width 0.1143)
		(layer "In2.Cu")
		(net "XDP_CPU_NODE1_VISA1")
	)
	(segment
		(start 98.140774 -72.174862)
		(end 98.140774 -71.917306)
		(width 0.1143)
		(layer "In2.Cu")
		(net "XDP_CPU_NODE1_VISA1")
	)
	(segment
		(start 96.481392 -71.734934)
		(end 96.29902 -71.552562)
		(width 0.1143)
		(layer "In2.Cu")
		(net "XDP_CPU_NODE1_VISA1")
	)
	(segment
		(start 97.958402 -72.357234)
		(end 98.140774 -72.174862)
		(width 0.1143)
		(layer "In2.Cu")
		(net "XDP_CPU_NODE1_VISA1")
	)
	(segment
		(start 95.67672 -72.174862)
		(end 95.859092 -72.357234)
		(width 0.1143)
		(layer "In2.Cu")
		(net "XDP_CPU_NODE1_VISA1")
	)
	(segment
		(start 91.087702 -70.203314)
		(end 91.087702 -70.285356)
		(width 0.1143)
		(layer "In2.Cu")
		(net "XDP_CPU_NODE1_VISA1")
	)
	(segment
		(start 90.28303 -70.467728)
		(end 90.465402 -70.285356)
		(width 0.1143)
		(layer "In2.Cu")
		(net "XDP_CPU_NODE1_VISA1")
	)
	(segment
		(start 81.02981 -73.16089)
		(end 84.584032 -69.606668)
		(width 0.1143)
		(layer "In2.Cu")
		(net "XDP_CPU_NODE1_VISA1")
	)
	(segment
		(start 90.465402 -70.203314)
		(end 90.647774 -70.020942)
		(width 0.1143)
		(layer "In2.Cu")
		(net "XDP_CPU_NODE1_VISA1")
	)
	(segment
		(start 97.958402 -71.734934)
		(end 96.481392 -71.734934)
		(width 0.1143)
		(layer "In2.Cu")
		(net "XDP_CPU_NODE1_VISA1")
	)
	(segment
		(start 96.481392 -71.112634)
		(end 98.140774 -71.112634)
		(width 0.1143)
		(layer "In2.Cu")
		(net "XDP_CPU_NODE1_VISA1")
	)
	(segment
		(start 92.514674 -70.467728)
		(end 92.77223 -70.467728)
		(width 0.1143)
		(layer "In2.Cu")
		(net "XDP_CPU_NODE1_VISA1")
	)
	(segment
		(start 95.219012 -71.112634)
		(end 95.494348 -71.112634)
		(width 0.1143)
		(layer "In2.Cu")
		(net "XDP_CPU_NODE1_VISA1")
	)
	(segment
		(start 94.36227 -70.513956)
		(end 94.101666 -70.77456)
		(width 0.1143)
		(layer "In2.Cu")
		(net "XDP_CPU_NODE1_VISA1")
	)
	(segment
		(start 69.604382 -73.524872)
		(end 70.918578 -74.839068)
		(width 0.1143)
		(layer "In2.Cu")
		(net "XDP_CPU_NODE1_VISA1")
	)
	(segment
		(start 94.101666 -71.032624)
		(end 94.283784 -71.214742)
		(width 0.1143)
		(layer "In2.Cu")
		(net "XDP_CPU_NODE1_VISA1")
	)
	(segment
		(start 96.29902 -71.295006)
		(end 96.481392 -71.112634)
		(width 0.1143)
		(layer "In2.Cu")
		(net "XDP_CPU_NODE1_VISA1")
	)
	(segment
		(start 90.025474 -70.467728)
		(end 90.28303 -70.467728)
		(width 0.1143)
		(layer "In2.Cu")
		(net "XDP_CPU_NODE1_VISA1")
	)
	(segment
		(start 68.52158 -73.103232)
		(end 68.760594 -73.103232)
		(width 0.1143)
		(layer "In2.Cu")
		(net "XDP_CPU_NODE1_VISA1")
	)
	(segment
		(start 98.140774 -71.917306)
		(end 97.958402 -71.734934)
		(width 0.1143)
		(layer "In2.Cu")
		(net "XDP_CPU_NODE1_VISA1")
	)
	(segment
		(start 89.66073 -70.020942)
		(end 89.843102 -70.203314)
		(width 0.1143)
		(layer "In2.Cu")
		(net "XDP_CPU_NODE1_VISA1")
	)
	(segment
		(start 93.136974 -70.020942)
		(end 94.12732 -70.020942)
		(width 0.1143)
		(layer "In2.Cu")
		(net "XDP_CPU_NODE1_VISA1")
	)
	(segment
		(start 94.36227 -70.255892)
		(end 94.36227 -70.513956)
		(width 0.1143)
		(layer "In2.Cu")
		(net "XDP_CPU_NODE1_VISA1")
	)
	(segment
		(start 92.332302 -70.203314)
		(end 92.332302 -70.285356)
		(width 0.1143)
		(layer "In2.Cu")
		(net "XDP_CPU_NODE1_VISA1")
	)
	(segment
		(start 92.77223 -70.467728)
		(end 92.954602 -70.285356)
		(width 0.1143)
		(layer "In2.Cu")
		(net "XDP_CPU_NODE1_VISA1")
	)
	(segment
		(start 67.851274 -72.690482)
		(end 68.10883 -72.690482)
		(width 0.1143)
		(layer "In2.Cu")
		(net "XDP_CPU_NODE1_VISA1")
	)
	(segment
		(start 80.146652 -72.886824)
		(end 80.432656 -73.172828)
		(width 0.1143)
		(layer "In2.Cu")
		(net "XDP_CPU_NODE1_VISA1")
	)
	(segment
		(start 84.584032 -69.606668)
		(end 88.931496 -69.606668)
		(width 0.1143)
		(layer "In2.Cu")
		(net "XDP_CPU_NODE1_VISA1")
	)
	(segment
		(start 91.892374 -70.020942)
		(end 92.14993 -70.020942)
		(width 0.1143)
		(layer "In2.Cu")
		(net "XDP_CPU_NODE1_VISA1")
	)
	(segment
		(start 67.505072 -73.036684)
		(end 67.851274 -72.690482)
		(width 0.1143)
		(layer "In2.Cu")
		(net "XDP_CPU_NODE1_VISA1")
	)
	(segment
		(start 91.270074 -70.467728)
		(end 91.52763 -70.467728)
		(width 0.1143)
		(layer "In2.Cu")
		(net "XDP_CPU_NODE1_VISA1")
	)
	(segment
		(start 89.843102 -70.203314)
		(end 89.843102 -70.285356)
		(width 0.1143)
		(layer "In2.Cu")
		(net "XDP_CPU_NODE1_VISA1")
	)
	(segment
		(start 94.101666 -70.77456)
		(end 94.101666 -71.032624)
		(width 0.1143)
		(layer "In2.Cu")
		(net "XDP_CPU_NODE1_VISA1")
	)
	(segment
		(start 69.182234 -73.524872)
		(end 69.604382 -73.524872)
		(width 0.1143)
		(layer "In2.Cu")
		(net "XDP_CPU_NODE1_VISA1")
	)
	(segment
		(start 89.843102 -70.285356)
		(end 90.025474 -70.467728)
		(width 0.1143)
		(layer "In2.Cu")
		(net "XDP_CPU_NODE1_VISA1")
	)
	(segment
		(start 95.859092 -72.357234)
		(end 97.958402 -72.357234)
		(width 0.1143)
		(layer "In2.Cu")
		(net "XDP_CPU_NODE1_VISA1")
	)
	(segment
		(start 74.457306 -73.676002)
		(end 77.19568 -73.676002)
		(width 0.1143)
		(layer "In2.Cu")
		(net "XDP_CPU_NODE1_VISA1")
	)
	(segment
		(start 78.040992 -73.51522)
		(end 78.669388 -72.886824)
		(width 0.1143)
		(layer "In2.Cu")
		(net "XDP_CPU_NODE1_VISA1")
	)
	(segment
		(start 94.541848 -71.214742)
		(end 94.802452 -70.954138)
		(width 0.1143)
		(layer "In2.Cu")
		(net "XDP_CPU_NODE1_VISA1")
	)
	(segment
		(start 88.931496 -69.606668)
		(end 89.34577 -70.020942)
		(width 0.1143)
		(layer "In2.Cu")
		(net "XDP_CPU_NODE1_VISA1")
	)
	(segment
		(start 92.954602 -70.285356)
		(end 92.954602 -70.203314)
		(width 0.1143)
		(layer "In2.Cu")
		(net "XDP_CPU_NODE1_VISA1")
	)
	(segment
		(start 80.759808 -73.172828)
		(end 80.771746 -73.16089)
		(width 0.1143)
		(layer "In2.Cu")
		(net "XDP_CPU_NODE1_VISA1")
	)
	(segment
		(start 92.954602 -70.203314)
		(end 93.136974 -70.020942)
		(width 0.1143)
		(layer "In2.Cu")
		(net "XDP_CPU_NODE1_VISA1")
	)
	(segment
		(start 77.19568 -73.676002)
		(end 77.356462 -73.51522)
		(width 0.1143)
		(layer "In2.Cu")
		(net "XDP_CPU_NODE1_VISA1")
	)
	(segment
		(start 95.060516 -70.954138)
		(end 95.219012 -71.112634)
		(width 0.1143)
		(layer "In2.Cu")
		(net "XDP_CPU_NODE1_VISA1")
	)
	(segment
		(start 73.29424 -74.839068)
		(end 74.457306 -73.676002)
		(width 0.1143)
		(layer "In2.Cu")
		(net "XDP_CPU_NODE1_VISA1")
	)
	(segment
		(start 94.283784 -71.214742)
		(end 94.541848 -71.214742)
		(width 0.1143)
		(layer "In2.Cu")
		(net "XDP_CPU_NODE1_VISA1")
	)
	(segment
		(start 96.29902 -71.552562)
		(end 96.29902 -71.295006)
		(width 0.1143)
		(layer "In2.Cu")
		(net "XDP_CPU_NODE1_VISA1")
	)
	(segment
		(start 95.494348 -71.112634)
		(end 95.67672 -71.295006)
		(width 0.1143)
		(layer "In2.Cu")
		(net "XDP_CPU_NODE1_VISA1")
	)
	(segment
		(start 98.140774 -71.112634)
		(end 99.255834 -69.997574)
		(width 0.1143)
		(layer "In2.Cu")
		(net "XDP_CPU_NODE1_VISA1")
	)
	(segment
		(start 77.356462 -73.51522)
		(end 78.040992 -73.51522)
		(width 0.1143)
		(layer "In2.Cu")
		(net "XDP_CPU_NODE1_VISA1")
	)
	(segment
		(start 91.52763 -70.467728)
		(end 91.710002 -70.285356)
		(width 0.1143)
		(layer "In2.Cu")
		(net "XDP_CPU_NODE1_VISA1")
	)
	(segment
		(start 99.255834 -69.997574)
		(end 99.697032 -69.997574)
		(width 0.1143)
		(layer "In2.Cu")
		(net "XDP_CPU_NODE1_VISA1")
	)
	(segment
		(start 90.90533 -70.020942)
		(end 91.087702 -70.203314)
		(width 0.1143)
		(layer "In2.Cu")
		(net "XDP_CPU_NODE1_VISA1")
	)
	(segment
		(start 80.432656 -73.172828)
		(end 80.759808 -73.172828)
		(width 0.1143)
		(layer "In2.Cu")
		(net "XDP_CPU_NODE1_VISA1")
	)
	(segment
		(start 91.710002 -70.203314)
		(end 91.892374 -70.020942)
		(width 0.1143)
		(layer "In2.Cu")
		(net "XDP_CPU_NODE1_VISA1")
	)
	(segment
		(start 80.771746 -73.16089)
		(end 81.02981 -73.16089)
		(width 0.1143)
		(layer "In2.Cu")
		(net "XDP_CPU_NODE1_VISA1")
	)
	(segment
		(start 68.10883 -72.690482)
		(end 68.52158 -73.103232)
		(width 0.1143)
		(layer "In2.Cu")
		(net "XDP_CPU_NODE1_VISA1")
	)
	(segment
		(start 94.12732 -70.020942)
		(end 94.36227 -70.255892)
		(width 0.1143)
		(layer "In2.Cu")
		(net "XDP_CPU_NODE1_VISA1")
	)
	(segment
		(start 92.14993 -70.020942)
		(end 92.332302 -70.203314)
		(width 0.1143)
		(layer "In2.Cu")
		(net "XDP_CPU_NODE1_VISA1")
	)
	(segment
		(start 78.669388 -72.886824)
		(end 80.146652 -72.886824)
		(width 0.1143)
		(layer "In2.Cu")
		(net "XDP_CPU_NODE1_VISA1")
	)
	(segment
		(start 89.34577 -70.020942)
		(end 89.66073 -70.020942)
		(width 0.1143)
		(layer "In2.Cu")
		(net "XDP_CPU_NODE1_VISA1")
	)
	(segment
		(start 95.67672 -71.295006)
		(end 95.67672 -72.174862)
		(width 0.1143)
		(layer "In2.Cu")
		(net "XDP_CPU_NODE1_VISA1")
	)
	(segment
		(start 68.760594 -73.103232)
		(end 69.182234 -73.524872)
		(width 0.1143)
		(layer "In2.Cu")
		(net "XDP_CPU_NODE1_VISA1")
	)
	(segment
		(start 94.802452 -70.954138)
		(end 95.060516 -70.954138)
		(width 0.1143)
		(layer "In2.Cu")
		(net "XDP_CPU_NODE1_VISA1")
	)
	(segment
		(start 38.482778 -8.087614)
		(end 38.81374 -7.756652)
		(width 0.1778)
		(layer "F.Cu")
		(net "PV_VDDR_NODE1_VID1")
	)
	(segment
		(start 38.482778 -8.738616)
		(end 38.482778 -8.087614)
		(width 0.1778)
		(layer "F.Cu")
		(net "PV_VDDR_NODE1_VID1")
	)
	(segment
		(start 39.266368 -6.950964)
		(end 38.81374 -7.403592)
		(width 0.254)
		(layer "F.Cu")
		(net "PV_VDDR_NODE1_VID1")
	)
	(segment
		(start 38.81374 -7.756652)
		(end 38.81374 -7.599934)
		(width 0.254)
		(layer "F.Cu")
		(net "PV_VDDR_NODE1_VID1")
	)
	(segment
		(start 38.81374 -7.403592)
		(end 38.81374 -7.599934)
		(width 0.254)
		(layer "F.Cu")
		(net "PV_VDDR_NODE1_VID1")
	)
	(via
		(at 38.81374 -7.599934)
		(size 0.508)
		(drill 0.254)
		(layers "F.Cu" "B.Cu")
		(net "PV_VDDR_NODE1_VID1")
	)
	(segment
		(start 16.312134 -131.82219)
		(end 16.312134 -132.437124)
		(width 0.254)
		(layer "F.Cu")
		(net "P1V05_NODE1_VREFIN")
	)
	(segment
		(start 16.312134 -132.437124)
		(end 16.715232 -132.840222)
		(width 0.254)
		(layer "F.Cu")
		(net "P1V05_NODE1_VREFIN")
	)
	(segment
		(start 16.715232 -132.840222)
		(end 17.111726 -132.840222)
		(width 0.254)
		(layer "F.Cu")
		(net "P1V05_NODE1_VREFIN")
	)
	(via
		(at 17.111726 -132.840222)
		(size 0.508)
		(drill 0.254)
		(layers "F.Cu" "B.Cu")
		(net "P1V05_NODE1_VREFIN")
	)
	(segment
		(start 16.650716 -133.301232)
		(end 17.111726 -132.840222)
		(width 0.254)
		(layer "B.Cu")
		(net "P1V05_NODE1_VREFIN")
	)
	(segment
		(start 16.650716 -134.106158)
		(end 16.650716 -133.301232)
		(width 0.254)
		(layer "B.Cu")
		(net "P1V05_NODE1_VREFIN")
	)
	(segment
		(start 70.923912 -77.030326)
		(end 71.057516 -77.030326)
		(width 0.1016)
		(layer "F.Cu")
		(net "PWRGD_CPU_NODE1_EPWRGOOD")
	)
	(segment
		(start 70.202044 -77.555598)
		(end 70.39864 -77.555598)
		(width 0.1016)
		(layer "F.Cu")
		(net "PWRGD_CPU_NODE1_EPWRGOOD")
	)
	(segment
		(start 70.39864 -77.555598)
		(end 70.923912 -77.030326)
		(width 0.1016)
		(layer "F.Cu")
		(net "PWRGD_CPU_NODE1_EPWRGOOD")
	)
	(via
		(at 86.229698 -76.463652)
		(size 0.6604)
		(drill 0.3302)
		(layers "F.Cu" "B.Cu")
		(net "PWRGD_CPU_NODE1_EPWRGOOD")
	)
	(via
		(at 71.057516 -77.030326)
		(size 0.508)
		(drill 0.254)
		(layers "F.Cu" "B.Cu")
		(net "PWRGD_CPU_NODE1_EPWRGOOD")
	)
	(segment
		(start 75.154282 -76.722224)
		(end 71.365618 -76.722224)
		(width 0.1016)
		(layer "B.Cu")
		(net "PWRGD_CPU_NODE1_EPWRGOOD")
	)
	(segment
		(start 75.260454 -76.828396)
		(end 75.154282 -76.722224)
		(width 0.1016)
		(layer "B.Cu")
		(net "PWRGD_CPU_NODE1_EPWRGOOD")
	)
	(segment
		(start 83.296252 -75.667616)
		(end 83.128866 -75.835002)
		(width 0.1016)
		(layer "B.Cu")
		(net "PWRGD_CPU_NODE1_EPWRGOOD")
	)
	(segment
		(start 77.469238 -75.835002)
		(end 76.475844 -76.828396)
		(width 0.1016)
		(layer "B.Cu")
		(net "PWRGD_CPU_NODE1_EPWRGOOD")
	)
	(segment
		(start 86.444328 -76.678282)
		(end 86.229698 -76.463652)
		(width 0.1016)
		(layer "B.Cu")
		(net "PWRGD_CPU_NODE1_EPWRGOOD")
	)
	(segment
		(start 76.475844 -76.828396)
		(end 75.260454 -76.828396)
		(width 0.1016)
		(layer "B.Cu")
		(net "PWRGD_CPU_NODE1_EPWRGOOD")
	)
	(segment
		(start 83.128866 -75.835002)
		(end 77.469238 -75.835002)
		(width 0.1016)
		(layer "B.Cu")
		(net "PWRGD_CPU_NODE1_EPWRGOOD")
	)
	(segment
		(start 85.433662 -75.667616)
		(end 83.296252 -75.667616)
		(width 0.1016)
		(layer "B.Cu")
		(net "PWRGD_CPU_NODE1_EPWRGOOD")
	)
	(segment
		(start 87.50808 -76.678282)
		(end 86.444328 -76.678282)
		(width 0.1016)
		(layer "B.Cu")
		(net "PWRGD_CPU_NODE1_EPWRGOOD")
	)
	(segment
		(start 71.365618 -76.722224)
		(end 71.057516 -77.030326)
		(width 0.1016)
		(layer "B.Cu")
		(net "PWRGD_CPU_NODE1_EPWRGOOD")
	)
	(segment
		(start 86.229698 -76.463652)
		(end 85.433662 -75.667616)
		(width 0.1016)
		(layer "B.Cu")
		(net "PWRGD_CPU_NODE1_EPWRGOOD")
	)
	(segment
		(start 99.938332 -73.904094)
		(end 99.938332 -71.864474)
		(width 0.1016)
		(layer "F.Cu")
		(net "XDP_CPU_NODE1_VISA9")
	)
	(segment
		(start 108.448856 -75.40625)
		(end 106.821732 -77.033374)
		(width 0.1016)
		(layer "F.Cu")
		(net "XDP_CPU_NODE1_VISA9")
	)
	(segment
		(start 106.821732 -77.033374)
		(end 103.067612 -77.033374)
		(width 0.1016)
		(layer "F.Cu")
		(net "XDP_CPU_NODE1_VISA9")
	)
	(segment
		(start 67.916044 -73.583038)
		(end 68.26885 -73.935844)
		(width 0.1016)
		(layer "F.Cu")
		(net "XDP_CPU_NODE1_VISA9")
	)
	(segment
		(start 110.460028 -75.40625)
		(end 108.448856 -75.40625)
		(width 0.1016)
		(layer "F.Cu")
		(net "XDP_CPU_NODE1_VISA9")
	)
	(segment
		(start 68.26885 -73.935844)
		(end 68.311522 -73.935844)
		(width 0.1016)
		(layer "F.Cu")
		(net "XDP_CPU_NODE1_VISA9")
	)
	(segment
		(start 103.067612 -77.033374)
		(end 99.938332 -73.904094)
		(width 0.1016)
		(layer "F.Cu")
		(net "XDP_CPU_NODE1_VISA9")
	)
	(via
		(at 68.311522 -73.935844)
		(size 0.49022)
		(drill 0.254)
		(layers "F.Cu" "B.Cu")
		(net "XDP_CPU_NODE1_VISA9")
	)
	(via
		(at 99.938332 -71.864474)
		(size 0.508)
		(drill 0.254)
		(layers "F.Cu" "B.Cu")
		(net "XDP_CPU_NODE1_VISA9")
	)
	(segment
		(start 88.404954 -70.867778)
		(end 85.179662 -70.867778)
		(width 0.1143)
		(layer "In2.Cu")
		(net "XDP_CPU_NODE1_VISA9")
	)
	(segment
		(start 74.850498 -75.295506)
		(end 74.312526 -75.833732)
		(width 0.1143)
		(layer "In2.Cu")
		(net "XDP_CPU_NODE1_VISA9")
	)
	(segment
		(start 99.9363 -72.321674)
		(end 98.667062 -73.590658)
		(width 0.1143)
		(layer "In2.Cu")
		(net "XDP_CPU_NODE1_VISA9")
	)
	(segment
		(start 92.81795 -71.74103)
		(end 89.278206 -71.74103)
		(width 0.1143)
		(layer "In2.Cu")
		(net "XDP_CPU_NODE1_VISA9")
	)
	(segment
		(start 78.051152 -74.539602)
		(end 77.295248 -75.295506)
		(width 0.1143)
		(layer "In2.Cu")
		(net "XDP_CPU_NODE1_VISA9")
	)
	(segment
		(start 97.390458 -74.720196)
		(end 97.208086 -74.537824)
		(width 0.1143)
		(layer "In2.Cu")
		(net "XDP_CPU_NODE1_VISA9")
	)
	(segment
		(start 81.507838 -74.539602)
		(end 78.051152 -74.539602)
		(width 0.1143)
		(layer "In2.Cu")
		(net "XDP_CPU_NODE1_VISA9")
	)
	(segment
		(start 94.808548 -73.731628)
		(end 92.81795 -71.74103)
		(width 0.1143)
		(layer "In2.Cu")
		(net "XDP_CPU_NODE1_VISA9")
	)
	(segment
		(start 99.225862 -74.407522)
		(end 99.225862 -74.665078)
		(width 0.1143)
		(layer "In2.Cu")
		(net "XDP_CPU_NODE1_VISA9")
	)
	(segment
		(start 97.390458 -74.895964)
		(end 97.390458 -74.720196)
		(width 0.1143)
		(layer "In2.Cu")
		(net "XDP_CPU_NODE1_VISA9")
	)
	(segment
		(start 96.007174 -73.731628)
		(end 94.808548 -73.731628)
		(width 0.1143)
		(layer "In2.Cu")
		(net "XDP_CPU_NODE1_VISA9")
	)
	(segment
		(start 98.785426 -74.84745)
		(end 98.4758 -74.537824)
		(width 0.1143)
		(layer "In2.Cu")
		(net "XDP_CPU_NODE1_VISA9")
	)
	(segment
		(start 77.295248 -75.295506)
		(end 74.850498 -75.295506)
		(width 0.1143)
		(layer "In2.Cu")
		(net "XDP_CPU_NODE1_VISA9")
	)
	(segment
		(start 69.414898 -75.833732)
		(end 68.704968 -75.123802)
		(width 0.1143)
		(layer "In2.Cu")
		(net "XDP_CPU_NODE1_VISA9")
	)
	(segment
		(start 98.667062 -73.590658)
		(end 98.667062 -73.848722)
		(width 0.1143)
		(layer "In2.Cu")
		(net "XDP_CPU_NODE1_VISA9")
	)
	(segment
		(start 96.81337 -74.537824)
		(end 96.007174 -73.731628)
		(width 0.1143)
		(layer "In2.Cu")
		(net "XDP_CPU_NODE1_VISA9")
	)
	(segment
		(start 68.704968 -74.19594)
		(end 68.444872 -73.935844)
		(width 0.1143)
		(layer "In2.Cu")
		(net "XDP_CPU_NODE1_VISA9")
	)
	(segment
		(start 98.19513 -74.537824)
		(end 98.012758 -74.720196)
		(width 0.1143)
		(layer "In2.Cu")
		(net "XDP_CPU_NODE1_VISA9")
	)
	(segment
		(start 99.9363 -71.866506)
		(end 99.9363 -72.321674)
		(width 0.1143)
		(layer "In2.Cu")
		(net "XDP_CPU_NODE1_VISA9")
	)
	(segment
		(start 98.012758 -74.720196)
		(end 98.012758 -74.895964)
		(width 0.1143)
		(layer "In2.Cu")
		(net "XDP_CPU_NODE1_VISA9")
	)
	(segment
		(start 97.57283 -75.078336)
		(end 97.390458 -74.895964)
		(width 0.1143)
		(layer "In2.Cu")
		(net "XDP_CPU_NODE1_VISA9")
	)
	(segment
		(start 68.444872 -73.935844)
		(end 68.311522 -73.935844)
		(width 0.1143)
		(layer "In2.Cu")
		(net "XDP_CPU_NODE1_VISA9")
	)
	(segment
		(start 68.704968 -75.123802)
		(end 68.704968 -74.19594)
		(width 0.1143)
		(layer "In2.Cu")
		(net "XDP_CPU_NODE1_VISA9")
	)
	(segment
		(start 98.4758 -74.537824)
		(end 98.19513 -74.537824)
		(width 0.1143)
		(layer "In2.Cu")
		(net "XDP_CPU_NODE1_VISA9")
	)
	(segment
		(start 99.938332 -71.864474)
		(end 99.9363 -71.866506)
		(width 0.1143)
		(layer "In2.Cu")
		(net "XDP_CPU_NODE1_VISA9")
	)
	(segment
		(start 98.012758 -74.895964)
		(end 97.830386 -75.078336)
		(width 0.1143)
		(layer "In2.Cu")
		(net "XDP_CPU_NODE1_VISA9")
	)
	(segment
		(start 89.278206 -71.74103)
		(end 88.404954 -70.867778)
		(width 0.1143)
		(layer "In2.Cu")
		(net "XDP_CPU_NODE1_VISA9")
	)
	(segment
		(start 99.043236 -74.84745)
		(end 98.785426 -74.84745)
		(width 0.1143)
		(layer "In2.Cu")
		(net "XDP_CPU_NODE1_VISA9")
	)
	(segment
		(start 97.208086 -74.537824)
		(end 96.81337 -74.537824)
		(width 0.1143)
		(layer "In2.Cu")
		(net "XDP_CPU_NODE1_VISA9")
	)
	(segment
		(start 85.179662 -70.867778)
		(end 81.507838 -74.539602)
		(width 0.1143)
		(layer "In2.Cu")
		(net "XDP_CPU_NODE1_VISA9")
	)
	(segment
		(start 74.312526 -75.833732)
		(end 69.414898 -75.833732)
		(width 0.1143)
		(layer "In2.Cu")
		(net "XDP_CPU_NODE1_VISA9")
	)
	(segment
		(start 98.667062 -73.848722)
		(end 99.225862 -74.407522)
		(width 0.1143)
		(layer "In2.Cu")
		(net "XDP_CPU_NODE1_VISA9")
	)
	(segment
		(start 97.830386 -75.078336)
		(end 97.57283 -75.078336)
		(width 0.1143)
		(layer "In2.Cu")
		(net "XDP_CPU_NODE1_VISA9")
	)
	(segment
		(start 99.225862 -74.665078)
		(end 99.043236 -74.84745)
		(width 0.1143)
		(layer "In2.Cu")
		(net "XDP_CPU_NODE1_VISA9")
	)
	(segment
		(start 142.86738 -128.833118)
		(end 143.34998 -129.315718)
		(width 0.127)
		(layer "F.Cu")
		(net "CLK_100M_USB_NODE1_DP")
	)
	(segment
		(start 161.6456 -103.659178)
		(end 160.678114 -103.659178)
		(width 0.127)
		(layer "F.Cu")
		(net "CLK_100M_USB_NODE1_DP")
	)
	(segment
		(start 160.678114 -103.659178)
		(end 160.195514 -104.141778)
		(width 0.127)
		(layer "F.Cu")
		(net "CLK_100M_USB_NODE1_DP")
	)
	(segment
		(start 131.378452 -123.805442)
		(end 130.99034 -124.193554)
		(width 0.127)
		(layer "F.Cu")
		(net "CLK_100M_USB_NODE1_DP")
	)
	(segment
		(start 131.607052 -122.53595)
		(end 131.378452 -122.76455)
		(width 0.127)
		(layer "F.Cu")
		(net "CLK_100M_USB_NODE1_DP")
	)
	(segment
		(start 163.340034 -102.935786)
		(end 162.368992 -102.935786)
		(width 0.127)
		(layer "F.Cu")
		(net "CLK_100M_USB_NODE1_DP")
	)
	(segment
		(start 131.553712 -121.492772)
		(end 131.607052 -121.546112)
		(width 0.127)
		(layer "F.Cu")
		(net "CLK_100M_USB_NODE1_DP")
	)
	(segment
		(start 130.99034 -124.193554)
		(end 130.99034 -126.821184)
		(width 0.127)
		(layer "F.Cu")
		(net "CLK_100M_USB_NODE1_DP")
	)
	(segment
		(start 130.99034 -126.821184)
		(end 132.03555 -127.866394)
		(width 0.127)
		(layer "F.Cu")
		(net "CLK_100M_USB_NODE1_DP")
	)
	(segment
		(start 132.03555 -127.866394)
		(end 140.682472 -127.866394)
		(width 0.127)
		(layer "F.Cu")
		(net "CLK_100M_USB_NODE1_DP")
	)
	(segment
		(start 131.607052 -121.546112)
		(end 131.607052 -122.53595)
		(width 0.127)
		(layer "F.Cu")
		(net "CLK_100M_USB_NODE1_DP")
	)
	(segment
		(start 162.368992 -102.935786)
		(end 161.6456 -103.659178)
		(width 0.127)
		(layer "F.Cu")
		(net "CLK_100M_USB_NODE1_DP")
	)
	(segment
		(start 141.649196 -128.833118)
		(end 142.86738 -128.833118)
		(width 0.127)
		(layer "F.Cu")
		(net "CLK_100M_USB_NODE1_DP")
	)
	(segment
		(start 140.682472 -127.866394)
		(end 141.649196 -128.833118)
		(width 0.127)
		(layer "F.Cu")
		(net "CLK_100M_USB_NODE1_DP")
	)
	(segment
		(start 131.553712 -121.064528)
		(end 131.553712 -121.492772)
		(width 0.127)
		(layer "F.Cu")
		(net "CLK_100M_USB_NODE1_DP")
	)
	(segment
		(start 131.378452 -122.76455)
		(end 131.378452 -123.805442)
		(width 0.127)
		(layer "F.Cu")
		(net "CLK_100M_USB_NODE1_DP")
	)
	(via
		(at 143.34998 -129.315718)
		(size 0.508)
		(drill 0.254)
		(layers "F.Cu" "B.Cu")
		(net "CLK_100M_USB_NODE1_DP")
	)
	(via
		(at 160.195514 -104.141778)
		(size 0.508)
		(drill 0.254)
		(layers "F.Cu" "B.Cu")
		(net "CLK_100M_USB_NODE1_DP")
	)
	(segment
		(start 159.585914 -103.659178)
		(end 159.18434 -104.060752)
		(width 0.127)
		(layer "B.Cu")
		(net "CLK_100M_USB_NODE1_DP")
	)
	(segment
		(start 159.18434 -108.25099)
		(end 156.20238 -111.23295)
		(width 0.127)
		(layer "B.Cu")
		(net "CLK_100M_USB_NODE1_DP")
	)
	(segment
		(start 143.83258 -128.833118)
		(end 143.34998 -129.315718)
		(width 0.127)
		(layer "B.Cu")
		(net "CLK_100M_USB_NODE1_DP")
	)
	(segment
		(start 144.279112 -128.833118)
		(end 143.83258 -128.833118)
		(width 0.127)
		(layer "B.Cu")
		(net "CLK_100M_USB_NODE1_DP")
	)
	(segment
		(start 145.107152 -128.005078)
		(end 144.279112 -128.833118)
		(width 0.127)
		(layer "B.Cu")
		(net "CLK_100M_USB_NODE1_DP")
	)
	(segment
		(start 156.20238 -118.345458)
		(end 146.54276 -128.005078)
		(width 0.127)
		(layer "B.Cu")
		(net "CLK_100M_USB_NODE1_DP")
	)
	(segment
		(start 156.20238 -111.23295)
		(end 156.20238 -118.345458)
		(width 0.127)
		(layer "B.Cu")
		(net "CLK_100M_USB_NODE1_DP")
	)
	(segment
		(start 146.54276 -128.005078)
		(end 145.107152 -128.005078)
		(width 0.127)
		(layer "B.Cu")
		(net "CLK_100M_USB_NODE1_DP")
	)
	(segment
		(start 159.712914 -103.659178)
		(end 159.585914 -103.659178)
		(width 0.127)
		(layer "B.Cu")
		(net "CLK_100M_USB_NODE1_DP")
	)
	(segment
		(start 159.18434 -104.060752)
		(end 159.18434 -108.25099)
		(width 0.127)
		(layer "B.Cu")
		(net "CLK_100M_USB_NODE1_DP")
	)
	(segment
		(start 160.195514 -104.141778)
		(end 159.712914 -103.659178)
		(width 0.127)
		(layer "B.Cu")
		(net "CLK_100M_USB_NODE1_DP")
	)
	(via
		(at 47.913036 -7.07644)
		(size 0.508)
		(drill 0.254)
		(layers "F.Cu" "B.Cu")
		(net "SW_PV_VDDR_NODE1_VIN_FLT")
	)
	(via
		(at 44.72686 -6.834124)
		(size 0.508)
		(drill 0.254)
		(layers "F.Cu" "B.Cu")
		(net "SW_PV_VDDR_NODE1_VIN_FLT")
	)
	(via
		(at 43.96994 -6.826758)
		(size 0.508)
		(drill 0.254)
		(layers "F.Cu" "B.Cu")
		(net "SW_PV_VDDR_NODE1_VIN_FLT")
	)
	(via
		(at 46.585378 -6.996176)
		(size 0.508)
		(drill 0.254)
		(layers "F.Cu" "B.Cu")
		(net "SW_PV_VDDR_NODE1_VIN_FLT")
	)
	(via
		(at 45.950378 -6.996176)
		(size 0.508)
		(drill 0.254)
		(layers "F.Cu" "B.Cu")
		(net "SW_PV_VDDR_NODE1_VIN_FLT")
	)
	(via
		(at 48.665384 -7.01548)
		(size 0.508)
		(drill 0.254)
		(layers "F.Cu" "B.Cu")
		(net "SW_PV_VDDR_NODE1_VIN_FLT")
	)
	(segment
		(start 13.82903 -131.60756)
		(end 13.966952 -131.745482)
		(width 0.254)
		(layer "F.Cu")
		(net "P1V05_NODE1_COMP")
	)
	(segment
		(start 13.82903 -131.272026)
		(end 13.82903 -131.60756)
		(width 0.254)
		(layer "F.Cu")
		(net "P1V05_NODE1_COMP")
	)
	(segment
		(start 14.078712 -131.022344)
		(end 13.82903 -131.272026)
		(width 0.254)
		(layer "F.Cu")
		(net "P1V05_NODE1_COMP")
	)
	(segment
		(start 14.51229 -131.022344)
		(end 14.078712 -131.022344)
		(width 0.254)
		(layer "F.Cu")
		(net "P1V05_NODE1_COMP")
	)
	(segment
		(start 14.059154 -131.837684)
		(end 13.966952 -131.745482)
		(width 0.254)
		(layer "F.Cu")
		(net "P1V05_NODE1_COMP")
	)
	(segment
		(start 14.059154 -132.818378)
		(end 14.059154 -131.837684)
		(width 0.254)
		(layer "F.Cu")
		(net "P1V05_NODE1_COMP")
	)
	(via
		(at 13.966952 -131.745482)
		(size 0.508)
		(drill 0.254)
		(layers "F.Cu" "B.Cu")
		(net "P1V05_NODE1_COMP")
	)
	(segment
		(start 158.26486 -101.383338)
		(end 161.935922 -101.383338)
		(width 0.127)
		(layer "F.Cu")
		(net "P2E_CPU_USB_NODE1_RX_C_DN")
	)
	(segment
		(start 162.462718 -101.383338)
		(end 161.935922 -101.383338)
		(width 0.127)
		(layer "F.Cu")
		(net "P2E_CPU_USB_NODE1_RX_C_DN")
	)
	(segment
		(start 163.340034 -101.33584)
		(end 162.510216 -101.33584)
		(width 0.127)
		(layer "F.Cu")
		(net "P2E_CPU_USB_NODE1_RX_C_DN")
	)
	(segment
		(start 162.510216 -101.33584)
		(end 162.462718 -101.383338)
		(width 0.127)
		(layer "F.Cu")
		(net "P2E_CPU_USB_NODE1_RX_C_DN")
	)
	(segment
		(start 157.98673 -101.105208)
		(end 158.26486 -101.383338)
		(width 0.127)
		(layer "F.Cu")
		(net "P2E_CPU_USB_NODE1_RX_C_DN")
	)
	(via
		(at 161.935922 -101.383338)
		(size 0.4064)
		(drill 0.2032)
		(layers "F.Cu" "B.Cu")
		(net "P2E_CPU_USB_NODE1_RX_C_DN")
	)
	(segment
		(start 70.590664 -71.596758)
		(end 70.964044 -71.223378)
		(width 0.1016)
		(layer "F.Cu")
		(net "XDP_CPU_NODE1_VISA2")
	)
	(segment
		(start 100.776532 -66.720974)
		(end 100.776532 -64.475614)
		(width 0.1016)
		(layer "F.Cu")
		(net "XDP_CPU_NODE1_VISA2")
	)
	(segment
		(start 100.776532 -64.475614)
		(end 101.157532 -64.094614)
		(width 0.1016)
		(layer "F.Cu")
		(net "XDP_CPU_NODE1_VISA2")
	)
	(segment
		(start 104.73182 -73.906126)
		(end 103.620824 -73.906126)
		(width 0.1016)
		(layer "F.Cu")
		(net "XDP_CPU_NODE1_VISA2")
	)
	(segment
		(start 100.319332 -69.240654)
		(end 100.319332 -67.178174)
		(width 0.1016)
		(layer "F.Cu")
		(net "XDP_CPU_NODE1_VISA2")
	)
	(segment
		(start 100.624132 -69.545454)
		(end 100.319332 -69.240654)
		(width 0.1016)
		(layer "F.Cu")
		(net "XDP_CPU_NODE1_VISA2")
	)
	(segment
		(start 100.624132 -70.909434)
		(end 100.624132 -69.545454)
		(width 0.1016)
		(layer "F.Cu")
		(net "XDP_CPU_NODE1_VISA2")
	)
	(segment
		(start 70.583044 -71.596758)
		(end 70.590664 -71.596758)
		(width 0.1016)
		(layer "F.Cu")
		(net "XDP_CPU_NODE1_VISA2")
	)
	(segment
		(start 100.319332 -67.178174)
		(end 100.776532 -66.720974)
		(width 0.1016)
		(layer "F.Cu")
		(net "XDP_CPU_NODE1_VISA2")
	)
	(segment
		(start 103.620824 -73.906126)
		(end 100.624132 -70.909434)
		(width 0.1016)
		(layer "F.Cu")
		(net "XDP_CPU_NODE1_VISA2")
	)
	(via
		(at 70.964044 -71.223378)
		(size 0.508)
		(drill 0.254)
		(layers "F.Cu" "B.Cu")
		(net "XDP_CPU_NODE1_VISA2")
	)
	(via
		(at 101.157532 -64.094614)
		(size 0.508)
		(drill 0.254)
		(layers "F.Cu" "B.Cu")
		(net "XDP_CPU_NODE1_VISA2")
	)
	(segment
		(start 95.19412 -60.245498)
		(end 95.376492 -60.063126)
		(width 0.1143)
		(layer "In2.Cu")
		(net "XDP_CPU_NODE1_VISA2")
	)
	(segment
		(start 96.621092 -60.063126)
		(end 96.878648 -60.063126)
		(width 0.1143)
		(layer "In2.Cu")
		(net "XDP_CPU_NODE1_VISA2")
	)
	(segment
		(start 95.81642 -60.245498)
		(end 95.81642 -60.407042)
		(width 0.1143)
		(layer "In2.Cu")
		(net "XDP_CPU_NODE1_VISA2")
	)
	(segment
		(start 97.06102 -60.245498)
		(end 97.06102 -60.407042)
		(width 0.1143)
		(layer "In2.Cu")
		(net "XDP_CPU_NODE1_VISA2")
	)
	(segment
		(start 97.06102 -60.407042)
		(end 97.243392 -60.589414)
		(width 0.1143)
		(layer "In2.Cu")
		(net "XDP_CPU_NODE1_VISA2")
	)
	(segment
		(start 78.801976 -68.22948)
		(end 80.267048 -68.22948)
		(width 0.1143)
		(layer "In2.Cu")
		(net "XDP_CPU_NODE1_VISA2")
	)
	(segment
		(start 94.754192 -60.589414)
		(end 95.011748 -60.589414)
		(width 0.1143)
		(layer "In2.Cu")
		(net "XDP_CPU_NODE1_VISA2")
	)
	(segment
		(start 93.509592 -60.589414)
		(end 93.767148 -60.589414)
		(width 0.1143)
		(layer "In2.Cu")
		(net "XDP_CPU_NODE1_VISA2")
	)
	(segment
		(start 92.522548 -60.589414)
		(end 92.70492 -60.407042)
		(width 0.1143)
		(layer "In2.Cu")
		(net "XDP_CPU_NODE1_VISA2")
	)
	(segment
		(start 88.84285 -59.653678)
		(end 91.17838 -59.653678)
		(width 0.1143)
		(layer "In2.Cu")
		(net "XDP_CPU_NODE1_VISA2")
	)
	(segment
		(start 93.32722 -60.407042)
		(end 93.509592 -60.589414)
		(width 0.1143)
		(layer "In2.Cu")
		(net "XDP_CPU_NODE1_VISA2")
	)
	(segment
		(start 100.950268 -63.14186)
		(end 100.692204 -63.14186)
		(width 0.1143)
		(layer "In2.Cu")
		(net "XDP_CPU_NODE1_VISA2")
	)
	(segment
		(start 93.94952 -60.407042)
		(end 93.94952 -60.245498)
		(width 0.1143)
		(layer "In2.Cu")
		(net "XDP_CPU_NODE1_VISA2")
	)
	(segment
		(start 95.376492 -60.063126)
		(end 95.634048 -60.063126)
		(width 0.1143)
		(layer "In2.Cu")
		(net "XDP_CPU_NODE1_VISA2")
	)
	(segment
		(start 98.57359 -61.90361)
		(end 100.764594 -64.094614)
		(width 0.1143)
		(layer "In2.Cu")
		(net "XDP_CPU_NODE1_VISA2")
	)
	(segment
		(start 96.256348 -60.589414)
		(end 96.43872 -60.407042)
		(width 0.1143)
		(layer "In2.Cu")
		(net "XDP_CPU_NODE1_VISA2")
	)
	(segment
		(start 94.57182 -60.245498)
		(end 94.57182 -60.407042)
		(width 0.1143)
		(layer "In2.Cu")
		(net "XDP_CPU_NODE1_VISA2")
	)
	(segment
		(start 94.57182 -60.407042)
		(end 94.754192 -60.589414)
		(width 0.1143)
		(layer "In2.Cu")
		(net "XDP_CPU_NODE1_VISA2")
	)
	(segment
		(start 92.112338 -60.589414)
		(end 92.522548 -60.589414)
		(width 0.1143)
		(layer "In2.Cu")
		(net "XDP_CPU_NODE1_VISA2")
	)
	(segment
		(start 78.148942 -68.882514)
		(end 78.801976 -68.22948)
		(width 0.1143)
		(layer "In2.Cu")
		(net "XDP_CPU_NODE1_VISA2")
	)
	(segment
		(start 93.144848 -60.063126)
		(end 93.32722 -60.245498)
		(width 0.1143)
		(layer "In2.Cu")
		(net "XDP_CPU_NODE1_VISA2")
	)
	(segment
		(start 91.34348 -59.820556)
		(end 92.112338 -60.589414)
		(width 0.1143)
		(layer "In2.Cu")
		(net "XDP_CPU_NODE1_VISA2")
	)
	(segment
		(start 80.267048 -68.22948)
		(end 88.84285 -59.653678)
		(width 0.1143)
		(layer "In2.Cu")
		(net "XDP_CPU_NODE1_VISA2")
	)
	(segment
		(start 94.131892 -60.063126)
		(end 94.389448 -60.063126)
		(width 0.1143)
		(layer "In2.Cu")
		(net "XDP_CPU_NODE1_VISA2")
	)
	(segment
		(start 70.964044 -71.223378)
		(end 71.169022 -71.223378)
		(width 0.1143)
		(layer "In2.Cu")
		(net "XDP_CPU_NODE1_VISA2")
	)
	(segment
		(start 96.878648 -60.063126)
		(end 97.06102 -60.245498)
		(width 0.1143)
		(layer "In2.Cu")
		(net "XDP_CPU_NODE1_VISA2")
	)
	(segment
		(start 96.43872 -60.407042)
		(end 96.43872 -60.245498)
		(width 0.1143)
		(layer "In2.Cu")
		(net "XDP_CPU_NODE1_VISA2")
	)
	(segment
		(start 95.81642 -60.407042)
		(end 95.998792 -60.589414)
		(width 0.1143)
		(layer "In2.Cu")
		(net "XDP_CPU_NODE1_VISA2")
	)
	(segment
		(start 98.755962 -61.463174)
		(end 98.57359 -61.6458)
		(width 0.1143)
		(layer "In2.Cu")
		(net "XDP_CPU_NODE1_VISA2")
	)
	(segment
		(start 101.132386 -62.959742)
		(end 100.950268 -63.14186)
		(width 0.1143)
		(layer "In2.Cu")
		(net "XDP_CPU_NODE1_VISA2")
	)
	(segment
		(start 92.887292 -60.063126)
		(end 93.144848 -60.063126)
		(width 0.1143)
		(layer "In2.Cu")
		(net "XDP_CPU_NODE1_VISA2")
	)
	(segment
		(start 99.020122 -60.589414)
		(end 101.132386 -62.701678)
		(width 0.1143)
		(layer "In2.Cu")
		(net "XDP_CPU_NODE1_VISA2")
	)
	(segment
		(start 100.692204 -63.14186)
		(end 99.013518 -61.463174)
		(width 0.1143)
		(layer "In2.Cu")
		(net "XDP_CPU_NODE1_VISA2")
	)
	(segment
		(start 72.743314 -70.647814)
		(end 74.508614 -68.882514)
		(width 0.1143)
		(layer "In2.Cu")
		(net "XDP_CPU_NODE1_VISA2")
	)
	(segment
		(start 97.243392 -60.589414)
		(end 99.020122 -60.589414)
		(width 0.1143)
		(layer "In2.Cu")
		(net "XDP_CPU_NODE1_VISA2")
	)
	(segment
		(start 71.433182 -70.959218)
		(end 71.809102 -70.959218)
		(width 0.1143)
		(layer "In2.Cu")
		(net "XDP_CPU_NODE1_VISA2")
	)
	(segment
		(start 95.634048 -60.063126)
		(end 95.81642 -60.245498)
		(width 0.1143)
		(layer "In2.Cu")
		(net "XDP_CPU_NODE1_VISA2")
	)
	(segment
		(start 98.57359 -61.6458)
		(end 98.57359 -61.90361)
		(width 0.1143)
		(layer "In2.Cu")
		(net "XDP_CPU_NODE1_VISA2")
	)
	(segment
		(start 92.70492 -60.245498)
		(end 92.887292 -60.063126)
		(width 0.1143)
		(layer "In2.Cu")
		(net "XDP_CPU_NODE1_VISA2")
	)
	(segment
		(start 71.809102 -70.959218)
		(end 72.120506 -70.647814)
		(width 0.1143)
		(layer "In2.Cu")
		(net "XDP_CPU_NODE1_VISA2")
	)
	(segment
		(start 74.508614 -68.882514)
		(end 78.148942 -68.882514)
		(width 0.1143)
		(layer "In2.Cu")
		(net "XDP_CPU_NODE1_VISA2")
	)
	(segment
		(start 91.34348 -59.818778)
		(end 91.34348 -59.820556)
		(width 0.1143)
		(layer "In2.Cu")
		(net "XDP_CPU_NODE1_VISA2")
	)
	(segment
		(start 95.998792 -60.589414)
		(end 96.256348 -60.589414)
		(width 0.1143)
		(layer "In2.Cu")
		(net "XDP_CPU_NODE1_VISA2")
	)
	(segment
		(start 94.389448 -60.063126)
		(end 94.57182 -60.245498)
		(width 0.1143)
		(layer "In2.Cu")
		(net "XDP_CPU_NODE1_VISA2")
	)
	(segment
		(start 93.767148 -60.589414)
		(end 93.94952 -60.407042)
		(width 0.1143)
		(layer "In2.Cu")
		(net "XDP_CPU_NODE1_VISA2")
	)
	(segment
		(start 93.94952 -60.245498)
		(end 94.131892 -60.063126)
		(width 0.1143)
		(layer "In2.Cu")
		(net "XDP_CPU_NODE1_VISA2")
	)
	(segment
		(start 100.764594 -64.094614)
		(end 101.157532 -64.094614)
		(width 0.1143)
		(layer "In2.Cu")
		(net "XDP_CPU_NODE1_VISA2")
	)
	(segment
		(start 93.32722 -60.245498)
		(end 93.32722 -60.407042)
		(width 0.1143)
		(layer "In2.Cu")
		(net "XDP_CPU_NODE1_VISA2")
	)
	(segment
		(start 71.169022 -71.223378)
		(end 71.433182 -70.959218)
		(width 0.1143)
		(layer "In2.Cu")
		(net "XDP_CPU_NODE1_VISA2")
	)
	(segment
		(start 95.19412 -60.407042)
		(end 95.19412 -60.245498)
		(width 0.1143)
		(layer "In2.Cu")
		(net "XDP_CPU_NODE1_VISA2")
	)
	(segment
		(start 92.70492 -60.407042)
		(end 92.70492 -60.245498)
		(width 0.1143)
		(layer "In2.Cu")
		(net "XDP_CPU_NODE1_VISA2")
	)
	(segment
		(start 99.013518 -61.463174)
		(end 98.755962 -61.463174)
		(width 0.1143)
		(layer "In2.Cu")
		(net "XDP_CPU_NODE1_VISA2")
	)
	(segment
		(start 95.011748 -60.589414)
		(end 95.19412 -60.407042)
		(width 0.1143)
		(layer "In2.Cu")
		(net "XDP_CPU_NODE1_VISA2")
	)
	(segment
		(start 101.132386 -62.701678)
		(end 101.132386 -62.959742)
		(width 0.1143)
		(layer "In2.Cu")
		(net "XDP_CPU_NODE1_VISA2")
	)
	(segment
		(start 91.17838 -59.653678)
		(end 91.34348 -59.818778)
		(width 0.1143)
		(layer "In2.Cu")
		(net "XDP_CPU_NODE1_VISA2")
	)
	(segment
		(start 96.43872 -60.245498)
		(end 96.621092 -60.063126)
		(width 0.1143)
		(layer "In2.Cu")
		(net "XDP_CPU_NODE1_VISA2")
	)
	(segment
		(start 72.120506 -70.647814)
		(end 72.743314 -70.647814)
		(width 0.1143)
		(layer "In2.Cu")
		(net "XDP_CPU_NODE1_VISA2")
	)
	(segment
		(start 40.111172 -15.207234)
		(end 39.88054 -14.976602)
		(width 0.254)
		(layer "F.Cu")
		(net "PV_VDDR_NODE1_MODE")
	)
	(segment
		(start 40.668194 -15.207234)
		(end 40.111172 -15.207234)
		(width 0.254)
		(layer "F.Cu")
		(net "PV_VDDR_NODE1_MODE")
	)
	(segment
		(start 39.88054 -14.976602)
		(end 39.697406 -14.793468)
		(width 0.254)
		(layer "F.Cu")
		(net "PV_VDDR_NODE1_MODE")
	)
	(segment
		(start 39.435024 -12.980162)
		(end 38.882828 -12.427966)
		(width 0.1778)
		(layer "F.Cu")
		(net "PV_VDDR_NODE1_MODE")
	)
	(segment
		(start 38.882828 -12.427966)
		(end 38.882828 -11.86434)
		(width 0.1778)
		(layer "F.Cu")
		(net "PV_VDDR_NODE1_MODE")
	)
	(segment
		(start 39.697406 -14.200124)
		(end 39.697406 -13.242544)
		(width 0.254)
		(layer "F.Cu")
		(net "PV_VDDR_NODE1_MODE")
	)
	(segment
		(start 39.697406 -13.242544)
		(end 39.435024 -12.980162)
		(width 0.254)
		(layer "F.Cu")
		(net "PV_VDDR_NODE1_MODE")
	)
	(segment
		(start 39.697406 -14.793468)
		(end 39.697406 -14.200124)
		(width 0.254)
		(layer "F.Cu")
		(net "PV_VDDR_NODE1_MODE")
	)
	(via
		(at 39.88054 -14.976602)
		(size 0.508)
		(drill 0.254)
		(layers "F.Cu" "B.Cu")
		(net "PV_VDDR_NODE1_MODE")
	)
	(segment
		(start 13.869162 -130.522218)
		(end 13.657326 -130.310382)
		(width 0.254)
		(layer "F.Cu")
		(net "P1V05_NODE1_TRIP")
	)
	(segment
		(start 12.930124 -130.520186)
		(end 13.447522 -130.520186)
		(width 0.254)
		(layer "F.Cu")
		(net "P1V05_NODE1_TRIP")
	)
	(segment
		(start 14.51229 -130.522218)
		(end 13.869162 -130.522218)
		(width 0.254)
		(layer "F.Cu")
		(net "P1V05_NODE1_TRIP")
	)
	(segment
		(start 13.447522 -130.520186)
		(end 13.657326 -130.310382)
		(width 0.254)
		(layer "F.Cu")
		(net "P1V05_NODE1_TRIP")
	)
	(via
		(at 13.657326 -130.310382)
		(size 0.508)
		(drill 0.254)
		(layers "F.Cu" "B.Cu")
		(net "P1V05_NODE1_TRIP")
	)
	(segment
		(start 163.889944 -92.865194)
		(end 164.127434 -92.627704)
		(width 0.1016)
		(layer "F.Cu")
		(net "SPI_USB_NODE1_CLK")
	)
	(segment
		(start 163.889944 -93.440758)
		(end 163.889944 -92.865194)
		(width 0.1016)
		(layer "F.Cu")
		(net "SPI_USB_NODE1_CLK")
	)
	(segment
		(start 159.547814 -87.583772)
		(end 161.14776 -87.583772)
		(width 0.1016)
		(layer "F.Cu")
		(net "SPI_USB_NODE1_CLK")
	)
	(via
		(at 159.547814 -87.583772)
		(size 0.508)
		(drill 0.254)
		(layers "F.Cu" "B.Cu")
		(net "SPI_USB_NODE1_CLK")
	)
	(via
		(at 164.127434 -92.627704)
		(size 0.508)
		(drill 0.254)
		(layers "F.Cu" "B.Cu")
		(net "SPI_USB_NODE1_CLK")
	)
	(segment
		(start 158.630112 -89.84869)
		(end 158.630112 -89.596214)
		(width 0.1016)
		(layer "B.Cu")
		(net "SPI_USB_NODE1_CLK")
	)
	(segment
		(start 160.35528 -91.573858)
		(end 160.35528 -91.321382)
		(width 0.1016)
		(layer "B.Cu")
		(net "SPI_USB_NODE1_CLK")
	)
	(segment
		(start 163.39566 -89.143586)
		(end 160.786572 -91.752674)
		(width 0.1016)
		(layer "B.Cu")
		(net "SPI_USB_NODE1_CLK")
	)
	(segment
		(start 161.704782 -87.636604)
		(end 161.452306 -87.636604)
		(width 0.1016)
		(layer "B.Cu")
		(net "SPI_USB_NODE1_CLK")
	)
	(segment
		(start 159.492696 -90.458798)
		(end 161.883598 -88.067896)
		(width 0.1016)
		(layer "B.Cu")
		(net "SPI_USB_NODE1_CLK")
	)
	(segment
		(start 159.671512 -90.89009)
		(end 159.492696 -90.711274)
		(width 0.1016)
		(layer "B.Cu")
		(net "SPI_USB_NODE1_CLK")
	)
	(segment
		(start 161.86658 -89.199974)
		(end 161.614104 -89.199974)
		(width 0.1016)
		(layer "B.Cu")
		(net "SPI_USB_NODE1_CLK")
	)
	(segment
		(start 163.187126 -91.939872)
		(end 163.187126 -91.687396)
		(width 0.1016)
		(layer "B.Cu")
		(net "SPI_USB_NODE1_CLK")
	)
	(segment
		(start 159.73679 -88.489536)
		(end 159.73679 -87.772748)
		(width 0.1016)
		(layer "B.Cu")
		(net "SPI_USB_NODE1_CLK")
	)
	(segment
		(start 158.808928 -90.027506)
		(end 158.630112 -89.84869)
		(width 0.1016)
		(layer "B.Cu")
		(net "SPI_USB_NODE1_CLK")
	)
	(segment
		(start 161.883598 -88.067896)
		(end 161.883598 -87.81542)
		(width 0.1016)
		(layer "B.Cu")
		(net "SPI_USB_NODE1_CLK")
	)
	(segment
		(start 159.73679 -87.772748)
		(end 159.547814 -87.583772)
		(width 0.1016)
		(layer "B.Cu")
		(net "SPI_USB_NODE1_CLK")
	)
	(segment
		(start 160.35528 -91.321382)
		(end 162.045396 -89.631266)
		(width 0.1016)
		(layer "B.Cu")
		(net "SPI_USB_NODE1_CLK")
	)
	(segment
		(start 161.452306 -87.636604)
		(end 159.061404 -90.027506)
		(width 0.1016)
		(layer "B.Cu")
		(net "SPI_USB_NODE1_CLK")
	)
	(segment
		(start 162.045396 -89.37879)
		(end 161.86658 -89.199974)
		(width 0.1016)
		(layer "B.Cu")
		(net "SPI_USB_NODE1_CLK")
	)
	(segment
		(start 162.259264 -93.477842)
		(end 162.080448 -93.299026)
		(width 0.1016)
		(layer "B.Cu")
		(net "SPI_USB_NODE1_CLK")
	)
	(segment
		(start 163.648136 -89.143586)
		(end 163.39566 -89.143586)
		(width 0.1016)
		(layer "B.Cu")
		(net "SPI_USB_NODE1_CLK")
	)
	(segment
		(start 158.630112 -89.596214)
		(end 159.73679 -88.489536)
		(width 0.1016)
		(layer "B.Cu")
		(net "SPI_USB_NODE1_CLK")
	)
	(segment
		(start 161.649156 -92.615258)
		(end 161.39668 -92.615258)
		(width 0.1016)
		(layer "B.Cu")
		(net "SPI_USB_NODE1_CLK")
	)
	(segment
		(start 161.217864 -92.436442)
		(end 161.217864 -92.183966)
		(width 0.1016)
		(layer "B.Cu")
		(net "SPI_USB_NODE1_CLK")
	)
	(segment
		(start 163.826952 -89.574878)
		(end 163.826952 -89.322402)
		(width 0.1016)
		(layer "B.Cu")
		(net "SPI_USB_NODE1_CLK")
	)
	(segment
		(start 163.870894 -92.371164)
		(end 163.618418 -92.371164)
		(width 0.1016)
		(layer "B.Cu")
		(net "SPI_USB_NODE1_CLK")
	)
	(segment
		(start 161.614104 -89.199974)
		(end 159.923988 -90.89009)
		(width 0.1016)
		(layer "B.Cu")
		(net "SPI_USB_NODE1_CLK")
	)
	(segment
		(start 162.080448 -93.04655)
		(end 163.187126 -91.939872)
		(width 0.1016)
		(layer "B.Cu")
		(net "SPI_USB_NODE1_CLK")
	)
	(segment
		(start 159.061404 -90.027506)
		(end 158.808928 -90.027506)
		(width 0.1016)
		(layer "B.Cu")
		(net "SPI_USB_NODE1_CLK")
	)
	(segment
		(start 162.51174 -93.477842)
		(end 162.259264 -93.477842)
		(width 0.1016)
		(layer "B.Cu")
		(net "SPI_USB_NODE1_CLK")
	)
	(segment
		(start 160.786572 -91.752674)
		(end 160.534096 -91.752674)
		(width 0.1016)
		(layer "B.Cu")
		(net "SPI_USB_NODE1_CLK")
	)
	(segment
		(start 163.00831 -91.50858)
		(end 162.755834 -91.50858)
		(width 0.1016)
		(layer "B.Cu")
		(net "SPI_USB_NODE1_CLK")
	)
	(segment
		(start 164.127434 -92.627704)
		(end 163.870894 -92.371164)
		(width 0.1016)
		(layer "B.Cu")
		(net "SPI_USB_NODE1_CLK")
	)
	(segment
		(start 162.080448 -93.299026)
		(end 162.080448 -93.04655)
		(width 0.1016)
		(layer "B.Cu")
		(net "SPI_USB_NODE1_CLK")
	)
	(segment
		(start 163.618418 -92.371164)
		(end 162.51174 -93.477842)
		(width 0.1016)
		(layer "B.Cu")
		(net "SPI_USB_NODE1_CLK")
	)
	(segment
		(start 161.883598 -87.81542)
		(end 161.704782 -87.636604)
		(width 0.1016)
		(layer "B.Cu")
		(net "SPI_USB_NODE1_CLK")
	)
	(segment
		(start 162.045396 -89.631266)
		(end 162.045396 -89.37879)
		(width 0.1016)
		(layer "B.Cu")
		(net "SPI_USB_NODE1_CLK")
	)
	(segment
		(start 163.187126 -91.687396)
		(end 163.00831 -91.50858)
		(width 0.1016)
		(layer "B.Cu")
		(net "SPI_USB_NODE1_CLK")
	)
	(segment
		(start 159.492696 -90.711274)
		(end 159.492696 -90.458798)
		(width 0.1016)
		(layer "B.Cu")
		(net "SPI_USB_NODE1_CLK")
	)
	(segment
		(start 161.39668 -92.615258)
		(end 161.217864 -92.436442)
		(width 0.1016)
		(layer "B.Cu")
		(net "SPI_USB_NODE1_CLK")
	)
	(segment
		(start 162.755834 -91.50858)
		(end 161.649156 -92.615258)
		(width 0.1016)
		(layer "B.Cu")
		(net "SPI_USB_NODE1_CLK")
	)
	(segment
		(start 163.826952 -89.322402)
		(end 163.648136 -89.143586)
		(width 0.1016)
		(layer "B.Cu")
		(net "SPI_USB_NODE1_CLK")
	)
	(segment
		(start 160.534096 -91.752674)
		(end 160.35528 -91.573858)
		(width 0.1016)
		(layer "B.Cu")
		(net "SPI_USB_NODE1_CLK")
	)
	(segment
		(start 161.217864 -92.183966)
		(end 163.826952 -89.574878)
		(width 0.1016)
		(layer "B.Cu")
		(net "SPI_USB_NODE1_CLK")
	)
	(segment
		(start 159.923988 -90.89009)
		(end 159.671512 -90.89009)
		(width 0.1016)
		(layer "B.Cu")
		(net "SPI_USB_NODE1_CLK")
	)
	(segment
		(start 109.387894 -74.406252)
		(end 110.460028 -74.406252)
		(width 0.1016)
		(layer "F.Cu")
		(net "XDP_CPU_NODE1_VISA10")
	)
	(segment
		(start 67.154044 -73.583038)
		(end 66.787776 -73.949306)
		(width 0.1016)
		(layer "F.Cu")
		(net "XDP_CPU_NODE1_VISA10")
	)
	(segment
		(start 106.966512 -74.320654)
		(end 107.420156 -74.774298)
		(width 0.1016)
		(layer "F.Cu")
		(net "XDP_CPU_NODE1_VISA10")
	)
	(segment
		(start 109.019848 -74.774298)
		(end 109.387894 -74.406252)
		(width 0.1016)
		(layer "F.Cu")
		(net "XDP_CPU_NODE1_VISA10")
	)
	(segment
		(start 107.420156 -74.774298)
		(end 109.019848 -74.774298)
		(width 0.1016)
		(layer "F.Cu")
		(net "XDP_CPU_NODE1_VISA10")
	)
	(segment
		(start 66.787776 -73.949306)
		(end 66.787776 -74.62774)
		(width 0.1016)
		(layer "F.Cu")
		(net "XDP_CPU_NODE1_VISA10")
	)
	(segment
		(start 66.787776 -74.62774)
		(end 66.777616 -74.6379)
		(width 0.1016)
		(layer "F.Cu")
		(net "XDP_CPU_NODE1_VISA10")
	)
	(via
		(at 66.777616 -74.6379)
		(size 0.49022)
		(drill 0.254)
		(layers "F.Cu" "B.Cu")
		(net "XDP_CPU_NODE1_VISA10")
	)
	(via
		(at 106.966512 -74.320654)
		(size 0.508)
		(drill 0.254)
		(layers "F.Cu" "B.Cu")
		(net "XDP_CPU_NODE1_VISA10")
	)
	(segment
		(start 87.961216 -71.734934)
		(end 85.59673 -71.734934)
		(width 0.1143)
		(layer "In2.Cu")
		(net "XDP_CPU_NODE1_VISA10")
	)
	(segment
		(start 88.80729 -72.581008)
		(end 87.961216 -71.734934)
		(width 0.1143)
		(layer "In2.Cu")
		(net "XDP_CPU_NODE1_VISA10")
	)
	(segment
		(start 65.47612 -74.74839)
		(end 66.667126 -74.74839)
		(width 0.1143)
		(layer "In2.Cu")
		(net "XDP_CPU_NODE1_VISA10")
	)
	(segment
		(start 104.236012 -74.963274)
		(end 103.230172 -73.957434)
		(width 0.1143)
		(layer "In2.Cu")
		(net "XDP_CPU_NODE1_VISA10")
	)
	(segment
		(start 84.03082 -73.300844)
		(end 84.03082 -73.30186)
		(width 0.1143)
		(layer "In2.Cu")
		(net "XDP_CPU_NODE1_VISA10")
	)
	(segment
		(start 100.06584 -75.520042)
		(end 99.612958 -75.972924)
		(width 0.1143)
		(layer "In2.Cu")
		(net "XDP_CPU_NODE1_VISA10")
	)
	(segment
		(start 94.459044 -74.57186)
		(end 92.468192 -72.581008)
		(width 0.1143)
		(layer "In2.Cu")
		(net "XDP_CPU_NODE1_VISA10")
	)
	(segment
		(start 100.06584 -73.882758)
		(end 100.06584 -75.520042)
		(width 0.1143)
		(layer "In2.Cu")
		(net "XDP_CPU_NODE1_VISA10")
	)
	(segment
		(start 92.468192 -72.581008)
		(end 88.80729 -72.581008)
		(width 0.1143)
		(layer "In2.Cu")
		(net "XDP_CPU_NODE1_VISA10")
	)
	(segment
		(start 85.59673 -71.734934)
		(end 84.03082 -73.300844)
		(width 0.1143)
		(layer "In2.Cu")
		(net "XDP_CPU_NODE1_VISA10")
	)
	(segment
		(start 69.29374 -76.323698)
		(end 68.681346 -75.711304)
		(width 0.1143)
		(layer "In2.Cu")
		(net "XDP_CPU_NODE1_VISA10")
	)
	(segment
		(start 81.908142 -75.423776)
		(end 77.884782 -75.423776)
		(width 0.1143)
		(layer "In2.Cu")
		(net "XDP_CPU_NODE1_VISA10")
	)
	(segment
		(start 65.49009 -75.711304)
		(end 65.21577 -75.436984)
		(width 0.1143)
		(layer "In2.Cu")
		(net "XDP_CPU_NODE1_VISA10")
	)
	(segment
		(start 99.612958 -75.972924)
		(end 97.058734 -75.972924)
		(width 0.1143)
		(layer "In2.Cu")
		(net "XDP_CPU_NODE1_VISA10")
	)
	(segment
		(start 77.449934 -75.858624)
		(end 75.191874 -75.858624)
		(width 0.1143)
		(layer "In2.Cu")
		(net "XDP_CPU_NODE1_VISA10")
	)
	(segment
		(start 74.7268 -76.323698)
		(end 69.29374 -76.323698)
		(width 0.1143)
		(layer "In2.Cu")
		(net "XDP_CPU_NODE1_VISA10")
	)
	(segment
		(start 103.230172 -73.957434)
		(end 103.230172 -73.6854)
		(width 0.1143)
		(layer "In2.Cu")
		(net "XDP_CPU_NODE1_VISA10")
	)
	(segment
		(start 100.786184 -73.162414)
		(end 100.06584 -73.882758)
		(width 0.1143)
		(layer "In2.Cu")
		(net "XDP_CPU_NODE1_VISA10")
	)
	(segment
		(start 106.966512 -74.320654)
		(end 106.425238 -74.320654)
		(width 0.1143)
		(layer "In2.Cu")
		(net "XDP_CPU_NODE1_VISA10")
	)
	(segment
		(start 65.21577 -75.00874)
		(end 65.47612 -74.74839)
		(width 0.1143)
		(layer "In2.Cu")
		(net "XDP_CPU_NODE1_VISA10")
	)
	(segment
		(start 103.230172 -73.6854)
		(end 102.707186 -73.162414)
		(width 0.1143)
		(layer "In2.Cu")
		(net "XDP_CPU_NODE1_VISA10")
	)
	(segment
		(start 106.425238 -74.320654)
		(end 105.782618 -74.963274)
		(width 0.1143)
		(layer "In2.Cu")
		(net "XDP_CPU_NODE1_VISA10")
	)
	(segment
		(start 68.681346 -75.711304)
		(end 65.49009 -75.711304)
		(width 0.1143)
		(layer "In2.Cu")
		(net "XDP_CPU_NODE1_VISA10")
	)
	(segment
		(start 66.667126 -74.74839)
		(end 66.777616 -74.6379)
		(width 0.1143)
		(layer "In2.Cu")
		(net "XDP_CPU_NODE1_VISA10")
	)
	(segment
		(start 75.191874 -75.858624)
		(end 74.7268 -76.323698)
		(width 0.1143)
		(layer "In2.Cu")
		(net "XDP_CPU_NODE1_VISA10")
	)
	(segment
		(start 77.884782 -75.423776)
		(end 77.449934 -75.858624)
		(width 0.1143)
		(layer "In2.Cu")
		(net "XDP_CPU_NODE1_VISA10")
	)
	(segment
		(start 102.707186 -73.162414)
		(end 100.786184 -73.162414)
		(width 0.1143)
		(layer "In2.Cu")
		(net "XDP_CPU_NODE1_VISA10")
	)
	(segment
		(start 84.03082 -73.30186)
		(end 81.908142 -75.423776)
		(width 0.1143)
		(layer "In2.Cu")
		(net "XDP_CPU_NODE1_VISA10")
	)
	(segment
		(start 95.65767 -74.57186)
		(end 94.459044 -74.57186)
		(width 0.1143)
		(layer "In2.Cu")
		(net "XDP_CPU_NODE1_VISA10")
	)
	(segment
		(start 105.782618 -74.963274)
		(end 104.236012 -74.963274)
		(width 0.1143)
		(layer "In2.Cu")
		(net "XDP_CPU_NODE1_VISA10")
	)
	(segment
		(start 97.058734 -75.972924)
		(end 95.65767 -74.57186)
		(width 0.1143)
		(layer "In2.Cu")
		(net "XDP_CPU_NODE1_VISA10")
	)
	(segment
		(start 65.21577 -75.436984)
		(end 65.21577 -75.00874)
		(width 0.1143)
		(layer "In2.Cu")
		(net "XDP_CPU_NODE1_VISA10")
	)
	(via
		(at 41.995344 -11.716004)
		(size 0.508)
		(drill 0.254)
		(layers "F.Cu" "B.Cu")
		(net "SW_PV_VDDR_NODE1_DRVL")
	)
	(segment
		(start 19.449796 -133.077712)
		(end 19.32559 -132.953506)
		(width 0.1016)
		(layer "F.Cu")
		(net "PWRGD_NODE1_P1V05_PG")
	)
	(segment
		(start 19.129756 -132.360416)
		(end 19.32559 -132.360416)
		(width 0.1016)
		(layer "F.Cu")
		(net "PWRGD_NODE1_P1V05_PG")
	)
	(segment
		(start 179.010564 -122.36577)
		(end 179.510436 -122.865642)
		(width 0.1016)
		(layer "F.Cu")
		(net "PWRGD_NODE1_P1V05_PG")
	)
	(segment
		(start 17.612106 -131.022344)
		(end 17.791684 -131.022344)
		(width 0.1016)
		(layer "F.Cu")
		(net "PWRGD_NODE1_P1V05_PG")
	)
	(segment
		(start 19.32559 -132.953506)
		(end 19.32559 -132.360416)
		(width 0.1016)
		(layer "F.Cu")
		(net "PWRGD_NODE1_P1V05_PG")
	)
	(segment
		(start 17.791684 -131.022344)
		(end 19.129756 -132.360416)
		(width 0.1016)
		(layer "F.Cu")
		(net "PWRGD_NODE1_P1V05_PG")
	)
	(segment
		(start 20.835874 -133.077712)
		(end 19.449796 -133.077712)
		(width 0.1016)
		(layer "F.Cu")
		(net "PWRGD_NODE1_P1V05_PG")
	)
	(via
		(at 179.510436 -122.865642)
		(size 0.49022)
		(drill 0.254)
		(layers "F.Cu" "B.Cu")
		(net "PWRGD_NODE1_P1V05_PG")
	)
	(via
		(at 20.835874 -133.077712)
		(size 0.508)
		(drill 0.254)
		(layers "F.Cu" "B.Cu")
		(net "PWRGD_NODE1_P1V05_PG")
	)
	(via
		(at 156.96692 -116.943632)
		(size 0.508)
		(drill 0.254)
		(layers "F.Cu" "B.Cu")
		(net "PWRGD_NODE1_P1V05_PG")
	)
	(segment
		(start 82.601054 -116.10467)
		(end 83.63585 -116.10467)
		(width 0.1143)
		(layer "In6.Cu")
		(net "PWRGD_NODE1_P1V05_PG")
	)
	(segment
		(start 137.885424 -122.071892)
		(end 138.21664 -121.740676)
		(width 0.1143)
		(layer "In6.Cu")
		(net "PWRGD_NODE1_P1V05_PG")
	)
	(segment
		(start 134.371334 -122.071892)
		(end 137.885424 -122.071892)
		(width 0.1143)
		(layer "In6.Cu")
		(net "PWRGD_NODE1_P1V05_PG")
	)
	(segment
		(start 83.63585 -116.10467)
		(end 84.685378 -117.154198)
		(width 0.1143)
		(layer "In6.Cu")
		(net "PWRGD_NODE1_P1V05_PG")
	)
	(segment
		(start 26.5049 -127.408686)
		(end 26.5049 -122.549158)
		(width 0.1143)
		(layer "In6.Cu")
		(net "PWRGD_NODE1_P1V05_PG")
	)
	(segment
		(start 20.835874 -133.077712)
		(end 26.5049 -127.408686)
		(width 0.1143)
		(layer "In6.Cu")
		(net "PWRGD_NODE1_P1V05_PG")
	)
	(segment
		(start 36.756086 -120.849644)
		(end 40.025574 -120.849644)
		(width 0.1143)
		(layer "In6.Cu")
		(net "PWRGD_NODE1_P1V05_PG")
	)
	(segment
		(start 95.088202 -117.154198)
		(end 101.246432 -110.995968)
		(width 0.1143)
		(layer "In6.Cu")
		(net "PWRGD_NODE1_P1V05_PG")
	)
	(segment
		(start 154.914346 -116.710968)
		(end 155.14701 -116.943632)
		(width 0.1143)
		(layer "In6.Cu")
		(net "PWRGD_NODE1_P1V05_PG")
	)
	(segment
		(start 28.5496 -120.504458)
		(end 36.4109 -120.504458)
		(width 0.1143)
		(layer "In6.Cu")
		(net "PWRGD_NODE1_P1V05_PG")
	)
	(segment
		(start 40.715438 -120.15978)
		(end 44.140628 -120.15978)
		(width 0.1143)
		(layer "In6.Cu")
		(net "PWRGD_NODE1_P1V05_PG")
	)
	(segment
		(start 50.471832 -115.565936)
		(end 82.06232 -115.565936)
		(width 0.1143)
		(layer "In6.Cu")
		(net "PWRGD_NODE1_P1V05_PG")
	)
	(segment
		(start 133.939534 -122.503692)
		(end 134.371334 -122.071892)
		(width 0.1143)
		(layer "In6.Cu")
		(net "PWRGD_NODE1_P1V05_PG")
	)
	(segment
		(start 119.95277 -110.614206)
		(end 120.21058 -110.872016)
		(width 0.1143)
		(layer "In6.Cu")
		(net "PWRGD_NODE1_P1V05_PG")
	)
	(segment
		(start 120.21058 -111.075978)
		(end 128.322832 -119.18823)
		(width 0.1143)
		(layer "In6.Cu")
		(net "PWRGD_NODE1_P1V05_PG")
	)
	(segment
		(start 128.322832 -120.774714)
		(end 130.0861 -122.537982)
		(width 0.1143)
		(layer "In6.Cu")
		(net "PWRGD_NODE1_P1V05_PG")
	)
	(segment
		(start 130.0861 -122.537982)
		(end 133.29539 -122.537982)
		(width 0.1143)
		(layer "In6.Cu")
		(net "PWRGD_NODE1_P1V05_PG")
	)
	(segment
		(start 119.207788 -110.995968)
		(end 119.58955 -110.614206)
		(width 0.1143)
		(layer "In6.Cu")
		(net "PWRGD_NODE1_P1V05_PG")
	)
	(segment
		(start 45.1993 -119.101108)
		(end 46.93666 -119.101108)
		(width 0.1143)
		(layer "In6.Cu")
		(net "PWRGD_NODE1_P1V05_PG")
	)
	(segment
		(start 101.246432 -110.995968)
		(end 119.207788 -110.995968)
		(width 0.1143)
		(layer "In6.Cu")
		(net "PWRGD_NODE1_P1V05_PG")
	)
	(segment
		(start 84.685378 -117.154198)
		(end 95.088202 -117.154198)
		(width 0.1143)
		(layer "In6.Cu")
		(net "PWRGD_NODE1_P1V05_PG")
	)
	(segment
		(start 40.025574 -120.849644)
		(end 40.715438 -120.15978)
		(width 0.1143)
		(layer "In6.Cu")
		(net "PWRGD_NODE1_P1V05_PG")
	)
	(segment
		(start 119.58955 -110.614206)
		(end 119.95277 -110.614206)
		(width 0.1143)
		(layer "In6.Cu")
		(net "PWRGD_NODE1_P1V05_PG")
	)
	(segment
		(start 153.143966 -116.710968)
		(end 154.914346 -116.710968)
		(width 0.1143)
		(layer "In6.Cu")
		(net "PWRGD_NODE1_P1V05_PG")
	)
	(segment
		(start 82.06232 -115.565936)
		(end 82.601054 -116.10467)
		(width 0.1143)
		(layer "In6.Cu")
		(net "PWRGD_NODE1_P1V05_PG")
	)
	(segment
		(start 133.29539 -122.537982)
		(end 133.32968 -122.503692)
		(width 0.1143)
		(layer "In6.Cu")
		(net "PWRGD_NODE1_P1V05_PG")
	)
	(segment
		(start 155.14701 -116.943632)
		(end 156.96692 -116.943632)
		(width 0.1143)
		(layer "In6.Cu")
		(net "PWRGD_NODE1_P1V05_PG")
	)
	(segment
		(start 44.140628 -120.15978)
		(end 45.1993 -119.101108)
		(width 0.1143)
		(layer "In6.Cu")
		(net "PWRGD_NODE1_P1V05_PG")
	)
	(segment
		(start 46.93666 -119.101108)
		(end 50.471832 -115.565936)
		(width 0.1143)
		(layer "In6.Cu")
		(net "PWRGD_NODE1_P1V05_PG")
	)
	(segment
		(start 120.21058 -110.872016)
		(end 120.21058 -111.075978)
		(width 0.1143)
		(layer "In6.Cu")
		(net "PWRGD_NODE1_P1V05_PG")
	)
	(segment
		(start 36.4109 -120.504458)
		(end 36.756086 -120.849644)
		(width 0.1143)
		(layer "In6.Cu")
		(net "PWRGD_NODE1_P1V05_PG")
	)
	(segment
		(start 138.21664 -121.740676)
		(end 148.114258 -121.740676)
		(width 0.1143)
		(layer "In6.Cu")
		(net "PWRGD_NODE1_P1V05_PG")
	)
	(segment
		(start 26.5049 -122.549158)
		(end 28.5496 -120.504458)
		(width 0.1143)
		(layer "In6.Cu")
		(net "PWRGD_NODE1_P1V05_PG")
	)
	(segment
		(start 148.114258 -121.740676)
		(end 153.143966 -116.710968)
		(width 0.1143)
		(layer "In6.Cu")
		(net "PWRGD_NODE1_P1V05_PG")
	)
	(segment
		(start 128.322832 -119.18823)
		(end 128.322832 -120.774714)
		(width 0.1143)
		(layer "In6.Cu")
		(net "PWRGD_NODE1_P1V05_PG")
	)
	(segment
		(start 133.32968 -122.503692)
		(end 133.939534 -122.503692)
		(width 0.1143)
		(layer "In6.Cu")
		(net "PWRGD_NODE1_P1V05_PG")
	)
	(segment
		(start 156.96692 -116.943632)
		(end 156.96692 -117.97284)
		(width 0.1143)
		(layer "In7.Cu")
		(net "PWRGD_NODE1_P1V05_PG")
	)
	(segment
		(start 179.279042 -122.865642)
		(end 179.510436 -122.865642)
		(width 0.1143)
		(layer "In7.Cu")
		(net "PWRGD_NODE1_P1V05_PG")
	)
	(segment
		(start 156.96692 -117.97284)
		(end 159.403542 -120.409462)
		(width 0.1143)
		(layer "In7.Cu")
		(net "PWRGD_NODE1_P1V05_PG")
	)
	(segment
		(start 172.727112 -122.30608)
		(end 178.71948 -122.30608)
		(width 0.1143)
		(layer "In7.Cu")
		(net "PWRGD_NODE1_P1V05_PG")
	)
	(segment
		(start 159.403542 -120.409462)
		(end 170.830494 -120.409462)
		(width 0.1143)
		(layer "In7.Cu")
		(net "PWRGD_NODE1_P1V05_PG")
	)
	(segment
		(start 170.830494 -120.409462)
		(end 172.727112 -122.30608)
		(width 0.1143)
		(layer "In7.Cu")
		(net "PWRGD_NODE1_P1V05_PG")
	)
	(segment
		(start 178.71948 -122.30608)
		(end 179.279042 -122.865642)
		(width 0.1143)
		(layer "In7.Cu")
		(net "PWRGD_NODE1_P1V05_PG")
	)
	(segment
		(start 153.439114 -88.799416)
		(end 153.632916 -88.799416)
		(width 0.1016)
		(layer "F.Cu")
		(net "SPI_USB_NODE1_SI_R")
	)
	(segment
		(start 154.328114 -89.494614)
		(end 154.39517 -89.494614)
		(width 0.1016)
		(layer "F.Cu")
		(net "SPI_USB_NODE1_SI_R")
	)
	(segment
		(start 155.86456 -88.853772)
		(end 155.036012 -88.853772)
		(width 0.1016)
		(layer "F.Cu")
		(net "SPI_USB_NODE1_SI_R")
	)
	(segment
		(start 155.036012 -88.853772)
		(end 154.39517 -89.494614)
		(width 0.1016)
		(layer "F.Cu")
		(net "SPI_USB_NODE1_SI_R")
	)
	(segment
		(start 153.632916 -88.799416)
		(end 154.328114 -89.494614)
		(width 0.1016)
		(layer "F.Cu")
		(net "SPI_USB_NODE1_SI_R")
	)
	(via
		(at 154.39517 -89.494614)
		(size 0.508)
		(drill 0.254)
		(layers "F.Cu" "B.Cu")
		(net "SPI_USB_NODE1_SI_R")
	)
	(via
		(at 108.665518 -65.742566)
		(size 0.508)
		(drill 0.254)
		(layers "F.Cu" "B.Cu")
		(net "P1V05_STB_NODE1_XDP_A")
	)
	(segment
		(start 110.686342 -66.624962)
		(end 110.686342 -65.543938)
		(width 0.508)
		(layer "B.Cu")
		(net "P1V05_STB_NODE1_XDP_A")
	)
	(segment
		(start 110.686342 -65.543938)
		(end 110.604554 -65.46215)
		(width 0.508)
		(layer "B.Cu")
		(net "P1V05_STB_NODE1_XDP_A")
	)
	(segment
		(start 108.945934 -65.46215)
		(end 110.604554 -65.46215)
		(width 0.508)
		(layer "B.Cu")
		(net "P1V05_STB_NODE1_XDP_A")
	)
	(segment
		(start 108.665518 -65.742566)
		(end 108.945934 -65.46215)
		(width 0.508)
		(layer "B.Cu")
		(net "P1V05_STB_NODE1_XDP_A")
	)
	(via
		(at 41.2369 -10.917936)
		(size 0.508)
		(drill 0.254)
		(layers "F.Cu" "B.Cu")
		(net "SW_PV_VDDR_NODE1_DRVH")
	)
	(via
		(at 42.916094 -6.876542)
		(size 0.508)
		(drill 0.254)
		(layers "F.Cu" "B.Cu")
		(net "SW_PV_VDDR_NODE1_DRVH")
	)
	(via
		(at 40.825674 -10.423652)
		(size 0.508)
		(drill 0.254)
		(layers "F.Cu" "B.Cu")
		(net "SW_PV_VDDR_NODE1_DRVH")
	)
	(via
		(at 42.153586 -6.891782)
		(size 0.508)
		(drill 0.254)
		(layers "F.Cu" "B.Cu")
		(net "SW_PV_VDDR_NODE1_DRVH")
	)
	(via
		(at 18.869914 -123.61291)
		(size 0.508)
		(drill 0.254)
		(layers "F.Cu" "B.Cu")
		(net "SW_P1V05_NODE1_PH")
	)
	(segment
		(start 164.04336 -96.129348)
		(end 163.889944 -95.975932)
		(width 0.1016)
		(layer "F.Cu")
		(net "SPI_USB_NODE1_CLK_R")
	)
	(segment
		(start 164.04336 -96.943672)
		(end 164.04336 -96.129348)
		(width 0.1016)
		(layer "F.Cu")
		(net "SPI_USB_NODE1_CLK_R")
	)
	(segment
		(start 163.889944 -95.975932)
		(end 163.889944 -94.240858)
		(width 0.1016)
		(layer "F.Cu")
		(net "SPI_USB_NODE1_CLK_R")
	)
	(via
		(at 163.889944 -95.975932)
		(size 0.508)
		(drill 0.254)
		(layers "F.Cu" "B.Cu")
		(net "SPI_USB_NODE1_CLK_R")
	)
	(segment
		(start 103.248206 -72.906128)
		(end 100.956872 -70.614794)
		(width 0.1016)
		(layer "F.Cu")
		(net "XDP_CPU_NODE1_VISA3")
	)
	(segment
		(start 68.304664 -71.596758)
		(end 68.678044 -71.223378)
		(width 0.1016)
		(layer "F.Cu")
		(net "XDP_CPU_NODE1_VISA3")
	)
	(segment
		(start 100.649532 -69.103494)
		(end 100.649532 -67.467734)
		(width 0.1016)
		(layer "F.Cu")
		(net "XDP_CPU_NODE1_VISA3")
	)
	(segment
		(start 104.73182 -72.906128)
		(end 103.248206 -72.906128)
		(width 0.1016)
		(layer "F.Cu")
		(net "XDP_CPU_NODE1_VISA3")
	)
	(segment
		(start 68.297044 -71.596758)
		(end 68.304664 -71.596758)
		(width 0.1016)
		(layer "F.Cu")
		(net "XDP_CPU_NODE1_VISA3")
	)
	(segment
		(start 100.649532 -67.467734)
		(end 101.497892 -66.619374)
		(width 0.1016)
		(layer "F.Cu")
		(net "XDP_CPU_NODE1_VISA3")
	)
	(segment
		(start 100.956872 -69.410834)
		(end 100.649532 -69.103494)
		(width 0.1016)
		(layer "F.Cu")
		(net "XDP_CPU_NODE1_VISA3")
	)
	(segment
		(start 101.497892 -66.619374)
		(end 101.497892 -66.103754)
		(width 0.1016)
		(layer "F.Cu")
		(net "XDP_CPU_NODE1_VISA3")
	)
	(segment
		(start 100.956872 -70.614794)
		(end 100.956872 -69.410834)
		(width 0.1016)
		(layer "F.Cu")
		(net "XDP_CPU_NODE1_VISA3")
	)
	(via
		(at 68.678044 -71.223378)
		(size 0.508)
		(drill 0.254)
		(layers "F.Cu" "B.Cu")
		(net "XDP_CPU_NODE1_VISA3")
	)
	(via
		(at 101.497892 -66.103754)
		(size 0.508)
		(drill 0.254)
		(layers "F.Cu" "B.Cu")
		(net "XDP_CPU_NODE1_VISA3")
	)
	(segment
		(start 92.967556 -62.673992)
		(end 90.82659 -60.533026)
		(width 0.1143)
		(layer "In2.Cu")
		(net "XDP_CPU_NODE1_VISA3")
	)
	(segment
		(start 93.59646 -63.73622)
		(end 93.59646 -63.478664)
		(width 0.1143)
		(layer "In2.Cu")
		(net "XDP_CPU_NODE1_VISA3")
	)
	(segment
		(start 80.300576 -69.483986)
		(end 74.69505 -69.483986)
		(width 0.1143)
		(layer "In2.Cu")
		(net "XDP_CPU_NODE1_VISA3")
	)
	(segment
		(start 93.778832 -63.918592)
		(end 93.59646 -63.73622)
		(width 0.1143)
		(layer "In2.Cu")
		(net "XDP_CPU_NODE1_VISA3")
	)
	(segment
		(start 72.140318 -72.038718)
		(end 71.58736 -72.038718)
		(width 0.1143)
		(layer "In2.Cu")
		(net "XDP_CPU_NODE1_VISA3")
	)
	(segment
		(start 100.80498 -65.595246)
		(end 100.80498 -65.323212)
		(width 0.1143)
		(layer "In2.Cu")
		(net "XDP_CPU_NODE1_VISA3")
	)
	(segment
		(start 69.243448 -71.96709)
		(end 68.678044 -71.401686)
		(width 0.1143)
		(layer "In2.Cu")
		(net "XDP_CPU_NODE1_VISA3")
	)
	(segment
		(start 100.80498 -65.323212)
		(end 99.40036 -63.918592)
		(width 0.1143)
		(layer "In2.Cu")
		(net "XDP_CPU_NODE1_VISA3")
	)
	(segment
		(start 99.40036 -63.918592)
		(end 93.778832 -63.918592)
		(width 0.1143)
		(layer "In2.Cu")
		(net "XDP_CPU_NODE1_VISA3")
	)
	(segment
		(start 101.313488 -66.103754)
		(end 100.80498 -65.595246)
		(width 0.1143)
		(layer "In2.Cu")
		(net "XDP_CPU_NODE1_VISA3")
	)
	(segment
		(start 93.59646 -63.478664)
		(end 93.778832 -63.296292)
		(width 0.1143)
		(layer "In2.Cu")
		(net "XDP_CPU_NODE1_VISA3")
	)
	(segment
		(start 90.82659 -60.533026)
		(end 89.251536 -60.533026)
		(width 0.1143)
		(layer "In2.Cu")
		(net "XDP_CPU_NODE1_VISA3")
	)
	(segment
		(start 97.87382 -62.856364)
		(end 97.691448 -62.673992)
		(width 0.1143)
		(layer "In2.Cu")
		(net "XDP_CPU_NODE1_VISA3")
	)
	(segment
		(start 71.515732 -71.96709)
		(end 69.243448 -71.96709)
		(width 0.1143)
		(layer "In2.Cu")
		(net "XDP_CPU_NODE1_VISA3")
	)
	(segment
		(start 101.497892 -66.103754)
		(end 101.313488 -66.103754)
		(width 0.1143)
		(layer "In2.Cu")
		(net "XDP_CPU_NODE1_VISA3")
	)
	(segment
		(start 97.87382 -63.11392)
		(end 97.87382 -62.856364)
		(width 0.1143)
		(layer "In2.Cu")
		(net "XDP_CPU_NODE1_VISA3")
	)
	(segment
		(start 74.69505 -69.483986)
		(end 72.140318 -72.038718)
		(width 0.1143)
		(layer "In2.Cu")
		(net "XDP_CPU_NODE1_VISA3")
	)
	(segment
		(start 89.251536 -60.533026)
		(end 80.300576 -69.483986)
		(width 0.1143)
		(layer "In2.Cu")
		(net "XDP_CPU_NODE1_VISA3")
	)
	(segment
		(start 97.691448 -63.296292)
		(end 97.87382 -63.11392)
		(width 0.1143)
		(layer "In2.Cu")
		(net "XDP_CPU_NODE1_VISA3")
	)
	(segment
		(start 97.691448 -62.673992)
		(end 92.967556 -62.673992)
		(width 0.1143)
		(layer "In2.Cu")
		(net "XDP_CPU_NODE1_VISA3")
	)
	(segment
		(start 68.678044 -71.401686)
		(end 68.678044 -71.223378)
		(width 0.1143)
		(layer "In2.Cu")
		(net "XDP_CPU_NODE1_VISA3")
	)
	(segment
		(start 93.778832 -63.296292)
		(end 97.691448 -63.296292)
		(width 0.1143)
		(layer "In2.Cu")
		(net "XDP_CPU_NODE1_VISA3")
	)
	(segment
		(start 71.58736 -72.038718)
		(end 71.515732 -71.96709)
		(width 0.1143)
		(layer "In2.Cu")
		(net "XDP_CPU_NODE1_VISA3")
	)
	(segment
		(start 58.948828 -88.688672)
		(end 58.722768 -88.914732)
		(width 0.1016)
		(layer "F.Cu")
		(net "TP_CPU0_NODE1_SFRANAD")
	)
	(segment
		(start 58.948828 -88.19896)
		(end 58.948828 -88.688672)
		(width 0.1016)
		(layer "F.Cu")
		(net "TP_CPU0_NODE1_SFRANAD")
	)
	(segment
		(start 58.722768 -88.914732)
		(end 58.722768 -89.26703)
		(width 0.1016)
		(layer "F.Cu")
		(net "TP_CPU0_NODE1_SFRANAD")
	)
	(segment
		(start 58.739278 -89.28354)
		(end 58.739278 -92.003372)
		(width 0.1016)
		(layer "F.Cu")
		(net "TP_CPU0_NODE1_SFRANAD")
	)
	(segment
		(start 58.722768 -89.26703)
		(end 58.739278 -89.28354)
		(width 0.1016)
		(layer "F.Cu")
		(net "TP_CPU0_NODE1_SFRANAD")
	)
	(segment
		(start 59.105546 -88.042242)
		(end 58.948828 -88.19896)
		(width 0.1016)
		(layer "F.Cu")
		(net "TP_CPU0_NODE1_SFRANAD")
	)
	(via
		(at 58.739278 -92.003372)
		(size 0.508)
		(drill 0.254)
		(layers "F.Cu" "B.Cu")
		(net "TP_CPU0_NODE1_SFRANAD")
	)
	(segment
		(start 34.381948 -8.96874)
		(end 34.057844 -9.292844)
		(width 0.254)
		(layer "F.Cu")
		(net "PV_VDDR_NODE1_V0")
	)
	(segment
		(start 35.91052 -9.336532)
		(end 35.542728 -8.96874)
		(width 0.254)
		(layer "F.Cu")
		(net "PV_VDDR_NODE1_V0")
	)
	(segment
		(start 36.075366 -9.501378)
		(end 35.91052 -9.336532)
		(width 0.1524)
		(layer "F.Cu")
		(net "PV_VDDR_NODE1_V0")
	)
	(segment
		(start 34.800286 -8.96874)
		(end 34.381948 -8.96874)
		(width 0.254)
		(layer "F.Cu")
		(net "PV_VDDR_NODE1_V0")
	)
	(segment
		(start 36.519866 -9.501378)
		(end 36.075366 -9.501378)
		(width 0.1524)
		(layer "F.Cu")
		(net "PV_VDDR_NODE1_V0")
	)
	(segment
		(start 35.542728 -8.96874)
		(end 34.800286 -8.96874)
		(width 0.254)
		(layer "F.Cu")
		(net "PV_VDDR_NODE1_V0")
	)
	(segment
		(start 34.057844 -9.292844)
		(end 34.057844 -9.954514)
		(width 0.254)
		(layer "F.Cu")
		(net "PV_VDDR_NODE1_V0")
	)
	(via
		(at 35.542728 -8.96874)
		(size 0.508)
		(drill 0.254)
		(layers "F.Cu" "B.Cu")
		(net "PV_VDDR_NODE1_V0")
	)
	(segment
		(start 177.433224 -114.6302)
		(end 177.433224 -116.942616)
		(width 0.1016)
		(layer "F.Cu")
		(net "FM_CPLD_NODE1_P1V05_EN")
	)
	(segment
		(start 22.339808 -128.536192)
		(end 23.230332 -128.536192)
		(width 0.1016)
		(layer "F.Cu")
		(net "FM_CPLD_NODE1_P1V05_EN")
	)
	(segment
		(start 22.281134 -128.477518)
		(end 22.339808 -128.536192)
		(width 0.1016)
		(layer "F.Cu")
		(net "FM_CPLD_NODE1_P1V05_EN")
	)
	(segment
		(start 170.463972 -111.363506)
		(end 170.5483 -111.279178)
		(width 0.1016)
		(layer "F.Cu")
		(net "FM_CPLD_NODE1_P1V05_EN")
	)
	(segment
		(start 159.780478 -111.363506)
		(end 170.463972 -111.363506)
		(width 0.1016)
		(layer "F.Cu")
		(net "FM_CPLD_NODE1_P1V05_EN")
	)
	(segment
		(start 21.362162 -128.526794)
		(end 22.231858 -128.526794)
		(width 0.1016)
		(layer "F.Cu")
		(net "FM_CPLD_NODE1_P1V05_EN")
	)
	(segment
		(start 170.5483 -111.279178)
		(end 174.082202 -111.279178)
		(width 0.1016)
		(layer "F.Cu")
		(net "FM_CPLD_NODE1_P1V05_EN")
	)
	(segment
		(start 155.092146 -115.821968)
		(end 155.322016 -115.821968)
		(width 0.1016)
		(layer "F.Cu")
		(net "FM_CPLD_NODE1_P1V05_EN")
	)
	(segment
		(start 22.231858 -128.526794)
		(end 22.281134 -128.477518)
		(width 0.1016)
		(layer "F.Cu")
		(net "FM_CPLD_NODE1_P1V05_EN")
	)
	(segment
		(start 177.433224 -116.942616)
		(end 177.010314 -117.365526)
		(width 0.1016)
		(layer "F.Cu")
		(net "FM_CPLD_NODE1_P1V05_EN")
	)
	(segment
		(start 154.94254 -115.971574)
		(end 155.092146 -115.821968)
		(width 0.1016)
		(layer "F.Cu")
		(net "FM_CPLD_NODE1_P1V05_EN")
	)
	(segment
		(start 155.322016 -115.821968)
		(end 159.780478 -111.363506)
		(width 0.1016)
		(layer "F.Cu")
		(net "FM_CPLD_NODE1_P1V05_EN")
	)
	(segment
		(start 174.082202 -111.279178)
		(end 177.433224 -114.6302)
		(width 0.1016)
		(layer "F.Cu")
		(net "FM_CPLD_NODE1_P1V05_EN")
	)
	(via
		(at 154.94254 -115.971574)
		(size 0.508)
		(drill 0.254)
		(layers "F.Cu" "B.Cu")
		(net "FM_CPLD_NODE1_P1V05_EN")
	)
	(via
		(at 22.281134 -128.477518)
		(size 0.508)
		(drill 0.254)
		(layers "F.Cu" "B.Cu")
		(net "FM_CPLD_NODE1_P1V05_EN")
	)
	(segment
		(start 101.040692 -110.500668)
		(end 119.000778 -110.500668)
		(width 0.1143)
		(layer "In6.Cu")
		(net "FM_CPLD_NODE1_P1V05_EN")
	)
	(segment
		(start 138.05662 -112.958626)
		(end 139.253468 -114.155474)
		(width 0.1143)
		(layer "In6.Cu")
		(net "FM_CPLD_NODE1_P1V05_EN")
	)
	(segment
		(start 26.0096 -122.271028)
		(end 28.345384 -119.935244)
		(width 0.1143)
		(layer "In6.Cu")
		(net "FM_CPLD_NODE1_P1V05_EN")
	)
	(segment
		(start 22.281134 -128.477518)
		(end 22.676104 -128.477518)
		(width 0.1143)
		(layer "In6.Cu")
		(net "FM_CPLD_NODE1_P1V05_EN")
	)
	(segment
		(start 84.89188 -116.658898)
		(end 94.882462 -116.658898)
		(width 0.1143)
		(layer "In6.Cu")
		(net "FM_CPLD_NODE1_P1V05_EN")
	)
	(segment
		(start 37.32657 -120.354344)
		(end 37.671756 -120.009158)
		(width 0.1143)
		(layer "In6.Cu")
		(net "FM_CPLD_NODE1_P1V05_EN")
	)
	(segment
		(start 31.961328 -120.009158)
		(end 36.61664 -120.009158)
		(width 0.1143)
		(layer "In6.Cu")
		(net "FM_CPLD_NODE1_P1V05_EN")
	)
	(segment
		(start 29.178758 -119.935244)
		(end 29.666946 -119.447056)
		(width 0.1143)
		(layer "In6.Cu")
		(net "FM_CPLD_NODE1_P1V05_EN")
	)
	(segment
		(start 152.872694 -116.281454)
		(end 153.054304 -116.099844)
		(width 0.1143)
		(layer "In6.Cu")
		(net "FM_CPLD_NODE1_P1V05_EN")
	)
	(segment
		(start 82.808572 -115.60937)
		(end 83.842352 -115.60937)
		(width 0.1143)
		(layer "In6.Cu")
		(net "FM_CPLD_NODE1_P1V05_EN")
	)
	(segment
		(start 26.0096 -125.144022)
		(end 26.0096 -122.271028)
		(width 0.1143)
		(layer "In6.Cu")
		(net "FM_CPLD_NODE1_P1V05_EN")
	)
	(segment
		(start 46.224698 -118.605808)
		(end 49.262538 -115.567968)
		(width 0.1143)
		(layer "In6.Cu")
		(net "FM_CPLD_NODE1_P1V05_EN")
	)
	(segment
		(start 40.163242 -120.009158)
		(end 40.50792 -119.66448)
		(width 0.1143)
		(layer "In6.Cu")
		(net "FM_CPLD_NODE1_P1V05_EN")
	)
	(segment
		(start 37.671756 -120.009158)
		(end 40.163242 -120.009158)
		(width 0.1143)
		(layer "In6.Cu")
		(net "FM_CPLD_NODE1_P1V05_EN")
	)
	(segment
		(start 154.94254 -115.972844)
		(end 154.94254 -115.971574)
		(width 0.1143)
		(layer "In6.Cu")
		(net "FM_CPLD_NODE1_P1V05_EN")
	)
	(segment
		(start 36.61664 -120.009158)
		(end 36.61664 -120.009412)
		(width 0.1143)
		(layer "In6.Cu")
		(net "FM_CPLD_NODE1_P1V05_EN")
	)
	(segment
		(start 146.20621 -114.155474)
		(end 148.33219 -116.281454)
		(width 0.1143)
		(layer "In6.Cu")
		(net "FM_CPLD_NODE1_P1V05_EN")
	)
	(segment
		(start 36.711382 -120.102376)
		(end 36.96335 -120.354344)
		(width 0.1143)
		(layer "In6.Cu")
		(net "FM_CPLD_NODE1_P1V05_EN")
	)
	(segment
		(start 133.734556 -113.132616)
		(end 134.44728 -112.419892)
		(width 0.1143)
		(layer "In6.Cu")
		(net "FM_CPLD_NODE1_P1V05_EN")
	)
	(segment
		(start 28.345384 -119.935244)
		(end 29.178758 -119.935244)
		(width 0.1143)
		(layer "In6.Cu")
		(net "FM_CPLD_NODE1_P1V05_EN")
	)
	(segment
		(start 119.38254 -110.118906)
		(end 122.375676 -110.118906)
		(width 0.1143)
		(layer "In6.Cu")
		(net "FM_CPLD_NODE1_P1V05_EN")
	)
	(segment
		(start 134.44728 -112.419892)
		(end 134.81304 -112.419892)
		(width 0.1143)
		(layer "In6.Cu")
		(net "FM_CPLD_NODE1_P1V05_EN")
	)
	(segment
		(start 53.156866 -115.007644)
		(end 82.206846 -115.007644)
		(width 0.1143)
		(layer "In6.Cu")
		(net "FM_CPLD_NODE1_P1V05_EN")
	)
	(segment
		(start 154.81554 -116.099844)
		(end 154.94254 -115.972844)
		(width 0.1143)
		(layer "In6.Cu")
		(net "FM_CPLD_NODE1_P1V05_EN")
	)
	(segment
		(start 40.50792 -119.66448)
		(end 43.934888 -119.66448)
		(width 0.1143)
		(layer "In6.Cu")
		(net "FM_CPLD_NODE1_P1V05_EN")
	)
	(segment
		(start 136.625584 -112.570006)
		(end 137.014204 -112.958626)
		(width 0.1143)
		(layer "In6.Cu")
		(net "FM_CPLD_NODE1_P1V05_EN")
	)
	(segment
		(start 36.61664 -120.009412)
		(end 36.709604 -120.102376)
		(width 0.1143)
		(layer "In6.Cu")
		(net "FM_CPLD_NODE1_P1V05_EN")
	)
	(segment
		(start 43.934888 -119.66448)
		(end 44.99356 -118.605808)
		(width 0.1143)
		(layer "In6.Cu")
		(net "FM_CPLD_NODE1_P1V05_EN")
	)
	(segment
		(start 36.96335 -120.354344)
		(end 37.32657 -120.354344)
		(width 0.1143)
		(layer "In6.Cu")
		(net "FM_CPLD_NODE1_P1V05_EN")
	)
	(segment
		(start 82.206846 -115.007644)
		(end 82.808572 -115.60937)
		(width 0.1143)
		(layer "In6.Cu")
		(net "FM_CPLD_NODE1_P1V05_EN")
	)
	(segment
		(start 129.515108 -112.561116)
		(end 130.086608 -113.132616)
		(width 0.1143)
		(layer "In6.Cu")
		(net "FM_CPLD_NODE1_P1V05_EN")
	)
	(segment
		(start 31.399226 -119.447056)
		(end 31.961328 -120.009158)
		(width 0.1143)
		(layer "In6.Cu")
		(net "FM_CPLD_NODE1_P1V05_EN")
	)
	(segment
		(start 51.693572 -113.54435)
		(end 53.156866 -115.007644)
		(width 0.1143)
		(layer "In6.Cu")
		(net "FM_CPLD_NODE1_P1V05_EN")
	)
	(segment
		(start 94.882462 -116.658898)
		(end 101.040692 -110.500668)
		(width 0.1143)
		(layer "In6.Cu")
		(net "FM_CPLD_NODE1_P1V05_EN")
	)
	(segment
		(start 130.086608 -113.132616)
		(end 133.734556 -113.132616)
		(width 0.1143)
		(layer "In6.Cu")
		(net "FM_CPLD_NODE1_P1V05_EN")
	)
	(segment
		(start 139.253468 -114.155474)
		(end 146.20621 -114.155474)
		(width 0.1143)
		(layer "In6.Cu")
		(net "FM_CPLD_NODE1_P1V05_EN")
	)
	(segment
		(start 119.000778 -110.500668)
		(end 119.38254 -110.118906)
		(width 0.1143)
		(layer "In6.Cu")
		(net "FM_CPLD_NODE1_P1V05_EN")
	)
	(segment
		(start 148.33219 -116.281454)
		(end 152.872694 -116.281454)
		(width 0.1143)
		(layer "In6.Cu")
		(net "FM_CPLD_NODE1_P1V05_EN")
	)
	(segment
		(start 134.81304 -112.419892)
		(end 134.963154 -112.570006)
		(width 0.1143)
		(layer "In6.Cu")
		(net "FM_CPLD_NODE1_P1V05_EN")
	)
	(segment
		(start 29.666946 -119.447056)
		(end 31.399226 -119.447056)
		(width 0.1143)
		(layer "In6.Cu")
		(net "FM_CPLD_NODE1_P1V05_EN")
	)
	(segment
		(start 137.014204 -112.958626)
		(end 138.05662 -112.958626)
		(width 0.1143)
		(layer "In6.Cu")
		(net "FM_CPLD_NODE1_P1V05_EN")
	)
	(segment
		(start 83.842352 -115.60937)
		(end 84.89188 -116.658898)
		(width 0.1143)
		(layer "In6.Cu")
		(net "FM_CPLD_NODE1_P1V05_EN")
	)
	(segment
		(start 22.676104 -128.477518)
		(end 26.0096 -125.144022)
		(width 0.1143)
		(layer "In6.Cu")
		(net "FM_CPLD_NODE1_P1V05_EN")
	)
	(segment
		(start 153.054304 -116.099844)
		(end 154.81554 -116.099844)
		(width 0.1143)
		(layer "In6.Cu")
		(net "FM_CPLD_NODE1_P1V05_EN")
	)
	(segment
		(start 134.963154 -112.570006)
		(end 136.625584 -112.570006)
		(width 0.1143)
		(layer "In6.Cu")
		(net "FM_CPLD_NODE1_P1V05_EN")
	)
	(segment
		(start 122.375676 -110.118906)
		(end 124.817886 -112.561116)
		(width 0.1143)
		(layer "In6.Cu")
		(net "FM_CPLD_NODE1_P1V05_EN")
	)
	(segment
		(start 49.262538 -114.910108)
		(end 50.628296 -113.54435)
		(width 0.1143)
		(layer "In6.Cu")
		(net "FM_CPLD_NODE1_P1V05_EN")
	)
	(segment
		(start 36.709604 -120.102376)
		(end 36.711382 -120.102376)
		(width 0.1143)
		(layer "In6.Cu")
		(net "FM_CPLD_NODE1_P1V05_EN")
	)
	(segment
		(start 49.262538 -115.567968)
		(end 49.262538 -114.910108)
		(width 0.1143)
		(layer "In6.Cu")
		(net "FM_CPLD_NODE1_P1V05_EN")
	)
	(segment
		(start 124.817886 -112.561116)
		(end 129.515108 -112.561116)
		(width 0.1143)
		(layer "In6.Cu")
		(net "FM_CPLD_NODE1_P1V05_EN")
	)
	(segment
		(start 44.99356 -118.605808)
		(end 46.224698 -118.605808)
		(width 0.1143)
		(layer "In6.Cu")
		(net "FM_CPLD_NODE1_P1V05_EN")
	)
	(segment
		(start 50.628296 -113.54435)
		(end 51.693572 -113.54435)
		(width 0.1143)
		(layer "In6.Cu")
		(net "FM_CPLD_NODE1_P1V05_EN")
	)
	(segment
		(start 160.25114 -100.446586)
		(end 157.890718 -99.480878)
		(width 0.127)
		(layer "F.Cu")
		(net "P2E_CPU_USB_NODE1_TX_DP")
	)
	(segment
		(start 162.714432 -100.48875)
		(end 162.268916 -100.48875)
		(width 0.127)
		(layer "F.Cu")
		(net "P2E_CPU_USB_NODE1_TX_DP")
	)
	(segment
		(start 133.47192 -130.087116)
		(end 133.82498 -129.734056)
		(width 0.127)
		(layer "F.Cu")
		(net "P2E_CPU_USB_NODE1_TX_DP")
	)
	(segment
		(start 133.470396 -130.087116)
		(end 133.47192 -130.087116)
		(width 0.127)
		(layer "F.Cu")
		(net "P2E_CPU_USB_NODE1_TX_DP")
	)
	(segment
		(start 163.340034 -100.53574)
		(end 162.761422 -100.53574)
		(width 0.127)
		(layer "F.Cu")
		(net "P2E_CPU_USB_NODE1_TX_DP")
	)
	(segment
		(start 162.268916 -100.48875)
		(end 162.226752 -100.446586)
		(width 0.127)
		(layer "F.Cu")
		(net "P2E_CPU_USB_NODE1_TX_DP")
	)
	(segment
		(start 162.226752 -100.446586)
		(end 160.25114 -100.446586)
		(width 0.127)
		(layer "F.Cu")
		(net "P2E_CPU_USB_NODE1_TX_DP")
	)
	(segment
		(start 133.82498 -129.26187)
		(end 134.32536 -128.76149)
		(width 0.127)
		(layer "F.Cu")
		(net "P2E_CPU_USB_NODE1_TX_DP")
	)
	(segment
		(start 138.0998 -130.008376)
		(end 138.26998 -129.838196)
		(width 0.127)
		(layer "F.Cu")
		(net "P2E_CPU_USB_NODE1_TX_DP")
	)
	(segment
		(start 157.890718 -99.480878)
		(end 155.188412 -99.480878)
		(width 0.127)
		(layer "F.Cu")
		(net "P2E_CPU_USB_NODE1_TX_DP")
	)
	(segment
		(start 137.547096 -130.008376)
		(end 138.0998 -130.008376)
		(width 0.127)
		(layer "F.Cu")
		(net "P2E_CPU_USB_NODE1_TX_DP")
	)
	(segment
		(start 133.82498 -129.734056)
		(end 133.82498 -129.26187)
		(width 0.127)
		(layer "F.Cu")
		(net "P2E_CPU_USB_NODE1_TX_DP")
	)
	(segment
		(start 134.32536 -128.76149)
		(end 136.30021 -128.76149)
		(width 0.127)
		(layer "F.Cu")
		(net "P2E_CPU_USB_NODE1_TX_DP")
	)
	(segment
		(start 155.188412 -99.480878)
		(end 154.705812 -99.963478)
		(width 0.127)
		(layer "F.Cu")
		(net "P2E_CPU_USB_NODE1_TX_DP")
	)
	(segment
		(start 136.30021 -128.76149)
		(end 137.547096 -130.008376)
		(width 0.127)
		(layer "F.Cu")
		(net "P2E_CPU_USB_NODE1_TX_DP")
	)
	(segment
		(start 162.761422 -100.53574)
		(end 162.714432 -100.48875)
		(width 0.127)
		(layer "F.Cu")
		(net "P2E_CPU_USB_NODE1_TX_DP")
	)
	(segment
		(start 138.26998 -129.838196)
		(end 138.26998 -129.607818)
		(width 0.127)
		(layer "F.Cu")
		(net "P2E_CPU_USB_NODE1_TX_DP")
	)
	(via
		(at 154.705812 -99.963478)
		(size 0.508)
		(drill 0.254)
		(layers "F.Cu" "B.Cu")
		(net "P2E_CPU_USB_NODE1_TX_DP")
	)
	(via
		(at 138.26998 -129.607818)
		(size 0.508)
		(drill 0.254)
		(layers "F.Cu" "B.Cu")
		(net "P2E_CPU_USB_NODE1_TX_DP")
	)
	(segment
		(start 142.276322 -126.939802)
		(end 142.006574 -127.20955)
		(width 0.127)
		(layer "B.Cu")
		(net "P2E_CPU_USB_NODE1_TX_DP")
	)
	(segment
		(start 141.737334 -127.659638)
		(end 141.647418 -127.659638)
		(width 0.127)
		(layer "B.Cu")
		(net "P2E_CPU_USB_NODE1_TX_DP")
	)
	(segment
		(start 140.568426 -128.828546)
		(end 140.298678 -129.098294)
		(width 0.127)
		(layer "B.Cu")
		(net "P2E_CPU_USB_NODE1_TX_DP")
	)
	(segment
		(start 138.26998 -129.907538)
		(end 138.26998 -129.607818)
		(width 0.127)
		(layer "B.Cu")
		(net "P2E_CPU_USB_NODE1_TX_DP")
	)
	(segment
		(start 141.556994 -127.65913)
		(end 141.287246 -127.928878)
		(width 0.127)
		(layer "B.Cu")
		(net "P2E_CPU_USB_NODE1_TX_DP")
	)
	(segment
		(start 152.50414 -115.64366)
		(end 152.50414 -116.099082)
		(width 0.127)
		(layer "B.Cu")
		(net "P2E_CPU_USB_NODE1_TX_DP")
	)
	(segment
		(start 154.906218 -104.38638)
		(end 154.726132 -104.38638)
		(width 0.127)
		(layer "B.Cu")
		(net "P2E_CPU_USB_NODE1_TX_DP")
	)
	(segment
		(start 141.287754 -128.109218)
		(end 141.018006 -128.378966)
		(width 0.127)
		(layer "B.Cu")
		(net "P2E_CPU_USB_NODE1_TX_DP")
	)
	(segment
		(start 138.45286 -130.090418)
		(end 138.26998 -129.907538)
		(width 0.127)
		(layer "B.Cu")
		(net "P2E_CPU_USB_NODE1_TX_DP")
	)
	(segment
		(start 152.37206 -115.13058)
		(end 152.37206 -115.51158)
		(width 0.127)
		(layer "B.Cu")
		(net "P2E_CPU_USB_NODE1_TX_DP")
	)
	(segment
		(start 141.287246 -127.928878)
		(end 141.287246 -128.018794)
		(width 0.127)
		(layer "B.Cu")
		(net "P2E_CPU_USB_NODE1_TX_DP")
	)
	(segment
		(start 152.50414 -113.59134)
		(end 152.50414 -113.97234)
		(width 0.127)
		(layer "B.Cu")
		(net "P2E_CPU_USB_NODE1_TX_DP")
	)
	(segment
		(start 156.78404 -102.508558)
		(end 155.625546 -103.667052)
		(width 0.127)
		(layer "B.Cu")
		(net "P2E_CPU_USB_NODE1_TX_DP")
	)
	(segment
		(start 156.007054 -99.480878)
		(end 156.78404 -100.257864)
		(width 0.127)
		(layer "B.Cu")
		(net "P2E_CPU_USB_NODE1_TX_DP")
	)
	(segment
		(start 152.50414 -111.79048)
		(end 152.50414 -112.94618)
		(width 0.127)
		(layer "B.Cu")
		(net "P2E_CPU_USB_NODE1_TX_DP")
	)
	(segment
		(start 140.92809 -128.378966)
		(end 140.927582 -128.378458)
		(width 0.127)
		(layer "B.Cu")
		(net "P2E_CPU_USB_NODE1_TX_DP")
	)
	(segment
		(start 140.567918 -128.738122)
		(end 140.568426 -128.73863)
		(width 0.127)
		(layer "B.Cu")
		(net "P2E_CPU_USB_NODE1_TX_DP")
	)
	(segment
		(start 152.528016 -111.066326)
		(end 152.50414 -111.79048)
		(width 0.127)
		(layer "B.Cu")
		(net "P2E_CPU_USB_NODE1_TX_DP")
	)
	(segment
		(start 145.889726 -126.487682)
		(end 142.90929 -126.487682)
		(width 0.127)
		(layer "B.Cu")
		(net "P2E_CPU_USB_NODE1_TX_DP")
	)
	(segment
		(start 140.567918 -128.648206)
		(end 140.567918 -128.738122)
		(width 0.127)
		(layer "B.Cu")
		(net "P2E_CPU_USB_NODE1_TX_DP")
	)
	(segment
		(start 154.456638 -104.746044)
		(end 154.456638 -104.83596)
		(width 0.127)
		(layer "B.Cu")
		(net "P2E_CPU_USB_NODE1_TX_DP")
	)
	(segment
		(start 139.84859 -129.367534)
		(end 139.84859 -129.45745)
		(width 0.127)
		(layer "B.Cu")
		(net "P2E_CPU_USB_NODE1_TX_DP")
	)
	(segment
		(start 152.37206 -114.48542)
		(end 152.50414 -114.6175)
		(width 0.127)
		(layer "B.Cu")
		(net "P2E_CPU_USB_NODE1_TX_DP")
	)
	(segment
		(start 155.625546 -103.667052)
		(end 155.44546 -103.667052)
		(width 0.127)
		(layer "B.Cu")
		(net "P2E_CPU_USB_NODE1_TX_DP")
	)
	(segment
		(start 142.456662 -126.94031)
		(end 142.366746 -126.94031)
		(width 0.127)
		(layer "B.Cu")
		(net "P2E_CPU_USB_NODE1_TX_DP")
	)
	(segment
		(start 141.64691 -127.65913)
		(end 141.556994 -127.65913)
		(width 0.127)
		(layer "B.Cu")
		(net "P2E_CPU_USB_NODE1_TX_DP")
	)
	(segment
		(start 142.007082 -127.299974)
		(end 142.007082 -127.38989)
		(width 0.127)
		(layer "B.Cu")
		(net "P2E_CPU_USB_NODE1_TX_DP")
	)
	(segment
		(start 154.726132 -104.38638)
		(end 154.456384 -104.656128)
		(width 0.127)
		(layer "B.Cu")
		(net "P2E_CPU_USB_NODE1_TX_DP")
	)
	(segment
		(start 141.647418 -127.659638)
		(end 141.64691 -127.65913)
		(width 0.127)
		(layer "B.Cu")
		(net "P2E_CPU_USB_NODE1_TX_DP")
	)
	(segment
		(start 139.849098 -129.547874)
		(end 139.306554 -130.090418)
		(width 0.127)
		(layer "B.Cu")
		(net "P2E_CPU_USB_NODE1_TX_DP")
	)
	(segment
		(start 140.208254 -129.097786)
		(end 140.118338 -129.097786)
		(width 0.127)
		(layer "B.Cu")
		(net "P2E_CPU_USB_NODE1_TX_DP")
	)
	(segment
		(start 152.50414 -114.6175)
		(end 152.50414 -114.9985)
		(width 0.127)
		(layer "B.Cu")
		(net "P2E_CPU_USB_NODE1_TX_DP")
	)
	(segment
		(start 139.84859 -129.45745)
		(end 139.849098 -129.457958)
		(width 0.127)
		(layer "B.Cu")
		(net "P2E_CPU_USB_NODE1_TX_DP")
	)
	(segment
		(start 154.456384 -104.656128)
		(end 154.456638 -104.746044)
		(width 0.127)
		(layer "B.Cu")
		(net "P2E_CPU_USB_NODE1_TX_DP")
	)
	(segment
		(start 140.208762 -129.098294)
		(end 140.208254 -129.097786)
		(width 0.127)
		(layer "B.Cu")
		(net "P2E_CPU_USB_NODE1_TX_DP")
	)
	(segment
		(start 155.175966 -104.026716)
		(end 155.175966 -104.116632)
		(width 0.127)
		(layer "B.Cu")
		(net "P2E_CPU_USB_NODE1_TX_DP")
	)
	(segment
		(start 154.456638 -104.83596)
		(end 153.793698 -105.4989)
		(width 0.127)
		(layer "B.Cu")
		(net "P2E_CPU_USB_NODE1_TX_DP")
	)
	(segment
		(start 152.37206 -113.45926)
		(end 152.50414 -113.59134)
		(width 0.127)
		(layer "B.Cu")
		(net "P2E_CPU_USB_NODE1_TX_DP")
	)
	(segment
		(start 139.306554 -130.090418)
		(end 138.45286 -130.090418)
		(width 0.127)
		(layer "B.Cu")
		(net "P2E_CPU_USB_NODE1_TX_DP")
	)
	(segment
		(start 152.50414 -113.97234)
		(end 152.37206 -114.10442)
		(width 0.127)
		(layer "B.Cu")
		(net "P2E_CPU_USB_NODE1_TX_DP")
	)
	(segment
		(start 140.118338 -129.097786)
		(end 139.84859 -129.367534)
		(width 0.127)
		(layer "B.Cu")
		(net "P2E_CPU_USB_NODE1_TX_DP")
	)
	(segment
		(start 141.018006 -128.378966)
		(end 140.92809 -128.378966)
		(width 0.127)
		(layer "B.Cu")
		(net "P2E_CPU_USB_NODE1_TX_DP")
	)
	(segment
		(start 142.007082 -127.38989)
		(end 141.737334 -127.659638)
		(width 0.127)
		(layer "B.Cu")
		(net "P2E_CPU_USB_NODE1_TX_DP")
	)
	(segment
		(start 149.943058 -122.43435)
		(end 145.889726 -126.487682)
		(width 0.127)
		(layer "B.Cu")
		(net "P2E_CPU_USB_NODE1_TX_DP")
	)
	(segment
		(start 155.44546 -103.667052)
		(end 155.175712 -103.9368)
		(width 0.127)
		(layer "B.Cu")
		(net "P2E_CPU_USB_NODE1_TX_DP")
	)
	(segment
		(start 140.927582 -128.378458)
		(end 140.837666 -128.378458)
		(width 0.127)
		(layer "B.Cu")
		(net "P2E_CPU_USB_NODE1_TX_DP")
	)
	(segment
		(start 142.006574 -127.20955)
		(end 142.006574 -127.299466)
		(width 0.127)
		(layer "B.Cu")
		(net "P2E_CPU_USB_NODE1_TX_DP")
	)
	(segment
		(start 155.188412 -99.480878)
		(end 156.007054 -99.480878)
		(width 0.127)
		(layer "B.Cu")
		(net "P2E_CPU_USB_NODE1_TX_DP")
	)
	(segment
		(start 152.50414 -114.9985)
		(end 152.37206 -115.13058)
		(width 0.127)
		(layer "B.Cu")
		(net "P2E_CPU_USB_NODE1_TX_DP")
	)
	(segment
		(start 155.175966 -104.116632)
		(end 154.906218 -104.38638)
		(width 0.127)
		(layer "B.Cu")
		(net "P2E_CPU_USB_NODE1_TX_DP")
	)
	(segment
		(start 156.78404 -100.257864)
		(end 156.78404 -102.508558)
		(width 0.127)
		(layer "B.Cu")
		(net "P2E_CPU_USB_NODE1_TX_DP")
	)
	(segment
		(start 152.50414 -116.099082)
		(end 149.943058 -122.43435)
		(width 0.127)
		(layer "B.Cu")
		(net "P2E_CPU_USB_NODE1_TX_DP")
	)
	(segment
		(start 152.50414 -112.94618)
		(end 152.37206 -113.07826)
		(width 0.127)
		(layer "B.Cu")
		(net "P2E_CPU_USB_NODE1_TX_DP")
	)
	(segment
		(start 142.366746 -126.94031)
		(end 142.366238 -126.939802)
		(width 0.127)
		(layer "B.Cu")
		(net "P2E_CPU_USB_NODE1_TX_DP")
	)
	(segment
		(start 140.298678 -129.098294)
		(end 140.208762 -129.098294)
		(width 0.127)
		(layer "B.Cu")
		(net "P2E_CPU_USB_NODE1_TX_DP")
	)
	(segment
		(start 141.287246 -128.018794)
		(end 141.287754 -128.019302)
		(width 0.127)
		(layer "B.Cu")
		(net "P2E_CPU_USB_NODE1_TX_DP")
	)
	(segment
		(start 140.837666 -128.378458)
		(end 140.567918 -128.648206)
		(width 0.127)
		(layer "B.Cu")
		(net "P2E_CPU_USB_NODE1_TX_DP")
	)
	(segment
		(start 154.705812 -99.963478)
		(end 155.188412 -99.480878)
		(width 0.127)
		(layer "B.Cu")
		(net "P2E_CPU_USB_NODE1_TX_DP")
	)
	(segment
		(start 142.006574 -127.299466)
		(end 142.007082 -127.299974)
		(width 0.127)
		(layer "B.Cu")
		(net "P2E_CPU_USB_NODE1_TX_DP")
	)
	(segment
		(start 141.287754 -128.019302)
		(end 141.287754 -128.109218)
		(width 0.127)
		(layer "B.Cu")
		(net "P2E_CPU_USB_NODE1_TX_DP")
	)
	(segment
		(start 140.568426 -128.73863)
		(end 140.568426 -128.828546)
		(width 0.127)
		(layer "B.Cu")
		(net "P2E_CPU_USB_NODE1_TX_DP")
	)
	(segment
		(start 142.90929 -126.487682)
		(end 142.456662 -126.94031)
		(width 0.127)
		(layer "B.Cu")
		(net "P2E_CPU_USB_NODE1_TX_DP")
	)
	(segment
		(start 152.37206 -115.51158)
		(end 152.50414 -115.64366)
		(width 0.127)
		(layer "B.Cu")
		(net "P2E_CPU_USB_NODE1_TX_DP")
	)
	(segment
		(start 152.37206 -113.07826)
		(end 152.37206 -113.45926)
		(width 0.127)
		(layer "B.Cu")
		(net "P2E_CPU_USB_NODE1_TX_DP")
	)
	(segment
		(start 152.37206 -114.10442)
		(end 152.37206 -114.48542)
		(width 0.127)
		(layer "B.Cu")
		(net "P2E_CPU_USB_NODE1_TX_DP")
	)
	(segment
		(start 153.793698 -105.4989)
		(end 152.528016 -111.066326)
		(width 0.127)
		(layer "B.Cu")
		(net "P2E_CPU_USB_NODE1_TX_DP")
	)
	(segment
		(start 142.366238 -126.939802)
		(end 142.276322 -126.939802)
		(width 0.127)
		(layer "B.Cu")
		(net "P2E_CPU_USB_NODE1_TX_DP")
	)
	(segment
		(start 155.175712 -103.9368)
		(end 155.175966 -104.026716)
		(width 0.127)
		(layer "B.Cu")
		(net "P2E_CPU_USB_NODE1_TX_DP")
	)
	(segment
		(start 139.849098 -129.457958)
		(end 139.849098 -129.547874)
		(width 0.127)
		(layer "B.Cu")
		(net "P2E_CPU_USB_NODE1_TX_DP")
	)
	(segment
		(start 58.942478 -88.98255)
		(end 58.942478 -90.298016)
		(width 0.1016)
		(layer "F.Cu")
		(net "TP_CPU_NODE1_EXTBGREF")
	)
	(segment
		(start 59.115452 -86.87308)
		(end 59.115452 -87.585042)
		(width 0.1016)
		(layer "F.Cu")
		(net "TP_CPU_NODE1_EXTBGREF")
	)
	(segment
		(start 59.115452 -87.585042)
		(end 59.435746 -87.905336)
		(width 0.1016)
		(layer "F.Cu")
		(net "TP_CPU_NODE1_EXTBGREF")
	)
	(segment
		(start 59.435746 -88.179148)
		(end 59.152028 -88.462866)
		(width 0.1016)
		(layer "F.Cu")
		(net "TP_CPU_NODE1_EXTBGREF")
	)
	(segment
		(start 58.942478 -90.298016)
		(end 59.34329 -90.698828)
		(width 0.1016)
		(layer "F.Cu")
		(net "TP_CPU_NODE1_EXTBGREF")
	)
	(segment
		(start 59.152028 -88.462866)
		(end 59.152028 -88.773)
		(width 0.1016)
		(layer "F.Cu")
		(net "TP_CPU_NODE1_EXTBGREF")
	)
	(segment
		(start 59.152028 -88.773)
		(end 58.942478 -88.98255)
		(width 0.1016)
		(layer "F.Cu")
		(net "TP_CPU_NODE1_EXTBGREF")
	)
	(segment
		(start 59.435746 -87.905336)
		(end 59.435746 -88.179148)
		(width 0.1016)
		(layer "F.Cu")
		(net "TP_CPU_NODE1_EXTBGREF")
	)
	(via
		(at 59.34329 -90.698828)
		(size 0.508)
		(drill 0.254)
		(layers "F.Cu" "B.Cu")
		(net "TP_CPU_NODE1_EXTBGREF")
	)
	(segment
		(start 104.73182 -72.406256)
		(end 103.233474 -72.406256)
		(width 0.1016)
		(layer "F.Cu")
		(net "XDP_CPU_NODE1_VISA4")
	)
	(segment
		(start 101.505512 -69.908674)
		(end 101.500432 -69.903594)
		(width 0.1016)
		(layer "F.Cu")
		(net "XDP_CPU_NODE1_VISA4")
	)
	(segment
		(start 68.299076 -72.296782)
		(end 68.692776 -72.690482)
		(width 0.1016)
		(layer "F.Cu")
		(net "XDP_CPU_NODE1_VISA4")
	)
	(segment
		(start 103.233474 -72.406256)
		(end 101.505512 -70.678294)
		(width 0.1016)
		(layer "F.Cu")
		(net "XDP_CPU_NODE1_VISA4")
	)
	(segment
		(start 68.297044 -72.296782)
		(end 68.299076 -72.296782)
		(width 0.1016)
		(layer "F.Cu")
		(net "XDP_CPU_NODE1_VISA4")
	)
	(segment
		(start 101.505512 -70.678294)
		(end 101.505512 -69.908674)
		(width 0.1016)
		(layer "F.Cu")
		(net "XDP_CPU_NODE1_VISA4")
	)
	(via
		(at 68.692776 -72.690482)
		(size 0.508)
		(drill 0.254)
		(layers "F.Cu" "B.Cu")
		(net "XDP_CPU_NODE1_VISA4")
	)
	(via
		(at 101.500432 -69.903594)
		(size 0.508)
		(drill 0.254)
		(layers "F.Cu" "B.Cu")
		(net "XDP_CPU_NODE1_VISA4")
	)
	(segment
		(start 99.00412 -68.856606)
		(end 99.00412 -69.362828)
		(width 0.1143)
		(layer "In2.Cu")
		(net "XDP_CPU_NODE1_VISA4")
	)
	(segment
		(start 90.435684 -68.538598)
		(end 90.435684 -68.796154)
		(width 0.1143)
		(layer "In2.Cu")
		(net "XDP_CPU_NODE1_VISA4")
	)
	(segment
		(start 96.636332 -70.668896)
		(end 96.45396 -70.486524)
		(width 0.1143)
		(layer "In2.Cu")
		(net "XDP_CPU_NODE1_VISA4")
	)
	(segment
		(start 71.073772 -74.576432)
		(end 69.637148 -73.139808)
		(width 0.1143)
		(layer "In2.Cu")
		(net "XDP_CPU_NODE1_VISA4")
	)
	(segment
		(start 90.618056 -68.978526)
		(end 90.924888 -68.978526)
		(width 0.1143)
		(layer "In2.Cu")
		(net "XDP_CPU_NODE1_VISA4")
	)
	(segment
		(start 101.193092 -70.210934)
		(end 100.823014 -70.210934)
		(width 0.1143)
		(layer "In2.Cu")
		(net "XDP_CPU_NODE1_VISA4")
	)
	(segment
		(start 87.003382 -68.899024)
		(end 87.003382 -68.538598)
		(width 0.1143)
		(layer "In2.Cu")
		(net "XDP_CPU_NODE1_VISA4")
	)
	(segment
		(start 79.52867 -72.279002)
		(end 78.742794 -72.279002)
		(width 0.1143)
		(layer "In2.Cu")
		(net "XDP_CPU_NODE1_VISA4")
	)
	(segment
		(start 97.07626 -70.486524)
		(end 96.893888 -70.668896)
		(width 0.1143)
		(layer "In2.Cu")
		(net "XDP_CPU_NODE1_VISA4")
	)
	(segment
		(start 85.57641 -68.356226)
		(end 85.241638 -68.356226)
		(width 0.1143)
		(layer "In2.Cu")
		(net "XDP_CPU_NODE1_VISA4")
	)
	(segment
		(start 87.185754 -69.081396)
		(end 87.003382 -68.899024)
		(width 0.1143)
		(layer "In2.Cu")
		(net "XDP_CPU_NODE1_VISA4")
	)
	(segment
		(start 86.563454 -68.356226)
		(end 86.381082 -68.538598)
		(width 0.1143)
		(layer "In2.Cu")
		(net "XDP_CPU_NODE1_VISA4")
	)
	(segment
		(start 77.729588 -73.292208)
		(end 74.384408 -73.292208)
		(width 0.1143)
		(layer "In2.Cu")
		(net "XDP_CPU_NODE1_VISA4")
	)
	(segment
		(start 96.45396 -70.486524)
		(end 96.45396 -69.782436)
		(width 0.1143)
		(layer "In2.Cu")
		(net "XDP_CPU_NODE1_VISA4")
	)
	(segment
		(start 69.18833 -73.139808)
		(end 68.739004 -72.690482)
		(width 0.1143)
		(layer "In2.Cu")
		(net "XDP_CPU_NODE1_VISA4")
	)
	(segment
		(start 91.10726 -69.160898)
		(end 91.10726 -69.418454)
		(width 0.1143)
		(layer "In2.Cu")
		(net "XDP_CPU_NODE1_VISA4")
	)
	(segment
		(start 89.631012 -68.356226)
		(end 89.052654 -68.356226)
		(width 0.1143)
		(layer "In2.Cu")
		(net "XDP_CPU_NODE1_VISA4")
	)
	(segment
		(start 95.83166 -69.782436)
		(end 95.83166 -70.508876)
		(width 0.1143)
		(layer "In2.Cu")
		(net "XDP_CPU_NODE1_VISA4")
	)
	(segment
		(start 91.528138 -68.356226)
		(end 90.618056 -68.356226)
		(width 0.1143)
		(layer "In2.Cu")
		(net "XDP_CPU_NODE1_VISA4")
	)
	(segment
		(start 88.430354 -69.081396)
		(end 88.247982 -68.899024)
		(width 0.1143)
		(layer "In2.Cu")
		(net "XDP_CPU_NODE1_VISA4")
	)
	(segment
		(start 81.32064 -72.277224)
		(end 79.530448 -72.277224)
		(width 0.1143)
		(layer "In2.Cu")
		(net "XDP_CPU_NODE1_VISA4")
	)
	(segment
		(start 96.893888 -70.668896)
		(end 96.636332 -70.668896)
		(width 0.1143)
		(layer "In2.Cu")
		(net "XDP_CPU_NODE1_VISA4")
	)
	(segment
		(start 96.45396 -69.782436)
		(end 96.271588 -69.600064)
		(width 0.1143)
		(layer "In2.Cu")
		(net "XDP_CPU_NODE1_VISA4")
	)
	(segment
		(start 86.19871 -69.081396)
		(end 85.941154 -69.081396)
		(width 0.1143)
		(layer "In2.Cu")
		(net "XDP_CPU_NODE1_VISA4")
	)
	(segment
		(start 97.69856 -69.782436)
		(end 97.516188 -69.600064)
		(width 0.1143)
		(layer "In2.Cu")
		(net "XDP_CPU_NODE1_VISA4")
	)
	(segment
		(start 88.870282 -68.899024)
		(end 88.68791 -69.081396)
		(width 0.1143)
		(layer "In2.Cu")
		(net "XDP_CPU_NODE1_VISA4")
	)
	(segment
		(start 88.247982 -68.899024)
		(end 88.247982 -68.538598)
		(width 0.1143)
		(layer "In2.Cu")
		(net "XDP_CPU_NODE1_VISA4")
	)
	(segment
		(start 98.32086 -70.337426)
		(end 98.138488 -70.519798)
		(width 0.1143)
		(layer "In2.Cu")
		(net "XDP_CPU_NODE1_VISA4")
	)
	(segment
		(start 98.766884 -69.600064)
		(end 98.503232 -69.600064)
		(width 0.1143)
		(layer "In2.Cu")
		(net "XDP_CPU_NODE1_VISA4")
	)
	(segment
		(start 85.758782 -68.538598)
		(end 85.57641 -68.356226)
		(width 0.1143)
		(layer "In2.Cu")
		(net "XDP_CPU_NODE1_VISA4")
	)
	(segment
		(start 88.247982 -68.538598)
		(end 88.06561 -68.356226)
		(width 0.1143)
		(layer "In2.Cu")
		(net "XDP_CPU_NODE1_VISA4")
	)
	(segment
		(start 95.026988 -69.600064)
		(end 92.771976 -69.600064)
		(width 0.1143)
		(layer "In2.Cu")
		(net "XDP_CPU_NODE1_VISA4")
	)
	(segment
		(start 97.258632 -69.600064)
		(end 97.07626 -69.782436)
		(width 0.1143)
		(layer "In2.Cu")
		(net "XDP_CPU_NODE1_VISA4")
	)
	(segment
		(start 69.637148 -73.139808)
		(end 69.18833 -73.139808)
		(width 0.1143)
		(layer "In2.Cu")
		(net "XDP_CPU_NODE1_VISA4")
	)
	(segment
		(start 98.32086 -69.782436)
		(end 98.32086 -70.337426)
		(width 0.1143)
		(layer "In2.Cu")
		(net "XDP_CPU_NODE1_VISA4")
	)
	(segment
		(start 88.870282 -68.538598)
		(end 88.870282 -68.899024)
		(width 0.1143)
		(layer "In2.Cu")
		(net "XDP_CPU_NODE1_VISA4")
	)
	(segment
		(start 86.381082 -68.899024)
		(end 86.19871 -69.081396)
		(width 0.1143)
		(layer "In2.Cu")
		(net "XDP_CPU_NODE1_VISA4")
	)
	(segment
		(start 74.384408 -73.292208)
		(end 73.100184 -74.576432)
		(width 0.1143)
		(layer "In2.Cu")
		(net "XDP_CPU_NODE1_VISA4")
	)
	(segment
		(start 89.813384 -68.538598)
		(end 89.631012 -68.356226)
		(width 0.1143)
		(layer "In2.Cu")
		(net "XDP_CPU_NODE1_VISA4")
	)
	(segment
		(start 87.003382 -68.538598)
		(end 86.82101 -68.356226)
		(width 0.1143)
		(layer "In2.Cu")
		(net "XDP_CPU_NODE1_VISA4")
	)
	(segment
		(start 90.618056 -68.356226)
		(end 90.435684 -68.538598)
		(width 0.1143)
		(layer "In2.Cu")
		(net "XDP_CPU_NODE1_VISA4")
	)
	(segment
		(start 90.924888 -69.600826)
		(end 89.995756 -69.600826)
		(width 0.1143)
		(layer "In2.Cu")
		(net "XDP_CPU_NODE1_VISA4")
	)
	(segment
		(start 89.052654 -68.356226)
		(end 88.870282 -68.538598)
		(width 0.1143)
		(layer "In2.Cu")
		(net "XDP_CPU_NODE1_VISA4")
	)
	(segment
		(start 87.625682 -68.899024)
		(end 87.44331 -69.081396)
		(width 0.1143)
		(layer "In2.Cu")
		(net "XDP_CPU_NODE1_VISA4")
	)
	(segment
		(start 89.813384 -69.418454)
		(end 89.813384 -68.538598)
		(width 0.1143)
		(layer "In2.Cu")
		(net "XDP_CPU_NODE1_VISA4")
	)
	(segment
		(start 95.391732 -70.691248)
		(end 95.20936 -70.508876)
		(width 0.1143)
		(layer "In2.Cu")
		(net "XDP_CPU_NODE1_VISA4")
	)
	(segment
		(start 87.808054 -68.356226)
		(end 87.625682 -68.538598)
		(width 0.1143)
		(layer "In2.Cu")
		(net "XDP_CPU_NODE1_VISA4")
	)
	(segment
		(start 98.503232 -69.600064)
		(end 98.32086 -69.782436)
		(width 0.1143)
		(layer "In2.Cu")
		(net "XDP_CPU_NODE1_VISA4")
	)
	(segment
		(start 95.83166 -70.508876)
		(end 95.649288 -70.691248)
		(width 0.1143)
		(layer "In2.Cu")
		(net "XDP_CPU_NODE1_VISA4")
	)
	(segment
		(start 86.381082 -68.538598)
		(end 86.381082 -68.899024)
		(width 0.1143)
		(layer "In2.Cu")
		(net "XDP_CPU_NODE1_VISA4")
	)
	(segment
		(start 79.530448 -72.277224)
		(end 79.52867 -72.279002)
		(width 0.1143)
		(layer "In2.Cu")
		(net "XDP_CPU_NODE1_VISA4")
	)
	(segment
		(start 90.435684 -68.796154)
		(end 90.618056 -68.978526)
		(width 0.1143)
		(layer "In2.Cu")
		(net "XDP_CPU_NODE1_VISA4")
	)
	(segment
		(start 100.09251 -68.572634)
		(end 99.288092 -68.572634)
		(width 0.1143)
		(layer "In2.Cu")
		(net "XDP_CPU_NODE1_VISA4")
	)
	(segment
		(start 100.354892 -68.835016)
		(end 100.09251 -68.572634)
		(width 0.1143)
		(layer "In2.Cu")
		(net "XDP_CPU_NODE1_VISA4")
	)
	(segment
		(start 87.625682 -68.538598)
		(end 87.625682 -68.899024)
		(width 0.1143)
		(layer "In2.Cu")
		(net "XDP_CPU_NODE1_VISA4")
	)
	(segment
		(start 88.68791 -69.081396)
		(end 88.430354 -69.081396)
		(width 0.1143)
		(layer "In2.Cu")
		(net "XDP_CPU_NODE1_VISA4")
	)
	(segment
		(start 68.739004 -72.690482)
		(end 68.692776 -72.690482)
		(width 0.1143)
		(layer "In2.Cu")
		(net "XDP_CPU_NODE1_VISA4")
	)
	(segment
		(start 100.354892 -69.742812)
		(end 100.354892 -68.835016)
		(width 0.1143)
		(layer "In2.Cu")
		(net "XDP_CPU_NODE1_VISA4")
	)
	(segment
		(start 73.100184 -74.576432)
		(end 71.073772 -74.576432)
		(width 0.1143)
		(layer "In2.Cu")
		(net "XDP_CPU_NODE1_VISA4")
	)
	(segment
		(start 97.516188 -69.600064)
		(end 97.258632 -69.600064)
		(width 0.1143)
		(layer "In2.Cu")
		(net "XDP_CPU_NODE1_VISA4")
	)
	(segment
		(start 92.771976 -69.600064)
		(end 91.528138 -68.356226)
		(width 0.1143)
		(layer "In2.Cu")
		(net "XDP_CPU_NODE1_VISA4")
	)
	(segment
		(start 86.82101 -68.356226)
		(end 86.563454 -68.356226)
		(width 0.1143)
		(layer "In2.Cu")
		(net "XDP_CPU_NODE1_VISA4")
	)
	(segment
		(start 91.10726 -69.418454)
		(end 90.924888 -69.600826)
		(width 0.1143)
		(layer "In2.Cu")
		(net "XDP_CPU_NODE1_VISA4")
	)
	(segment
		(start 98.138488 -70.519798)
		(end 97.880932 -70.519798)
		(width 0.1143)
		(layer "In2.Cu")
		(net "XDP_CPU_NODE1_VISA4")
	)
	(segment
		(start 85.941154 -69.081396)
		(end 85.758782 -68.899024)
		(width 0.1143)
		(layer "In2.Cu")
		(net "XDP_CPU_NODE1_VISA4")
	)
	(segment
		(start 101.500432 -69.903594)
		(end 101.193092 -70.210934)
		(width 0.1143)
		(layer "In2.Cu")
		(net "XDP_CPU_NODE1_VISA4")
	)
	(segment
		(start 96.014032 -69.600064)
		(end 95.83166 -69.782436)
		(width 0.1143)
		(layer "In2.Cu")
		(net "XDP_CPU_NODE1_VISA4")
	)
	(segment
		(start 85.241638 -68.356226)
		(end 81.32064 -72.277224)
		(width 0.1143)
		(layer "In2.Cu")
		(net "XDP_CPU_NODE1_VISA4")
	)
	(segment
		(start 100.823014 -70.210934)
		(end 100.354892 -69.742812)
		(width 0.1143)
		(layer "In2.Cu")
		(net "XDP_CPU_NODE1_VISA4")
	)
	(segment
		(start 99.00412 -69.362828)
		(end 98.766884 -69.600064)
		(width 0.1143)
		(layer "In2.Cu")
		(net "XDP_CPU_NODE1_VISA4")
	)
	(segment
		(start 78.742794 -72.279002)
		(end 77.729588 -73.292208)
		(width 0.1143)
		(layer "In2.Cu")
		(net "XDP_CPU_NODE1_VISA4")
	)
	(segment
		(start 89.995756 -69.600826)
		(end 89.813384 -69.418454)
		(width 0.1143)
		(layer "In2.Cu")
		(net "XDP_CPU_NODE1_VISA4")
	)
	(segment
		(start 96.271588 -69.600064)
		(end 96.014032 -69.600064)
		(width 0.1143)
		(layer "In2.Cu")
		(net "XDP_CPU_NODE1_VISA4")
	)
	(segment
		(start 88.06561 -68.356226)
		(end 87.808054 -68.356226)
		(width 0.1143)
		(layer "In2.Cu")
		(net "XDP_CPU_NODE1_VISA4")
	)
	(segment
		(start 97.07626 -69.782436)
		(end 97.07626 -70.486524)
		(width 0.1143)
		(layer "In2.Cu")
		(net "XDP_CPU_NODE1_VISA4")
	)
	(segment
		(start 95.649288 -70.691248)
		(end 95.391732 -70.691248)
		(width 0.1143)
		(layer "In2.Cu")
		(net "XDP_CPU_NODE1_VISA4")
	)
	(segment
		(start 95.20936 -69.782436)
		(end 95.026988 -69.600064)
		(width 0.1143)
		(layer "In2.Cu")
		(net "XDP_CPU_NODE1_VISA4")
	)
	(segment
		(start 85.758782 -68.899024)
		(end 85.758782 -68.538598)
		(width 0.1143)
		(layer "In2.Cu")
		(net "XDP_CPU_NODE1_VISA4")
	)
	(segment
		(start 99.288092 -68.572634)
		(end 99.00412 -68.856606)
		(width 0.1143)
		(layer "In2.Cu")
		(net "XDP_CPU_NODE1_VISA4")
	)
	(segment
		(start 87.44331 -69.081396)
		(end 87.185754 -69.081396)
		(width 0.1143)
		(layer "In2.Cu")
		(net "XDP_CPU_NODE1_VISA4")
	)
	(segment
		(start 97.69856 -70.337426)
		(end 97.69856 -69.782436)
		(width 0.1143)
		(layer "In2.Cu")
		(net "XDP_CPU_NODE1_VISA4")
	)
	(segment
		(start 97.880932 -70.519798)
		(end 97.69856 -70.337426)
		(width 0.1143)
		(layer "In2.Cu")
		(net "XDP_CPU_NODE1_VISA4")
	)
	(segment
		(start 90.924888 -68.978526)
		(end 91.10726 -69.160898)
		(width 0.1143)
		(layer "In2.Cu")
		(net "XDP_CPU_NODE1_VISA4")
	)
	(segment
		(start 95.20936 -70.508876)
		(end 95.20936 -69.782436)
		(width 0.1143)
		(layer "In2.Cu")
		(net "XDP_CPU_NODE1_VISA4")
	)
	(segment
		(start 38.882828 -8.738616)
		(end 38.882828 -8.455406)
		(width 0.1778)
		(layer "F.Cu")
		(net "PV_VDDR_NODE1_EN")
	)
	(segment
		(start 40.17391 -7.718044)
		(end 40.100758 -7.791196)
		(width 0.254)
		(layer "F.Cu")
		(net "PV_VDDR_NODE1_EN")
	)
	(segment
		(start 39.150544 -8.18769)
		(end 39.514018 -8.18769)
		(width 0.1778)
		(layer "F.Cu")
		(net "PV_VDDR_NODE1_EN")
	)
	(segment
		(start 39.704264 -8.18769)
		(end 40.100758 -7.791196)
		(width 0.254)
		(layer "F.Cu")
		(net "PV_VDDR_NODE1_EN")
	)
	(segment
		(start 38.882828 -8.455406)
		(end 39.150544 -8.18769)
		(width 0.1778)
		(layer "F.Cu")
		(net "PV_VDDR_NODE1_EN")
	)
	(segment
		(start 39.514018 -8.18769)
		(end 39.704264 -8.18769)
		(width 0.254)
		(layer "F.Cu")
		(net "PV_VDDR_NODE1_EN")
	)
	(segment
		(start 40.17391 -6.990588)
		(end 40.17391 -7.718044)
		(width 0.254)
		(layer "F.Cu")
		(net "PV_VDDR_NODE1_EN")
	)
	(via
		(at 40.100758 -7.791196)
		(size 0.508)
		(drill 0.254)
		(layers "F.Cu" "B.Cu")
		(net "PV_VDDR_NODE1_EN")
	)
	(segment
		(start 18.716498 -130.328416)
		(end 18.410428 -130.022346)
		(width 0.2032)
		(layer "F.Cu")
		(net "P1V05_NODE1_EN")
	)
	(segment
		(start 19.32559 -130.328416)
		(end 19.32559 -130.24612)
		(width 0.254)
		(layer "F.Cu")
		(net "P1V05_NODE1_EN")
	)
	(segment
		(start 18.410428 -130.022346)
		(end 17.612106 -130.022346)
		(width 0.2032)
		(layer "F.Cu")
		(net "P1V05_NODE1_EN")
	)
	(segment
		(start 20.24253 -129.32918)
		(end 20.413472 -129.32918)
		(width 0.254)
		(layer "F.Cu")
		(net "P1V05_NODE1_EN")
	)
	(segment
		(start 19.32559 -130.328416)
		(end 18.716498 -130.328416)
		(width 0.2032)
		(layer "F.Cu")
		(net "P1V05_NODE1_EN")
	)
	(segment
		(start 21.362162 -129.326894)
		(end 21.362162 -129.807208)
		(width 0.254)
		(layer "F.Cu")
		(net "P1V05_NODE1_EN")
	)
	(segment
		(start 21.362162 -129.807208)
		(end 21.677884 -130.12293)
		(width 0.254)
		(layer "F.Cu")
		(net "P1V05_NODE1_EN")
	)
	(segment
		(start 19.32559 -130.24612)
		(end 20.24253 -129.32918)
		(width 0.254)
		(layer "F.Cu")
		(net "P1V05_NODE1_EN")
	)
	(segment
		(start 20.413472 -129.32918)
		(end 21.359876 -129.32918)
		(width 0.254)
		(layer "F.Cu")
		(net "P1V05_NODE1_EN")
	)
	(segment
		(start 21.359876 -129.32918)
		(end 21.362162 -129.326894)
		(width 0.254)
		(layer "F.Cu")
		(net "P1V05_NODE1_EN")
	)
	(via
		(at 21.677884 -130.12293)
		(size 0.508)
		(drill 0.254)
		(layers "F.Cu" "B.Cu")
		(net "P1V05_NODE1_EN")
	)
	(segment
		(start 156.293566 -93.354398)
		(end 156.293566 -93.101922)
		(width 0.1016)
		(layer "F.Cu")
		(net "SPI_USB_NODE1_SI")
	)
	(segment
		(start 152.759664 -94.75216)
		(end 156.260546 -94.75216)
		(width 0.1016)
		(layer "F.Cu")
		(net "SPI_USB_NODE1_SI")
	)
	(segment
		(start 156.260546 -94.75216)
		(end 156.439108 -94.573598)
		(width 0.1016)
		(layer "F.Cu")
		(net "SPI_USB_NODE1_SI")
	)
	(segment
		(start 152.581102 -92.744798)
		(end 152.581102 -92.492322)
		(width 0.1016)
		(layer "F.Cu")
		(net "SPI_USB_NODE1_SI")
	)
	(segment
		(start 155.23083 -92.31376)
		(end 155.409392 -92.135198)
		(width 0.1016)
		(layer "F.Cu")
		(net "SPI_USB_NODE1_SI")
	)
	(segment
		(start 152.759664 -93.53296)
		(end 156.115004 -93.53296)
		(width 0.1016)
		(layer "F.Cu")
		(net "SPI_USB_NODE1_SI")
	)
	(segment
		(start 156.439108 -94.321122)
		(end 156.260546 -94.14256)
		(width 0.1016)
		(layer "F.Cu")
		(net "SPI_USB_NODE1_SI")
	)
	(segment
		(start 152.759664 -92.31376)
		(end 155.23083 -92.31376)
		(width 0.1016)
		(layer "F.Cu")
		(net "SPI_USB_NODE1_SI")
	)
	(segment
		(start 156.260546 -94.14256)
		(end 152.759664 -94.14256)
		(width 0.1016)
		(layer "F.Cu")
		(net "SPI_USB_NODE1_SI")
	)
	(segment
		(start 157.57525 -96.097344)
		(end 156.839666 -95.36176)
		(width 0.1016)
		(layer "F.Cu")
		(net "SPI_USB_NODE1_SI")
	)
	(segment
		(start 154.953716 -90.92946)
		(end 155.409392 -91.385136)
		(width 0.1016)
		(layer "F.Cu")
		(net "SPI_USB_NODE1_SI")
	)
	(segment
		(start 153.439114 -90.827352)
		(end 153.541222 -90.92946)
		(width 0.1016)
		(layer "F.Cu")
		(net "SPI_USB_NODE1_SI")
	)
	(segment
		(start 152.581102 -94.930722)
		(end 152.759664 -94.75216)
		(width 0.1016)
		(layer "F.Cu")
		(net "SPI_USB_NODE1_SI")
	)
	(segment
		(start 152.581102 -93.963998)
		(end 152.581102 -93.711522)
		(width 0.1016)
		(layer "F.Cu")
		(net "SPI_USB_NODE1_SI")
	)
	(segment
		(start 163.340034 -98.135694)
		(end 162.757866 -98.135694)
		(width 0.1016)
		(layer "F.Cu")
		(net "SPI_USB_NODE1_SI")
	)
	(segment
		(start 162.757866 -98.135694)
		(end 160.719516 -96.097344)
		(width 0.1016)
		(layer "F.Cu")
		(net "SPI_USB_NODE1_SI")
	)
	(segment
		(start 156.115004 -92.92336)
		(end 152.759664 -92.92336)
		(width 0.1016)
		(layer "F.Cu")
		(net "SPI_USB_NODE1_SI")
	)
	(segment
		(start 156.439108 -94.573598)
		(end 156.439108 -94.321122)
		(width 0.1016)
		(layer "F.Cu")
		(net "SPI_USB_NODE1_SI")
	)
	(segment
		(start 153.541222 -90.92946)
		(end 154.953716 -90.92946)
		(width 0.1016)
		(layer "F.Cu")
		(net "SPI_USB_NODE1_SI")
	)
	(segment
		(start 153.439114 -89.599516)
		(end 153.439114 -90.827352)
		(width 0.1016)
		(layer "F.Cu")
		(net "SPI_USB_NODE1_SI")
	)
	(segment
		(start 156.115004 -93.53296)
		(end 156.293566 -93.354398)
		(width 0.1016)
		(layer "F.Cu")
		(net "SPI_USB_NODE1_SI")
	)
	(segment
		(start 152.759664 -94.14256)
		(end 152.581102 -93.963998)
		(width 0.1016)
		(layer "F.Cu")
		(net "SPI_USB_NODE1_SI")
	)
	(segment
		(start 155.409392 -92.135198)
		(end 155.409392 -91.385136)
		(width 0.1016)
		(layer "F.Cu")
		(net "SPI_USB_NODE1_SI")
	)
	(segment
		(start 160.719516 -96.097344)
		(end 157.57525 -96.097344)
		(width 0.1016)
		(layer "F.Cu")
		(net "SPI_USB_NODE1_SI")
	)
	(segment
		(start 152.759664 -95.36176)
		(end 152.581102 -95.183198)
		(width 0.1016)
		(layer "F.Cu")
		(net "SPI_USB_NODE1_SI")
	)
	(segment
		(start 152.581102 -95.183198)
		(end 152.581102 -94.930722)
		(width 0.1016)
		(layer "F.Cu")
		(net "SPI_USB_NODE1_SI")
	)
	(segment
		(start 156.839666 -95.36176)
		(end 152.759664 -95.36176)
		(width 0.1016)
		(layer "F.Cu")
		(net "SPI_USB_NODE1_SI")
	)
	(segment
		(start 152.581102 -93.711522)
		(end 152.759664 -93.53296)
		(width 0.1016)
		(layer "F.Cu")
		(net "SPI_USB_NODE1_SI")
	)
	(segment
		(start 156.293566 -93.101922)
		(end 156.115004 -92.92336)
		(width 0.1016)
		(layer "F.Cu")
		(net "SPI_USB_NODE1_SI")
	)
	(segment
		(start 152.581102 -92.492322)
		(end 152.759664 -92.31376)
		(width 0.1016)
		(layer "F.Cu")
		(net "SPI_USB_NODE1_SI")
	)
	(segment
		(start 152.759664 -92.92336)
		(end 152.581102 -92.744798)
		(width 0.1016)
		(layer "F.Cu")
		(net "SPI_USB_NODE1_SI")
	)
	(via
		(at 155.409392 -91.385136)
		(size 0.508)
		(drill 0.254)
		(layers "F.Cu" "B.Cu")
		(net "SPI_USB_NODE1_SI")
	)
	(segment
		(start 104.73182 -66.406268)
		(end 106.869738 -66.406268)
		(width 0.1016)
		(layer "F.Cu")
		(net "XDP_CPU_NODE1_PG_RST_R")
	)
	(segment
		(start 106.869738 -66.406268)
		(end 106.897932 -66.378074)
		(width 0.1016)
		(layer "F.Cu")
		(net "XDP_CPU_NODE1_PG_RST_R")
	)
	(via
		(at 106.897932 -66.378074)
		(size 0.508)
		(drill 0.254)
		(layers "F.Cu" "B.Cu")
		(net "XDP_CPU_NODE1_PG_RST_R")
	)
	(segment
		(start 106.361484 -65.148206)
		(end 104.808274 -65.148206)
		(width 0.1016)
		(layer "B.Cu")
		(net "XDP_CPU_NODE1_PG_RST_R")
	)
	(segment
		(start 104.808274 -65.148206)
		(end 104.808274 -64.132206)
		(width 0.1016)
		(layer "B.Cu")
		(net "XDP_CPU_NODE1_PG_RST_R")
	)
	(segment
		(start 106.897932 -65.684654)
		(end 106.361484 -65.148206)
		(width 0.1016)
		(layer "B.Cu")
		(net "XDP_CPU_NODE1_PG_RST_R")
	)
	(segment
		(start 106.897932 -66.378074)
		(end 106.897932 -65.684654)
		(width 0.1016)
		(layer "B.Cu")
		(net "XDP_CPU_NODE1_PG_RST_R")
	)
	(segment
		(start 70.202044 -78.255622)
		(end 70.202044 -78.294992)
		(width 0.1016)
		(layer "F.Cu")
		(net "SVID_CPU_NODE1_PVCCP_DAT_R")
	)
	(segment
		(start 70.202044 -78.294992)
		(end 70.565264 -78.658212)
		(width 0.1016)
		(layer "F.Cu")
		(net "SVID_CPU_NODE1_PVCCP_DAT_R")
	)
	(via
		(at 70.565264 -78.658212)
		(size 0.508)
		(drill 0.254)
		(layers "F.Cu" "B.Cu")
		(net "SVID_CPU_NODE1_PVCCP_DAT_R")
	)
	(via
		(at 72.281796 -77.6478)
		(size 0.6604)
		(drill 0.3302)
		(layers "F.Cu" "B.Cu")
		(net "SVID_CPU_NODE1_PVCCP_DAT_R")
	)
	(segment
		(start 72.580246 -77.94625)
		(end 72.281796 -77.6478)
		(width 0.1016)
		(layer "B.Cu")
		(net "SVID_CPU_NODE1_PVCCP_DAT_R")
	)
	(segment
		(start 72.049386 -77.88021)
		(end 72.281796 -77.6478)
		(width 0.1016)
		(layer "B.Cu")
		(net "SVID_CPU_NODE1_PVCCP_DAT_R")
	)
	(segment
		(start 70.565264 -78.658212)
		(end 70.565264 -78.369922)
		(width 0.1016)
		(layer "B.Cu")
		(net "SVID_CPU_NODE1_PVCCP_DAT_R")
	)
	(segment
		(start 71.054976 -77.88021)
		(end 72.049386 -77.88021)
		(width 0.1016)
		(layer "B.Cu")
		(net "SVID_CPU_NODE1_PVCCP_DAT_R")
	)
	(segment
		(start 70.565264 -78.369922)
		(end 71.054976 -77.88021)
		(width 0.1016)
		(layer "B.Cu")
		(net "SVID_CPU_NODE1_PVCCP_DAT_R")
	)
	(segment
		(start 73.391268 -77.94625)
		(end 72.580246 -77.94625)
		(width 0.1016)
		(layer "B.Cu")
		(net "SVID_CPU_NODE1_PVCCP_DAT_R")
	)
	(segment
		(start 37.282628 -8.35914)
		(end 37.156644 -8.233156)
		(width 0.1778)
		(layer "F.Cu")
		(net "PV_VDDR_NODE1_VREF")
	)
	(segment
		(start 37.282628 -8.738616)
		(end 37.282628 -8.35914)
		(width 0.1778)
		(layer "F.Cu")
		(net "PV_VDDR_NODE1_VREF")
	)
	(segment
		(start 37.156644 -8.233156)
		(end 36.646104 -8.233156)
		(width 0.1778)
		(layer "F.Cu")
		(net "PV_VDDR_NODE1_VREF")
	)
	(via
		(at 35.019488 -7.505954)
		(size 0.508)
		(drill 0.254)
		(layers "F.Cu" "B.Cu")
		(net "PV_VDDR_NODE1_VREF")
	)
	(segment
		(start 13.039598 -134.257796)
		(end 12.86002 -134.437374)
		(width 0.1016)
		(layer "F.Cu")
		(net "P1V05_NODE1_VSNS")
	)
	(segment
		(start 14.059154 -133.618478)
		(end 14.058392 -133.61924)
		(width 0.254)
		(layer "F.Cu")
		(net "P1V05_NODE1_VSNS")
	)
	(segment
		(start 15.061946 -133.617462)
		(end 15.061946 -132.616956)
		(width 0.254)
		(layer "F.Cu")
		(net "P1V05_NODE1_VSNS")
	)
	(segment
		(start 14.059154 -133.618478)
		(end 15.06093 -133.618478)
		(width 0.254)
		(layer "F.Cu")
		(net "P1V05_NODE1_VSNS")
	)
	(segment
		(start 13.039598 -133.61924)
		(end 13.039598 -134.257796)
		(width 0.1016)
		(layer "F.Cu")
		(net "P1V05_NODE1_VSNS")
	)
	(segment
		(start 15.06093 -133.618478)
		(end 15.061946 -133.617462)
		(width 0.254)
		(layer "F.Cu")
		(net "P1V05_NODE1_VSNS")
	)
	(segment
		(start 15.061946 -132.616956)
		(end 15.312136 -132.366766)
		(width 0.254)
		(layer "F.Cu")
		(net "P1V05_NODE1_VSNS")
	)
	(segment
		(start 14.058392 -133.61924)
		(end 13.039598 -133.61924)
		(width 0.254)
		(layer "F.Cu")
		(net "P1V05_NODE1_VSNS")
	)
	(segment
		(start 15.312136 -132.366766)
		(end 15.312136 -131.82219)
		(width 0.254)
		(layer "F.Cu")
		(net "P1V05_NODE1_VSNS")
	)
	(via
		(at 12.86002 -134.437374)
		(size 0.508)
		(drill 0.254)
		(layers "F.Cu" "B.Cu")
		(net "P1V05_NODE1_VSNS")
	)
	(segment
		(start 163.251134 -97.735898)
		(end 162.869372 -97.735898)
		(width 0.1016)
		(layer "F.Cu")
		(net "SPI_USB_NODE1_CSB_R_L")
	)
	(segment
		(start 162.873944 -96.930464)
		(end 162.873944 -94.240858)
		(width 0.1016)
		(layer "F.Cu")
		(net "SPI_USB_NODE1_CSB_R_L")
	)
	(segment
		(start 162.869372 -97.735898)
		(end 162.652964 -97.51949)
		(width 0.1016)
		(layer "F.Cu")
		(net "SPI_USB_NODE1_CSB_R_L")
	)
	(segment
		(start 162.652964 -97.151444)
		(end 162.873944 -96.930464)
		(width 0.1016)
		(layer "F.Cu")
		(net "SPI_USB_NODE1_CSB_R_L")
	)
	(segment
		(start 162.652964 -97.51949)
		(end 162.652964 -97.151444)
		(width 0.1016)
		(layer "F.Cu")
		(net "SPI_USB_NODE1_CSB_R_L")
	)
	(via
		(at 162.873944 -96.930464)
		(size 0.508)
		(drill 0.254)
		(layers "F.Cu" "B.Cu")
		(net "SPI_USB_NODE1_CSB_R_L")
	)
	(segment
		(start 66.07937 -76.269342)
		(end 66.52641 -76.716382)
		(width 0.1143)
		(layer "F.Cu")
		(net "TP_CPU1_NODE1_HFPLL")
	)
	(segment
		(start 66.011044 -76.269342)
		(end 66.07937 -76.269342)
		(width 0.1143)
		(layer "F.Cu")
		(net "TP_CPU1_NODE1_HFPLL")
	)
	(via
		(at 66.52641 -76.716382)
		(size 0.508)
		(drill 0.254)
		(layers "F.Cu" "B.Cu")
		(net "TP_CPU1_NODE1_HFPLL")
	)
	(segment
		(start 113.646204 -61.255148)
		(end 113.646204 -61.301122)
		(width 0.1016)
		(layer "F.Cu")
		(net "XDP_SOC_CPU_NODE1_TRST_L")
	)
	(segment
		(start 71.82104 -79.187802)
		(end 71.592186 -78.958948)
		(width 0.1016)
		(layer "F.Cu")
		(net "XDP_SOC_CPU_NODE1_TRST_L")
	)
	(segment
		(start 72.081136 -79.187802)
		(end 71.82104 -79.187802)
		(width 0.1016)
		(layer "F.Cu")
		(net "XDP_SOC_CPU_NODE1_TRST_L")
	)
	(segment
		(start 108.553758 -63.406274)
		(end 110.460028 -63.406274)
		(width 0.1016)
		(layer "F.Cu")
		(net "XDP_SOC_CPU_NODE1_TRST_L")
	)
	(segment
		(start 108.455968 -63.504064)
		(end 108.553758 -63.406274)
		(width 0.1016)
		(layer "F.Cu")
		(net "XDP_SOC_CPU_NODE1_TRST_L")
	)
	(segment
		(start 113.646204 -61.301122)
		(end 111.541052 -63.406274)
		(width 0.1016)
		(layer "F.Cu")
		(net "XDP_SOC_CPU_NODE1_TRST_L")
	)
	(segment
		(start 111.541052 -63.406274)
		(end 110.460028 -63.406274)
		(width 0.1016)
		(layer "F.Cu")
		(net "XDP_SOC_CPU_NODE1_TRST_L")
	)
	(via
		(at 71.592186 -78.958948)
		(size 0.508)
		(drill 0.254)
		(layers "F.Cu" "B.Cu")
		(net "XDP_SOC_CPU_NODE1_TRST_L")
	)
	(via
		(at 108.455968 -63.504064)
		(size 0.508)
		(drill 0.254)
		(layers "F.Cu" "B.Cu")
		(net "XDP_SOC_CPU_NODE1_TRST_L")
	)
	(segment
		(start 75.571858 -77.813408)
		(end 76.690728 -76.694538)
		(width 0.1143)
		(layer "In2.Cu")
		(net "XDP_SOC_CPU_NODE1_TRST_L")
	)
	(segment
		(start 77.881226 -76.332334)
		(end 82.351118 -76.332334)
		(width 0.1143)
		(layer "In2.Cu")
		(net "XDP_SOC_CPU_NODE1_TRST_L")
	)
	(segment
		(start 100.133658 -78.015084)
		(end 101.872796 -76.275946)
		(width 0.1143)
		(layer "In2.Cu")
		(net "XDP_SOC_CPU_NODE1_TRST_L")
	)
	(segment
		(start 91.94673 -73.840848)
		(end 93.937328 -75.831446)
		(width 0.1143)
		(layer "In2.Cu")
		(net "XDP_SOC_CPU_NODE1_TRST_L")
	)
	(segment
		(start 87.700612 -75.426316)
		(end 89.28608 -73.840848)
		(width 0.1143)
		(layer "In2.Cu")
		(net "XDP_SOC_CPU_NODE1_TRST_L")
	)
	(segment
		(start 76.690728 -76.694538)
		(end 77.519022 -76.694538)
		(width 0.1143)
		(layer "In2.Cu")
		(net "XDP_SOC_CPU_NODE1_TRST_L")
	)
	(segment
		(start 73.100692 -77.813408)
		(end 75.571858 -77.813408)
		(width 0.1143)
		(layer "In2.Cu")
		(net "XDP_SOC_CPU_NODE1_TRST_L")
	)
	(segment
		(start 85.38718 -75.063604)
		(end 85.749892 -75.426316)
		(width 0.1143)
		(layer "In2.Cu")
		(net "XDP_SOC_CPU_NODE1_TRST_L")
	)
	(segment
		(start 82.351118 -76.332334)
		(end 83.619848 -75.063604)
		(width 0.1143)
		(layer "In2.Cu")
		(net "XDP_SOC_CPU_NODE1_TRST_L")
	)
	(segment
		(start 95.133922 -75.831446)
		(end 97.31756 -78.015084)
		(width 0.1143)
		(layer "In2.Cu")
		(net "XDP_SOC_CPU_NODE1_TRST_L")
	)
	(segment
		(start 83.619848 -75.063604)
		(end 85.38718 -75.063604)
		(width 0.1143)
		(layer "In2.Cu")
		(net "XDP_SOC_CPU_NODE1_TRST_L")
	)
	(segment
		(start 108.27512 -75.41387)
		(end 109.658912 -74.030078)
		(width 0.1143)
		(layer "In2.Cu")
		(net "XDP_SOC_CPU_NODE1_TRST_L")
	)
	(segment
		(start 77.519022 -76.694538)
		(end 77.881226 -76.332334)
		(width 0.1143)
		(layer "In2.Cu")
		(net "XDP_SOC_CPU_NODE1_TRST_L")
	)
	(segment
		(start 93.937328 -75.831446)
		(end 95.133922 -75.831446)
		(width 0.1143)
		(layer "In2.Cu")
		(net "XDP_SOC_CPU_NODE1_TRST_L")
	)
	(segment
		(start 71.592186 -78.958948)
		(end 71.955152 -78.958948)
		(width 0.1143)
		(layer "In2.Cu")
		(net "XDP_SOC_CPU_NODE1_TRST_L")
	)
	(segment
		(start 109.658912 -74.030078)
		(end 109.658912 -64.541146)
		(width 0.1143)
		(layer "In2.Cu")
		(net "XDP_SOC_CPU_NODE1_TRST_L")
	)
	(segment
		(start 97.31756 -78.015084)
		(end 100.133658 -78.015084)
		(width 0.1143)
		(layer "In2.Cu")
		(net "XDP_SOC_CPU_NODE1_TRST_L")
	)
	(segment
		(start 105.113328 -76.275946)
		(end 105.975404 -75.41387)
		(width 0.1143)
		(layer "In2.Cu")
		(net "XDP_SOC_CPU_NODE1_TRST_L")
	)
	(segment
		(start 85.749892 -75.426316)
		(end 87.700612 -75.426316)
		(width 0.1143)
		(layer "In2.Cu")
		(net "XDP_SOC_CPU_NODE1_TRST_L")
	)
	(segment
		(start 109.658912 -64.541146)
		(end 108.62183 -63.504064)
		(width 0.1143)
		(layer "In2.Cu")
		(net "XDP_SOC_CPU_NODE1_TRST_L")
	)
	(segment
		(start 101.872796 -76.275946)
		(end 105.113328 -76.275946)
		(width 0.1143)
		(layer "In2.Cu")
		(net "XDP_SOC_CPU_NODE1_TRST_L")
	)
	(segment
		(start 89.28608 -73.840848)
		(end 91.94673 -73.840848)
		(width 0.1143)
		(layer "In2.Cu")
		(net "XDP_SOC_CPU_NODE1_TRST_L")
	)
	(segment
		(start 105.975404 -75.41387)
		(end 108.27512 -75.41387)
		(width 0.1143)
		(layer "In2.Cu")
		(net "XDP_SOC_CPU_NODE1_TRST_L")
	)
	(segment
		(start 71.955152 -78.958948)
		(end 73.100692 -77.813408)
		(width 0.1143)
		(layer "In2.Cu")
		(net "XDP_SOC_CPU_NODE1_TRST_L")
	)
	(segment
		(start 108.62183 -63.504064)
		(end 108.455968 -63.504064)
		(width 0.1143)
		(layer "In2.Cu")
		(net "XDP_SOC_CPU_NODE1_TRST_L")
	)
	(segment
		(start 37.885878 -13.82522)
		(end 37.885878 -13.170408)
		(width 0.254)
		(layer "F.Cu")
		(net "PV_VDDR_NODE1_TRIP")
	)
	(segment
		(start 38.082728 -12.906502)
		(end 37.85235 -13.13688)
		(width 0.1778)
		(layer "F.Cu")
		(net "PV_VDDR_NODE1_TRIP")
	)
	(segment
		(start 38.082728 -11.86434)
		(end 38.082728 -12.906502)
		(width 0.1778)
		(layer "F.Cu")
		(net "PV_VDDR_NODE1_TRIP")
	)
	(segment
		(start 37.885878 -13.170408)
		(end 37.85235 -13.13688)
		(width 0.254)
		(layer "F.Cu")
		(net "PV_VDDR_NODE1_TRIP")
	)
	(via
		(at 37.85235 -13.13688)
		(size 0.508)
		(drill 0.254)
		(layers "F.Cu" "B.Cu")
		(net "PV_VDDR_NODE1_TRIP")
	)
	(segment
		(start 13.03655 -131.838192)
		(end 12.663678 -132.211064)
		(width 0.254)
		(layer "F.Cu")
		(net "VSENSE_P1V05_NODE1_P")
	)
	(segment
		(start 13.03655 -132.816092)
		(end 13.03655 -132.583936)
		(width 0.254)
		(layer "F.Cu")
		(net "VSENSE_P1V05_NODE1_P")
	)
	(segment
		(start 13.03655 -131.590288)
		(end 13.03655 -131.838192)
		(width 0.254)
		(layer "F.Cu")
		(net "VSENSE_P1V05_NODE1_P")
	)
	(segment
		(start 13.039598 -132.81914)
		(end 13.03655 -132.816092)
		(width 0.254)
		(layer "F.Cu")
		(net "VSENSE_P1V05_NODE1_P")
	)
	(segment
		(start 13.03655 -132.583936)
		(end 12.663678 -132.211064)
		(width 0.254)
		(layer "F.Cu")
		(net "VSENSE_P1V05_NODE1_P")
	)
	(via
		(at 12.663678 -132.211064)
		(size 0.508)
		(drill 0.254)
		(layers "F.Cu" "B.Cu")
		(net "VSENSE_P1V05_NODE1_P")
	)
	(via
		(at 27.99842 -92.26169)
		(size 0.508)
		(drill 0.254)
		(layers "F.Cu" "B.Cu")
		(net "VSENSE_P1V05_NODE1_P")
	)
	(via
		(at 58.838592 -69.657722)
		(size 0.508)
		(drill 0.254)
		(layers "F.Cu" "B.Cu")
		(net "VSENSE_P1V05_NODE1_P")
	)
	(segment
		(start 8.74776 -122.03049)
		(end 7.48792 -123.29033)
		(width 0.254)
		(layer "B.Cu")
		(net "VSENSE_P1V05_NODE1_P")
	)
	(segment
		(start 8.74776 -105.206292)
		(end 8.74776 -122.03049)
		(width 0.254)
		(layer "B.Cu")
		(net "VSENSE_P1V05_NODE1_P")
	)
	(segment
		(start 16.6624 -96.835722)
		(end 16.6624 -100.745798)
		(width 0.254)
		(layer "B.Cu")
		(net "VSENSE_P1V05_NODE1_P")
	)
	(segment
		(start 7.48792 -131.946396)
		(end 7.488682 -131.946396)
		(width 0.254)
		(layer "B.Cu")
		(net "VSENSE_P1V05_NODE1_P")
	)
	(segment
		(start 14.238732 -103.169466)
		(end 10.784586 -103.169466)
		(width 0.254)
		(layer "B.Cu")
		(net "VSENSE_P1V05_NODE1_P")
	)
	(segment
		(start 58.602372 -70.570852)
		(end 58.602372 -69.893942)
		(width 0.254)
		(layer "B.Cu")
		(net "VSENSE_P1V05_NODE1_P")
	)
	(segment
		(start 10.973308 -133.279134)
		(end 11.57986 -132.672582)
		(width 0.254)
		(layer "B.Cu")
		(net "VSENSE_P1V05_NODE1_P")
	)
	(segment
		(start 27.99842 -92.26169)
		(end 27.88412 -92.14739)
		(width 0.254)
		(layer "B.Cu")
		(net "VSENSE_P1V05_NODE1_P")
	)
	(segment
		(start 10.784586 -103.169466)
		(end 8.74776 -105.206292)
		(width 0.254)
		(layer "B.Cu")
		(net "VSENSE_P1V05_NODE1_P")
	)
	(segment
		(start 7.488682 -131.946396)
		(end 8.82142 -133.279134)
		(width 0.254)
		(layer "B.Cu")
		(net "VSENSE_P1V05_NODE1_P")
	)
	(segment
		(start 12.663678 -132.211318)
		(end 12.663678 -132.211064)
		(width 0.254)
		(layer "B.Cu")
		(net "VSENSE_P1V05_NODE1_P")
	)
	(segment
		(start 11.57986 -132.672582)
		(end 12.202414 -132.672582)
		(width 0.254)
		(layer "B.Cu")
		(net "VSENSE_P1V05_NODE1_P")
	)
	(segment
		(start 12.202414 -132.672582)
		(end 12.663678 -132.211318)
		(width 0.254)
		(layer "B.Cu")
		(net "VSENSE_P1V05_NODE1_P")
	)
	(segment
		(start 7.48792 -123.29033)
		(end 7.48792 -131.946396)
		(width 0.254)
		(layer "B.Cu")
		(net "VSENSE_P1V05_NODE1_P")
	)
	(segment
		(start 58.602372 -69.893942)
		(end 58.838592 -69.657722)
		(width 0.254)
		(layer "B.Cu")
		(net "VSENSE_P1V05_NODE1_P")
	)
	(segment
		(start 16.6624 -100.745798)
		(end 14.238732 -103.169466)
		(width 0.254)
		(layer "B.Cu")
		(net "VSENSE_P1V05_NODE1_P")
	)
	(segment
		(start 8.82142 -133.279134)
		(end 10.973308 -133.279134)
		(width 0.254)
		(layer "B.Cu")
		(net "VSENSE_P1V05_NODE1_P")
	)
	(segment
		(start 27.88412 -92.14739)
		(end 21.350732 -92.14739)
		(width 0.254)
		(layer "B.Cu")
		(net "VSENSE_P1V05_NODE1_P")
	)
	(segment
		(start 21.350732 -92.14739)
		(end 16.6624 -96.835722)
		(width 0.254)
		(layer "B.Cu")
		(net "VSENSE_P1V05_NODE1_P")
	)
	(segment
		(start 39.21887 -72.687688)
		(end 34.495994 -72.687688)
		(width 0.254)
		(layer "In2.Cu")
		(net "VSENSE_P1V05_NODE1_P")
	)
	(segment
		(start 28.129992 -92.130118)
		(end 27.99842 -92.26169)
		(width 0.254)
		(layer "In2.Cu")
		(net "VSENSE_P1V05_NODE1_P")
	)
	(segment
		(start 56.836564 -70.634098)
		(end 56.607456 -70.863206)
		(width 0.254)
		(layer "In2.Cu")
		(net "VSENSE_P1V05_NODE1_P")
	)
	(segment
		(start 58.838592 -69.657722)
		(end 58.526934 -69.96938)
		(width 0.254)
		(layer "In2.Cu")
		(net "VSENSE_P1V05_NODE1_P")
	)
	(segment
		(start 34.495994 -72.687688)
		(end 32.3342 -74.849482)
		(width 0.254)
		(layer "In2.Cu")
		(net "VSENSE_P1V05_NODE1_P")
	)
	(segment
		(start 58.526934 -70.125336)
		(end 58.018172 -70.634098)
		(width 0.254)
		(layer "In2.Cu")
		(net "VSENSE_P1V05_NODE1_P")
	)
	(segment
		(start 56.607456 -71.79437)
		(end 55.951882 -72.449944)
		(width 0.254)
		(layer "In2.Cu")
		(net "VSENSE_P1V05_NODE1_P")
	)
	(segment
		(start 29.45892 -92.130118)
		(end 28.129992 -92.130118)
		(width 0.254)
		(layer "In2.Cu")
		(net "VSENSE_P1V05_NODE1_P")
	)
	(segment
		(start 56.607456 -70.863206)
		(end 56.607456 -71.79437)
		(width 0.254)
		(layer "In2.Cu")
		(net "VSENSE_P1V05_NODE1_P")
	)
	(segment
		(start 55.951882 -72.449944)
		(end 50.893726 -72.449944)
		(width 0.254)
		(layer "In2.Cu")
		(net "VSENSE_P1V05_NODE1_P")
	)
	(segment
		(start 40.067484 -71.839074)
		(end 39.21887 -72.687688)
		(width 0.254)
		(layer "In2.Cu")
		(net "VSENSE_P1V05_NODE1_P")
	)
	(segment
		(start 58.526934 -69.96938)
		(end 58.526934 -70.125336)
		(width 0.254)
		(layer "In2.Cu")
		(net "VSENSE_P1V05_NODE1_P")
	)
	(segment
		(start 32.3342 -74.849482)
		(end 32.3342 -89.254838)
		(width 0.254)
		(layer "In2.Cu")
		(net "VSENSE_P1V05_NODE1_P")
	)
	(segment
		(start 50.893726 -72.449944)
		(end 50.282856 -71.839074)
		(width 0.254)
		(layer "In2.Cu")
		(net "VSENSE_P1V05_NODE1_P")
	)
	(segment
		(start 58.018172 -70.634098)
		(end 56.836564 -70.634098)
		(width 0.254)
		(layer "In2.Cu")
		(net "VSENSE_P1V05_NODE1_P")
	)
	(segment
		(start 50.282856 -71.839074)
		(end 40.067484 -71.839074)
		(width 0.254)
		(layer "In2.Cu")
		(net "VSENSE_P1V05_NODE1_P")
	)
	(segment
		(start 32.3342 -89.254838)
		(end 29.45892 -92.130118)
		(width 0.254)
		(layer "In2.Cu")
		(net "VSENSE_P1V05_NODE1_P")
	)
	(segment
		(start 158.4198 -101.688138)
		(end 158.96209 -101.688138)
		(width 0.127)
		(layer "F.Cu")
		(net "P2E_CPU_USB_NODE1_RX_C_DP")
	)
	(segment
		(start 162.462718 -101.688138)
		(end 158.96209 -101.688138)
		(width 0.127)
		(layer "F.Cu")
		(net "P2E_CPU_USB_NODE1_RX_C_DP")
	)
	(segment
		(start 157.98673 -102.121208)
		(end 158.4198 -101.688138)
		(width 0.127)
		(layer "F.Cu")
		(net "P2E_CPU_USB_NODE1_RX_C_DP")
	)
	(segment
		(start 163.340034 -101.73589)
		(end 162.51047 -101.73589)
		(width 0.127)
		(layer "F.Cu")
		(net "P2E_CPU_USB_NODE1_RX_C_DP")
	)
	(segment
		(start 162.51047 -101.73589)
		(end 162.462718 -101.688138)
		(width 0.127)
		(layer "F.Cu")
		(net "P2E_CPU_USB_NODE1_RX_C_DP")
	)
	(via
		(at 158.96209 -101.688138)
		(size 0.4064)
		(drill 0.2032)
		(layers "F.Cu" "B.Cu")
		(net "P2E_CPU_USB_NODE1_RX_C_DP")
	)
	(segment
		(start 131.385564 -135.03529)
		(end 131.385564 -134.02564)
		(width 0.127)
		(layer "F.Cu")
		(net "P2E_CPU_USB_NODE1_TX_C_DP")
	)
	(segment
		(start 133.825488 -132.180584)
		(end 133.37159 -132.634482)
		(width 0.127)
		(layer "F.Cu")
		(net "P2E_CPU_USB_NODE1_TX_C_DP")
	)
	(segment
		(start 132.409946 -133.001258)
		(end 133.004814 -133.001258)
		(width 0.127)
		(layer "F.Cu")
		(net "P2E_CPU_USB_NODE1_TX_C_DP")
	)
	(segment
		(start 131.385564 -134.02564)
		(end 132.409946 -133.001258)
		(width 0.127)
		(layer "F.Cu")
		(net "P2E_CPU_USB_NODE1_TX_C_DP")
	)
	(segment
		(start 133.825488 -131.735068)
		(end 133.825488 -132.180584)
		(width 0.127)
		(layer "F.Cu")
		(net "P2E_CPU_USB_NODE1_TX_C_DP")
	)
	(segment
		(start 131.338066 -135.825484)
		(end 131.338066 -135.082788)
		(width 0.127)
		(layer "F.Cu")
		(net "P2E_CPU_USB_NODE1_TX_C_DP")
	)
	(segment
		(start 133.82498 -131.73456)
		(end 133.825488 -131.735068)
		(width 0.127)
		(layer "F.Cu")
		(net "P2E_CPU_USB_NODE1_TX_C_DP")
	)
	(segment
		(start 133.47192 -130.887216)
		(end 133.82498 -131.240276)
		(width 0.127)
		(layer "F.Cu")
		(net "P2E_CPU_USB_NODE1_TX_C_DP")
	)
	(segment
		(start 133.82498 -131.240276)
		(end 133.82498 -131.73456)
		(width 0.127)
		(layer "F.Cu")
		(net "P2E_CPU_USB_NODE1_TX_C_DP")
	)
	(segment
		(start 133.470396 -130.887216)
		(end 133.47192 -130.887216)
		(width 0.127)
		(layer "F.Cu")
		(net "P2E_CPU_USB_NODE1_TX_C_DP")
	)
	(segment
		(start 131.338066 -135.082788)
		(end 131.385564 -135.03529)
		(width 0.127)
		(layer "F.Cu")
		(net "P2E_CPU_USB_NODE1_TX_C_DP")
	)
	(segment
		(start 133.004814 -133.001258)
		(end 133.37159 -132.634482)
		(width 0.127)
		(layer "F.Cu")
		(net "P2E_CPU_USB_NODE1_TX_C_DP")
	)
	(via
		(at 133.37159 -132.634482)
		(size 0.4064)
		(drill 0.2032)
		(layers "F.Cu" "B.Cu")
		(net "P2E_CPU_USB_NODE1_TX_C_DP")
	)
	(segment
		(start 75.667362 -77.291438)
		(end 77.012038 -77.291438)
		(width 0.1016)
		(layer "F.Cu")
		(net "XDP_SOC_CPU_NODE1_TCK")
	)
	(segment
		(start 74.145394 -76.905612)
		(end 75.045062 -76.905612)
		(width 0.1016)
		(layer "F.Cu")
		(net "XDP_SOC_CPU_NODE1_TCK")
	)
	(segment
		(start 77.88021 -76.186284)
		(end 77.012038 -77.054456)
		(width 0.1016)
		(layer "F.Cu")
		(net "XDP_SOC_CPU_NODE1_TCK")
	)
	(segment
		(start 73.738486 -77.31252)
		(end 74.145394 -76.905612)
		(width 0.1016)
		(layer "F.Cu")
		(net "XDP_SOC_CPU_NODE1_TCK")
	)
	(segment
		(start 79.61249 -76.186284)
		(end 77.88021 -76.186284)
		(width 0.1016)
		(layer "F.Cu")
		(net "XDP_SOC_CPU_NODE1_TCK")
	)
	(segment
		(start 75.332336 -76.956412)
		(end 75.667362 -77.291438)
		(width 0.1016)
		(layer "F.Cu")
		(net "XDP_SOC_CPU_NODE1_TCK")
	)
	(segment
		(start 72.6567 -77.342746)
		(end 73.037446 -77.342746)
		(width 0.1016)
		(layer "F.Cu")
		(net "XDP_SOC_CPU_NODE1_TCK")
	)
	(segment
		(start 73.384664 -77.416152)
		(end 73.488296 -77.31252)
		(width 0.1016)
		(layer "F.Cu")
		(net "XDP_SOC_CPU_NODE1_TCK")
	)
	(segment
		(start 104.73182 -62.406276)
		(end 106.40187 -62.406276)
		(width 0.1016)
		(layer "F.Cu")
		(net "XDP_SOC_CPU_NODE1_TCK")
	)
	(segment
		(start 75.095862 -76.956412)
		(end 75.332336 -76.956412)
		(width 0.1016)
		(layer "F.Cu")
		(net "XDP_SOC_CPU_NODE1_TCK")
	)
	(segment
		(start 77.012038 -77.054456)
		(end 77.012038 -77.291438)
		(width 0.1016)
		(layer "F.Cu")
		(net "XDP_SOC_CPU_NODE1_TCK")
	)
	(segment
		(start 73.037446 -77.342746)
		(end 73.110852 -77.416152)
		(width 0.1016)
		(layer "F.Cu")
		(net "XDP_SOC_CPU_NODE1_TCK")
	)
	(segment
		(start 72.205088 -77.794358)
		(end 72.6567 -77.342746)
		(width 0.1016)
		(layer "F.Cu")
		(net "XDP_SOC_CPU_NODE1_TCK")
	)
	(segment
		(start 73.110852 -77.416152)
		(end 73.384664 -77.416152)
		(width 0.1016)
		(layer "F.Cu")
		(net "XDP_SOC_CPU_NODE1_TCK")
	)
	(segment
		(start 75.045062 -76.905612)
		(end 75.095862 -76.956412)
		(width 0.1016)
		(layer "F.Cu")
		(net "XDP_SOC_CPU_NODE1_TCK")
	)
	(segment
		(start 73.488296 -77.31252)
		(end 73.738486 -77.31252)
		(width 0.1016)
		(layer "F.Cu")
		(net "XDP_SOC_CPU_NODE1_TCK")
	)
	(via
		(at 77.012038 -77.291438)
		(size 0.508)
		(drill 0.254)
		(layers "F.Cu" "B.Cu")
		(net "XDP_SOC_CPU_NODE1_TCK")
	)
	(via
		(at 106.40187 -62.406276)
		(size 0.508)
		(drill 0.254)
		(layers "F.Cu" "B.Cu")
		(net "XDP_SOC_CPU_NODE1_TCK")
	)
	(segment
		(start 85.576664 -75.846686)
		(end 87.875364 -75.846686)
		(width 0.1143)
		(layer "In2.Cu")
		(net "XDP_SOC_CPU_NODE1_TCK")
	)
	(segment
		(start 108.523532 -62.860174)
		(end 106.855768 -62.860174)
		(width 0.1143)
		(layer "In2.Cu")
		(net "XDP_SOC_CPU_NODE1_TCK")
	)
	(segment
		(start 77.815694 -76.766674)
		(end 82.639916 -76.766674)
		(width 0.1143)
		(layer "In2.Cu")
		(net "XDP_SOC_CPU_NODE1_TCK")
	)
	(segment
		(start 90.725244 -74.26071)
		(end 91.694 -75.229466)
		(width 0.1143)
		(layer "In2.Cu")
		(net "XDP_SOC_CPU_NODE1_TCK")
	)
	(segment
		(start 108.447586 -75.83424)
		(end 110.265972 -74.015854)
		(width 0.1143)
		(layer "In2.Cu")
		(net "XDP_SOC_CPU_NODE1_TCK")
	)
	(segment
		(start 102.048056 -76.696316)
		(end 105.286048 -76.696316)
		(width 0.1143)
		(layer "In2.Cu")
		(net "XDP_SOC_CPU_NODE1_TCK")
	)
	(segment
		(start 91.694 -76.984606)
		(end 93.143832 -78.434438)
		(width 0.1143)
		(layer "In2.Cu")
		(net "XDP_SOC_CPU_NODE1_TCK")
	)
	(segment
		(start 100.309934 -78.434438)
		(end 102.048056 -76.696316)
		(width 0.1143)
		(layer "In2.Cu")
		(net "XDP_SOC_CPU_NODE1_TCK")
	)
	(segment
		(start 77.29093 -77.291438)
		(end 77.815694 -76.766674)
		(width 0.1143)
		(layer "In2.Cu")
		(net "XDP_SOC_CPU_NODE1_TCK")
	)
	(segment
		(start 77.012038 -77.291438)
		(end 77.29093 -77.291438)
		(width 0.1143)
		(layer "In2.Cu")
		(net "XDP_SOC_CPU_NODE1_TCK")
	)
	(segment
		(start 108.559092 -62.895734)
		(end 108.523532 -62.860174)
		(width 0.1143)
		(layer "In2.Cu")
		(net "XDP_SOC_CPU_NODE1_TCK")
	)
	(segment
		(start 106.148124 -75.83424)
		(end 108.447586 -75.83424)
		(width 0.1143)
		(layer "In2.Cu")
		(net "XDP_SOC_CPU_NODE1_TCK")
	)
	(segment
		(start 87.875364 -75.846686)
		(end 89.46134 -74.26071)
		(width 0.1143)
		(layer "In2.Cu")
		(net "XDP_SOC_CPU_NODE1_TCK")
	)
	(segment
		(start 83.92414 -75.483212)
		(end 85.21319 -75.483212)
		(width 0.1143)
		(layer "In2.Cu")
		(net "XDP_SOC_CPU_NODE1_TCK")
	)
	(segment
		(start 110.265972 -74.015854)
		(end 110.265972 -64.368934)
		(width 0.1143)
		(layer "In2.Cu")
		(net "XDP_SOC_CPU_NODE1_TCK")
	)
	(segment
		(start 89.46134 -74.26071)
		(end 90.725244 -74.26071)
		(width 0.1143)
		(layer "In2.Cu")
		(net "XDP_SOC_CPU_NODE1_TCK")
	)
	(segment
		(start 110.265972 -64.368934)
		(end 108.792772 -62.895734)
		(width 0.1143)
		(layer "In2.Cu")
		(net "XDP_SOC_CPU_NODE1_TCK")
	)
	(segment
		(start 82.740246 -76.667106)
		(end 83.92414 -75.483212)
		(width 0.1143)
		(layer "In2.Cu")
		(net "XDP_SOC_CPU_NODE1_TCK")
	)
	(segment
		(start 106.855768 -62.860174)
		(end 106.40187 -62.406276)
		(width 0.1143)
		(layer "In2.Cu")
		(net "XDP_SOC_CPU_NODE1_TCK")
	)
	(segment
		(start 85.21319 -75.483212)
		(end 85.576664 -75.846686)
		(width 0.1143)
		(layer "In2.Cu")
		(net "XDP_SOC_CPU_NODE1_TCK")
	)
	(segment
		(start 82.639916 -76.766674)
		(end 82.740246 -76.667106)
		(width 0.1143)
		(layer "In2.Cu")
		(net "XDP_SOC_CPU_NODE1_TCK")
	)
	(segment
		(start 105.286048 -76.696316)
		(end 106.148124 -75.83424)
		(width 0.1143)
		(layer "In2.Cu")
		(net "XDP_SOC_CPU_NODE1_TCK")
	)
	(segment
		(start 91.694 -75.229466)
		(end 91.694 -76.984606)
		(width 0.1143)
		(layer "In2.Cu")
		(net "XDP_SOC_CPU_NODE1_TCK")
	)
	(segment
		(start 93.143832 -78.434438)
		(end 100.309934 -78.434438)
		(width 0.1143)
		(layer "In2.Cu")
		(net "XDP_SOC_CPU_NODE1_TCK")
	)
	(segment
		(start 108.792772 -62.895734)
		(end 108.559092 -62.895734)
		(width 0.1143)
		(layer "In2.Cu")
		(net "XDP_SOC_CPU_NODE1_TCK")
	)
	(via
		(at 40.604694 -9.178036)
		(size 0.508)
		(drill 0.254)
		(layers "F.Cu" "B.Cu")
		(net "SW_PV_VDDR_NODE1_BT")
	)
	(via
		(at 14.219428 -125.613922)
		(size 0.508)
		(drill 0.254)
		(layers "F.Cu" "B.Cu")
		(net "SW_P1V05_NODE1_VIN_FLT")
	)
	(via
		(at 15.541752 -124.362718)
		(size 0.508)
		(drill 0.254)
		(layers "F.Cu" "B.Cu")
		(net "SW_P1V05_NODE1_VIN_FLT")
	)
	(via
		(at 15.584678 -122.781568)
		(size 0.508)
		(drill 0.254)
		(layers "F.Cu" "B.Cu")
		(net "SW_P1V05_NODE1_VIN_FLT")
	)
	(via
		(at 15.584678 -121.384568)
		(size 0.508)
		(drill 0.254)
		(layers "F.Cu" "B.Cu")
		(net "SW_P1V05_NODE1_VIN_FLT")
	)
	(via
		(at 15.584678 -122.146568)
		(size 0.508)
		(drill 0.254)
		(layers "F.Cu" "B.Cu")
		(net "SW_P1V05_NODE1_VIN_FLT")
	)
	(via
		(at 15.541752 -123.727718)
		(size 0.508)
		(drill 0.254)
		(layers "F.Cu" "B.Cu")
		(net "SW_P1V05_NODE1_VIN_FLT")
	)
	(via
		(at 15.541752 -124.997718)
		(size 0.508)
		(drill 0.254)
		(layers "F.Cu" "B.Cu")
		(net "SW_P1V05_NODE1_VIN_FLT")
	)
	(segment
		(start 168.658794 -93.866208)
		(end 168.658794 -95.068644)
		(width 0.1016)
		(layer "F.Cu")
		(net "USB_NODE1_XTA2")
	)
	(segment
		(start 167.369744 -91.326208)
		(end 168.562528 -92.518992)
		(width 0.1016)
		(layer "F.Cu")
		(net "USB_NODE1_XTA2")
	)
	(segment
		(start 168.562528 -92.518992)
		(end 168.562528 -93.141292)
		(width 0.1016)
		(layer "F.Cu")
		(net "USB_NODE1_XTA2")
	)
	(segment
		(start 168.562528 -93.141292)
		(end 168.658794 -93.237558)
		(width 0.1016)
		(layer "F.Cu")
		(net "USB_NODE1_XTA2")
	)
	(segment
		(start 168.843198 -95.253048)
		(end 168.843198 -97.032572)
		(width 0.1016)
		(layer "F.Cu")
		(net "USB_NODE1_XTA2")
	)
	(segment
		(start 168.658794 -93.237558)
		(end 168.658794 -93.866208)
		(width 0.1016)
		(layer "F.Cu")
		(net "USB_NODE1_XTA2")
	)
	(segment
		(start 168.658794 -95.068644)
		(end 168.843198 -95.253048)
		(width 0.1016)
		(layer "F.Cu")
		(net "USB_NODE1_XTA2")
	)
	(via
		(at 168.562528 -93.141292)
		(size 0.508)
		(drill 0.254)
		(layers "F.Cu" "B.Cu")
		(net "USB_NODE1_XTA2")
	)
	(segment
		(start 134.130288 -131.735068)
		(end 134.130288 -132.307076)
		(width 0.127)
		(layer "F.Cu")
		(net "P2E_CPU_USB_NODE1_TX_C_DN")
	)
	(segment
		(start 133.131306 -133.306058)
		(end 132.536438 -133.306058)
		(width 0.127)
		(layer "F.Cu")
		(net "P2E_CPU_USB_NODE1_TX_C_DN")
	)
	(segment
		(start 134.12978 -131.242816)
		(end 134.12978 -131.624832)
		(width 0.127)
		(layer "F.Cu")
		(net "P2E_CPU_USB_NODE1_TX_C_DN")
	)
	(segment
		(start 134.130796 -131.624832)
		(end 134.130796 -131.73456)
		(width 0.127)
		(layer "F.Cu")
		(net "P2E_CPU_USB_NODE1_TX_C_DN")
	)
	(segment
		(start 134.130288 -132.307076)
		(end 133.131306 -133.306058)
		(width 0.127)
		(layer "F.Cu")
		(net "P2E_CPU_USB_NODE1_TX_C_DN")
	)
	(segment
		(start 134.48538 -130.887216)
		(end 134.12978 -131.242816)
		(width 0.127)
		(layer "F.Cu")
		(net "P2E_CPU_USB_NODE1_TX_C_DN")
	)
	(segment
		(start 134.486396 -130.887216)
		(end 134.48538 -130.887216)
		(width 0.127)
		(layer "F.Cu")
		(net "P2E_CPU_USB_NODE1_TX_C_DN")
	)
	(segment
		(start 131.690364 -135.055102)
		(end 131.690364 -134.152132)
		(width 0.127)
		(layer "F.Cu")
		(net "P2E_CPU_USB_NODE1_TX_C_DN")
	)
	(segment
		(start 131.737862 -135.1026)
		(end 131.690364 -135.055102)
		(width 0.127)
		(layer "F.Cu")
		(net "P2E_CPU_USB_NODE1_TX_C_DN")
	)
	(segment
		(start 134.130796 -131.73456)
		(end 134.130288 -131.735068)
		(width 0.127)
		(layer "F.Cu")
		(net "P2E_CPU_USB_NODE1_TX_C_DN")
	)
	(segment
		(start 131.690364 -134.152132)
		(end 132.07619 -133.766306)
		(width 0.127)
		(layer "F.Cu")
		(net "P2E_CPU_USB_NODE1_TX_C_DN")
	)
	(segment
		(start 131.737862 -135.825484)
		(end 131.737862 -135.1026)
		(width 0.127)
		(layer "F.Cu")
		(net "P2E_CPU_USB_NODE1_TX_C_DN")
	)
	(segment
		(start 134.12978 -131.624832)
		(end 134.130796 -131.624832)
		(width 0.127)
		(layer "F.Cu")
		(net "P2E_CPU_USB_NODE1_TX_C_DN")
	)
	(segment
		(start 132.536438 -133.306058)
		(end 132.07619 -133.766306)
		(width 0.127)
		(layer "F.Cu")
		(net "P2E_CPU_USB_NODE1_TX_C_DN")
	)
	(via
		(at 132.07619 -133.766306)
		(size 0.4064)
		(drill 0.2032)
		(layers "F.Cu" "B.Cu")
		(net "P2E_CPU_USB_NODE1_TX_C_DN")
	)
	(segment
		(start 110.460028 -65.906142)
		(end 112.215168 -65.906142)
		(width 0.254)
		(layer "F.Cu")
		(net "P1V05_STB_NODE1_XDP_B")
	)
	(via
		(at 112.215168 -65.906142)
		(size 0.508)
		(drill 0.254)
		(layers "F.Cu" "B.Cu")
		(net "P1V05_STB_NODE1_XDP_B")
	)
	(segment
		(start 58.565796 -87.594186)
		(end 58.565796 -88.137492)
		(width 0.1016)
		(layer "F.Cu")
		(net "TP_CPU1_NODE1_SFRANAD")
	)
	(segment
		(start 58.565796 -88.137492)
		(end 58.202068 -88.50122)
		(width 0.1016)
		(layer "F.Cu")
		(net "TP_CPU1_NODE1_SFRANAD")
	)
	(segment
		(start 58.332878 -89.871804)
		(end 58.018426 -90.186256)
		(width 0.1016)
		(layer "F.Cu")
		(net "TP_CPU1_NODE1_SFRANAD")
	)
	(segment
		(start 58.202068 -88.50122)
		(end 58.202068 -89.321386)
		(width 0.1016)
		(layer "F.Cu")
		(net "TP_CPU1_NODE1_SFRANAD")
	)
	(segment
		(start 58.018426 -90.186256)
		(end 58.018426 -90.64117)
		(width 0.1016)
		(layer "F.Cu")
		(net "TP_CPU1_NODE1_SFRANAD")
	)
	(segment
		(start 58.202068 -89.321386)
		(end 58.332878 -89.452196)
		(width 0.1016)
		(layer "F.Cu")
		(net "TP_CPU1_NODE1_SFRANAD")
	)
	(segment
		(start 58.332878 -89.452196)
		(end 58.332878 -89.871804)
		(width 0.1016)
		(layer "F.Cu")
		(net "TP_CPU1_NODE1_SFRANAD")
	)
	(via
		(at 58.018426 -90.64117)
		(size 0.508)
		(drill 0.254)
		(layers "F.Cu" "B.Cu")
		(net "TP_CPU1_NODE1_SFRANAD")
	)
	(via
		(at 35.542474 -10.373868)
		(size 0.508)
		(drill 0.254)
		(layers "F.Cu" "B.Cu")
		(net "PV_VDDR_NODE1_V1")
	)
	(via
		(at 15.665704 -127.674624)
		(size 0.508)
		(drill 0.254)
		(layers "F.Cu" "B.Cu")
		(net "SW_P1V05_NODE1_DRVL")
	)
	(via
		(at 22.02053 -126.53772)
		(size 0.508)
		(drill 0.254)
		(layers "F.Cu" "B.Cu")
		(net "SW_P1V05_NODE1_DRVL")
	)
	(via
		(at 15.665704 -127.039624)
		(size 0.508)
		(drill 0.254)
		(layers "F.Cu" "B.Cu")
		(net "SW_P1V05_NODE1_DRVL")
	)
	(via
		(at 21.218144 -126.570232)
		(size 0.508)
		(drill 0.254)
		(layers "F.Cu" "B.Cu")
		(net "SW_P1V05_NODE1_DRVL")
	)
	(segment
		(start 74.186796 -75.522074)
		(end 75.780646 -75.522074)
		(width 0.1016)
		(layer "F.Cu")
		(net "XDP_CPU_NODE1_PREQ_L")
	)
	(segment
		(start 72.093328 -77.116178)
		(end 72.422004 -76.787248)
		(width 0.1016)
		(layer "F.Cu")
		(net "XDP_CPU_NODE1_PREQ_L")
	)
	(segment
		(start 72.527414 -76.233274)
		(end 73.402444 -76.233274)
		(width 0.1016)
		(layer "F.Cu")
		(net "XDP_CPU_NODE1_PREQ_L")
	)
	(segment
		(start 81.76006 -73.676002)
		(end 82.408014 -74.323956)
		(width 0.1016)
		(layer "F.Cu")
		(net "XDP_CPU_NODE1_PREQ_L")
	)
	(segment
		(start 72.422004 -76.787248)
		(end 72.422004 -76.338684)
		(width 0.1016)
		(layer "F.Cu")
		(net "XDP_CPU_NODE1_PREQ_L")
	)
	(segment
		(start 104.73182 -75.906122)
		(end 102.52456 -75.906122)
		(width 0.1016)
		(layer "F.Cu")
		(net "XDP_CPU_NODE1_PREQ_L")
	)
	(segment
		(start 73.402444 -76.233274)
		(end 73.565258 -76.07046)
		(width 0.1016)
		(layer "F.Cu")
		(net "XDP_CPU_NODE1_PREQ_L")
	)
	(segment
		(start 72.422004 -76.338684)
		(end 72.527414 -76.233274)
		(width 0.1016)
		(layer "F.Cu")
		(net "XDP_CPU_NODE1_PREQ_L")
	)
	(segment
		(start 82.926936 -73.804526)
		(end 82.408014 -74.323448)
		(width 0.1016)
		(layer "F.Cu")
		(net "XDP_CPU_NODE1_PREQ_L")
	)
	(segment
		(start 85.46973 -73.804526)
		(end 82.926936 -73.804526)
		(width 0.1016)
		(layer "F.Cu")
		(net "XDP_CPU_NODE1_PREQ_L")
	)
	(segment
		(start 73.565258 -76.07046)
		(end 73.63841 -76.07046)
		(width 0.1016)
		(layer "F.Cu")
		(net "XDP_CPU_NODE1_PREQ_L")
	)
	(segment
		(start 101.101652 -74.483214)
		(end 101.101652 -74.313034)
		(width 0.1016)
		(layer "F.Cu")
		(net "XDP_CPU_NODE1_PREQ_L")
	)
	(segment
		(start 102.52456 -75.906122)
		(end 101.101652 -74.483214)
		(width 0.1016)
		(layer "F.Cu")
		(net "XDP_CPU_NODE1_PREQ_L")
	)
	(segment
		(start 75.780646 -75.522074)
		(end 77.626718 -73.676002)
		(width 0.1016)
		(layer "F.Cu")
		(net "XDP_CPU_NODE1_PREQ_L")
	)
	(segment
		(start 73.63841 -76.07046)
		(end 74.186796 -75.522074)
		(width 0.1016)
		(layer "F.Cu")
		(net "XDP_CPU_NODE1_PREQ_L")
	)
	(segment
		(start 77.626718 -73.676002)
		(end 81.76006 -73.676002)
		(width 0.1016)
		(layer "F.Cu")
		(net "XDP_CPU_NODE1_PREQ_L")
	)
	(segment
		(start 72.014334 -77.116178)
		(end 72.093328 -77.116178)
		(width 0.1016)
		(layer "F.Cu")
		(net "XDP_CPU_NODE1_PREQ_L")
	)
	(segment
		(start 82.408014 -74.323448)
		(end 82.408014 -74.323956)
		(width 0.1016)
		(layer "F.Cu")
		(net "XDP_CPU_NODE1_PREQ_L")
	)
	(via
		(at 101.101652 -74.313034)
		(size 0.508)
		(drill 0.254)
		(layers "F.Cu" "B.Cu")
		(net "XDP_CPU_NODE1_PREQ_L")
	)
	(via
		(at 85.46973 -73.804526)
		(size 0.508)
		(drill 0.254)
		(layers "F.Cu" "B.Cu")
		(net "XDP_CPU_NODE1_PREQ_L")
	)
	(segment
		(start 86.421468 -74.75855)
		(end 85.46973 -73.806812)
		(width 0.1143)
		(layer "In2.Cu")
		(net "XDP_CPU_NODE1_PREQ_L")
	)
	(segment
		(start 94.111318 -75.411584)
		(end 92.121228 -73.421494)
		(width 0.1143)
		(layer "In2.Cu")
		(net "XDP_CPU_NODE1_PREQ_L")
	)
	(segment
		(start 87.774272 -74.75855)
		(end 86.421468 -74.75855)
		(width 0.1143)
		(layer "In2.Cu")
		(net "XDP_CPU_NODE1_PREQ_L")
	)
	(segment
		(start 101.101652 -74.313034)
		(end 101.09962 -74.313034)
		(width 0.1143)
		(layer "In2.Cu")
		(net "XDP_CPU_NODE1_PREQ_L")
	)
	(segment
		(start 101.09962 -74.313034)
		(end 101.09962 -76.304394)
		(width 0.1143)
		(layer "In2.Cu")
		(net "XDP_CPU_NODE1_PREQ_L")
	)
	(segment
		(start 97.08642 -77.1906)
		(end 95.307404 -75.411584)
		(width 0.1143)
		(layer "In2.Cu")
		(net "XDP_CPU_NODE1_PREQ_L")
	)
	(segment
		(start 89.111328 -73.421494)
		(end 87.774272 -74.75855)
		(width 0.1143)
		(layer "In2.Cu")
		(net "XDP_CPU_NODE1_PREQ_L")
	)
	(segment
		(start 100.213414 -77.1906)
		(end 97.08642 -77.1906)
		(width 0.1143)
		(layer "In2.Cu")
		(net "XDP_CPU_NODE1_PREQ_L")
	)
	(segment
		(start 92.121228 -73.421494)
		(end 89.111328 -73.421494)
		(width 0.1143)
		(layer "In2.Cu")
		(net "XDP_CPU_NODE1_PREQ_L")
	)
	(segment
		(start 85.46973 -73.806812)
		(end 85.46973 -73.804526)
		(width 0.1143)
		(layer "In2.Cu")
		(net "XDP_CPU_NODE1_PREQ_L")
	)
	(segment
		(start 95.307404 -75.411584)
		(end 94.111318 -75.411584)
		(width 0.1143)
		(layer "In2.Cu")
		(net "XDP_CPU_NODE1_PREQ_L")
	)
	(segment
		(start 101.09962 -76.304394)
		(end 100.213414 -77.1906)
		(width 0.1143)
		(layer "In2.Cu")
		(net "XDP_CPU_NODE1_PREQ_L")
	)
	(segment
		(start 38.082728 -7.693406)
		(end 38.082728 -8.738616)
		(width 0.1778)
		(layer "F.Cu")
		(net "PV_VDDR_NODE1_VID0")
	)
	(segment
		(start 36.627562 -4.204716)
		(end 35.93846 -4.893818)
		(width 0.1016)
		(layer "F.Cu")
		(net "PV_VDDR_NODE1_VID0")
	)
	(segment
		(start 38.11143 -7.664704)
		(end 38.082728 -7.693406)
		(width 0.1778)
		(layer "F.Cu")
		(net "PV_VDDR_NODE1_VID0")
	)
	(segment
		(start 36.627562 -3.851148)
		(end 36.627562 -4.204716)
		(width 0.1016)
		(layer "F.Cu")
		(net "PV_VDDR_NODE1_VID0")
	)
	(segment
		(start 37.224462 -3.851148)
		(end 37.7063 -4.332986)
		(width 0.254)
		(layer "F.Cu")
		(net "PV_VDDR_NODE1_VID0")
	)
	(segment
		(start 38.12159 -6.950964)
		(end 38.250368 -6.950964)
		(width 0.254)
		(layer "F.Cu")
		(net "PV_VDDR_NODE1_VID0")
	)
	(segment
		(start 38.250368 -7.070598)
		(end 38.11143 -7.209536)
		(width 0.254)
		(layer "F.Cu")
		(net "PV_VDDR_NODE1_VID0")
	)
	(segment
		(start 37.7063 -6.535674)
		(end 38.12159 -6.950964)
		(width 0.254)
		(layer "F.Cu")
		(net "PV_VDDR_NODE1_VID0")
	)
	(segment
		(start 38.250368 -6.950964)
		(end 38.250368 -7.070598)
		(width 0.254)
		(layer "F.Cu")
		(net "PV_VDDR_NODE1_VID0")
	)
	(segment
		(start 36.627562 -3.851148)
		(end 37.224462 -3.851148)
		(width 0.254)
		(layer "F.Cu")
		(net "PV_VDDR_NODE1_VID0")
	)
	(segment
		(start 38.11143 -7.209536)
		(end 38.11143 -7.664704)
		(width 0.254)
		(layer "F.Cu")
		(net "PV_VDDR_NODE1_VID0")
	)
	(segment
		(start 37.7063 -4.332986)
		(end 37.7063 -6.535674)
		(width 0.254)
		(layer "F.Cu")
		(net "PV_VDDR_NODE1_VID0")
	)
	(via
		(at 35.93846 -4.893818)
		(size 0.508)
		(drill 0.254)
		(layers "F.Cu" "B.Cu")
		(net "PV_VDDR_NODE1_VID0")
	)
	(segment
		(start 16.099282 -133.709918)
		(end 15.812262 -133.422898)
		(width 0.254)
		(layer "F.Cu")
		(net "VSENSE_P1V05_NODE1_N")
	)
	(segment
		(start 15.812262 -133.422898)
		(end 15.812262 -132.737606)
		(width 0.254)
		(layer "F.Cu")
		(net "VSENSE_P1V05_NODE1_N")
	)
	(segment
		(start 15.812262 -132.737606)
		(end 15.812262 -131.82219)
		(width 0.254)
		(layer "F.Cu")
		(net "VSENSE_P1V05_NODE1_N")
	)
	(segment
		(start 16.099282 -134.725918)
		(end 16.099282 -133.709918)
		(width 0.254)
		(layer "F.Cu")
		(net "VSENSE_P1V05_NODE1_N")
	)
	(via
		(at 58.120534 -69.646038)
		(size 0.508)
		(drill 0.254)
		(layers "F.Cu" "B.Cu")
		(net "VSENSE_P1V05_NODE1_N")
	)
	(via
		(at 27.99842 -91.62669)
		(size 0.508)
		(drill 0.254)
		(layers "F.Cu" "B.Cu")
		(net "VSENSE_P1V05_NODE1_N")
	)
	(via
		(at 15.812262 -132.737606)
		(size 0.508)
		(drill 0.254)
		(layers "F.Cu" "B.Cu")
		(net "VSENSE_P1V05_NODE1_N")
	)
	(segment
		(start 8.34136 -121.862088)
		(end 7.08152 -123.121928)
		(width 0.254)
		(layer "B.Cu")
		(net "VSENSE_P1V05_NODE1_N")
	)
	(segment
		(start 11.142472 -133.685534)
		(end 11.749024 -133.078982)
		(width 0.254)
		(layer "B.Cu")
		(net "VSENSE_P1V05_NODE1_N")
	)
	(segment
		(start 7.08152 -132.114798)
		(end 8.652256 -133.685534)
		(width 0.254)
		(layer "B.Cu")
		(net "VSENSE_P1V05_NODE1_N")
	)
	(segment
		(start 13.287502 -133.078982)
		(end 13.628878 -132.737606)
		(width 0.254)
		(layer "B.Cu")
		(net "VSENSE_P1V05_NODE1_N")
	)
	(segment
		(start 14.068552 -102.763066)
		(end 10.616184 -102.763066)
		(width 0.254)
		(layer "B.Cu")
		(net "VSENSE_P1V05_NODE1_N")
	)
	(segment
		(start 57.840372 -69.9262)
		(end 58.120534 -69.646038)
		(width 0.254)
		(layer "B.Cu")
		(net "VSENSE_P1V05_NODE1_N")
	)
	(segment
		(start 27.88412 -91.74099)
		(end 21.18233 -91.74099)
		(width 0.254)
		(layer "B.Cu")
		(net "VSENSE_P1V05_NODE1_N")
	)
	(segment
		(start 7.08152 -123.121928)
		(end 7.08152 -132.114798)
		(width 0.254)
		(layer "B.Cu")
		(net "VSENSE_P1V05_NODE1_N")
	)
	(segment
		(start 10.616184 -102.763066)
		(end 8.34136 -105.03789)
		(width 0.254)
		(layer "B.Cu")
		(net "VSENSE_P1V05_NODE1_N")
	)
	(segment
		(start 57.840372 -70.570852)
		(end 57.840372 -69.9262)
		(width 0.254)
		(layer "B.Cu")
		(net "VSENSE_P1V05_NODE1_N")
	)
	(segment
		(start 27.99842 -91.62669)
		(end 27.88412 -91.74099)
		(width 0.254)
		(layer "B.Cu")
		(net "VSENSE_P1V05_NODE1_N")
	)
	(segment
		(start 21.18233 -91.74099)
		(end 16.256 -96.66732)
		(width 0.254)
		(layer "B.Cu")
		(net "VSENSE_P1V05_NODE1_N")
	)
	(segment
		(start 8.34136 -105.03789)
		(end 8.34136 -121.862088)
		(width 0.254)
		(layer "B.Cu")
		(net "VSENSE_P1V05_NODE1_N")
	)
	(segment
		(start 16.256 -96.66732)
		(end 16.256 -100.575618)
		(width 0.254)
		(layer "B.Cu")
		(net "VSENSE_P1V05_NODE1_N")
	)
	(segment
		(start 11.749024 -133.078982)
		(end 13.287502 -133.078982)
		(width 0.254)
		(layer "B.Cu")
		(net "VSENSE_P1V05_NODE1_N")
	)
	(segment
		(start 16.256 -100.575618)
		(end 14.068552 -102.763066)
		(width 0.254)
		(layer "B.Cu")
		(net "VSENSE_P1V05_NODE1_N")
	)
	(segment
		(start 13.628878 -132.737606)
		(end 15.812262 -132.737606)
		(width 0.254)
		(layer "B.Cu")
		(net "VSENSE_P1V05_NODE1_N")
	)
	(segment
		(start 8.652256 -133.685534)
		(end 11.142472 -133.685534)
		(width 0.254)
		(layer "B.Cu")
		(net "VSENSE_P1V05_NODE1_N")
	)
	(segment
		(start 51.062128 -72.043544)
		(end 50.451258 -71.432674)
		(width 0.254)
		(layer "In2.Cu")
		(net "VSENSE_P1V05_NODE1_N")
	)
	(segment
		(start 58.120534 -69.956934)
		(end 57.84977 -70.227698)
		(width 0.254)
		(layer "In2.Cu")
		(net "VSENSE_P1V05_NODE1_N")
	)
	(segment
		(start 28.095448 -91.723718)
		(end 27.99842 -91.62669)
		(width 0.254)
		(layer "In2.Cu")
		(net "VSENSE_P1V05_NODE1_N")
	)
	(segment
		(start 56.668162 -70.227698)
		(end 56.201056 -70.694804)
		(width 0.254)
		(layer "In2.Cu")
		(net "VSENSE_P1V05_NODE1_N")
	)
	(segment
		(start 50.451258 -71.432674)
		(end 39.899082 -71.432674)
		(width 0.254)
		(layer "In2.Cu")
		(net "VSENSE_P1V05_NODE1_N")
	)
	(segment
		(start 56.201056 -70.694804)
		(end 56.201056 -71.625968)
		(width 0.254)
		(layer "In2.Cu")
		(net "VSENSE_P1V05_NODE1_N")
	)
	(segment
		(start 58.120534 -69.646038)
		(end 58.120534 -69.956934)
		(width 0.254)
		(layer "In2.Cu")
		(net "VSENSE_P1V05_NODE1_N")
	)
	(segment
		(start 57.84977 -70.227698)
		(end 56.668162 -70.227698)
		(width 0.254)
		(layer "In2.Cu")
		(net "VSENSE_P1V05_NODE1_N")
	)
	(segment
		(start 56.201056 -71.625968)
		(end 55.78348 -72.043544)
		(width 0.254)
		(layer "In2.Cu")
		(net "VSENSE_P1V05_NODE1_N")
	)
	(segment
		(start 39.050468 -72.281288)
		(end 34.327592 -72.281288)
		(width 0.254)
		(layer "In2.Cu")
		(net "VSENSE_P1V05_NODE1_N")
	)
	(segment
		(start 34.327592 -72.281288)
		(end 31.9278 -74.68108)
		(width 0.254)
		(layer "In2.Cu")
		(net "VSENSE_P1V05_NODE1_N")
	)
	(segment
		(start 31.9278 -74.68108)
		(end 31.9278 -89.084658)
		(width 0.254)
		(layer "In2.Cu")
		(net "VSENSE_P1V05_NODE1_N")
	)
	(segment
		(start 39.899082 -71.432674)
		(end 39.050468 -72.281288)
		(width 0.254)
		(layer "In2.Cu")
		(net "VSENSE_P1V05_NODE1_N")
	)
	(segment
		(start 29.28874 -91.723718)
		(end 28.095448 -91.723718)
		(width 0.254)
		(layer "In2.Cu")
		(net "VSENSE_P1V05_NODE1_N")
	)
	(segment
		(start 55.78348 -72.043544)
		(end 51.062128 -72.043544)
		(width 0.254)
		(layer "In2.Cu")
		(net "VSENSE_P1V05_NODE1_N")
	)
	(segment
		(start 31.9278 -89.084658)
		(end 29.28874 -91.723718)
		(width 0.254)
		(layer "In2.Cu")
		(net "VSENSE_P1V05_NODE1_N")
	)
	(segment
		(start 163.312602 -88.84539)
		(end 163.30422 -88.853772)
		(width 0.1016)
		(layer "F.Cu")
		(net "SPI_USB_NODE1_HOLD_L")
	)
	(segment
		(start 163.30422 -88.853772)
		(end 162.518852 -88.853772)
		(width 0.1016)
		(layer "F.Cu")
		(net "SPI_USB_NODE1_HOLD_L")
	)
	(segment
		(start 161.14776 -88.853772)
		(end 162.518852 -88.853772)
		(width 0.1016)
		(layer "F.Cu")
		(net "SPI_USB_NODE1_HOLD_L")
	)
	(via
		(at 162.518852 -88.853772)
		(size 0.508)
		(drill 0.254)
		(layers "F.Cu" "B.Cu")
		(net "SPI_USB_NODE1_HOLD_L")
	)
	(segment
		(start 104.73182 -75.40625)
		(end 102.961948 -75.40625)
		(width 0.1016)
		(layer "F.Cu")
		(net "XDP_CPU_NODE1_PRDY_L")
	)
	(segment
		(start 102.961948 -75.40625)
		(end 102.521512 -74.965814)
		(width 0.1016)
		(layer "F.Cu")
		(net "XDP_CPU_NODE1_PRDY_L")
	)
	(segment
		(start 79.584042 -75.146154)
		(end 77.51191 -75.146154)
		(width 0.1016)
		(layer "F.Cu")
		(net "XDP_CPU_NODE1_PRDY_L")
	)
	(segment
		(start 102.521512 -74.965814)
		(end 102.521512 -74.219054)
		(width 0.1016)
		(layer "F.Cu")
		(net "XDP_CPU_NODE1_PRDY_L")
	)
	(segment
		(start 77.51191 -75.146154)
		(end 76.511404 -76.14666)
		(width 0.1016)
		(layer "F.Cu")
		(net "XDP_CPU_NODE1_PRDY_L")
	)
	(segment
		(start 76.511404 -76.14666)
		(end 76.511404 -76.161646)
		(width 0.1016)
		(layer "F.Cu")
		(net "XDP_CPU_NODE1_PRDY_L")
	)
	(segment
		(start 76.511404 -76.161646)
		(end 76.251054 -76.421996)
		(width 0.1016)
		(layer "F.Cu")
		(net "XDP_CPU_NODE1_PRDY_L")
	)
	(segment
		(start 67.154044 -78.255622)
		(end 67.156838 -78.255622)
		(width 0.1016)
		(layer "F.Cu")
		(net "XDP_CPU_NODE1_PRDY_L")
	)
	(segment
		(start 67.156838 -78.255622)
		(end 67.549776 -78.64856)
		(width 0.1016)
		(layer "F.Cu")
		(net "XDP_CPU_NODE1_PRDY_L")
	)
	(via
		(at 76.251054 -76.421996)
		(size 0.508)
		(drill 0.254)
		(layers "F.Cu" "B.Cu")
		(net "XDP_CPU_NODE1_PRDY_L")
	)
	(via
		(at 67.549776 -78.64856)
		(size 0.508)
		(drill 0.254)
		(layers "F.Cu" "B.Cu")
		(net "XDP_CPU_NODE1_PRDY_L")
	)
	(via
		(at 102.521512 -74.219054)
		(size 0.508)
		(drill 0.254)
		(layers "F.Cu" "B.Cu")
		(net "XDP_CPU_NODE1_PRDY_L")
	)
	(segment
		(start 100.959666 -73.582784)
		(end 100.48494 -74.05751)
		(width 0.1143)
		(layer "In2.Cu")
		(net "XDP_CPU_NODE1_PRDY_L")
	)
	(segment
		(start 76.251054 -76.495148)
		(end 76.251054 -76.421996)
		(width 0.1143)
		(layer "In2.Cu")
		(net "XDP_CPU_NODE1_PRDY_L")
	)
	(segment
		(start 83.238086 -74.687684)
		(end 82.038952 -75.886818)
		(width 0.1143)
		(layer "In2.Cu")
		(net "XDP_CPU_NODE1_PRDY_L")
	)
	(segment
		(start 85.791294 -73.133712)
		(end 84.792058 -73.133712)
		(width 0.1143)
		(layer "In2.Cu")
		(net "XDP_CPU_NODE1_PRDY_L")
	)
	(segment
		(start 101.885242 -73.582784)
		(end 100.959666 -73.582784)
		(width 0.1143)
		(layer "In2.Cu")
		(net "XDP_CPU_NODE1_PRDY_L")
	)
	(segment
		(start 76.448666 -76.224384)
		(end 76.251054 -76.421996)
		(width 0.1143)
		(layer "In2.Cu")
		(net "XDP_CPU_NODE1_PRDY_L")
	)
	(segment
		(start 100.48494 -75.787758)
		(end 99.879912 -76.392786)
		(width 0.1143)
		(layer "In2.Cu")
		(net "XDP_CPU_NODE1_PRDY_L")
	)
	(segment
		(start 71.08952 -77.597508)
		(end 71.834248 -77.597508)
		(width 0.1143)
		(layer "In2.Cu")
		(net "XDP_CPU_NODE1_PRDY_L")
	)
	(segment
		(start 84.071968 -73.854056)
		(end 83.238086 -74.687684)
		(width 0.1143)
		(layer "In2.Cu")
		(net "XDP_CPU_NODE1_PRDY_L")
	)
	(segment
		(start 82.038952 -75.886818)
		(end 77.93736 -75.886818)
		(width 0.1143)
		(layer "In2.Cu")
		(net "XDP_CPU_NODE1_PRDY_L")
	)
	(segment
		(start 75.849734 -76.896468)
		(end 76.251054 -76.495148)
		(width 0.1143)
		(layer "In2.Cu")
		(net "XDP_CPU_NODE1_PRDY_L")
	)
	(segment
		(start 88.419178 -73.349866)
		(end 86.007448 -73.349866)
		(width 0.1143)
		(layer "In2.Cu")
		(net "XDP_CPU_NODE1_PRDY_L")
	)
	(segment
		(start 71.834248 -77.597508)
		(end 72.535288 -76.896468)
		(width 0.1143)
		(layer "In2.Cu")
		(net "XDP_CPU_NODE1_PRDY_L")
	)
	(segment
		(start 95.482156 -74.991468)
		(end 94.284038 -74.991468)
		(width 0.1143)
		(layer "In2.Cu")
		(net "XDP_CPU_NODE1_PRDY_L")
	)
	(segment
		(start 102.521512 -74.219054)
		(end 101.885242 -73.582784)
		(width 0.1143)
		(layer "In2.Cu")
		(net "XDP_CPU_NODE1_PRDY_L")
	)
	(segment
		(start 77.93736 -75.886818)
		(end 77.599794 -76.224384)
		(width 0.1143)
		(layer "In2.Cu")
		(net "XDP_CPU_NODE1_PRDY_L")
	)
	(segment
		(start 72.535288 -76.896468)
		(end 75.849734 -76.896468)
		(width 0.1143)
		(layer "In2.Cu")
		(net "XDP_CPU_NODE1_PRDY_L")
	)
	(segment
		(start 100.48494 -74.05751)
		(end 100.48494 -75.787758)
		(width 0.1143)
		(layer "In2.Cu")
		(net "XDP_CPU_NODE1_PRDY_L")
	)
	(segment
		(start 67.549776 -78.64856)
		(end 67.549776 -78.370176)
		(width 0.1143)
		(layer "In2.Cu")
		(net "XDP_CPU_NODE1_PRDY_L")
	)
	(segment
		(start 99.879912 -76.392786)
		(end 96.883474 -76.392786)
		(width 0.1143)
		(layer "In2.Cu")
		(net "XDP_CPU_NODE1_PRDY_L")
	)
	(segment
		(start 86.007448 -73.349866)
		(end 85.791294 -73.133712)
		(width 0.1143)
		(layer "In2.Cu")
		(net "XDP_CPU_NODE1_PRDY_L")
	)
	(segment
		(start 70.764146 -77.922882)
		(end 71.08952 -77.597508)
		(width 0.1143)
		(layer "In2.Cu")
		(net "XDP_CPU_NODE1_PRDY_L")
	)
	(segment
		(start 77.599794 -76.224384)
		(end 76.448666 -76.224384)
		(width 0.1143)
		(layer "In2.Cu")
		(net "XDP_CPU_NODE1_PRDY_L")
	)
	(segment
		(start 67.99707 -77.922882)
		(end 70.764146 -77.922882)
		(width 0.1143)
		(layer "In2.Cu")
		(net "XDP_CPU_NODE1_PRDY_L")
	)
	(segment
		(start 88.767666 -73.001378)
		(end 88.419178 -73.349866)
		(width 0.1143)
		(layer "In2.Cu")
		(net "XDP_CPU_NODE1_PRDY_L")
	)
	(segment
		(start 84.071968 -73.853802)
		(end 84.071968 -73.854056)
		(width 0.1143)
		(layer "In2.Cu")
		(net "XDP_CPU_NODE1_PRDY_L")
	)
	(segment
		(start 92.293948 -73.001378)
		(end 88.767666 -73.001378)
		(width 0.1143)
		(layer "In2.Cu")
		(net "XDP_CPU_NODE1_PRDY_L")
	)
	(segment
		(start 67.549776 -78.370176)
		(end 67.99707 -77.922882)
		(width 0.1143)
		(layer "In2.Cu")
		(net "XDP_CPU_NODE1_PRDY_L")
	)
	(segment
		(start 84.792058 -73.133712)
		(end 84.071968 -73.853802)
		(width 0.1143)
		(layer "In2.Cu")
		(net "XDP_CPU_NODE1_PRDY_L")
	)
	(segment
		(start 94.284038 -74.991468)
		(end 92.293948 -73.001378)
		(width 0.1143)
		(layer "In2.Cu")
		(net "XDP_CPU_NODE1_PRDY_L")
	)
	(segment
		(start 96.883474 -76.392786)
		(end 95.482156 -74.991468)
		(width 0.1143)
		(layer "In2.Cu")
		(net "XDP_CPU_NODE1_PRDY_L")
	)
	(segment
		(start 37.15512 -13.028676)
		(end 36.704524 -13.028676)
		(width 0.254)
		(layer "F.Cu")
		(net "PV_VDDR_NODE1_SLEW")
	)
	(segment
		(start 37.682678 -11.86434)
		(end 37.682678 -12.501118)
		(width 0.1778)
		(layer "F.Cu")
		(net "PV_VDDR_NODE1_SLEW")
	)
	(segment
		(start 36.88334 -13.537184)
		(end 36.539678 -13.193522)
		(width 0.254)
		(layer "F.Cu")
		(net "PV_VDDR_NODE1_SLEW")
	)
	(segment
		(start 36.88334 -13.84554)
		(end 36.88334 -13.537184)
		(width 0.254)
		(layer "F.Cu")
		(net "PV_VDDR_NODE1_SLEW")
	)
	(segment
		(start 37.682678 -12.501118)
		(end 37.15512 -13.028676)
		(width 0.1778)
		(layer "F.Cu")
		(net "PV_VDDR_NODE1_SLEW")
	)
	(segment
		(start 36.704524 -13.028676)
		(end 36.539678 -13.193522)
		(width 0.254)
		(layer "F.Cu")
		(net "PV_VDDR_NODE1_SLEW")
	)
	(via
		(at 36.539678 -13.193522)
		(size 0.508)
		(drill 0.254)
		(layers "F.Cu" "B.Cu")
		(net "PV_VDDR_NODE1_SLEW")
	)
	(segment
		(start 64.722502 -107.719876)
		(end 64.722502 -108.462572)
		(width 0.1016)
		(layer "F.Cu")
		(net "FM_CPLD_NODE1_P1V8_EN_G")
	)
	(segment
		(start 64.722502 -109.33303)
		(end 64.722502 -108.462572)
		(width 0.1016)
		(layer "F.Cu")
		(net "FM_CPLD_NODE1_P1V8_EN_G")
	)
	(segment
		(start 64.718692 -107.716066)
		(end 64.722502 -107.719876)
		(width 0.1016)
		(layer "F.Cu")
		(net "FM_CPLD_NODE1_P1V8_EN_G")
	)
	(via
		(at 64.722502 -108.462572)
		(size 0.508)
		(drill 0.254)
		(layers "F.Cu" "B.Cu")
		(net "FM_CPLD_NODE1_P1V8_EN_G")
	)
	(segment
		(start 122.894852 -142.22095)
		(end 122.894852 -142.531592)
		(width 0.127)
		(layer "F.Cu")
		(net "P2E_CPU_BMC_NODE1_TX_C_DN")
	)
	(segment
		(start 125.787912 -142.575534)
		(end 125.074172 -142.575534)
		(width 0.127)
		(layer "F.Cu")
		(net "P2E_CPU_BMC_NODE1_TX_C_DN")
	)
	(segment
		(start 125.074172 -142.575534)
		(end 125.024388 -142.52575)
		(width 0.127)
		(layer "F.Cu")
		(net "P2E_CPU_BMC_NODE1_TX_C_DN")
	)
	(segment
		(start 125.024388 -142.52575)
		(end 124.29236 -142.52575)
		(width 0.127)
		(layer "F.Cu")
		(net "P2E_CPU_BMC_NODE1_TX_C_DN")
	)
	(segment
		(start 123.78436 -142.01775)
		(end 123.098052 -142.01775)
		(width 0.127)
		(layer "F.Cu")
		(net "P2E_CPU_BMC_NODE1_TX_C_DN")
	)
	(segment
		(start 123.098052 -142.01775)
		(end 122.894852 -142.22095)
		(width 0.127)
		(layer "F.Cu")
		(net "P2E_CPU_BMC_NODE1_TX_C_DN")
	)
	(segment
		(start 124.29236 -142.52575)
		(end 123.78436 -142.01775)
		(width 0.127)
		(layer "F.Cu")
		(net "P2E_CPU_BMC_NODE1_TX_C_DN")
	)
	(via
		(at 122.894852 -142.531592)
		(size 0.508)
		(drill 0.254)
		(layers "F.Cu" "B.Cu")
		(net "P2E_CPU_BMC_NODE1_TX_C_DN")
	)
	(segment
		(start 122.412252 -142.048992)
		(end 122.894852 -142.531592)
		(width 0.127)
		(layer "B.Cu")
		(net "P2E_CPU_BMC_NODE1_TX_C_DN")
	)
	(segment
		(start 121.80189 -142.404592)
		(end 122.15749 -142.048992)
		(width 0.127)
		(layer "B.Cu")
		(net "P2E_CPU_BMC_NODE1_TX_C_DN")
	)
	(segment
		(start 122.15749 -142.048992)
		(end 122.412252 -142.048992)
		(width 0.127)
		(layer "B.Cu")
		(net "P2E_CPU_BMC_NODE1_TX_C_DN")
	)
	(segment
		(start 104.73182 -66.90614)
		(end 106.246676 -66.90614)
		(width 0.1016)
		(layer "F.Cu")
		(net "XDP_CPU_NODE1_PWROK_R")
	)
	(segment
		(start 106.246676 -66.90614)
		(end 106.31805 -66.977514)
		(width 0.1016)
		(layer "F.Cu")
		(net "XDP_CPU_NODE1_PWROK_R")
	)
	(via
		(at 106.31805 -66.977514)
		(size 0.508)
		(drill 0.254)
		(layers "F.Cu" "B.Cu")
		(net "XDP_CPU_NODE1_PWROK_R")
	)
	(via
		(at 105.980992 -67.640454)
		(size 0.6604)
		(drill 0.3302)
		(layers "F.Cu" "B.Cu")
		(net "XDP_CPU_NODE1_PWROK_R")
	)
	(segment
		(start 104.808274 -66.164206)
		(end 105.038144 -66.164206)
		(width 0.1016)
		(layer "B.Cu")
		(net "XDP_CPU_NODE1_PWROK_R")
	)
	(segment
		(start 105.302812 -66.428874)
		(end 105.302812 -66.962274)
		(width 0.1016)
		(layer "B.Cu")
		(net "XDP_CPU_NODE1_PWROK_R")
	)
	(segment
		(start 106.31805 -67.303396)
		(end 106.31805 -66.977514)
		(width 0.1016)
		(layer "B.Cu")
		(net "XDP_CPU_NODE1_PWROK_R")
	)
	(segment
		(start 105.980992 -67.640454)
		(end 106.31805 -67.303396)
		(width 0.1016)
		(layer "B.Cu")
		(net "XDP_CPU_NODE1_PWROK_R")
	)
	(segment
		(start 105.038144 -66.164206)
		(end 105.302812 -66.428874)
		(width 0.1016)
		(layer "B.Cu")
		(net "XDP_CPU_NODE1_PWROK_R")
	)
	(segment
		(start 105.302812 -66.962274)
		(end 105.980992 -67.640454)
		(width 0.1016)
		(layer "B.Cu")
		(net "XDP_CPU_NODE1_PWROK_R")
	)
	(segment
		(start 40.344598 -69.785484)
		(end 38.681406 -69.785484)
		(width 0.1016)
		(layer "F.Cu")
		(net "TP_CPU_NODE1_RP0_PERP7")
	)
	(segment
		(start 38.681406 -69.785484)
		(end 37.6809 -70.78599)
		(width 0.1016)
		(layer "F.Cu")
		(net "TP_CPU_NODE1_RP0_PERP7")
	)
	(segment
		(start 41.011856 -69.118226)
		(end 40.344598 -69.785484)
		(width 0.1016)
		(layer "F.Cu")
		(net "TP_CPU_NODE1_RP0_PERP7")
	)
	(segment
		(start 42.359834 -69.404738)
		(end 42.337736 -69.404738)
		(width 0.1016)
		(layer "F.Cu")
		(net "TP_CPU_NODE1_RP0_PERP7")
	)
	(segment
		(start 42.337736 -69.404738)
		(end 42.051224 -69.118226)
		(width 0.1016)
		(layer "F.Cu")
		(net "TP_CPU_NODE1_RP0_PERP7")
	)
	(segment
		(start 37.6809 -70.78599)
		(end 37.6809 -71.569326)
		(width 0.1016)
		(layer "F.Cu")
		(net "TP_CPU_NODE1_RP0_PERP7")
	)
	(segment
		(start 42.051224 -69.118226)
		(end 41.011856 -69.118226)
		(width 0.1016)
		(layer "F.Cu")
		(net "TP_CPU_NODE1_RP0_PERP7")
	)
	(via
		(at 37.6809 -71.569326)
		(size 0.508)
		(drill 0.254)
		(layers "F.Cu" "B.Cu")
		(net "TP_CPU_NODE1_RP0_PERP7")
	)
	(segment
		(start 35.85464 -13.83792)
		(end 35.85464 -12.71143)
		(width 0.254)
		(layer "F.Cu")
		(net "VSENSE_PV_VDDR_NODE1_P")
	)
	(segment
		(start 37.0205 -12.472162)
		(end 37.282628 -12.210034)
		(width 0.1778)
		(layer "F.Cu")
		(net "VSENSE_PV_VDDR_NODE1_P")
	)
	(segment
		(start 37.282628 -12.210034)
		(end 37.282628 -11.86434)
		(width 0.1778)
		(layer "F.Cu")
		(net "VSENSE_PV_VDDR_NODE1_P")
	)
	(segment
		(start 34.93516 -14.278356)
		(end 35.375596 -13.83792)
		(width 0.254)
		(layer "F.Cu")
		(net "VSENSE_PV_VDDR_NODE1_P")
	)
	(segment
		(start 35.85464 -12.71143)
		(end 36.093908 -12.472162)
		(width 0.254)
		(layer "F.Cu")
		(net "VSENSE_PV_VDDR_NODE1_P")
	)
	(segment
		(start 35.375596 -13.83792)
		(end 35.85464 -13.83792)
		(width 0.254)
		(layer "F.Cu")
		(net "VSENSE_PV_VDDR_NODE1_P")
	)
	(segment
		(start 36.093908 -12.472162)
		(end 37.0205 -12.472162)
		(width 0.254)
		(layer "F.Cu")
		(net "VSENSE_PV_VDDR_NODE1_P")
	)
	(segment
		(start 34.93516 -14.79677)
		(end 34.93516 -14.278356)
		(width 0.254)
		(layer "F.Cu")
		(net "VSENSE_PV_VDDR_NODE1_P")
	)
	(via
		(at 107.09656 -56.744362)
		(size 0.508)
		(drill 0.254)
		(layers "F.Cu" "B.Cu")
		(net "VSENSE_PV_VDDR_NODE1_P")
	)
	(via
		(at 34.93516 -14.79677)
		(size 0.508)
		(drill 0.254)
		(layers "F.Cu" "B.Cu")
		(net "VSENSE_PV_VDDR_NODE1_P")
	)
	(segment
		(start 80.03413 -57.176162)
		(end 74.229722 -62.98057)
		(width 0.254)
		(layer "B.Cu")
		(net "VSENSE_PV_VDDR_NODE1_P")
	)
	(segment
		(start 73.942956 -62.98057)
		(end 73.649586 -62.6872)
		(width 0.254)
		(layer "B.Cu")
		(net "VSENSE_PV_VDDR_NODE1_P")
	)
	(segment
		(start 106.66476 -57.176162)
		(end 80.03413 -57.176162)
		(width 0.254)
		(layer "B.Cu")
		(net "VSENSE_PV_VDDR_NODE1_P")
	)
	(segment
		(start 74.229722 -62.98057)
		(end 73.942956 -62.98057)
		(width 0.254)
		(layer "B.Cu")
		(net "VSENSE_PV_VDDR_NODE1_P")
	)
	(segment
		(start 107.09656 -56.744362)
		(end 106.66476 -57.176162)
		(width 0.254)
		(layer "B.Cu")
		(net "VSENSE_PV_VDDR_NODE1_P")
	)
	(segment
		(start 107.52836 -57.176162)
		(end 107.09656 -56.744362)
		(width 0.254)
		(layer "In7.Cu")
		(net "VSENSE_PV_VDDR_NODE1_P")
	)
	(segment
		(start 96.68637 -20.864322)
		(end 103.515922 -20.864322)
		(width 0.254)
		(layer "In7.Cu")
		(net "VSENSE_PV_VDDR_NODE1_P")
	)
	(segment
		(start 92.2147 -18.794222)
		(end 94.61627 -18.794222)
		(width 0.254)
		(layer "In7.Cu")
		(net "VSENSE_PV_VDDR_NODE1_P")
	)
	(segment
		(start 65.019682 -18.967958)
		(end 66.290698 -17.696942)
		(width 0.254)
		(layer "In7.Cu")
		(net "VSENSE_PV_VDDR_NODE1_P")
	)
	(segment
		(start 37.483542 -17.914112)
		(end 42.879518 -17.914112)
		(width 0.254)
		(layer "In7.Cu")
		(net "VSENSE_PV_VDDR_NODE1_P")
	)
	(segment
		(start 43.933364 -18.967958)
		(end 65.019682 -18.967958)
		(width 0.254)
		(layer "In7.Cu")
		(net "VSENSE_PV_VDDR_NODE1_P")
	)
	(segment
		(start 103.515922 -20.864322)
		(end 107.23626 -24.58466)
		(width 0.254)
		(layer "In7.Cu")
		(net "VSENSE_PV_VDDR_NODE1_P")
	)
	(segment
		(start 94.61627 -18.794222)
		(end 96.68637 -20.864322)
		(width 0.254)
		(layer "In7.Cu")
		(net "VSENSE_PV_VDDR_NODE1_P")
	)
	(segment
		(start 107.23626 -29.575252)
		(end 108.4961 -30.835092)
		(width 0.254)
		(layer "In7.Cu")
		(net "VSENSE_PV_VDDR_NODE1_P")
	)
	(segment
		(start 42.879518 -17.914112)
		(end 43.933364 -18.967958)
		(width 0.254)
		(layer "In7.Cu")
		(net "VSENSE_PV_VDDR_NODE1_P")
	)
	(segment
		(start 108.4961 -30.835092)
		(end 108.4961 -56.548782)
		(width 0.254)
		(layer "In7.Cu")
		(net "VSENSE_PV_VDDR_NODE1_P")
	)
	(segment
		(start 107.23626 -24.58466)
		(end 107.23626 -29.575252)
		(width 0.254)
		(layer "In7.Cu")
		(net "VSENSE_PV_VDDR_NODE1_P")
	)
	(segment
		(start 91.11742 -17.696942)
		(end 92.2147 -18.794222)
		(width 0.254)
		(layer "In7.Cu")
		(net "VSENSE_PV_VDDR_NODE1_P")
	)
	(segment
		(start 108.4961 -56.548782)
		(end 107.86872 -57.176162)
		(width 0.254)
		(layer "In7.Cu")
		(net "VSENSE_PV_VDDR_NODE1_P")
	)
	(segment
		(start 66.290698 -17.696942)
		(end 91.11742 -17.696942)
		(width 0.254)
		(layer "In7.Cu")
		(net "VSENSE_PV_VDDR_NODE1_P")
	)
	(segment
		(start 34.93516 -15.36573)
		(end 37.483542 -17.914112)
		(width 0.254)
		(layer "In7.Cu")
		(net "VSENSE_PV_VDDR_NODE1_P")
	)
	(segment
		(start 34.93516 -14.79677)
		(end 34.93516 -15.36573)
		(width 0.254)
		(layer "In7.Cu")
		(net "VSENSE_PV_VDDR_NODE1_P")
	)
	(segment
		(start 107.86872 -57.176162)
		(end 107.52836 -57.176162)
		(width 0.254)
		(layer "In7.Cu")
		(net "VSENSE_PV_VDDR_NODE1_P")
	)
	(segment
		(start 169.636694 -94.91853)
		(end 169.243248 -95.311976)
		(width 0.1016)
		(layer "F.Cu")
		(net "USB_NODE1_XTA1")
	)
	(segment
		(start 169.636694 -92.970858)
		(end 169.636694 -93.866208)
		(width 0.1016)
		(layer "F.Cu")
		(net "USB_NODE1_XTA1")
	)
	(segment
		(start 169.90695 -92.700602)
		(end 169.636694 -92.970858)
		(width 0.1016)
		(layer "F.Cu")
		(net "USB_NODE1_XTA1")
	)
	(segment
		(start 169.636694 -93.866208)
		(end 169.636694 -94.91853)
		(width 0.1016)
		(layer "F.Cu")
		(net "USB_NODE1_XTA1")
	)
	(segment
		(start 169.90695 -92.681298)
		(end 169.90695 -92.700602)
		(width 0.1016)
		(layer "F.Cu")
		(net "USB_NODE1_XTA1")
	)
	(segment
		(start 169.243248 -95.311976)
		(end 169.243248 -97.032572)
		(width 0.1016)
		(layer "F.Cu")
		(net "USB_NODE1_XTA1")
	)
	(segment
		(start 169.90695 -92.589096)
		(end 169.90695 -92.681298)
		(width 0.1016)
		(layer "F.Cu")
		(net "USB_NODE1_XTA1")
	)
	(segment
		(start 171.169838 -91.326208)
		(end 169.90695 -92.589096)
		(width 0.1016)
		(layer "F.Cu")
		(net "USB_NODE1_XTA1")
	)
	(via
		(at 169.90695 -92.681298)
		(size 0.508)
		(drill 0.254)
		(layers "F.Cu" "B.Cu")
		(net "USB_NODE1_XTA1")
	)
	(segment
		(start 123.910852 -141.71295)
		(end 123.038362 -141.71295)
		(width 0.127)
		(layer "F.Cu")
		(net "P2E_CPU_BMC_NODE1_TX_C_DP")
	)
	(segment
		(start 125.021086 -142.22095)
		(end 124.418852 -142.22095)
		(width 0.127)
		(layer "F.Cu")
		(net "P2E_CPU_BMC_NODE1_TX_C_DP")
	)
	(segment
		(start 122.894852 -141.56944)
		(end 122.894852 -141.261592)
		(width 0.127)
		(layer "F.Cu")
		(net "P2E_CPU_BMC_NODE1_TX_C_DP")
	)
	(segment
		(start 124.418852 -142.22095)
		(end 123.910852 -141.71295)
		(width 0.127)
		(layer "F.Cu")
		(net "P2E_CPU_BMC_NODE1_TX_C_DP")
	)
	(segment
		(start 125.787912 -142.175484)
		(end 125.066552 -142.175484)
		(width 0.127)
		(layer "F.Cu")
		(net "P2E_CPU_BMC_NODE1_TX_C_DP")
	)
	(segment
		(start 125.066552 -142.175484)
		(end 125.021086 -142.22095)
		(width 0.127)
		(layer "F.Cu")
		(net "P2E_CPU_BMC_NODE1_TX_C_DP")
	)
	(segment
		(start 123.038362 -141.71295)
		(end 122.894852 -141.56944)
		(width 0.127)
		(layer "F.Cu")
		(net "P2E_CPU_BMC_NODE1_TX_C_DP")
	)
	(via
		(at 122.894852 -141.261592)
		(size 0.508)
		(drill 0.254)
		(layers "F.Cu" "B.Cu")
		(net "P2E_CPU_BMC_NODE1_TX_C_DP")
	)
	(segment
		(start 122.412252 -141.744192)
		(end 122.894852 -141.261592)
		(width 0.127)
		(layer "B.Cu")
		(net "P2E_CPU_BMC_NODE1_TX_C_DP")
	)
	(segment
		(start 122.15749 -141.744192)
		(end 122.412252 -141.744192)
		(width 0.127)
		(layer "B.Cu")
		(net "P2E_CPU_BMC_NODE1_TX_C_DP")
	)
	(segment
		(start 121.80189 -141.388592)
		(end 122.15749 -141.744192)
		(width 0.127)
		(layer "B.Cu")
		(net "P2E_CPU_BMC_NODE1_TX_C_DP")
	)
	(segment
		(start 69.442076 -70.310502)
		(end 69.835776 -70.704202)
		(width 0.1016)
		(layer "F.Cu")
		(net "XDP_CPU_NODE1_VISA14")
	)
	(segment
		(start 110.460028 -69.906388)
		(end 108.901992 -69.906388)
		(width 0.1016)
		(layer "F.Cu")
		(net "XDP_CPU_NODE1_VISA14")
	)
	(segment
		(start 69.440044 -70.310502)
		(end 69.442076 -70.310502)
		(width 0.1016)
		(layer "F.Cu")
		(net "XDP_CPU_NODE1_VISA14")
	)
	(via
		(at 69.835776 -70.704202)
		(size 0.508)
		(drill 0.254)
		(layers "F.Cu" "B.Cu")
		(net "XDP_CPU_NODE1_VISA14")
	)
	(via
		(at 108.901992 -69.906388)
		(size 0.508)
		(drill 0.254)
		(layers "F.Cu" "B.Cu")
		(net "XDP_CPU_NODE1_VISA14")
	)
	(segment
		(start 80.008222 -66.704464)
		(end 78.22438 -66.704464)
		(width 0.1143)
		(layer "In2.Cu")
		(net "XDP_CPU_NODE1_VISA14")
	)
	(segment
		(start 103.791512 -58.87593)
		(end 103.791512 -58.617866)
		(width 0.1143)
		(layer "In2.Cu")
		(net "XDP_CPU_NODE1_VISA14")
	)
	(segment
		(start 104.235504 -60.822586)
		(end 103.169212 -59.756294)
		(width 0.1143)
		(layer "In2.Cu")
		(net "XDP_CPU_NODE1_VISA14")
	)
	(segment
		(start 105.66908 -63.678562)
		(end 105.66908 -60.495434)
		(width 0.1143)
		(layer "In2.Cu")
		(net "XDP_CPU_NODE1_VISA14")
	)
	(segment
		(start 108.471208 -67.194176)
		(end 108.142532 -66.8655)
		(width 0.1143)
		(layer "In2.Cu")
		(net "XDP_CPU_NODE1_VISA14")
	)
	(segment
		(start 70.730364 -69.804534)
		(end 69.835776 -70.699122)
		(width 0.1143)
		(layer "In2.Cu")
		(net "XDP_CPU_NODE1_VISA14")
	)
	(segment
		(start 109.00156 -67.464686)
		(end 108.73105 -67.194176)
		(width 0.1143)
		(layer "In2.Cu")
		(net "XDP_CPU_NODE1_VISA14")
	)
	(segment
		(start 108.142532 -66.152014)
		(end 105.66908 -63.678562)
		(width 0.1143)
		(layer "In2.Cu")
		(net "XDP_CPU_NODE1_VISA14")
	)
	(segment
		(start 77.25156 -67.677284)
		(end 76.545186 -67.677284)
		(width 0.1143)
		(layer "In2.Cu")
		(net "XDP_CPU_NODE1_VISA14")
	)
	(segment
		(start 104.675686 -60.640468)
		(end 104.493568 -60.822586)
		(width 0.1143)
		(layer "In2.Cu")
		(net "XDP_CPU_NODE1_VISA14")
	)
	(segment
		(start 108.73105 -67.194176)
		(end 108.471208 -67.194176)
		(width 0.1143)
		(layer "In2.Cu")
		(net "XDP_CPU_NODE1_VISA14")
	)
	(segment
		(start 76.0349 -68.18757)
		(end 73.05929 -68.18757)
		(width 0.1143)
		(layer "In2.Cu")
		(net "XDP_CPU_NODE1_VISA14")
	)
	(segment
		(start 103.477822 -58.304176)
		(end 88.40851 -58.304176)
		(width 0.1143)
		(layer "In2.Cu")
		(net "XDP_CPU_NODE1_VISA14")
	)
	(segment
		(start 76.545186 -67.677284)
		(end 76.0349 -68.18757)
		(width 0.1143)
		(layer "In2.Cu")
		(net "XDP_CPU_NODE1_VISA14")
	)
	(segment
		(start 104.675686 -60.382404)
		(end 104.675686 -60.640468)
		(width 0.1143)
		(layer "In2.Cu")
		(net "XDP_CPU_NODE1_VISA14")
	)
	(segment
		(start 105.66908 -60.495434)
		(end 104.489758 -59.316112)
		(width 0.1143)
		(layer "In2.Cu")
		(net "XDP_CPU_NODE1_VISA14")
	)
	(segment
		(start 88.40851 -58.304176)
		(end 80.008222 -66.704464)
		(width 0.1143)
		(layer "In2.Cu")
		(net "XDP_CPU_NODE1_VISA14")
	)
	(segment
		(start 73.05929 -68.18757)
		(end 71.442326 -69.804534)
		(width 0.1143)
		(layer "In2.Cu")
		(net "XDP_CPU_NODE1_VISA14")
	)
	(segment
		(start 104.493568 -60.822586)
		(end 104.235504 -60.822586)
		(width 0.1143)
		(layer "In2.Cu")
		(net "XDP_CPU_NODE1_VISA14")
	)
	(segment
		(start 104.049576 -59.49823)
		(end 104.049576 -59.756294)
		(width 0.1143)
		(layer "In2.Cu")
		(net "XDP_CPU_NODE1_VISA14")
	)
	(segment
		(start 109.00156 -69.807328)
		(end 109.00156 -67.464686)
		(width 0.1143)
		(layer "In2.Cu")
		(net "XDP_CPU_NODE1_VISA14")
	)
	(segment
		(start 108.9025 -69.906388)
		(end 109.00156 -69.807328)
		(width 0.1143)
		(layer "In2.Cu")
		(net "XDP_CPU_NODE1_VISA14")
	)
	(segment
		(start 71.442326 -69.804534)
		(end 70.730364 -69.804534)
		(width 0.1143)
		(layer "In2.Cu")
		(net "XDP_CPU_NODE1_VISA14")
	)
	(segment
		(start 104.489758 -59.316112)
		(end 104.231694 -59.316112)
		(width 0.1143)
		(layer "In2.Cu")
		(net "XDP_CPU_NODE1_VISA14")
	)
	(segment
		(start 103.169212 -59.756294)
		(end 103.169212 -59.49823)
		(width 0.1143)
		(layer "In2.Cu")
		(net "XDP_CPU_NODE1_VISA14")
	)
	(segment
		(start 103.791512 -58.617866)
		(end 103.477822 -58.304176)
		(width 0.1143)
		(layer "In2.Cu")
		(net "XDP_CPU_NODE1_VISA14")
	)
	(segment
		(start 108.901992 -69.906388)
		(end 108.9025 -69.906388)
		(width 0.1143)
		(layer "In2.Cu")
		(net "XDP_CPU_NODE1_VISA14")
	)
	(segment
		(start 103.169212 -59.49823)
		(end 103.791512 -58.87593)
		(width 0.1143)
		(layer "In2.Cu")
		(net "XDP_CPU_NODE1_VISA14")
	)
	(segment
		(start 69.835776 -70.699122)
		(end 69.835776 -70.704202)
		(width 0.1143)
		(layer "In2.Cu")
		(net "XDP_CPU_NODE1_VISA14")
	)
	(segment
		(start 78.22438 -66.704464)
		(end 77.25156 -67.677284)
		(width 0.1143)
		(layer "In2.Cu")
		(net "XDP_CPU_NODE1_VISA14")
	)
	(segment
		(start 104.231694 -59.316112)
		(end 104.049576 -59.49823)
		(width 0.1143)
		(layer "In2.Cu")
		(net "XDP_CPU_NODE1_VISA14")
	)
	(segment
		(start 104.049576 -59.756294)
		(end 104.675686 -60.382404)
		(width 0.1143)
		(layer "In2.Cu")
		(net "XDP_CPU_NODE1_VISA14")
	)
	(segment
		(start 108.142532 -66.8655)
		(end 108.142532 -66.152014)
		(width 0.1143)
		(layer "In2.Cu")
		(net "XDP_CPU_NODE1_VISA14")
	)
	(segment
		(start 52.869084 -83.312)
		(end 53.0098 -83.312)
		(width 0.1016)
		(layer "F.Cu")
		(net "TP_CPU_NODE1_SOC_THERMATP1")
	)
	(segment
		(start 52.27193 -82.714846)
		(end 52.869084 -83.312)
		(width 0.1016)
		(layer "F.Cu")
		(net "TP_CPU_NODE1_SOC_THERMATP1")
	)
	(via
		(at 53.0098 -83.312)
		(size 0.508)
		(drill 0.254)
		(layers "F.Cu" "B.Cu")
		(net "TP_CPU_NODE1_SOC_THERMATP1")
	)
	(via
		(at 52.404772 -85.086698)
		(size 0.6604)
		(drill 0.3302)
		(layers "F.Cu" "B.Cu")
		(net "TP_CPU_NODE1_SOC_THERMATP1")
	)
	(segment
		(start 52.197 -84.878926)
		(end 52.404772 -85.086698)
		(width 0.1016)
		(layer "B.Cu")
		(net "TP_CPU_NODE1_SOC_THERMATP1")
	)
	(segment
		(start 52.64531 -83.21929)
		(end 52.197 -83.6676)
		(width 0.1016)
		(layer "B.Cu")
		(net "TP_CPU_NODE1_SOC_THERMATP1")
	)
	(segment
		(start 53.0098 -83.312)
		(end 53.0098 -83.29549)
		(width 0.1016)
		(layer "B.Cu")
		(net "TP_CPU_NODE1_SOC_THERMATP1")
	)
	(segment
		(start 53.0098 -83.29549)
		(end 52.9336 -83.21929)
		(width 0.1016)
		(layer "B.Cu")
		(net "TP_CPU_NODE1_SOC_THERMATP1")
	)
	(segment
		(start 52.9336 -83.21929)
		(end 52.64531 -83.21929)
		(width 0.1016)
		(layer "B.Cu")
		(net "TP_CPU_NODE1_SOC_THERMATP1")
	)
	(segment
		(start 52.197 -83.6676)
		(end 52.197 -84.878926)
		(width 0.1016)
		(layer "B.Cu")
		(net "TP_CPU_NODE1_SOC_THERMATP1")
	)
	(segment
		(start 57.530746 -83.857846)
		(end 57.525666 -83.857846)
		(width 0.254)
		(layer "F.Cu")
		(net "P1V8_NODE1")
	)
	(segment
		(start 57.4802 -82.333846)
		(end 57.186322 -82.039968)
		(width 0.3048)
		(layer "F.Cu")
		(net "P1V8_NODE1")
	)
	(segment
		(start 57.600596 -80.600042)
		(end 57.530746 -80.669892)
		(width 0.3048)
		(layer "F.Cu")
		(net "P1V8_NODE1")
	)
	(segment
		(start 57.076594 -82.784188)
		(end 57.219088 -82.784188)
		(width 0.254)
		(layer "F.Cu")
		(net "P1V8_NODE1")
	)
	(segment
		(start 57.200546 -80.199992)
		(end 57.600596 -80.600042)
		(width 0.3048)
		(layer "F.Cu")
		(net "P1V8_NODE1")
	)
	(segment
		(start 57.530746 -82.333846)
		(end 57.526936 -82.333846)
		(width 0.3048)
		(layer "F.Cu")
		(net "P1V8_NODE1")
	)
	(segment
		(start 57.159398 -83.491578)
		(end 57.137046 -83.491578)
		(width 0.254)
		(layer "F.Cu")
		(net "P1V8_NODE1")
	)
	(segment
		(start 57.530746 -83.095846)
		(end 57.530746 -83.12531)
		(width 0.254)
		(layer "F.Cu")
		(net "P1V8_NODE1")
	)
	(segment
		(start 58.097166 -97.847658)
		(end 58.097166 -97.110042)
		(width 0.508)
		(layer "F.Cu")
		(net "P1V8_NODE1")
	)
	(segment
		(start 57.512712 -81.571846)
		(end 57.04459 -82.039968)
		(width 0.3048)
		(layer "F.Cu")
		(net "P1V8_NODE1")
	)
	(segment
		(start 57.530746 -80.669892)
		(end 57.530746 -81.571846)
		(width 0.3048)
		(layer "F.Cu")
		(net "P1V8_NODE1")
	)
	(segment
		(start 55.600346 -76.199492)
		(end 55.200296 -75.799442)
		(width 0.3048)
		(layer "F.Cu")
		(net "P1V8_NODE1")
	)
	(segment
		(start 57.219088 -82.784188)
		(end 57.530746 -83.095846)
		(width 0.254)
		(layer "F.Cu")
		(net "P1V8_NODE1")
	)
	(segment
		(start 35.953954 -75.37069)
		(end 35.04946 -75.37069)
		(width 0.508)
		(layer "F.Cu")
		(net "P1V8_NODE1")
	)
	(segment
		(start 57.530746 -81.571846)
		(end 57.512712 -81.571846)
		(width 0.3048)
		(layer "F.Cu")
		(net "P1V8_NODE1")
	)
	(segment
		(start 57.525666 -83.857846)
		(end 57.159398 -83.491578)
		(width 0.254)
		(layer "F.Cu")
		(net "P1V8_NODE1")
	)
	(segment
		(start 57.164478 -83.491578)
		(end 57.159398 -83.491578)
		(width 0.254)
		(layer "F.Cu")
		(net "P1V8_NODE1")
	)
	(segment
		(start 57.186322 -82.039968)
		(end 57.04459 -82.039968)
		(width 0.3048)
		(layer "F.Cu")
		(net "P1V8_NODE1")
	)
	(segment
		(start 57.526936 -82.333846)
		(end 57.4802 -82.333846)
		(width 0.3048)
		(layer "F.Cu")
		(net "P1V8_NODE1")
	)
	(segment
		(start 57.526936 -82.333846)
		(end 57.076594 -82.784188)
		(width 0.254)
		(layer "F.Cu")
		(net "P1V8_NODE1")
	)
	(segment
		(start 57.530746 -83.12531)
		(end 57.164478 -83.491578)
		(width 0.254)
		(layer "F.Cu")
		(net "P1V8_NODE1")
	)
	(via
		(at 89.7636 -128.84404)
		(size 0.508)
		(drill 0.254)
		(layers "F.Cu" "B.Cu")
		(net "P1V8_NODE1")
	)
	(via
		(at 83.918552 -143.713962)
		(size 0.508)
		(drill 0.254)
		(layers "F.Cu" "B.Cu")
		(net "P1V8_NODE1")
	)
	(via
		(at 84.16544 -113.615724)
		(size 0.508)
		(drill 0.254)
		(layers "F.Cu" "B.Cu")
		(net "P1V8_NODE1")
	)
	(via
		(at 83.25612 -113.238026)
		(size 0.508)
		(drill 0.254)
		(layers "F.Cu" "B.Cu")
		(net "P1V8_NODE1")
	)
	(via
		(at 57.200546 -80.199992)
		(size 0.508)
		(drill 0.254)
		(layers "F.Cu" "B.Cu")
		(net "P1V8_NODE1")
	)
	(via
		(at 68.84289 -112.534954)
		(size 0.508)
		(drill 0.254)
		(layers "F.Cu" "B.Cu")
		(net "P1V8_NODE1")
	)
	(via
		(at 133.07822 -81.697068)
		(size 0.508)
		(drill 0.254)
		(layers "F.Cu" "B.Cu")
		(net "P1V8_NODE1")
	)
	(via
		(at 89.69248 -129.540762)
		(size 0.508)
		(drill 0.254)
		(layers "F.Cu" "B.Cu")
		(net "P1V8_NODE1")
	)
	(via
		(at 72.6694 -112.343692)
		(size 0.508)
		(drill 0.254)
		(layers "F.Cu" "B.Cu")
		(net "P1V8_NODE1")
	)
	(via
		(at 114.03838 -102.576884)
		(size 0.508)
		(drill 0.254)
		(layers "F.Cu" "B.Cu")
		(net "P1V8_NODE1")
	)
	(via
		(at 89.63406 -121.832624)
		(size 0.508)
		(drill 0.254)
		(layers "F.Cu" "B.Cu")
		(net "P1V8_NODE1")
	)
	(via
		(at 57.137046 -83.491578)
		(size 0.508)
		(drill 0.254)
		(layers "F.Cu" "B.Cu")
		(net "P1V8_NODE1")
	)
	(via
		(at 70.894448 -113.018316)
		(size 0.508)
		(drill 0.254)
		(layers "F.Cu" "B.Cu")
		(net "P1V8_NODE1")
	)
	(via
		(at 57.04459 -82.039968)
		(size 0.508)
		(drill 0.254)
		(layers "F.Cu" "B.Cu")
		(net "P1V8_NODE1")
	)
	(via
		(at 72.69734 -113.011204)
		(size 0.508)
		(drill 0.254)
		(layers "F.Cu" "B.Cu")
		(net "P1V8_NODE1")
	)
	(via
		(at 114.7953 -102.218236)
		(size 0.508)
		(drill 0.254)
		(layers "F.Cu" "B.Cu")
		(net "P1V8_NODE1")
	)
	(via
		(at 88.44026 -129.9337)
		(size 0.508)
		(drill 0.254)
		(layers "F.Cu" "B.Cu")
		(net "P1V8_NODE1")
	)
	(via
		(at 73.047352 -122.436382)
		(size 0.6604)
		(drill 0.3302)
		(layers "F.Cu" "B.Cu")
		(net "P1V8_NODE1")
	)
	(via
		(at 111.5441 -101.83622)
		(size 0.508)
		(drill 0.254)
		(layers "F.Cu" "B.Cu")
		(net "P1V8_NODE1")
	)
	(via
		(at 52.27066 -98.298762)
		(size 0.508)
		(drill 0.254)
		(layers "F.Cu" "B.Cu")
		(net "P1V8_NODE1")
	)
	(via
		(at 158.10738 -66.453512)
		(size 0.508)
		(drill 0.254)
		(layers "F.Cu" "B.Cu")
		(net "P1V8_NODE1")
	)
	(via
		(at 30.979872 -124.074174)
		(size 0.508)
		(drill 0.254)
		(layers "F.Cu" "B.Cu")
		(net "P1V8_NODE1")
	)
	(via
		(at 54.28234 -102.168198)
		(size 0.508)
		(drill 0.254)
		(layers "F.Cu" "B.Cu")
		(net "P1V8_NODE1")
	)
	(via
		(at 98.31832 -123.5456)
		(size 0.508)
		(drill 0.254)
		(layers "F.Cu" "B.Cu")
		(net "P1V8_NODE1")
	)
	(via
		(at 55.600346 -76.199492)
		(size 0.508)
		(drill 0.254)
		(layers "F.Cu" "B.Cu")
		(net "P1V8_NODE1")
	)
	(via
		(at 57.076594 -82.784188)
		(size 0.508)
		(drill 0.254)
		(layers "F.Cu" "B.Cu")
		(net "P1V8_NODE1")
	)
	(via
		(at 89.2175 -126.937008)
		(size 0.508)
		(drill 0.254)
		(layers "F.Cu" "B.Cu")
		(net "P1V8_NODE1")
	)
	(via
		(at 98.97618 -121.224548)
		(size 0.508)
		(drill 0.254)
		(layers "F.Cu" "B.Cu")
		(net "P1V8_NODE1")
	)
	(via
		(at 29.724604 -124.032264)
		(size 0.508)
		(drill 0.254)
		(layers "F.Cu" "B.Cu")
		(net "P1V8_NODE1")
	)
	(via
		(at 166.13124 -76.824586)
		(size 0.508)
		(drill 0.254)
		(layers "F.Cu" "B.Cu")
		(net "P1V8_NODE1")
	)
	(via
		(at 131.9911 -81.377536)
		(size 0.508)
		(drill 0.254)
		(layers "F.Cu" "B.Cu")
		(net "P1V8_NODE1")
	)
	(via
		(at 58.097166 -97.847658)
		(size 0.508)
		(drill 0.254)
		(layers "F.Cu" "B.Cu")
		(net "P1V8_NODE1")
	)
	(via
		(at 52.42052 -102.159054)
		(size 0.508)
		(drill 0.254)
		(layers "F.Cu" "B.Cu")
		(net "P1V8_NODE1")
	)
	(via
		(at 75.747372 -121.628662)
		(size 0.6604)
		(drill 0.3302)
		(layers "F.Cu" "B.Cu")
		(net "P1V8_NODE1")
	)
	(via
		(at 134.28472 -80.606646)
		(size 0.508)
		(drill 0.254)
		(layers "F.Cu" "B.Cu")
		(net "P1V8_NODE1")
	)
	(via
		(at 73.56602 -112.986312)
		(size 0.508)
		(drill 0.254)
		(layers "F.Cu" "B.Cu")
		(net "P1V8_NODE1")
	)
	(via
		(at 84.426552 -144.196562)
		(size 0.508)
		(drill 0.254)
		(layers "F.Cu" "B.Cu")
		(net "P1V8_NODE1")
	)
	(via
		(at 29.341064 -123.366784)
		(size 0.508)
		(drill 0.254)
		(layers "F.Cu" "B.Cu")
		(net "P1V8_NODE1")
	)
	(via
		(at 98.02876 -122.549412)
		(size 0.508)
		(drill 0.254)
		(layers "F.Cu" "B.Cu")
		(net "P1V8_NODE1")
	)
	(via
		(at 30.308804 -124.385324)
		(size 0.508)
		(drill 0.254)
		(layers "F.Cu" "B.Cu")
		(net "P1V8_NODE1")
	)
	(via
		(at 74.21118 -113.280444)
		(size 0.508)
		(drill 0.254)
		(layers "F.Cu" "B.Cu")
		(net "P1V8_NODE1")
	)
	(via
		(at 82.85226 -113.949734)
		(size 0.508)
		(drill 0.254)
		(layers "F.Cu" "B.Cu")
		(net "P1V8_NODE1")
	)
	(via
		(at 156.915612 -60.673742)
		(size 0.508)
		(drill 0.254)
		(layers "F.Cu" "B.Cu")
		(net "P1V8_NODE1")
	)
	(via
		(at 35.04946 -75.37069)
		(size 0.508)
		(drill 0.254)
		(layers "F.Cu" "B.Cu")
		(net "P1V8_NODE1")
	)
	(via
		(at 136.086088 -63.519304)
		(size 0.508)
		(drill 0.254)
		(layers "F.Cu" "B.Cu")
		(net "P1V8_NODE1")
	)
	(via
		(at 146.280632 -75.083924)
		(size 0.508)
		(drill 0.254)
		(layers "F.Cu" "B.Cu")
		(net "P1V8_NODE1")
	)
	(via
		(at 74.13244 -112.503458)
		(size 0.508)
		(drill 0.254)
		(layers "F.Cu" "B.Cu")
		(net "P1V8_NODE1")
	)
	(via
		(at 53.56352 -102.199186)
		(size 0.508)
		(drill 0.254)
		(layers "F.Cu" "B.Cu")
		(net "P1V8_NODE1")
	)
	(via
		(at 71.935848 -112.340644)
		(size 0.508)
		(drill 0.254)
		(layers "F.Cu" "B.Cu")
		(net "P1V8_NODE1")
	)
	(via
		(at 98.77806 -122.031506)
		(size 0.508)
		(drill 0.254)
		(layers "F.Cu" "B.Cu")
		(net "P1V8_NODE1")
	)
	(via
		(at 83.334352 -144.145762)
		(size 0.508)
		(drill 0.254)
		(layers "F.Cu" "B.Cu")
		(net "P1V8_NODE1")
	)
	(via
		(at 165.699948 -77.875892)
		(size 0.508)
		(drill 0.254)
		(layers "F.Cu" "B.Cu")
		(net "P1V8_NODE1")
	)
	(via
		(at 111.33836 -102.45725)
		(size 0.508)
		(drill 0.254)
		(layers "F.Cu" "B.Cu")
		(net "P1V8_NODE1")
	)
	(via
		(at 166.69258 -76.042266)
		(size 0.508)
		(drill 0.254)
		(layers "F.Cu" "B.Cu")
		(net "P1V8_NODE1")
	)
	(via
		(at 71.628 -113.021364)
		(size 0.508)
		(drill 0.254)
		(layers "F.Cu" "B.Cu")
		(net "P1V8_NODE1")
	)
	(via
		(at 73.340468 -112.29086)
		(size 0.508)
		(drill 0.254)
		(layers "F.Cu" "B.Cu")
		(net "P1V8_NODE1")
	)
	(via
		(at 73.14438 -113.46307)
		(size 0.508)
		(drill 0.254)
		(layers "F.Cu" "B.Cu")
		(net "P1V8_NODE1")
	)
	(via
		(at 40.56126 -118.18366)
		(size 0.6604)
		(drill 0.3302)
		(layers "F.Cu" "B.Cu")
		(net "P1V8_NODE1")
	)
	(via
		(at 167.4749 -75.89774)
		(size 0.508)
		(drill 0.254)
		(layers "F.Cu" "B.Cu")
		(net "P1V8_NODE1")
	)
	(via
		(at 89.47404 -122.689366)
		(size 0.508)
		(drill 0.254)
		(layers "F.Cu" "B.Cu")
		(net "P1V8_NODE1")
	)
	(via
		(at 131.38404 -80.258412)
		(size 0.508)
		(drill 0.254)
		(layers "F.Cu" "B.Cu")
		(net "P1V8_NODE1")
	)
	(via
		(at 129.81178 -78.922626)
		(size 0.508)
		(drill 0.254)
		(layers "F.Cu" "B.Cu")
		(net "P1V8_NODE1")
	)
	(via
		(at 112.58296 -102.103936)
		(size 0.508)
		(drill 0.254)
		(layers "F.Cu" "B.Cu")
		(net "P1V8_NODE1")
	)
	(via
		(at 113.2586 -102.47884)
		(size 0.508)
		(drill 0.254)
		(layers "F.Cu" "B.Cu")
		(net "P1V8_NODE1")
	)
	(via
		(at 166.360348 -78.155292)
		(size 0.508)
		(drill 0.254)
		(layers "F.Cu" "B.Cu")
		(net "P1V8_NODE1")
	)
	(via
		(at 146.27352 -74.426064)
		(size 0.508)
		(drill 0.254)
		(layers "F.Cu" "B.Cu")
		(net "P1V8_NODE1")
	)
	(via
		(at 89.44864 -127.543052)
		(size 0.508)
		(drill 0.254)
		(layers "F.Cu" "B.Cu")
		(net "P1V8_NODE1")
	)
	(via
		(at 69.52869 -112.530636)
		(size 0.508)
		(drill 0.254)
		(layers "F.Cu" "B.Cu")
		(net "P1V8_NODE1")
	)
	(via
		(at 89.77884 -128.152144)
		(size 0.508)
		(drill 0.254)
		(layers "F.Cu" "B.Cu")
		(net "P1V8_NODE1")
	)
	(via
		(at 132.69468 -80.13065)
		(size 0.508)
		(drill 0.254)
		(layers "F.Cu" "B.Cu")
		(net "P1V8_NODE1")
	)
	(via
		(at 155.695396 -68.35013)
		(size 0.508)
		(drill 0.254)
		(layers "F.Cu" "B.Cu")
		(net "P1V8_NODE1")
	)
	(via
		(at 83.59648 -114.097562)
		(size 0.508)
		(drill 0.254)
		(layers "F.Cu" "B.Cu")
		(net "P1V8_NODE1")
	)
	(via
		(at 131.72186 -78.772766)
		(size 0.508)
		(drill 0.254)
		(layers "F.Cu" "B.Cu")
		(net "P1V8_NODE1")
	)
	(via
		(at 88.392 -121.7041)
		(size 0.508)
		(drill 0.254)
		(layers "F.Cu" "B.Cu")
		(net "P1V8_NODE1")
	)
	(via
		(at 70.263004 -112.499902)
		(size 0.508)
		(drill 0.254)
		(layers "F.Cu" "B.Cu")
		(net "P1V8_NODE1")
	)
	(via
		(at 133.6675 -78.97876)
		(size 0.508)
		(drill 0.254)
		(layers "F.Cu" "B.Cu")
		(net "P1V8_NODE1")
	)
	(via
		(at 55.024782 -97.787206)
		(size 0.508)
		(drill 0.254)
		(layers "F.Cu" "B.Cu")
		(net "P1V8_NODE1")
	)
	(via
		(at 69.915024 -113.221262)
		(size 0.508)
		(drill 0.254)
		(layers "F.Cu" "B.Cu")
		(net "P1V8_NODE1")
	)
	(via
		(at 71.11746 -112.286034)
		(size 0.508)
		(drill 0.254)
		(layers "F.Cu" "B.Cu")
		(net "P1V8_NODE1")
	)
	(via
		(at 113.49482 -101.739954)
		(size 0.508)
		(drill 0.254)
		(layers "F.Cu" "B.Cu")
		(net "P1V8_NODE1")
	)
	(via
		(at 98.14814 -121.304304)
		(size 0.508)
		(drill 0.254)
		(layers "F.Cu" "B.Cu")
		(net "P1V8_NODE1")
	)
	(segment
		(start 55.038498 -97.096834)
		(end 55.024782 -97.11055)
		(width 0.508)
		(layer "B.Cu")
		(net "P1V8_NODE1")
	)
	(segment
		(start 53.006498 -97.096834)
		(end 53.006498 -97.587054)
		(width 0.508)
		(layer "B.Cu")
		(net "P1V8_NODE1")
	)
	(segment
		(start 52.29479 -98.298762)
		(end 52.27066 -98.298762)
		(width 0.508)
		(layer "B.Cu")
		(net "P1V8_NODE1")
	)
	(segment
		(start 53.006498 -97.587054)
		(end 52.29479 -98.298762)
		(width 0.508)
		(layer "B.Cu")
		(net "P1V8_NODE1")
	)
	(segment
		(start 55.024782 -97.11055)
		(end 55.024782 -97.787206)
		(width 0.508)
		(layer "B.Cu")
		(net "P1V8_NODE1")
	)
	(segment
		(start 56.063642 -75.544172)
		(end 57.572656 -75.544172)
		(width 0.508)
		(layer "In2.Cu")
		(net "P1V8_NODE1")
	)
	(segment
		(start 55.600346 -76.199492)
		(end 55.600346 -76.007468)
		(width 0.508)
		(layer "In2.Cu")
		(net "P1V8_NODE1")
	)
	(segment
		(start 57.262776 -80.199992)
		(end 57.200546 -80.199992)
		(width 0.508)
		(layer "In2.Cu")
		(net "P1V8_NODE1")
	)
	(segment
		(start 57.572656 -75.544172)
		(end 57.810654 -75.78217)
		(width 0.508)
		(layer "In2.Cu")
		(net "P1V8_NODE1")
	)
	(segment
		(start 55.600346 -76.007468)
		(end 56.063642 -75.544172)
		(width 0.508)
		(layer "In2.Cu")
		(net "P1V8_NODE1")
	)
	(segment
		(start 57.810654 -75.78217)
		(end 57.810654 -79.652114)
		(width 0.508)
		(layer "In2.Cu")
		(net "P1V8_NODE1")
	)
	(segment
		(start 57.810654 -79.652114)
		(end 57.262776 -80.199992)
		(width 0.508)
		(layer "In2.Cu")
		(net "P1V8_NODE1")
	)
	(segment
		(start 52.27066 -98.298762)
		(end 53.580792 -96.98863)
		(width 0.508)
		(layer "In6.Cu")
		(net "P1V8_NODE1")
	)
	(segment
		(start 57.401714 -97.152206)
		(end 58.097166 -97.847658)
		(width 0.508)
		(layer "In6.Cu")
		(net "P1V8_NODE1")
	)
	(segment
		(start 54.602126 -96.98863)
		(end 55.024782 -97.411286)
		(width 0.508)
		(layer "In6.Cu")
		(net "P1V8_NODE1")
	)
	(segment
		(start 55.024782 -97.787206)
		(end 55.659782 -97.152206)
		(width 0.508)
		(layer "In6.Cu")
		(net "P1V8_NODE1")
	)
	(segment
		(start 55.024782 -97.411286)
		(end 55.024782 -97.787206)
		(width 0.508)
		(layer "In6.Cu")
		(net "P1V8_NODE1")
	)
	(segment
		(start 53.580792 -96.98863)
		(end 54.602126 -96.98863)
		(width 0.508)
		(layer "In6.Cu")
		(net "P1V8_NODE1")
	)
	(segment
		(start 55.659782 -97.152206)
		(end 57.401714 -97.152206)
		(width 0.508)
		(layer "In6.Cu")
		(net "P1V8_NODE1")
	)
	(segment
		(start 42.898314 -69.398642)
		(end 42.564304 -69.732652)
		(width 0.1016)
		(layer "F.Cu")
		(net "TP_CPU_NODE1_RP0_PERN7")
	)
	(segment
		(start 43.099736 -69.398642)
		(end 42.898314 -69.398642)
		(width 0.1016)
		(layer "F.Cu")
		(net "TP_CPU_NODE1_RP0_PERN7")
	)
	(segment
		(start 40.257984 -70.309486)
		(end 38.769036 -70.309486)
		(width 0.1016)
		(layer "F.Cu")
		(net "TP_CPU_NODE1_RP0_PERN7")
	)
	(segment
		(start 41.848278 -69.390514)
		(end 41.176956 -69.390514)
		(width 0.1016)
		(layer "F.Cu")
		(net "TP_CPU_NODE1_RP0_PERN7")
	)
	(segment
		(start 41.176956 -69.390514)
		(end 40.257984 -70.309486)
		(width 0.1016)
		(layer "F.Cu")
		(net "TP_CPU_NODE1_RP0_PERN7")
	)
	(segment
		(start 42.564304 -69.732652)
		(end 42.190416 -69.732652)
		(width 0.1016)
		(layer "F.Cu")
		(net "TP_CPU_NODE1_RP0_PERN7")
	)
	(segment
		(start 42.190416 -69.732652)
		(end 41.848278 -69.390514)
		(width 0.1016)
		(layer "F.Cu")
		(net "TP_CPU_NODE1_RP0_PERN7")
	)
	(via
		(at 38.769036 -70.309486)
		(size 0.508)
		(drill 0.254)
		(layers "F.Cu" "B.Cu")
		(net "TP_CPU_NODE1_RP0_PERN7")
	)
	(segment
		(start 36.00323 -11.101578)
		(end 36.519866 -11.101578)
		(width 0.1778)
		(layer "F.Cu")
		(net "VSENSE_PV_VDDR_NODE1_N")
	)
	(segment
		(start 34.3027 -13.587222)
		(end 34.316416 -13.587222)
		(width 0.254)
		(layer "F.Cu")
		(net "VSENSE_PV_VDDR_NODE1_N")
	)
	(segment
		(start 35.700716 -11.404092)
		(end 36.00323 -11.101578)
		(width 0.1778)
		(layer "F.Cu")
		(net "VSENSE_PV_VDDR_NODE1_N")
	)
	(segment
		(start 34.923476 -11.982958)
		(end 35.12185 -11.982958)
		(width 0.254)
		(layer "F.Cu")
		(net "VSENSE_PV_VDDR_NODE1_N")
	)
	(segment
		(start 34.874454 -13.029184)
		(end 34.874454 -12.03198)
		(width 0.254)
		(layer "F.Cu")
		(net "VSENSE_PV_VDDR_NODE1_N")
	)
	(segment
		(start 35.12185 -11.982958)
		(end 35.700716 -11.404092)
		(width 0.254)
		(layer "F.Cu")
		(net "VSENSE_PV_VDDR_NODE1_N")
	)
	(segment
		(start 34.874454 -12.03198)
		(end 34.923476 -11.982958)
		(width 0.254)
		(layer "F.Cu")
		(net "VSENSE_PV_VDDR_NODE1_N")
	)
	(segment
		(start 34.316416 -13.587222)
		(end 34.874454 -13.029184)
		(width 0.254)
		(layer "F.Cu")
		(net "VSENSE_PV_VDDR_NODE1_N")
	)
	(via
		(at 34.3027 -13.587222)
		(size 0.508)
		(drill 0.254)
		(layers "F.Cu" "B.Cu")
		(net "VSENSE_PV_VDDR_NODE1_N")
	)
	(via
		(at 107.09656 -58.014362)
		(size 0.508)
		(drill 0.254)
		(layers "F.Cu" "B.Cu")
		(net "VSENSE_PV_VDDR_NODE1_N")
	)
	(segment
		(start 80.202532 -57.582562)
		(end 74.398124 -63.38697)
		(width 0.254)
		(layer "B.Cu")
		(net "VSENSE_PV_VDDR_NODE1_N")
	)
	(segment
		(start 73.745852 -63.38697)
		(end 73.587102 -63.54572)
		(width 0.254)
		(layer "B.Cu")
		(net "VSENSE_PV_VDDR_NODE1_N")
	)
	(segment
		(start 106.66476 -57.582562)
		(end 80.202532 -57.582562)
		(width 0.254)
		(layer "B.Cu")
		(net "VSENSE_PV_VDDR_NODE1_N")
	)
	(segment
		(start 74.398124 -63.38697)
		(end 73.745852 -63.38697)
		(width 0.254)
		(layer "B.Cu")
		(net "VSENSE_PV_VDDR_NODE1_N")
	)
	(segment
		(start 107.09656 -58.014362)
		(end 106.66476 -57.582562)
		(width 0.254)
		(layer "B.Cu")
		(net "VSENSE_PV_VDDR_NODE1_N")
	)
	(segment
		(start 37.651944 -17.507712)
		(end 43.04792 -17.507712)
		(width 0.254)
		(layer "In7.Cu")
		(net "VSENSE_PV_VDDR_NODE1_N")
	)
	(segment
		(start 108.037122 -57.582562)
		(end 107.52836 -57.582562)
		(width 0.254)
		(layer "In7.Cu")
		(net "VSENSE_PV_VDDR_NODE1_N")
	)
	(segment
		(start 108.9025 -30.66669)
		(end 108.9025 -56.717184)
		(width 0.254)
		(layer "In7.Cu")
		(net "VSENSE_PV_VDDR_NODE1_N")
	)
	(segment
		(start 96.854772 -20.457922)
		(end 103.68534 -20.457922)
		(width 0.254)
		(layer "In7.Cu")
		(net "VSENSE_PV_VDDR_NODE1_N")
	)
	(segment
		(start 107.64266 -29.40685)
		(end 108.9025 -30.66669)
		(width 0.254)
		(layer "In7.Cu")
		(net "VSENSE_PV_VDDR_NODE1_N")
	)
	(segment
		(start 34.3027 -13.587222)
		(end 34.932874 -14.217396)
		(width 0.254)
		(layer "In7.Cu")
		(net "VSENSE_PV_VDDR_NODE1_N")
	)
	(segment
		(start 107.52836 -57.582562)
		(end 107.09656 -58.014362)
		(width 0.254)
		(layer "In7.Cu")
		(net "VSENSE_PV_VDDR_NODE1_N")
	)
	(segment
		(start 103.68534 -20.457922)
		(end 107.64266 -24.415242)
		(width 0.254)
		(layer "In7.Cu")
		(net "VSENSE_PV_VDDR_NODE1_N")
	)
	(segment
		(start 94.784672 -18.387822)
		(end 96.854772 -20.457922)
		(width 0.254)
		(layer "In7.Cu")
		(net "VSENSE_PV_VDDR_NODE1_N")
	)
	(segment
		(start 43.04792 -17.507712)
		(end 44.101766 -18.561558)
		(width 0.254)
		(layer "In7.Cu")
		(net "VSENSE_PV_VDDR_NODE1_N")
	)
	(segment
		(start 91.285822 -17.290542)
		(end 92.383102 -18.387822)
		(width 0.254)
		(layer "In7.Cu")
		(net "VSENSE_PV_VDDR_NODE1_N")
	)
	(segment
		(start 35.49142 -14.49705)
		(end 35.49142 -15.347188)
		(width 0.254)
		(layer "In7.Cu")
		(net "VSENSE_PV_VDDR_NODE1_N")
	)
	(segment
		(start 66.121534 -17.290542)
		(end 91.285822 -17.290542)
		(width 0.254)
		(layer "In7.Cu")
		(net "VSENSE_PV_VDDR_NODE1_N")
	)
	(segment
		(start 64.850518 -18.561558)
		(end 66.121534 -17.290542)
		(width 0.254)
		(layer "In7.Cu")
		(net "VSENSE_PV_VDDR_NODE1_N")
	)
	(segment
		(start 92.383102 -18.387822)
		(end 94.784672 -18.387822)
		(width 0.254)
		(layer "In7.Cu")
		(net "VSENSE_PV_VDDR_NODE1_N")
	)
	(segment
		(start 35.49142 -15.347188)
		(end 37.651944 -17.507712)
		(width 0.254)
		(layer "In7.Cu")
		(net "VSENSE_PV_VDDR_NODE1_N")
	)
	(segment
		(start 44.101766 -18.561558)
		(end 64.850518 -18.561558)
		(width 0.254)
		(layer "In7.Cu")
		(net "VSENSE_PV_VDDR_NODE1_N")
	)
	(segment
		(start 107.64266 -24.415242)
		(end 107.64266 -29.40685)
		(width 0.254)
		(layer "In7.Cu")
		(net "VSENSE_PV_VDDR_NODE1_N")
	)
	(segment
		(start 35.211766 -14.217396)
		(end 35.49142 -14.49705)
		(width 0.254)
		(layer "In7.Cu")
		(net "VSENSE_PV_VDDR_NODE1_N")
	)
	(segment
		(start 34.932874 -14.217396)
		(end 35.211766 -14.217396)
		(width 0.254)
		(layer "In7.Cu")
		(net "VSENSE_PV_VDDR_NODE1_N")
	)
	(segment
		(start 108.9025 -56.717184)
		(end 108.037122 -57.582562)
		(width 0.254)
		(layer "In7.Cu")
		(net "VSENSE_PV_VDDR_NODE1_N")
	)
	(segment
		(start 66.750692 -108.363766)
		(end 66.750692 -107.716066)
		(width 0.1016)
		(layer "F.Cu")
		(net "FM_CPLD_NODE1_P1V8_EN")
	)
	(segment
		(start 67.749928 -106.703622)
		(end 67.749928 -107.047792)
		(width 0.1016)
		(layer "F.Cu")
		(net "FM_CPLD_NODE1_P1V8_EN")
	)
	(segment
		(start 66.750692 -107.716066)
		(end 67.081654 -107.716066)
		(width 0.1016)
		(layer "F.Cu")
		(net "FM_CPLD_NODE1_P1V8_EN")
	)
	(segment
		(start 176.679098 -109.991906)
		(end 180.433472 -113.74628)
		(width 0.1016)
		(layer "F.Cu")
		(net "FM_CPLD_NODE1_P1V8_EN")
	)
	(segment
		(start 66.622422 -108.492036)
		(end 66.750692 -108.363766)
		(width 0.1016)
		(layer "F.Cu")
		(net "FM_CPLD_NODE1_P1V8_EN")
	)
	(segment
		(start 180.433472 -116.942616)
		(end 180.010562 -117.365526)
		(width 0.1016)
		(layer "F.Cu")
		(net "FM_CPLD_NODE1_P1V8_EN")
	)
	(segment
		(start 159.055562 -109.991906)
		(end 176.679098 -109.991906)
		(width 0.1016)
		(layer "F.Cu")
		(net "FM_CPLD_NODE1_P1V8_EN")
	)
	(segment
		(start 65.734692 -107.716066)
		(end 66.750692 -107.716066)
		(width 0.1016)
		(layer "F.Cu")
		(net "FM_CPLD_NODE1_P1V8_EN")
	)
	(segment
		(start 67.749928 -107.047792)
		(end 67.445128 -107.352592)
		(width 0.1016)
		(layer "F.Cu")
		(net "FM_CPLD_NODE1_P1V8_EN")
	)
	(segment
		(start 67.081654 -107.716066)
		(end 67.445128 -107.352592)
		(width 0.1016)
		(layer "F.Cu")
		(net "FM_CPLD_NODE1_P1V8_EN")
	)
	(segment
		(start 66.622422 -109.33303)
		(end 66.622422 -108.492036)
		(width 0.1016)
		(layer "F.Cu")
		(net "FM_CPLD_NODE1_P1V8_EN")
	)
	(segment
		(start 180.433472 -113.74628)
		(end 180.433472 -116.942616)
		(width 0.1016)
		(layer "F.Cu")
		(net "FM_CPLD_NODE1_P1V8_EN")
	)
	(segment
		(start 155.08732 -113.960148)
		(end 159.055562 -109.991906)
		(width 0.1016)
		(layer "F.Cu")
		(net "FM_CPLD_NODE1_P1V8_EN")
	)
	(via
		(at 81.0133 -109.848142)
		(size 0.508)
		(drill 0.254)
		(layers "F.Cu" "B.Cu")
		(net "FM_CPLD_NODE1_P1V8_EN")
	)
	(via
		(at 155.08732 -113.960148)
		(size 0.508)
		(drill 0.254)
		(layers "F.Cu" "B.Cu")
		(net "FM_CPLD_NODE1_P1V8_EN")
	)
	(via
		(at 67.445128 -107.352592)
		(size 0.508)
		(drill 0.254)
		(layers "F.Cu" "B.Cu")
		(net "FM_CPLD_NODE1_P1V8_EN")
	)
	(segment
		(start 149.62886 -113.894362)
		(end 153.275284 -113.894362)
		(width 0.1143)
		(layer "In6.Cu")
		(net "FM_CPLD_NODE1_P1V8_EN")
	)
	(segment
		(start 81.05648 -109.891322)
		(end 81.05648 -110.049818)
		(width 0.1143)
		(layer "In6.Cu")
		(net "FM_CPLD_NODE1_P1V8_EN")
	)
	(segment
		(start 153.275284 -113.894362)
		(end 153.34107 -113.960148)
		(width 0.1143)
		(layer "In6.Cu")
		(net "FM_CPLD_NODE1_P1V8_EN")
	)
	(segment
		(start 146.090386 -110.355888)
		(end 149.62886 -113.894362)
		(width 0.1143)
		(layer "In6.Cu")
		(net "FM_CPLD_NODE1_P1V8_EN")
	)
	(segment
		(start 87.753698 -113.383314)
		(end 87.753698 -113.387886)
		(width 0.1143)
		(layer "In6.Cu")
		(net "FM_CPLD_NODE1_P1V8_EN")
	)
	(segment
		(start 123.142502 -108.600748)
		(end 124.91974 -110.377986)
		(width 0.1143)
		(layer "In6.Cu")
		(net "FM_CPLD_NODE1_P1V8_EN")
	)
	(segment
		(start 153.34107 -113.960148)
		(end 155.08732 -113.960148)
		(width 0.1143)
		(layer "In6.Cu")
		(net "FM_CPLD_NODE1_P1V8_EN")
	)
	(segment
		(start 131.191 -110.684056)
		(end 131.519168 -110.355888)
		(width 0.1143)
		(layer "In6.Cu")
		(net "FM_CPLD_NODE1_P1V8_EN")
	)
	(segment
		(start 85.516212 -111.145828)
		(end 87.753698 -113.383314)
		(width 0.1143)
		(layer "In6.Cu")
		(net "FM_CPLD_NODE1_P1V8_EN")
	)
	(segment
		(start 124.91974 -110.377986)
		(end 128.97485 -110.377986)
		(width 0.1143)
		(layer "In6.Cu")
		(net "FM_CPLD_NODE1_P1V8_EN")
	)
	(segment
		(start 129.28092 -110.684056)
		(end 131.191 -110.684056)
		(width 0.1143)
		(layer "In6.Cu")
		(net "FM_CPLD_NODE1_P1V8_EN")
	)
	(segment
		(start 94.251018 -115.401598)
		(end 101.051868 -108.600748)
		(width 0.1143)
		(layer "In6.Cu")
		(net "FM_CPLD_NODE1_P1V8_EN")
	)
	(segment
		(start 82.15249 -111.145828)
		(end 85.516212 -111.145828)
		(width 0.1143)
		(layer "In6.Cu")
		(net "FM_CPLD_NODE1_P1V8_EN")
	)
	(segment
		(start 101.051868 -108.600748)
		(end 123.142502 -108.600748)
		(width 0.1143)
		(layer "In6.Cu")
		(net "FM_CPLD_NODE1_P1V8_EN")
	)
	(segment
		(start 89.76741 -115.401598)
		(end 94.251018 -115.401598)
		(width 0.1143)
		(layer "In6.Cu")
		(net "FM_CPLD_NODE1_P1V8_EN")
	)
	(segment
		(start 87.753698 -113.387886)
		(end 89.76741 -115.401598)
		(width 0.1143)
		(layer "In6.Cu")
		(net "FM_CPLD_NODE1_P1V8_EN")
	)
	(segment
		(start 128.97485 -110.377986)
		(end 129.28092 -110.684056)
		(width 0.1143)
		(layer "In6.Cu")
		(net "FM_CPLD_NODE1_P1V8_EN")
	)
	(segment
		(start 81.0133 -109.848142)
		(end 81.05648 -109.891322)
		(width 0.1143)
		(layer "In6.Cu")
		(net "FM_CPLD_NODE1_P1V8_EN")
	)
	(segment
		(start 81.05648 -110.049818)
		(end 82.15249 -111.145828)
		(width 0.1143)
		(layer "In6.Cu")
		(net "FM_CPLD_NODE1_P1V8_EN")
	)
	(segment
		(start 131.519168 -110.355888)
		(end 146.090386 -110.355888)
		(width 0.1143)
		(layer "In6.Cu")
		(net "FM_CPLD_NODE1_P1V8_EN")
	)
	(segment
		(start 81.0133 -109.848142)
		(end 80.555084 -110.306358)
		(width 0.1143)
		(layer "In7.Cu")
		(net "FM_CPLD_NODE1_P1V8_EN")
	)
	(segment
		(start 67.977004 -106.820716)
		(end 67.445128 -107.352592)
		(width 0.1143)
		(layer "In7.Cu")
		(net "FM_CPLD_NODE1_P1V8_EN")
	)
	(segment
		(start 71.877428 -106.820716)
		(end 67.977004 -106.820716)
		(width 0.1143)
		(layer "In7.Cu")
		(net "FM_CPLD_NODE1_P1V8_EN")
	)
	(segment
		(start 80.555084 -110.306358)
		(end 75.36307 -110.306358)
		(width 0.1143)
		(layer "In7.Cu")
		(net "FM_CPLD_NODE1_P1V8_EN")
	)
	(segment
		(start 75.36307 -110.306358)
		(end 71.877428 -106.820716)
		(width 0.1143)
		(layer "In7.Cu")
		(net "FM_CPLD_NODE1_P1V8_EN")
	)
	(segment
		(start 123.372626 -70.972934)
		(end 128.364488 -70.972934)
		(width 0.508)
		(layer "F.Cu")
		(net "P3V_COIN_CELL")
	)
	(segment
		(start 128.364488 -70.972934)
		(end 128.902206 -71.510652)
		(width 0.508)
		(layer "F.Cu")
		(net "P3V_COIN_CELL")
	)
	(segment
		(start 102.331266 -62.86246)
		(end 101.290374 -62.86246)
		(width 0.1016)
		(layer "F.Cu")
		(net "SMB_CPU_NODE1_XDP_DAT")
	)
	(segment
		(start 98.640392 -65.512442)
		(end 98.640392 -74.282808)
		(width 0.1016)
		(layer "F.Cu")
		(net "SMB_CPU_NODE1_XDP_DAT")
	)
	(segment
		(start 98.640392 -74.282808)
		(end 104.45496 -80.097376)
		(width 0.1016)
		(layer "F.Cu")
		(net "SMB_CPU_NODE1_XDP_DAT")
	)
	(segment
		(start 103.374952 -63.906146)
		(end 102.331266 -62.86246)
		(width 0.1016)
		(layer "F.Cu")
		(net "SMB_CPU_NODE1_XDP_DAT")
	)
	(segment
		(start 104.73182 -63.906146)
		(end 103.374952 -63.906146)
		(width 0.1016)
		(layer "F.Cu")
		(net "SMB_CPU_NODE1_XDP_DAT")
	)
	(segment
		(start 101.290374 -62.86246)
		(end 98.640392 -65.512442)
		(width 0.1016)
		(layer "F.Cu")
		(net "SMB_CPU_NODE1_XDP_DAT")
	)
	(segment
		(start 104.45496 -80.097376)
		(end 104.45496 -80.386428)
		(width 0.1016)
		(layer "F.Cu")
		(net "SMB_CPU_NODE1_XDP_DAT")
	)
	(via
		(at 104.45496 -80.386428)
		(size 0.508)
		(drill 0.254)
		(layers "F.Cu" "B.Cu")
		(net "SMB_CPU_NODE1_XDP_DAT")
	)
	(via
		(at 47.008796 -96.704404)
		(size 0.508)
		(drill 0.254)
		(layers "F.Cu" "B.Cu")
		(net "SMB_CPU_NODE1_XDP_DAT")
	)
	(via
		(at 92.9259 -105.377996)
		(size 0.508)
		(drill 0.254)
		(layers "F.Cu" "B.Cu")
		(net "SMB_CPU_NODE1_XDP_DAT")
	)
	(segment
		(start 47.766732 -94.80042)
		(end 47.766732 -96.682052)
		(width 0.1016)
		(layer "B.Cu")
		(net "SMB_CPU_NODE1_XDP_DAT")
	)
	(segment
		(start 47.766732 -96.682052)
		(end 47.74438 -96.704404)
		(width 0.1016)
		(layer "B.Cu")
		(net "SMB_CPU_NODE1_XDP_DAT")
	)
	(segment
		(start 47.008796 -96.704404)
		(end 47.74438 -96.704404)
		(width 0.1016)
		(layer "B.Cu")
		(net "SMB_CPU_NODE1_XDP_DAT")
	)
	(segment
		(start 95.2881 -100.92436)
		(end 95.2881 -86.331806)
		(width 0.1143)
		(layer "In2.Cu")
		(net "SMB_CPU_NODE1_XDP_DAT")
	)
	(segment
		(start 94.881446 -101.331014)
		(end 95.2881 -100.92436)
		(width 0.1143)
		(layer "In2.Cu")
		(net "SMB_CPU_NODE1_XDP_DAT")
	)
	(segment
		(start 95.2881 -86.331806)
		(end 99.20224 -82.417666)
		(width 0.1143)
		(layer "In2.Cu")
		(net "SMB_CPU_NODE1_XDP_DAT")
	)
	(segment
		(start 94.881446 -102.455218)
		(end 94.881446 -101.331014)
		(width 0.1143)
		(layer "In2.Cu")
		(net "SMB_CPU_NODE1_XDP_DAT")
	)
	(segment
		(start 92.9259 -104.410764)
		(end 94.881446 -102.455218)
		(width 0.1143)
		(layer "In2.Cu")
		(net "SMB_CPU_NODE1_XDP_DAT")
	)
	(segment
		(start 99.326446 -82.294476)
		(end 101.246686 -82.294476)
		(width 0.1143)
		(layer "In2.Cu")
		(net "SMB_CPU_NODE1_XDP_DAT")
	)
	(segment
		(start 99.203256 -82.417666)
		(end 99.326446 -82.294476)
		(width 0.1143)
		(layer "In2.Cu")
		(net "SMB_CPU_NODE1_XDP_DAT")
	)
	(segment
		(start 99.20224 -82.417666)
		(end 99.203256 -82.417666)
		(width 0.1143)
		(layer "In2.Cu")
		(net "SMB_CPU_NODE1_XDP_DAT")
	)
	(segment
		(start 92.9259 -105.377996)
		(end 92.9259 -104.410764)
		(width 0.1143)
		(layer "In2.Cu")
		(net "SMB_CPU_NODE1_XDP_DAT")
	)
	(segment
		(start 104.103678 -80.035146)
		(end 104.45496 -80.386428)
		(width 0.1143)
		(layer "In2.Cu")
		(net "SMB_CPU_NODE1_XDP_DAT")
	)
	(segment
		(start 103.506016 -80.035146)
		(end 104.103678 -80.035146)
		(width 0.1143)
		(layer "In2.Cu")
		(net "SMB_CPU_NODE1_XDP_DAT")
	)
	(segment
		(start 101.246686 -82.294476)
		(end 103.506016 -80.035146)
		(width 0.1143)
		(layer "In2.Cu")
		(net "SMB_CPU_NODE1_XDP_DAT")
	)
	(segment
		(start 80.73517 -107.569)
		(end 81.079086 -107.225084)
		(width 0.1143)
		(layer "In7.Cu")
		(net "SMB_CPU_NODE1_XDP_DAT")
	)
	(segment
		(start 64.493394 -102.693216)
		(end 65.42659 -103.626412)
		(width 0.1143)
		(layer "In7.Cu")
		(net "SMB_CPU_NODE1_XDP_DAT")
	)
	(segment
		(start 79.915512 -107.112562)
		(end 80.37195 -107.569)
		(width 0.1143)
		(layer "In7.Cu")
		(net "SMB_CPU_NODE1_XDP_DAT")
	)
	(segment
		(start 47.84852 -101.88067)
		(end 49.337976 -103.370126)
		(width 0.1143)
		(layer "In7.Cu")
		(net "SMB_CPU_NODE1_XDP_DAT")
	)
	(segment
		(start 72.208136 -103.626412)
		(end 75.694286 -107.112562)
		(width 0.1143)
		(layer "In7.Cu")
		(net "SMB_CPU_NODE1_XDP_DAT")
	)
	(segment
		(start 84.55406 -107.225084)
		(end 85.174836 -106.604308)
		(width 0.1143)
		(layer "In7.Cu")
		(net "SMB_CPU_NODE1_XDP_DAT")
	)
	(segment
		(start 75.694286 -107.112562)
		(end 79.915512 -107.112562)
		(width 0.1143)
		(layer "In7.Cu")
		(net "SMB_CPU_NODE1_XDP_DAT")
	)
	(segment
		(start 49.337976 -103.370126)
		(end 59.701684 -103.370126)
		(width 0.1143)
		(layer "In7.Cu")
		(net "SMB_CPU_NODE1_XDP_DAT")
	)
	(segment
		(start 47.84852 -97.544128)
		(end 47.84852 -101.88067)
		(width 0.1143)
		(layer "In7.Cu")
		(net "SMB_CPU_NODE1_XDP_DAT")
	)
	(segment
		(start 88.381332 -105.377996)
		(end 92.9259 -105.377996)
		(width 0.1143)
		(layer "In7.Cu")
		(net "SMB_CPU_NODE1_XDP_DAT")
	)
	(segment
		(start 87.15502 -106.604308)
		(end 88.381332 -105.377996)
		(width 0.1143)
		(layer "In7.Cu")
		(net "SMB_CPU_NODE1_XDP_DAT")
	)
	(segment
		(start 47.008796 -96.704404)
		(end 47.84852 -97.544128)
		(width 0.1143)
		(layer "In7.Cu")
		(net "SMB_CPU_NODE1_XDP_DAT")
	)
	(segment
		(start 81.079086 -107.225084)
		(end 84.55406 -107.225084)
		(width 0.1143)
		(layer "In7.Cu")
		(net "SMB_CPU_NODE1_XDP_DAT")
	)
	(segment
		(start 65.42659 -103.626412)
		(end 72.208136 -103.626412)
		(width 0.1143)
		(layer "In7.Cu")
		(net "SMB_CPU_NODE1_XDP_DAT")
	)
	(segment
		(start 60.378594 -102.693216)
		(end 64.493394 -102.693216)
		(width 0.1143)
		(layer "In7.Cu")
		(net "SMB_CPU_NODE1_XDP_DAT")
	)
	(segment
		(start 80.37195 -107.569)
		(end 80.73517 -107.569)
		(width 0.1143)
		(layer "In7.Cu")
		(net "SMB_CPU_NODE1_XDP_DAT")
	)
	(segment
		(start 59.701684 -103.370126)
		(end 60.378594 -102.693216)
		(width 0.1143)
		(layer "In7.Cu")
		(net "SMB_CPU_NODE1_XDP_DAT")
	)
	(segment
		(start 85.174836 -106.604308)
		(end 87.15502 -106.604308)
		(width 0.1143)
		(layer "In7.Cu")
		(net "SMB_CPU_NODE1_XDP_DAT")
	)
	(segment
		(start 37.094668 -69.050662)
		(end 35.28822 -70.85711)
		(width 0.1016)
		(layer "F.Cu")
		(net "TP_CPU_NODE1_RP0_PERN5")
	)
	(segment
		(start 40.657018 -68.478146)
		(end 40.084502 -69.050662)
		(width 0.1016)
		(layer "F.Cu")
		(net "TP_CPU_NODE1_RP0_PERN5")
	)
	(segment
		(start 40.084502 -69.050662)
		(end 37.094668 -69.050662)
		(width 0.1016)
		(layer "F.Cu")
		(net "TP_CPU_NODE1_RP0_PERN5")
	)
	(segment
		(start 42.361612 -68.478146)
		(end 40.657018 -68.478146)
		(width 0.1016)
		(layer "F.Cu")
		(net "TP_CPU_NODE1_RP0_PERN5")
	)
	(via
		(at 35.28822 -70.85711)
		(size 0.508)
		(drill 0.254)
		(layers "F.Cu" "B.Cu")
		(net "TP_CPU_NODE1_RP0_PERN5")
	)
	(segment
		(start 131.953762 -121.064528)
		(end 131.953762 -121.52884)
		(width 0.127)
		(layer "F.Cu")
		(net "CLK_100M_USB_NODE1_DN")
	)
	(segment
		(start 133.496304 -127.561594)
		(end 133.877304 -127.561594)
		(width 0.127)
		(layer "F.Cu")
		(net "CLK_100M_USB_NODE1_DN")
	)
	(segment
		(start 132.162042 -127.561594)
		(end 132.78104 -127.561594)
		(width 0.127)
		(layer "F.Cu")
		(net "CLK_100M_USB_NODE1_DN")
	)
	(segment
		(start 131.683252 -122.891042)
		(end 131.683252 -123.931934)
		(width 0.127)
		(layer "F.Cu")
		(net "CLK_100M_USB_NODE1_DN")
	)
	(segment
		(start 136.617964 -127.394462)
		(end 136.785096 -127.561594)
		(width 0.127)
		(layer "F.Cu")
		(net "CLK_100M_USB_NODE1_DN")
	)
	(segment
		(start 135.688832 -127.561594)
		(end 136.069832 -127.561594)
		(width 0.127)
		(layer "F.Cu")
		(net "CLK_100M_USB_NODE1_DN")
	)
	(segment
		(start 136.069832 -127.561594)
		(end 136.236964 -127.394462)
		(width 0.127)
		(layer "F.Cu")
		(net "CLK_100M_USB_NODE1_DN")
	)
	(segment
		(start 162.691572 -102.630986)
		(end 162.2425 -102.630986)
		(width 0.127)
		(layer "F.Cu")
		(net "CLK_100M_USB_NODE1_DN")
	)
	(segment
		(start 131.953762 -121.52884)
		(end 131.911852 -121.57075)
		(width 0.127)
		(layer "F.Cu")
		(net "CLK_100M_USB_NODE1_DN")
	)
	(segment
		(start 135.1407 -127.394462)
		(end 135.5217 -127.394462)
		(width 0.127)
		(layer "F.Cu")
		(net "CLK_100M_USB_NODE1_DN")
	)
	(segment
		(start 135.5217 -127.394462)
		(end 135.688832 -127.561594)
		(width 0.127)
		(layer "F.Cu")
		(net "CLK_100M_USB_NODE1_DN")
	)
	(segment
		(start 131.911852 -121.57075)
		(end 131.911852 -122.662442)
		(width 0.127)
		(layer "F.Cu")
		(net "CLK_100M_USB_NODE1_DN")
	)
	(segment
		(start 132.78104 -127.561594)
		(end 132.948172 -127.394462)
		(width 0.127)
		(layer "F.Cu")
		(net "CLK_100M_USB_NODE1_DN")
	)
	(segment
		(start 163.340034 -102.535736)
		(end 162.786822 -102.535736)
		(width 0.127)
		(layer "F.Cu")
		(net "CLK_100M_USB_NODE1_DN")
	)
	(segment
		(start 162.786822 -102.535736)
		(end 162.691572 -102.630986)
		(width 0.127)
		(layer "F.Cu")
		(net "CLK_100M_USB_NODE1_DN")
	)
	(segment
		(start 133.877304 -127.561594)
		(end 134.044436 -127.394462)
		(width 0.127)
		(layer "F.Cu")
		(net "CLK_100M_USB_NODE1_DN")
	)
	(segment
		(start 162.2425 -102.630986)
		(end 161.519108 -103.354378)
		(width 0.127)
		(layer "F.Cu")
		(net "CLK_100M_USB_NODE1_DN")
	)
	(segment
		(start 132.948172 -127.394462)
		(end 133.329172 -127.394462)
		(width 0.127)
		(layer "F.Cu")
		(net "CLK_100M_USB_NODE1_DN")
	)
	(segment
		(start 131.911852 -122.662442)
		(end 131.683252 -122.891042)
		(width 0.127)
		(layer "F.Cu")
		(net "CLK_100M_USB_NODE1_DN")
	)
	(segment
		(start 136.236964 -127.394462)
		(end 136.617964 -127.394462)
		(width 0.127)
		(layer "F.Cu")
		(net "CLK_100M_USB_NODE1_DN")
	)
	(segment
		(start 160.678114 -103.354378)
		(end 160.195514 -102.871778)
		(width 0.127)
		(layer "F.Cu")
		(net "CLK_100M_USB_NODE1_DN")
	)
	(segment
		(start 134.044436 -127.394462)
		(end 134.425436 -127.394462)
		(width 0.127)
		(layer "F.Cu")
		(net "CLK_100M_USB_NODE1_DN")
	)
	(segment
		(start 131.683252 -123.931934)
		(end 131.29514 -124.320046)
		(width 0.127)
		(layer "F.Cu")
		(net "CLK_100M_USB_NODE1_DN")
	)
	(segment
		(start 131.29514 -124.320046)
		(end 131.29514 -126.694692)
		(width 0.127)
		(layer "F.Cu")
		(net "CLK_100M_USB_NODE1_DN")
	)
	(segment
		(start 134.973568 -127.561594)
		(end 135.1407 -127.394462)
		(width 0.127)
		(layer "F.Cu")
		(net "CLK_100M_USB_NODE1_DN")
	)
	(segment
		(start 140.808964 -127.561594)
		(end 141.775688 -128.528318)
		(width 0.127)
		(layer "F.Cu")
		(net "CLK_100M_USB_NODE1_DN")
	)
	(segment
		(start 134.425436 -127.394462)
		(end 134.592568 -127.561594)
		(width 0.127)
		(layer "F.Cu")
		(net "CLK_100M_USB_NODE1_DN")
	)
	(segment
		(start 142.86738 -128.528318)
		(end 143.34998 -128.045718)
		(width 0.127)
		(layer "F.Cu")
		(net "CLK_100M_USB_NODE1_DN")
	)
	(segment
		(start 134.592568 -127.561594)
		(end 134.973568 -127.561594)
		(width 0.127)
		(layer "F.Cu")
		(net "CLK_100M_USB_NODE1_DN")
	)
	(segment
		(start 161.519108 -103.354378)
		(end 160.678114 -103.354378)
		(width 0.127)
		(layer "F.Cu")
		(net "CLK_100M_USB_NODE1_DN")
	)
	(segment
		(start 136.785096 -127.561594)
		(end 140.808964 -127.561594)
		(width 0.127)
		(layer "F.Cu")
		(net "CLK_100M_USB_NODE1_DN")
	)
	(segment
		(start 131.29514 -126.694692)
		(end 132.162042 -127.561594)
		(width 0.127)
		(layer "F.Cu")
		(net "CLK_100M_USB_NODE1_DN")
	)
	(segment
		(start 133.329172 -127.394462)
		(end 133.496304 -127.561594)
		(width 0.127)
		(layer "F.Cu")
		(net "CLK_100M_USB_NODE1_DN")
	)
	(segment
		(start 141.775688 -128.528318)
		(end 142.86738 -128.528318)
		(width 0.127)
		(layer "F.Cu")
		(net "CLK_100M_USB_NODE1_DN")
	)
	(via
		(at 143.34998 -128.045718)
		(size 0.508)
		(drill 0.254)
		(layers "F.Cu" "B.Cu")
		(net "CLK_100M_USB_NODE1_DN")
	)
	(via
		(at 160.195514 -102.871778)
		(size 0.508)
		(drill 0.254)
		(layers "F.Cu" "B.Cu")
		(net "CLK_100M_USB_NODE1_DN")
	)
	(segment
		(start 158.87954 -108.124498)
		(end 158.87954 -103.93426)
		(width 0.127)
		(layer "B.Cu")
		(net "CLK_100M_USB_NODE1_DN")
	)
	(segment
		(start 155.89758 -118.218966)
		(end 155.89758 -111.106458)
		(width 0.127)
		(layer "B.Cu")
		(net "CLK_100M_USB_NODE1_DN")
	)
	(segment
		(start 143.83258 -128.528318)
		(end 144.15262 -128.528318)
		(width 0.127)
		(layer "B.Cu")
		(net "CLK_100M_USB_NODE1_DN")
	)
	(segment
		(start 143.34998 -128.045718)
		(end 143.83258 -128.528318)
		(width 0.127)
		(layer "B.Cu")
		(net "CLK_100M_USB_NODE1_DN")
	)
	(segment
		(start 159.712914 -103.354378)
		(end 160.195514 -102.871778)
		(width 0.127)
		(layer "B.Cu")
		(net "CLK_100M_USB_NODE1_DN")
	)
	(segment
		(start 144.15262 -128.528318)
		(end 144.98066 -127.700278)
		(width 0.127)
		(layer "B.Cu")
		(net "CLK_100M_USB_NODE1_DN")
	)
	(segment
		(start 144.98066 -127.700278)
		(end 146.416268 -127.700278)
		(width 0.127)
		(layer "B.Cu")
		(net "CLK_100M_USB_NODE1_DN")
	)
	(segment
		(start 159.459422 -103.354378)
		(end 159.712914 -103.354378)
		(width 0.127)
		(layer "B.Cu")
		(net "CLK_100M_USB_NODE1_DN")
	)
	(segment
		(start 155.89758 -111.106458)
		(end 158.87954 -108.124498)
		(width 0.127)
		(layer "B.Cu")
		(net "CLK_100M_USB_NODE1_DN")
	)
	(segment
		(start 158.87954 -103.93426)
		(end 159.459422 -103.354378)
		(width 0.127)
		(layer "B.Cu")
		(net "CLK_100M_USB_NODE1_DN")
	)
	(segment
		(start 146.416268 -127.700278)
		(end 155.89758 -118.218966)
		(width 0.127)
		(layer "B.Cu")
		(net "CLK_100M_USB_NODE1_DN")
	)
	(via
		(at 45.760386 -10.327894)
		(size 0.508)
		(drill 0.254)
		(layers "F.Cu" "B.Cu")
		(net "SW_PV_VDDR_NODE1_PH")
	)
	(segment
		(start 88.960452 -151.859996)
		(end 88.6206 -152.199848)
		(width 0.254)
		(layer "F.Cu")
		(net "P1V8_STB_NODE1")
	)
	(segment
		(start 105.547668 -148.833078)
		(end 103.9114 -147.19681)
		(width 0.254)
		(layer "F.Cu")
		(net "P1V8_STB_NODE1")
	)
	(segment
		(start 91.155774 -147.19681)
		(end 88.960452 -149.392132)
		(width 0.254)
		(layer "F.Cu")
		(net "P1V8_STB_NODE1")
	)
	(segment
		(start 105.547668 -152.719278)
		(end 105.547668 -151.7142)
		(width 0.254)
		(layer "F.Cu")
		(net "P1V8_STB_NODE1")
	)
	(segment
		(start 103.9114 -147.19681)
		(end 91.155774 -147.19681)
		(width 0.254)
		(layer "F.Cu")
		(net "P1V8_STB_NODE1")
	)
	(segment
		(start 103.326946 -152.719278)
		(end 103.091742 -152.954482)
		(width 0.254)
		(layer "F.Cu")
		(net "P1V8_STB_NODE1")
	)
	(segment
		(start 105.547668 -151.7142)
		(end 105.547668 -148.833078)
		(width 0.254)
		(layer "F.Cu")
		(net "P1V8_STB_NODE1")
	)
	(segment
		(start 88.960452 -149.392132)
		(end 88.960452 -151.859996)
		(width 0.254)
		(layer "F.Cu")
		(net "P1V8_STB_NODE1")
	)
	(segment
		(start 103.091742 -152.954482)
		(end 103.091742 -153.299922)
		(width 0.254)
		(layer "F.Cu")
		(net "P1V8_STB_NODE1")
	)
	(segment
		(start 105.547668 -152.719278)
		(end 103.326946 -152.719278)
		(width 0.254)
		(layer "F.Cu")
		(net "P1V8_STB_NODE1")
	)
	(via
		(at 69.01688 -107.337098)
		(size 0.508)
		(drill 0.254)
		(layers "F.Cu" "B.Cu")
		(net "P1V8_STB_NODE1")
	)
	(via
		(at 62.305438 -103.131366)
		(size 0.508)
		(drill 0.254)
		(layers "F.Cu" "B.Cu")
		(net "P1V8_STB_NODE1")
	)
	(via
		(at 71.42226 -107.941364)
		(size 0.508)
		(drill 0.254)
		(layers "F.Cu" "B.Cu")
		(net "P1V8_STB_NODE1")
	)
	(via
		(at 29.394658 -103.084376)
		(size 0.508)
		(drill 0.254)
		(layers "F.Cu" "B.Cu")
		(net "P1V8_STB_NODE1")
	)
	(via
		(at 29.083508 -101.920548)
		(size 0.6604)
		(drill 0.3302)
		(layers "F.Cu" "B.Cu")
		(net "P1V8_STB_NODE1")
	)
	(via
		(at 90.163142 -157.629352)
		(size 0.508)
		(drill 0.254)
		(layers "F.Cu" "B.Cu")
		(net "P1V8_STB_NODE1")
	)
	(via
		(at 91.814142 -157.629352)
		(size 0.508)
		(drill 0.254)
		(layers "F.Cu" "B.Cu")
		(net "P1V8_STB_NODE1")
	)
	(via
		(at 90.163142 -158.391352)
		(size 0.508)
		(drill 0.254)
		(layers "F.Cu" "B.Cu")
		(net "P1V8_STB_NODE1")
	)
	(via
		(at 89.398856 -152.230328)
		(size 0.508)
		(drill 0.254)
		(layers "F.Cu" "B.Cu")
		(net "P1V8_STB_NODE1")
	)
	(via
		(at 91.604338 -153.069544)
		(size 0.508)
		(drill 0.254)
		(layers "F.Cu" "B.Cu")
		(net "P1V8_STB_NODE1")
	)
	(via
		(at 71.12254 -107.258866)
		(size 0.508)
		(drill 0.254)
		(layers "F.Cu" "B.Cu")
		(net "P1V8_STB_NODE1")
	)
	(via
		(at 90.163142 -156.105352)
		(size 0.508)
		(drill 0.254)
		(layers "F.Cu" "B.Cu")
		(net "P1V8_STB_NODE1")
	)
	(via
		(at 62.940438 -103.131366)
		(size 0.508)
		(drill 0.254)
		(layers "F.Cu" "B.Cu")
		(net "P1V8_STB_NODE1")
	)
	(via
		(at 63.575438 -103.131366)
		(size 0.508)
		(drill 0.254)
		(layers "F.Cu" "B.Cu")
		(net "P1V8_STB_NODE1")
	)
	(via
		(at 68.48602 -107.920536)
		(size 0.508)
		(drill 0.254)
		(layers "F.Cu" "B.Cu")
		(net "P1V8_STB_NODE1")
	)
	(via
		(at 90.163142 -153.057352)
		(size 0.508)
		(drill 0.254)
		(layers "F.Cu" "B.Cu")
		(net "P1V8_STB_NODE1")
	)
	(via
		(at 90.163142 -153.819352)
		(size 0.508)
		(drill 0.254)
		(layers "F.Cu" "B.Cu")
		(net "P1V8_STB_NODE1")
	)
	(via
		(at 28.830016 -103.548942)
		(size 0.508)
		(drill 0.254)
		(layers "F.Cu" "B.Cu")
		(net "P1V8_STB_NODE1")
	)
	(via
		(at 69.64172 -107.941364)
		(size 0.508)
		(drill 0.254)
		(layers "F.Cu" "B.Cu")
		(net "P1V8_STB_NODE1")
	)
	(via
		(at 28.806648 -102.825804)
		(size 0.508)
		(drill 0.254)
		(layers "F.Cu" "B.Cu")
		(net "P1V8_STB_NODE1")
	)
	(via
		(at 90.163142 -155.343352)
		(size 0.508)
		(drill 0.254)
		(layers "F.Cu" "B.Cu")
		(net "P1V8_STB_NODE1")
	)
	(via
		(at 64.210438 -103.131366)
		(size 0.508)
		(drill 0.254)
		(layers "F.Cu" "B.Cu")
		(net "P1V8_STB_NODE1")
	)
	(via
		(at 30.516576 -101.880416)
		(size 0.6604)
		(drill 0.3302)
		(layers "F.Cu" "B.Cu")
		(net "P1V8_STB_NODE1")
	)
	(via
		(at 70.2056 -107.274614)
		(size 0.508)
		(drill 0.254)
		(layers "F.Cu" "B.Cu")
		(net "P1V8_STB_NODE1")
	)
	(via
		(at 94.878652 -132.134102)
		(size 0.508)
		(drill 0.254)
		(layers "F.Cu" "B.Cu")
		(net "P1V8_STB_NODE1")
	)
	(via
		(at 70.63232 -107.88904)
		(size 0.508)
		(drill 0.254)
		(layers "F.Cu" "B.Cu")
		(net "P1V8_STB_NODE1")
	)
	(via
		(at 95.638112 -132.115052)
		(size 0.508)
		(drill 0.254)
		(layers "F.Cu" "B.Cu")
		(net "P1V8_STB_NODE1")
	)
	(segment
		(start 123.372626 -70.172834)
		(end 123.372626 -69.701918)
		(width 0.1016)
		(layer "F.Cu")
		(net "P3V0_BAT_NODE1_R")
	)
	(segment
		(start 121.86793 -69.308218)
		(end 122.978926 -69.308218)
		(width 0.1016)
		(layer "F.Cu")
		(net "P3V0_BAT_NODE1_R")
	)
	(segment
		(start 123.372626 -69.701918)
		(end 122.978926 -69.308218)
		(width 0.1016)
		(layer "F.Cu")
		(net "P3V0_BAT_NODE1_R")
	)
	(via
		(at 122.978926 -69.308218)
		(size 0.508)
		(drill 0.254)
		(layers "F.Cu" "B.Cu")
		(net "P3V0_BAT_NODE1_R")
	)
	(segment
		(start 50.28565 -81.571846)
		(end 50.28565 -81.255362)
		(width 0.1016)
		(layer "F.Cu")
		(net "TP_CPU_NODE1_SOC_THERMATP0")
	)
	(segment
		(start 50.28565 -81.255362)
		(end 49.98847 -80.958182)
		(width 0.1016)
		(layer "F.Cu")
		(net "TP_CPU_NODE1_SOC_THERMATP0")
	)
	(segment
		(start 49.98847 -80.958182)
		(end 48.951134 -80.958182)
		(width 0.1016)
		(layer "F.Cu")
		(net "TP_CPU_NODE1_SOC_THERMATP0")
	)
	(segment
		(start 48.951134 -80.958182)
		(end 48.554386 -80.561434)
		(width 0.1016)
		(layer "F.Cu")
		(net "TP_CPU_NODE1_SOC_THERMATP0")
	)
	(via
		(at 48.554386 -80.561434)
		(size 0.508)
		(drill 0.254)
		(layers "F.Cu" "B.Cu")
		(net "TP_CPU_NODE1_SOC_THERMATP0")
	)
	(segment
		(start 110.460028 -62.906148)
		(end 108.495338 -62.906148)
		(width 0.1016)
		(layer "F.Cu")
		(net "XDP_SOC_CPU_NODE1_TDI")
	)
	(segment
		(start 108.495338 -62.906148)
		(end 107.940094 -62.350904)
		(width 0.1016)
		(layer "F.Cu")
		(net "XDP_SOC_CPU_NODE1_TDI")
	)
	(segment
		(start 74.250042 -78.96733)
		(end 74.387456 -79.104744)
		(width 0.1016)
		(layer "F.Cu")
		(net "XDP_SOC_CPU_NODE1_TDI")
	)
	(segment
		(start 74.387456 -79.104744)
		(end 75.78344 -79.104744)
		(width 0.1016)
		(layer "F.Cu")
		(net "XDP_SOC_CPU_NODE1_TDI")
	)
	(segment
		(start 77.107034 -78.400402)
		(end 77.5335 -78.826868)
		(width 0.1016)
		(layer "F.Cu")
		(net "XDP_SOC_CPU_NODE1_TDI")
	)
	(segment
		(start 75.78344 -79.104744)
		(end 76.487782 -78.400402)
		(width 0.1016)
		(layer "F.Cu")
		(net "XDP_SOC_CPU_NODE1_TDI")
	)
	(segment
		(start 107.940094 -62.350904)
		(end 107.940094 -61.265562)
		(width 0.1016)
		(layer "F.Cu")
		(net "XDP_SOC_CPU_NODE1_TDI")
	)
	(segment
		(start 77.7748 -78.826868)
		(end 77.5335 -78.826868)
		(width 0.1016)
		(layer "F.Cu")
		(net "XDP_SOC_CPU_NODE1_TDI")
	)
	(segment
		(start 76.487782 -78.400402)
		(end 77.107034 -78.400402)
		(width 0.1016)
		(layer "F.Cu")
		(net "XDP_SOC_CPU_NODE1_TDI")
	)
	(segment
		(start 78.409546 -78.192122)
		(end 77.7748 -78.826868)
		(width 0.1016)
		(layer "F.Cu")
		(net "XDP_SOC_CPU_NODE1_TDI")
	)
	(segment
		(start 79.545942 -78.192122)
		(end 78.409546 -78.192122)
		(width 0.1016)
		(layer "F.Cu")
		(net "XDP_SOC_CPU_NODE1_TDI")
	)
	(via
		(at 107.940094 -61.265562)
		(size 0.508)
		(drill 0.254)
		(layers "F.Cu" "B.Cu")
		(net "XDP_SOC_CPU_NODE1_TDI")
	)
	(via
		(at 77.5335 -78.826868)
		(size 0.508)
		(drill 0.254)
		(layers "F.Cu" "B.Cu")
		(net "XDP_SOC_CPU_NODE1_TDI")
	)
	(segment
		(start 77.656436 -78.703932)
		(end 82.70494 -78.703932)
		(width 0.1143)
		(layer "In2.Cu")
		(net "XDP_SOC_CPU_NODE1_TDI")
	)
	(segment
		(start 82.70494 -78.703932)
		(end 83.025742 -79.024734)
		(width 0.1143)
		(layer "In2.Cu")
		(net "XDP_SOC_CPU_NODE1_TDI")
	)
	(segment
		(start 91.762326 -79.693262)
		(end 100.953062 -79.693262)
		(width 0.1143)
		(layer "In2.Cu")
		(net "XDP_SOC_CPU_NODE1_TDI")
	)
	(segment
		(start 108.09986 -77.960474)
		(end 111.524542 -74.535792)
		(width 0.1143)
		(layer "In2.Cu")
		(net "XDP_SOC_CPU_NODE1_TDI")
	)
	(segment
		(start 112.77727 -63.43015)
		(end 110.612682 -61.265562)
		(width 0.1143)
		(layer "In2.Cu")
		(net "XDP_SOC_CPU_NODE1_TDI")
	)
	(segment
		(start 87.48903 -77.389228)
		(end 89.198196 -79.098394)
		(width 0.1143)
		(layer "In2.Cu")
		(net "XDP_SOC_CPU_NODE1_TDI")
	)
	(segment
		(start 83.025742 -79.024734)
		(end 84.581746 -79.024734)
		(width 0.1143)
		(layer "In2.Cu")
		(net "XDP_SOC_CPU_NODE1_TDI")
	)
	(segment
		(start 100.953062 -79.693262)
		(end 102.68585 -77.960474)
		(width 0.1143)
		(layer "In2.Cu")
		(net "XDP_SOC_CPU_NODE1_TDI")
	)
	(segment
		(start 112.77727 -64.273176)
		(end 112.77727 -63.43015)
		(width 0.1143)
		(layer "In2.Cu")
		(net "XDP_SOC_CPU_NODE1_TDI")
	)
	(segment
		(start 77.5335 -78.826868)
		(end 77.656436 -78.703932)
		(width 0.1143)
		(layer "In2.Cu")
		(net "XDP_SOC_CPU_NODE1_TDI")
	)
	(segment
		(start 86.217252 -77.389228)
		(end 87.48903 -77.389228)
		(width 0.1143)
		(layer "In2.Cu")
		(net "XDP_SOC_CPU_NODE1_TDI")
	)
	(segment
		(start 91.167458 -79.098394)
		(end 91.762326 -79.693262)
		(width 0.1143)
		(layer "In2.Cu")
		(net "XDP_SOC_CPU_NODE1_TDI")
	)
	(segment
		(start 111.524542 -65.525904)
		(end 112.77727 -64.273176)
		(width 0.1143)
		(layer "In2.Cu")
		(net "XDP_SOC_CPU_NODE1_TDI")
	)
	(segment
		(start 84.581746 -79.024734)
		(end 86.217252 -77.389228)
		(width 0.1143)
		(layer "In2.Cu")
		(net "XDP_SOC_CPU_NODE1_TDI")
	)
	(segment
		(start 110.612682 -61.265562)
		(end 107.940094 -61.265562)
		(width 0.1143)
		(layer "In2.Cu")
		(net "XDP_SOC_CPU_NODE1_TDI")
	)
	(segment
		(start 102.68585 -77.960474)
		(end 108.09986 -77.960474)
		(width 0.1143)
		(layer "In2.Cu")
		(net "XDP_SOC_CPU_NODE1_TDI")
	)
	(segment
		(start 89.198196 -79.098394)
		(end 91.167458 -79.098394)
		(width 0.1143)
		(layer "In2.Cu")
		(net "XDP_SOC_CPU_NODE1_TDI")
	)
	(segment
		(start 111.524542 -74.535792)
		(end 111.524542 -65.525904)
		(width 0.1143)
		(layer "In2.Cu")
		(net "XDP_SOC_CPU_NODE1_TDI")
	)
	(segment
		(start 40.654478 -68.91147)
		(end 40.217598 -69.34835)
		(width 0.1016)
		(layer "F.Cu")
		(net "TP_CPU_NODE1_RP0_PERP5")
	)
	(segment
		(start 43.099736 -68.509642)
		(end 42.931842 -68.509642)
		(width 0.1016)
		(layer "F.Cu")
		(net "TP_CPU_NODE1_RP0_PERP5")
	)
	(segment
		(start 37.75456 -69.34835)
		(end 36.8808 -70.22211)
		(width 0.1016)
		(layer "F.Cu")
		(net "TP_CPU_NODE1_RP0_PERP5")
	)
	(segment
		(start 40.217598 -69.34835)
		(end 37.75456 -69.34835)
		(width 0.1016)
		(layer "F.Cu")
		(net "TP_CPU_NODE1_RP0_PERP5")
	)
	(segment
		(start 36.8808 -70.22211)
		(end 36.8808 -70.222872)
		(width 0.1016)
		(layer "F.Cu")
		(net "TP_CPU_NODE1_RP0_PERP5")
	)
	(segment
		(start 42.931842 -68.509642)
		(end 42.530014 -68.91147)
		(width 0.1016)
		(layer "F.Cu")
		(net "TP_CPU_NODE1_RP0_PERP5")
	)
	(segment
		(start 42.530014 -68.91147)
		(end 40.654478 -68.91147)
		(width 0.1016)
		(layer "F.Cu")
		(net "TP_CPU_NODE1_RP0_PERP5")
	)
	(via
		(at 36.8808 -70.222872)
		(size 0.508)
		(drill 0.254)
		(layers "F.Cu" "B.Cu")
		(net "TP_CPU_NODE1_RP0_PERP5")
	)
	(segment
		(start 68.085208 -112.285018)
		(end 67.772788 -112.597438)
		(width 0.1016)
		(layer "F.Cu")
		(net "FM_CPLD_NODE1_P1V8_EN_LV")
	)
	(segment
		(start 66.502534 -113.521744)
		(end 65.653158 -112.672368)
		(width 0.1016)
		(layer "F.Cu")
		(net "FM_CPLD_NODE1_P1V8_EN_LV")
	)
	(segment
		(start 68.085208 -111.801148)
		(end 68.085208 -112.285018)
		(width 0.1016)
		(layer "F.Cu")
		(net "FM_CPLD_NODE1_P1V8_EN_LV")
	)
	(segment
		(start 65.672462 -112.653064)
		(end 65.653158 -112.672368)
		(width 0.1016)
		(layer "F.Cu")
		(net "FM_CPLD_NODE1_P1V8_EN_LV")
	)
	(segment
		(start 67.486784 -113.521744)
		(end 66.502534 -113.521744)
		(width 0.1016)
		(layer "F.Cu")
		(net "FM_CPLD_NODE1_P1V8_EN_LV")
	)
	(segment
		(start 67.486784 -112.883442)
		(end 67.486784 -113.521744)
		(width 0.1016)
		(layer "F.Cu")
		(net "FM_CPLD_NODE1_P1V8_EN_LV")
	)
	(segment
		(start 65.672462 -111.333026)
		(end 65.672462 -112.653064)
		(width 0.1016)
		(layer "F.Cu")
		(net "FM_CPLD_NODE1_P1V8_EN_LV")
	)
	(segment
		(start 67.772788 -112.597438)
		(end 67.486784 -112.883442)
		(width 0.1016)
		(layer "F.Cu")
		(net "FM_CPLD_NODE1_P1V8_EN_LV")
	)
	(via
		(at 67.772788 -112.597438)
		(size 0.508)
		(drill 0.254)
		(layers "F.Cu" "B.Cu")
		(net "FM_CPLD_NODE1_P1V8_EN_LV")
	)
	(segment
		(start 49.228248 -80.497426)
		(end 49.265078 -80.534256)
		(width 0.1016)
		(layer "F.Cu")
		(net "SMB_CPU_NODE1_BMC_DAT_RR")
	)
	(segment
		(start 49.228248 -80.002126)
		(end 49.228248 -80.497426)
		(width 0.1016)
		(layer "F.Cu")
		(net "SMB_CPU_NODE1_BMC_DAT_RR")
	)
	(via
		(at 46.428152 -89.435432)
		(size 0.6604)
		(drill 0.3302)
		(layers "F.Cu" "B.Cu")
		(net "SMB_CPU_NODE1_BMC_DAT_RR")
	)
	(via
		(at 49.265078 -80.534256)
		(size 0.508)
		(drill 0.254)
		(layers "F.Cu" "B.Cu")
		(net "SMB_CPU_NODE1_BMC_DAT_RR")
	)
	(segment
		(start 44.718732 -94.00032)
		(end 44.718732 -93.263212)
		(width 0.1016)
		(layer "B.Cu")
		(net "SMB_CPU_NODE1_BMC_DAT_RR")
	)
	(segment
		(start 46.428152 -89.435432)
		(end 46.428152 -85.972904)
		(width 0.1016)
		(layer "B.Cu")
		(net "SMB_CPU_NODE1_BMC_DAT_RR")
	)
	(segment
		(start 44.718732 -93.263212)
		(end 46.428152 -91.553792)
		(width 0.1016)
		(layer "B.Cu")
		(net "SMB_CPU_NODE1_BMC_DAT_RR")
	)
	(segment
		(start 49.072292 -81.180686)
		(end 49.265078 -80.9879)
		(width 0.1016)
		(layer "B.Cu")
		(net "SMB_CPU_NODE1_BMC_DAT_RR")
	)
	(segment
		(start 46.428152 -85.972904)
		(end 46.422818 -85.96757)
		(width 0.1016)
		(layer "B.Cu")
		(net "SMB_CPU_NODE1_BMC_DAT_RR")
	)
	(segment
		(start 45.734732 -94.00032)
		(end 44.718732 -94.00032)
		(width 0.1016)
		(layer "B.Cu")
		(net "SMB_CPU_NODE1_BMC_DAT_RR")
	)
	(segment
		(start 46.422818 -85.96757)
		(end 46.422818 -82.92211)
		(width 0.1016)
		(layer "B.Cu")
		(net "SMB_CPU_NODE1_BMC_DAT_RR")
	)
	(segment
		(start 46.422818 -82.92211)
		(end 48.164242 -81.180686)
		(width 0.1016)
		(layer "B.Cu")
		(net "SMB_CPU_NODE1_BMC_DAT_RR")
	)
	(segment
		(start 46.428152 -91.553792)
		(end 46.428152 -89.435432)
		(width 0.1016)
		(layer "B.Cu")
		(net "SMB_CPU_NODE1_BMC_DAT_RR")
	)
	(segment
		(start 49.265078 -80.9879)
		(end 49.265078 -80.534256)
		(width 0.1016)
		(layer "B.Cu")
		(net "SMB_CPU_NODE1_BMC_DAT_RR")
	)
	(segment
		(start 48.164242 -81.180686)
		(end 49.072292 -81.180686)
		(width 0.1016)
		(layer "B.Cu")
		(net "SMB_CPU_NODE1_BMC_DAT_RR")
	)
	(segment
		(start 106.674412 -72.240394)
		(end 106.674412 -72.463914)
		(width 0.1016)
		(layer "F.Cu")
		(net "XDP_CPU_NODE1_VISA15")
	)
	(segment
		(start 67.916044 -74.283062)
		(end 67.916044 -74.285094)
		(width 0.1016)
		(layer "F.Cu")
		(net "XDP_CPU_NODE1_VISA15")
	)
	(segment
		(start 67.916044 -74.285094)
		(end 68.292218 -74.661268)
		(width 0.1016)
		(layer "F.Cu")
		(net "XDP_CPU_NODE1_VISA15")
	)
	(segment
		(start 106.674412 -72.463914)
		(end 106.321352 -72.816974)
		(width 0.1016)
		(layer "F.Cu")
		(net "XDP_CPU_NODE1_VISA15")
	)
	(segment
		(start 109.057186 -69.372988)
		(end 108.508038 -69.372988)
		(width 0.1016)
		(layer "F.Cu")
		(net "XDP_CPU_NODE1_VISA15")
	)
	(segment
		(start 110.460028 -69.406262)
		(end 109.09046 -69.406262)
		(width 0.1016)
		(layer "F.Cu")
		(net "XDP_CPU_NODE1_VISA15")
	)
	(segment
		(start 108.266992 -69.614034)
		(end 108.266992 -70.647814)
		(width 0.1016)
		(layer "F.Cu")
		(net "XDP_CPU_NODE1_VISA15")
	)
	(segment
		(start 108.508038 -69.372988)
		(end 108.266992 -69.614034)
		(width 0.1016)
		(layer "F.Cu")
		(net "XDP_CPU_NODE1_VISA15")
	)
	(segment
		(start 109.09046 -69.406262)
		(end 109.057186 -69.372988)
		(width 0.1016)
		(layer "F.Cu")
		(net "XDP_CPU_NODE1_VISA15")
	)
	(segment
		(start 108.266992 -70.647814)
		(end 106.674412 -72.240394)
		(width 0.1016)
		(layer "F.Cu")
		(net "XDP_CPU_NODE1_VISA15")
	)
	(via
		(at 68.292218 -74.661268)
		(size 0.508)
		(drill 0.254)
		(layers "F.Cu" "B.Cu")
		(net "XDP_CPU_NODE1_VISA15")
	)
	(via
		(at 106.321352 -72.816974)
		(size 0.508)
		(drill 0.254)
		(layers "F.Cu" "B.Cu")
		(net "XDP_CPU_NODE1_VISA15")
	)
	(segment
		(start 100.597208 -72.735694)
		(end 99.64674 -73.686162)
		(width 0.1143)
		(layer "In2.Cu")
		(net "XDP_CPU_NODE1_VISA15")
	)
	(segment
		(start 68.489068 -75.213464)
		(end 68.489068 -74.858118)
		(width 0.1143)
		(layer "In2.Cu")
		(net "XDP_CPU_NODE1_VISA15")
	)
	(segment
		(start 104.46766 -73.074784)
		(end 104.46766 -73.763886)
		(width 0.1143)
		(layer "In2.Cu")
		(net "XDP_CPU_NODE1_VISA15")
	)
	(segment
		(start 105.08996 -74.29754)
		(end 105.08996 -73.074784)
		(width 0.1143)
		(layer "In2.Cu")
		(net "XDP_CPU_NODE1_VISA15")
	)
	(segment
		(start 106.321352 -72.816974)
		(end 106.321352 -72.816212)
		(width 0.1143)
		(layer "In2.Cu")
		(net "XDP_CPU_NODE1_VISA15")
	)
	(segment
		(start 81.725008 -74.987912)
		(end 77.951584 -74.987912)
		(width 0.1143)
		(layer "In2.Cu")
		(net "XDP_CPU_NODE1_VISA15")
	)
	(segment
		(start 104.650032 -72.892412)
		(end 104.46766 -73.074784)
		(width 0.1143)
		(layer "In2.Cu")
		(net "XDP_CPU_NODE1_VISA15")
	)
	(segment
		(start 99.64674 -74.8411)
		(end 98.988626 -75.499214)
		(width 0.1143)
		(layer "In2.Cu")
		(net "XDP_CPU_NODE1_VISA15")
	)
	(segment
		(start 94.634304 -74.151744)
		(end 92.64396 -72.1614)
		(width 0.1143)
		(layer "In2.Cu")
		(net "XDP_CPU_NODE1_VISA15")
	)
	(segment
		(start 104.46766 -73.763886)
		(end 104.282748 -73.948798)
		(width 0.1143)
		(layer "In2.Cu")
		(net "XDP_CPU_NODE1_VISA15")
	)
	(segment
		(start 104.282748 -73.948798)
		(end 104.282748 -73.949814)
		(width 0.1143)
		(layer "In2.Cu")
		(net "XDP_CPU_NODE1_VISA15")
	)
	(segment
		(start 77.370432 -75.569064)
		(end 74.982324 -75.569064)
		(width 0.1143)
		(layer "In2.Cu")
		(net "XDP_CPU_NODE1_VISA15")
	)
	(segment
		(start 105.71226 -74.29754)
		(end 105.529888 -74.479912)
		(width 0.1143)
		(layer "In2.Cu")
		(net "XDP_CPU_NODE1_VISA15")
	)
	(segment
		(start 106.321352 -72.816212)
		(end 106.158792 -72.653652)
		(width 0.1143)
		(layer "In2.Cu")
		(net "XDP_CPU_NODE1_VISA15")
	)
	(segment
		(start 103.84536 -72.918066)
		(end 103.662988 -72.735694)
		(width 0.1143)
		(layer "In2.Cu")
		(net "XDP_CPU_NODE1_VISA15")
	)
	(segment
		(start 104.907588 -72.892412)
		(end 104.650032 -72.892412)
		(width 0.1143)
		(layer "In2.Cu")
		(net "XDP_CPU_NODE1_VISA15")
	)
	(segment
		(start 69.325236 -76.049632)
		(end 68.489068 -75.213464)
		(width 0.1143)
		(layer "In2.Cu")
		(net "XDP_CPU_NODE1_VISA15")
	)
	(segment
		(start 99.64674 -73.686162)
		(end 99.64674 -74.8411)
		(width 0.1143)
		(layer "In2.Cu")
		(net "XDP_CPU_NODE1_VISA15")
	)
	(segment
		(start 74.982324 -75.569064)
		(end 74.501756 -76.049632)
		(width 0.1143)
		(layer "In2.Cu")
		(net "XDP_CPU_NODE1_VISA15")
	)
	(segment
		(start 95.832168 -74.151744)
		(end 94.634304 -74.151744)
		(width 0.1143)
		(layer "In2.Cu")
		(net "XDP_CPU_NODE1_VISA15")
	)
	(segment
		(start 105.71226 -72.806052)
		(end 105.71226 -74.29754)
		(width 0.1143)
		(layer "In2.Cu")
		(net "XDP_CPU_NODE1_VISA15")
	)
	(segment
		(start 89.103454 -72.1614)
		(end 88.229694 -71.28764)
		(width 0.1143)
		(layer "In2.Cu")
		(net "XDP_CPU_NODE1_VISA15")
	)
	(segment
		(start 104.025192 -73.949814)
		(end 103.84536 -73.769982)
		(width 0.1143)
		(layer "In2.Cu")
		(net "XDP_CPU_NODE1_VISA15")
	)
	(segment
		(start 104.282748 -73.949814)
		(end 104.025192 -73.949814)
		(width 0.1143)
		(layer "In2.Cu")
		(net "XDP_CPU_NODE1_VISA15")
	)
	(segment
		(start 106.158792 -72.653652)
		(end 105.86466 -72.653652)
		(width 0.1143)
		(layer "In2.Cu")
		(net "XDP_CPU_NODE1_VISA15")
	)
	(segment
		(start 98.988626 -75.499214)
		(end 97.179638 -75.499214)
		(width 0.1143)
		(layer "In2.Cu")
		(net "XDP_CPU_NODE1_VISA15")
	)
	(segment
		(start 105.08996 -73.074784)
		(end 104.907588 -72.892412)
		(width 0.1143)
		(layer "In2.Cu")
		(net "XDP_CPU_NODE1_VISA15")
	)
	(segment
		(start 103.84536 -73.769982)
		(end 103.84536 -72.918066)
		(width 0.1143)
		(layer "In2.Cu")
		(net "XDP_CPU_NODE1_VISA15")
	)
	(segment
		(start 88.229694 -71.28764)
		(end 85.42528 -71.28764)
		(width 0.1143)
		(layer "In2.Cu")
		(net "XDP_CPU_NODE1_VISA15")
	)
	(segment
		(start 103.662988 -72.735694)
		(end 100.597208 -72.735694)
		(width 0.1143)
		(layer "In2.Cu")
		(net "XDP_CPU_NODE1_VISA15")
	)
	(segment
		(start 105.86466 -72.653652)
		(end 105.71226 -72.806052)
		(width 0.1143)
		(layer "In2.Cu")
		(net "XDP_CPU_NODE1_VISA15")
	)
	(segment
		(start 105.529888 -74.479912)
		(end 105.272332 -74.479912)
		(width 0.1143)
		(layer "In2.Cu")
		(net "XDP_CPU_NODE1_VISA15")
	)
	(segment
		(start 77.951584 -74.987912)
		(end 77.370432 -75.569064)
		(width 0.1143)
		(layer "In2.Cu")
		(net "XDP_CPU_NODE1_VISA15")
	)
	(segment
		(start 68.489068 -74.858118)
		(end 68.292218 -74.661268)
		(width 0.1143)
		(layer "In2.Cu")
		(net "XDP_CPU_NODE1_VISA15")
	)
	(segment
		(start 85.42528 -71.28764)
		(end 81.725008 -74.987912)
		(width 0.1143)
		(layer "In2.Cu")
		(net "XDP_CPU_NODE1_VISA15")
	)
	(segment
		(start 74.501756 -76.049632)
		(end 69.325236 -76.049632)
		(width 0.1143)
		(layer "In2.Cu")
		(net "XDP_CPU_NODE1_VISA15")
	)
	(segment
		(start 97.179638 -75.499214)
		(end 95.832168 -74.151744)
		(width 0.1143)
		(layer "In2.Cu")
		(net "XDP_CPU_NODE1_VISA15")
	)
	(segment
		(start 105.272332 -74.479912)
		(end 105.08996 -74.29754)
		(width 0.1143)
		(layer "In2.Cu")
		(net "XDP_CPU_NODE1_VISA15")
	)
	(segment
		(start 92.64396 -72.1614)
		(end 89.103454 -72.1614)
		(width 0.1143)
		(layer "In2.Cu")
		(net "XDP_CPU_NODE1_VISA15")
	)
	(segment
		(start 41.445434 -66.345308)
		(end 41.337738 -66.453004)
		(width 0.1016)
		(layer "F.Cu")
		(net "TP_CPU_NODE1_RP0_PERP3")
	)
	(segment
		(start 40.433244 -66.453004)
		(end 39.254684 -65.274444)
		(width 0.1016)
		(layer "F.Cu")
		(net "TP_CPU_NODE1_RP0_PERP3")
	)
	(segment
		(start 42.513758 -66.740786)
		(end 42.11828 -66.345308)
		(width 0.1016)
		(layer "F.Cu")
		(net "TP_CPU_NODE1_RP0_PERP3")
	)
	(segment
		(start 42.69613 -66.740786)
		(end 42.513758 -66.740786)
		(width 0.1016)
		(layer "F.Cu")
		(net "TP_CPU_NODE1_RP0_PERP3")
	)
	(segment
		(start 41.337738 -66.453004)
		(end 40.433244 -66.453004)
		(width 0.1016)
		(layer "F.Cu")
		(net "TP_CPU_NODE1_RP0_PERP3")
	)
	(segment
		(start 42.11828 -66.345308)
		(end 41.445434 -66.345308)
		(width 0.1016)
		(layer "F.Cu")
		(net "TP_CPU_NODE1_RP0_PERP3")
	)
	(via
		(at 39.254684 -65.274444)
		(size 0.508)
		(drill 0.254)
		(layers "F.Cu" "B.Cu")
		(net "TP_CPU_NODE1_RP0_PERP3")
	)
	(via
		(at 73.092564 -5.407406)
		(size 0.508)
		(drill 0.254)
		(layers "F.Cu" "B.Cu")
		(net "SW_P3V3_NODE1_PH")
	)
	(segment
		(start 74.172826 -78.239112)
		(end 74.274426 -78.137512)
		(width 0.1016)
		(layer "F.Cu")
		(net "SVID_CPU_NODE1_PVCCP_ALERT_R_L")
	)
	(segment
		(start 72.901556 -78.58633)
		(end 72.945752 -78.58633)
		(width 0.1016)
		(layer "F.Cu")
		(net "SVID_CPU_NODE1_PVCCP_ALERT_R_L")
	)
	(segment
		(start 74.274426 -78.137512)
		(end 75.23734 -78.137512)
		(width 0.1016)
		(layer "F.Cu")
		(net "SVID_CPU_NODE1_PVCCP_ALERT_R_L")
	)
	(segment
		(start 72.945752 -78.58633)
		(end 73.29297 -78.239112)
		(width 0.1016)
		(layer "F.Cu")
		(net "SVID_CPU_NODE1_PVCCP_ALERT_R_L")
	)
	(segment
		(start 73.29297 -78.239112)
		(end 74.172826 -78.239112)
		(width 0.1016)
		(layer "F.Cu")
		(net "SVID_CPU_NODE1_PVCCP_ALERT_R_L")
	)
	(segment
		(start 75.23734 -78.137512)
		(end 75.346306 -78.246478)
		(width 0.1016)
		(layer "F.Cu")
		(net "SVID_CPU_NODE1_PVCCP_ALERT_R_L")
	)
	(via
		(at 78.688692 -77.750416)
		(size 0.6604)
		(drill 0.3302)
		(layers "F.Cu" "B.Cu")
		(net "SVID_CPU_NODE1_PVCCP_ALERT_R_L")
	)
	(via
		(at 75.346306 -78.246478)
		(size 0.508)
		(drill 0.254)
		(layers "F.Cu" "B.Cu")
		(net "SVID_CPU_NODE1_PVCCP_ALERT_R_L")
	)
	(segment
		(start 77.979524 -78.021942)
		(end 78.25105 -77.750416)
		(width 0.1016)
		(layer "B.Cu")
		(net "SVID_CPU_NODE1_PVCCP_ALERT_R_L")
	)
	(segment
		(start 78.88478 -77.946504)
		(end 78.688692 -77.750416)
		(width 0.1016)
		(layer "B.Cu")
		(net "SVID_CPU_NODE1_PVCCP_ALERT_R_L")
	)
	(segment
		(start 79.872078 -77.946504)
		(end 78.88478 -77.946504)
		(width 0.1016)
		(layer "B.Cu")
		(net "SVID_CPU_NODE1_PVCCP_ALERT_R_L")
	)
	(segment
		(start 75.346306 -78.246478)
		(end 75.570842 -78.021942)
		(width 0.1016)
		(layer "B.Cu")
		(net "SVID_CPU_NODE1_PVCCP_ALERT_R_L")
	)
	(segment
		(start 75.570842 -78.021942)
		(end 77.979524 -78.021942)
		(width 0.1016)
		(layer "B.Cu")
		(net "SVID_CPU_NODE1_PVCCP_ALERT_R_L")
	)
	(segment
		(start 78.25105 -77.750416)
		(end 78.688692 -77.750416)
		(width 0.1016)
		(layer "B.Cu")
		(net "SVID_CPU_NODE1_PVCCP_ALERT_R_L")
	)
	(segment
		(start 79.575152 -77.196696)
		(end 78.116684 -77.196696)
		(width 0.1016)
		(layer "F.Cu")
		(net "XDP_SOC_CPU_NODE1_TMS")
	)
	(segment
		(start 77.587602 -77.725778)
		(end 78.029816 -77.283564)
		(width 0.1016)
		(layer "F.Cu")
		(net "XDP_SOC_CPU_NODE1_TMS")
	)
	(segment
		(start 73.22566 -78.021434)
		(end 73.778364 -78.021434)
		(width 0.1016)
		(layer "F.Cu")
		(net "XDP_SOC_CPU_NODE1_TMS")
	)
	(segment
		(start 72.901556 -77.69733)
		(end 73.22566 -78.021434)
		(width 0.1016)
		(layer "F.Cu")
		(net "XDP_SOC_CPU_NODE1_TMS")
	)
	(segment
		(start 74.830178 -77.92847)
		(end 75.03287 -77.725778)
		(width 0.1016)
		(layer "F.Cu")
		(net "XDP_SOC_CPU_NODE1_TMS")
	)
	(segment
		(start 108.94187 -62.406276)
		(end 108.81487 -62.279276)
		(width 0.1016)
		(layer "F.Cu")
		(net "XDP_SOC_CPU_NODE1_TMS")
	)
	(segment
		(start 73.778364 -78.021434)
		(end 73.871328 -77.92847)
		(width 0.1016)
		(layer "F.Cu")
		(net "XDP_SOC_CPU_NODE1_TMS")
	)
	(segment
		(start 79.584296 -77.187552)
		(end 79.575152 -77.196696)
		(width 0.1016)
		(layer "F.Cu")
		(net "XDP_SOC_CPU_NODE1_TMS")
	)
	(segment
		(start 73.871328 -77.92847)
		(end 74.830178 -77.92847)
		(width 0.1016)
		(layer "F.Cu")
		(net "XDP_SOC_CPU_NODE1_TMS")
	)
	(segment
		(start 78.029816 -77.269848)
		(end 78.029816 -77.283564)
		(width 0.1016)
		(layer "F.Cu")
		(net "XDP_SOC_CPU_NODE1_TMS")
	)
	(segment
		(start 110.460028 -62.406276)
		(end 108.94187 -62.406276)
		(width 0.1016)
		(layer "F.Cu")
		(net "XDP_SOC_CPU_NODE1_TMS")
	)
	(segment
		(start 75.03287 -77.725778)
		(end 77.587602 -77.725778)
		(width 0.1016)
		(layer "F.Cu")
		(net "XDP_SOC_CPU_NODE1_TMS")
	)
	(segment
		(start 78.116684 -77.196696)
		(end 78.029816 -77.283564)
		(width 0.1016)
		(layer "F.Cu")
		(net "XDP_SOC_CPU_NODE1_TMS")
	)
	(via
		(at 78.029816 -77.269848)
		(size 0.508)
		(drill 0.254)
		(layers "F.Cu" "B.Cu")
		(net "XDP_SOC_CPU_NODE1_TMS")
	)
	(via
		(at 108.81487 -62.279276)
		(size 0.508)
		(drill 0.254)
		(layers "F.Cu" "B.Cu")
		(net "XDP_SOC_CPU_NODE1_TMS")
	)
	(segment
		(start 91.15806 -75.288394)
		(end 91.15806 -77.04201)
		(width 0.1143)
		(layer "In2.Cu")
		(net "XDP_SOC_CPU_NODE1_TMS")
	)
	(segment
		(start 100.603304 -78.855062)
		(end 102.337616 -77.12075)
		(width 0.1143)
		(layer "In2.Cu")
		(net "XDP_SOC_CPU_NODE1_TMS")
	)
	(segment
		(start 78.029816 -77.269848)
		(end 78.07452 -77.225144)
		(width 0.1143)
		(layer "In2.Cu")
		(net "XDP_SOC_CPU_NODE1_TMS")
	)
	(segment
		(start 84.702904 -77.225144)
		(end 85.602064 -76.325984)
		(width 0.1143)
		(layer "In2.Cu")
		(net "XDP_SOC_CPU_NODE1_TMS")
	)
	(segment
		(start 92.971112 -78.855062)
		(end 100.603304 -78.855062)
		(width 0.1143)
		(layer "In2.Cu")
		(net "XDP_SOC_CPU_NODE1_TMS")
	)
	(segment
		(start 107.753912 -77.12075)
		(end 110.686342 -74.18832)
		(width 0.1143)
		(layer "In2.Cu")
		(net "XDP_SOC_CPU_NODE1_TMS")
	)
	(segment
		(start 110.686342 -64.150748)
		(end 108.81487 -62.279276)
		(width 0.1143)
		(layer "In2.Cu")
		(net "XDP_SOC_CPU_NODE1_TMS")
	)
	(segment
		(start 78.07452 -77.225144)
		(end 84.702904 -77.225144)
		(width 0.1143)
		(layer "In2.Cu")
		(net "XDP_SOC_CPU_NODE1_TMS")
	)
	(segment
		(start 89.635838 -74.680064)
		(end 90.54973 -74.680064)
		(width 0.1143)
		(layer "In2.Cu")
		(net "XDP_SOC_CPU_NODE1_TMS")
	)
	(segment
		(start 87.989918 -76.325984)
		(end 89.635838 -74.680064)
		(width 0.1143)
		(layer "In2.Cu")
		(net "XDP_SOC_CPU_NODE1_TMS")
	)
	(segment
		(start 110.686342 -74.18832)
		(end 110.686342 -64.150748)
		(width 0.1143)
		(layer "In2.Cu")
		(net "XDP_SOC_CPU_NODE1_TMS")
	)
	(segment
		(start 85.602064 -76.325984)
		(end 87.989918 -76.325984)
		(width 0.1143)
		(layer "In2.Cu")
		(net "XDP_SOC_CPU_NODE1_TMS")
	)
	(segment
		(start 91.15806 -77.04201)
		(end 92.971112 -78.855062)
		(width 0.1143)
		(layer "In2.Cu")
		(net "XDP_SOC_CPU_NODE1_TMS")
	)
	(segment
		(start 90.54973 -74.680064)
		(end 91.15806 -75.288394)
		(width 0.1143)
		(layer "In2.Cu")
		(net "XDP_SOC_CPU_NODE1_TMS")
	)
	(segment
		(start 102.337616 -77.12075)
		(end 107.753912 -77.12075)
		(width 0.1143)
		(layer "In2.Cu")
		(net "XDP_SOC_CPU_NODE1_TMS")
	)
	(segment
		(start 39.067486 -65.736724)
		(end 37.67582 -65.736724)
		(width 0.1016)
		(layer "F.Cu")
		(net "TP_CPU_NODE1_RP0_PERN3")
	)
	(segment
		(start 41.75125 -66.689986)
		(end 41.614598 -66.826638)
		(width 0.1016)
		(layer "F.Cu")
		(net "TP_CPU_NODE1_RP0_PERN3")
	)
	(segment
		(start 40.1574 -66.826638)
		(end 39.067486 -65.736724)
		(width 0.1016)
		(layer "F.Cu")
		(net "TP_CPU_NODE1_RP0_PERN3")
	)
	(segment
		(start 41.614598 -66.826638)
		(end 40.1574 -66.826638)
		(width 0.1016)
		(layer "F.Cu")
		(net "TP_CPU_NODE1_RP0_PERN3")
	)
	(via
		(at 37.67582 -65.736724)
		(size 0.508)
		(drill 0.254)
		(layers "F.Cu" "B.Cu")
		(net "TP_CPU_NODE1_RP0_PERN3")
	)
	(segment
		(start 69.842888 -4.160012)
		(end 69.84746 -4.164584)
		(width 0.1016)
		(layer "F.Cu")
		(net "FM_CPLD_NODE1_P3V3_S_EN")
	)
	(segment
		(start 69.842888 -3.523488)
		(end 69.842888 -4.160012)
		(width 0.1016)
		(layer "F.Cu")
		(net "FM_CPLD_NODE1_P3V3_S_EN")
	)
	(segment
		(start 69.84746 -4.971288)
		(end 69.84746 -4.164584)
		(width 0.1016)
		(layer "F.Cu")
		(net "FM_CPLD_NODE1_P3V3_S_EN")
	)
	(via
		(at 69.84746 -4.164584)
		(size 0.508)
		(drill 0.254)
		(layers "F.Cu" "B.Cu")
		(net "FM_CPLD_NODE1_P3V3_S_EN")
	)
	(segment
		(start 113.646204 -62.271148)
		(end 113.575592 -62.271148)
		(width 0.1016)
		(layer "F.Cu")
		(net "XDP_SOC_CPU_NODE1_TDO")
	)
	(segment
		(start 110.460028 -63.906146)
		(end 111.940594 -63.906146)
		(width 0.1016)
		(layer "F.Cu")
		(net "XDP_SOC_CPU_NODE1_TDO")
	)
	(segment
		(start 73.843388 -79.197708)
		(end 74.021696 -79.376016)
		(width 0.1016)
		(layer "F.Cu")
		(net "XDP_SOC_CPU_NODE1_TDO")
	)
	(segment
		(start 76.121006 -79.376016)
		(end 76.65593 -78.841092)
		(width 0.1016)
		(layer "F.Cu")
		(net "XDP_SOC_CPU_NODE1_TDO")
	)
	(segment
		(start 113.575592 -62.271148)
		(end 112.16132 -63.68542)
		(width 0.1016)
		(layer "F.Cu")
		(net "XDP_SOC_CPU_NODE1_TDO")
	)
	(segment
		(start 111.940594 -63.906146)
		(end 112.16132 -63.68542)
		(width 0.1016)
		(layer "F.Cu")
		(net "XDP_SOC_CPU_NODE1_TDO")
	)
	(segment
		(start 74.021696 -79.376016)
		(end 76.121006 -79.376016)
		(width 0.1016)
		(layer "F.Cu")
		(net "XDP_SOC_CPU_NODE1_TDO")
	)
	(segment
		(start 73.24344 -79.197708)
		(end 73.843388 -79.197708)
		(width 0.1016)
		(layer "F.Cu")
		(net "XDP_SOC_CPU_NODE1_TDO")
	)
	(via
		(at 76.65593 -78.841092)
		(size 0.508)
		(drill 0.254)
		(layers "F.Cu" "B.Cu")
		(net "XDP_SOC_CPU_NODE1_TDO")
	)
	(via
		(at 112.16132 -63.68542)
		(size 0.508)
		(drill 0.254)
		(layers "F.Cu" "B.Cu")
		(net "XDP_SOC_CPU_NODE1_TDO")
	)
	(segment
		(start 112.16132 -64.0969)
		(end 112.16132 -63.68542)
		(width 0.1143)
		(layer "In2.Cu")
		(net "XDP_SOC_CPU_NODE1_TDO")
	)
	(segment
		(start 88.091772 -76.817728)
		(end 89.807796 -75.101704)
		(width 0.1143)
		(layer "In2.Cu")
		(net "XDP_SOC_CPU_NODE1_TDO")
	)
	(segment
		(start 92.797376 -79.274162)
		(end 100.778564 -79.274162)
		(width 0.1143)
		(layer "In2.Cu")
		(net "XDP_SOC_CPU_NODE1_TDO")
	)
	(segment
		(start 90.31859 -75.101704)
		(end 90.71102 -75.494134)
		(width 0.1143)
		(layer "In2.Cu")
		(net "XDP_SOC_CPU_NODE1_TDO")
	)
	(segment
		(start 107.927648 -77.53985)
		(end 111.105442 -74.362056)
		(width 0.1143)
		(layer "In2.Cu")
		(net "XDP_SOC_CPU_NODE1_TDO")
	)
	(segment
		(start 89.807796 -75.101704)
		(end 90.31859 -75.101704)
		(width 0.1143)
		(layer "In2.Cu")
		(net "XDP_SOC_CPU_NODE1_TDO")
	)
	(segment
		(start 111.105442 -65.152778)
		(end 112.16132 -64.0969)
		(width 0.1143)
		(layer "In2.Cu")
		(net "XDP_SOC_CPU_NODE1_TDO")
	)
	(segment
		(start 90.71102 -77.187806)
		(end 92.797376 -79.274162)
		(width 0.1143)
		(layer "In2.Cu")
		(net "XDP_SOC_CPU_NODE1_TDO")
	)
	(segment
		(start 77.723238 -77.773784)
		(end 85.033104 -77.773784)
		(width 0.1143)
		(layer "In2.Cu")
		(net "XDP_SOC_CPU_NODE1_TDO")
	)
	(segment
		(start 102.512876 -77.53985)
		(end 107.927648 -77.53985)
		(width 0.1143)
		(layer "In2.Cu")
		(net "XDP_SOC_CPU_NODE1_TDO")
	)
	(segment
		(start 85.98916 -76.817728)
		(end 88.091772 -76.817728)
		(width 0.1143)
		(layer "In2.Cu")
		(net "XDP_SOC_CPU_NODE1_TDO")
	)
	(segment
		(start 76.65593 -78.841092)
		(end 77.723238 -77.773784)
		(width 0.1143)
		(layer "In2.Cu")
		(net "XDP_SOC_CPU_NODE1_TDO")
	)
	(segment
		(start 85.033104 -77.773784)
		(end 85.98916 -76.817728)
		(width 0.1143)
		(layer "In2.Cu")
		(net "XDP_SOC_CPU_NODE1_TDO")
	)
	(segment
		(start 100.778564 -79.274162)
		(end 102.512876 -77.53985)
		(width 0.1143)
		(layer "In2.Cu")
		(net "XDP_SOC_CPU_NODE1_TDO")
	)
	(segment
		(start 111.105442 -74.362056)
		(end 111.105442 -65.152778)
		(width 0.1143)
		(layer "In2.Cu")
		(net "XDP_SOC_CPU_NODE1_TDO")
	)
	(segment
		(start 90.71102 -75.494134)
		(end 90.71102 -77.187806)
		(width 0.1143)
		(layer "In2.Cu")
		(net "XDP_SOC_CPU_NODE1_TDO")
	)
	(via
		(at 72.26427 -7.791704)
		(size 0.508)
		(drill 0.254)
		(layers "F.Cu" "B.Cu")
		(net "SW_P3V3_NODE1_BT")
	)
	(segment
		(start 107.118912 -70.635114)
		(end 107.118912 -70.901814)
		(width 0.1016)
		(layer "F.Cu")
		(net "XDP_CPU_NODE1_VISA16")
	)
	(segment
		(start 110.460028 -68.406264)
		(end 108.870242 -68.406264)
		(width 0.1016)
		(layer "F.Cu")
		(net "XDP_CPU_NODE1_VISA16")
	)
	(segment
		(start 67.154044 -74.283062)
		(end 67.154044 -74.307192)
		(width 0.1016)
		(layer "F.Cu")
		(net "XDP_CPU_NODE1_VISA16")
	)
	(segment
		(start 67.154044 -74.307192)
		(end 67.51955 -74.672698)
		(width 0.1016)
		(layer "F.Cu")
		(net "XDP_CPU_NODE1_VISA16")
	)
	(segment
		(start 108.870242 -68.406264)
		(end 107.832652 -69.443854)
		(width 0.1016)
		(layer "F.Cu")
		(net "XDP_CPU_NODE1_VISA16")
	)
	(segment
		(start 107.832652 -69.921374)
		(end 107.118912 -70.635114)
		(width 0.1016)
		(layer "F.Cu")
		(net "XDP_CPU_NODE1_VISA16")
	)
	(segment
		(start 107.832652 -69.443854)
		(end 107.832652 -69.921374)
		(width 0.1016)
		(layer "F.Cu")
		(net "XDP_CPU_NODE1_VISA16")
	)
	(via
		(at 67.51955 -74.672698)
		(size 0.508)
		(drill 0.254)
		(layers "F.Cu" "B.Cu")
		(net "XDP_CPU_NODE1_VISA16")
	)
	(via
		(at 107.118912 -70.901814)
		(size 0.508)
		(drill 0.254)
		(layers "F.Cu" "B.Cu")
		(net "XDP_CPU_NODE1_VISA16")
	)
	(segment
		(start 76.811632 -74.592434)
		(end 77.6605 -73.743566)
		(width 0.1143)
		(layer "In2.Cu")
		(net "XDP_CPU_NODE1_VISA16")
	)
	(segment
		(start 98.79838 -71.53656)
		(end 99.506532 -70.828408)
		(width 0.1143)
		(layer "In2.Cu")
		(net "XDP_CPU_NODE1_VISA16")
	)
	(segment
		(start 68.081398 -73.531984)
		(end 68.478908 -73.531984)
		(width 0.1143)
		(layer "In2.Cu")
		(net "XDP_CPU_NODE1_VISA16")
	)
	(segment
		(start 102.945692 -70.495414)
		(end 103.131112 -70.309994)
		(width 0.1143)
		(layer "In2.Cu")
		(net "XDP_CPU_NODE1_VISA16")
	)
	(segment
		(start 102.717092 -71.714614)
		(end 102.945692 -71.486014)
		(width 0.1143)
		(layer "In2.Cu")
		(net "XDP_CPU_NODE1_VISA16")
	)
	(segment
		(start 104.907588 -68.767706)
		(end 105.08996 -68.585334)
		(width 0.1143)
		(layer "In2.Cu")
		(net "XDP_CPU_NODE1_VISA16")
	)
	(segment
		(start 78.256638 -73.605136)
		(end 81.204054 -73.605136)
		(width 0.1143)
		(layer "In2.Cu")
		(net "XDP_CPU_NODE1_VISA16")
	)
	(segment
		(start 88.757252 -70.0278)
		(end 89.629488 -70.900036)
		(width 0.1143)
		(layer "In2.Cu")
		(net "XDP_CPU_NODE1_VISA16")
	)
	(segment
		(start 98.79838 -72.270874)
		(end 98.79838 -71.53656)
		(width 0.1143)
		(layer "In2.Cu")
		(net "XDP_CPU_NODE1_VISA16")
	)
	(segment
		(start 77.6605 -73.743566)
		(end 78.118208 -73.743566)
		(width 0.1143)
		(layer "In2.Cu")
		(net "XDP_CPU_NODE1_VISA16")
	)
	(segment
		(start 67.51955 -74.093832)
		(end 68.081398 -73.531984)
		(width 0.1143)
		(layer "In2.Cu")
		(net "XDP_CPU_NODE1_VISA16")
	)
	(segment
		(start 95.266002 -72.867774)
		(end 98.20148 -72.867774)
		(width 0.1143)
		(layer "In2.Cu")
		(net "XDP_CPU_NODE1_VISA16")
	)
	(segment
		(start 69.719444 -74.039984)
		(end 70.82028 -75.14082)
		(width 0.1143)
		(layer "In2.Cu")
		(net "XDP_CPU_NODE1_VISA16")
	)
	(segment
		(start 78.118208 -73.743566)
		(end 78.256638 -73.605136)
		(width 0.1143)
		(layer "In2.Cu")
		(net "XDP_CPU_NODE1_VISA16")
	)
	(segment
		(start 105.529888 -68.767706)
		(end 105.529888 -70.089522)
		(width 0.1143)
		(layer "In2.Cu")
		(net "XDP_CPU_NODE1_VISA16")
	)
	(segment
		(start 102.945692 -71.486014)
		(end 102.945692 -70.495414)
		(width 0.1143)
		(layer "In2.Cu")
		(net "XDP_CPU_NODE1_VISA16")
	)
	(segment
		(start 81.204054 -73.605136)
		(end 84.782152 -70.0278)
		(width 0.1143)
		(layer "In2.Cu")
		(net "XDP_CPU_NODE1_VISA16")
	)
	(segment
		(start 70.82028 -75.14082)
		(end 73.739756 -75.14082)
		(width 0.1143)
		(layer "In2.Cu")
		(net "XDP_CPU_NODE1_VISA16")
	)
	(segment
		(start 98.20148 -72.867774)
		(end 98.79838 -72.270874)
		(width 0.1143)
		(layer "In2.Cu")
		(net "XDP_CPU_NODE1_VISA16")
	)
	(segment
		(start 84.782152 -70.0278)
		(end 88.757252 -70.0278)
		(width 0.1143)
		(layer "In2.Cu")
		(net "XDP_CPU_NODE1_VISA16")
	)
	(segment
		(start 103.131112 -70.309994)
		(end 104.687116 -70.309994)
		(width 0.1143)
		(layer "In2.Cu")
		(net "XDP_CPU_NODE1_VISA16")
	)
	(segment
		(start 67.51955 -74.672698)
		(end 67.51955 -74.093832)
		(width 0.1143)
		(layer "In2.Cu")
		(net "XDP_CPU_NODE1_VISA16")
	)
	(segment
		(start 106.625136 -70.408038)
		(end 107.118912 -70.901814)
		(width 0.1143)
		(layer "In2.Cu")
		(net "XDP_CPU_NODE1_VISA16")
	)
	(segment
		(start 105.08996 -68.585334)
		(end 105.347516 -68.585334)
		(width 0.1143)
		(layer "In2.Cu")
		(net "XDP_CPU_NODE1_VISA16")
	)
	(segment
		(start 99.506532 -70.828408)
		(end 101.051106 -70.828408)
		(width 0.1143)
		(layer "In2.Cu")
		(net "XDP_CPU_NODE1_VISA16")
	)
	(segment
		(start 101.937312 -71.714614)
		(end 102.717092 -71.714614)
		(width 0.1143)
		(layer "In2.Cu")
		(net "XDP_CPU_NODE1_VISA16")
	)
	(segment
		(start 101.051106 -70.828408)
		(end 101.937312 -71.714614)
		(width 0.1143)
		(layer "In2.Cu")
		(net "XDP_CPU_NODE1_VISA16")
	)
	(segment
		(start 104.907588 -70.089522)
		(end 104.907588 -68.767706)
		(width 0.1143)
		(layer "In2.Cu")
		(net "XDP_CPU_NODE1_VISA16")
	)
	(segment
		(start 105.529888 -70.089522)
		(end 105.848404 -70.408038)
		(width 0.1143)
		(layer "In2.Cu")
		(net "XDP_CPU_NODE1_VISA16")
	)
	(segment
		(start 105.848404 -70.408038)
		(end 106.625136 -70.408038)
		(width 0.1143)
		(layer "In2.Cu")
		(net "XDP_CPU_NODE1_VISA16")
	)
	(segment
		(start 104.687116 -70.309994)
		(end 104.907588 -70.089522)
		(width 0.1143)
		(layer "In2.Cu")
		(net "XDP_CPU_NODE1_VISA16")
	)
	(segment
		(start 68.478908 -73.531984)
		(end 68.986908 -74.039984)
		(width 0.1143)
		(layer "In2.Cu")
		(net "XDP_CPU_NODE1_VISA16")
	)
	(segment
		(start 93.298264 -70.900036)
		(end 95.266002 -72.867774)
		(width 0.1143)
		(layer "In2.Cu")
		(net "XDP_CPU_NODE1_VISA16")
	)
	(segment
		(start 105.347516 -68.585334)
		(end 105.529888 -68.767706)
		(width 0.1143)
		(layer "In2.Cu")
		(net "XDP_CPU_NODE1_VISA16")
	)
	(segment
		(start 74.288142 -74.592434)
		(end 76.811632 -74.592434)
		(width 0.1143)
		(layer "In2.Cu")
		(net "XDP_CPU_NODE1_VISA16")
	)
	(segment
		(start 89.629488 -70.900036)
		(end 93.298264 -70.900036)
		(width 0.1143)
		(layer "In2.Cu")
		(net "XDP_CPU_NODE1_VISA16")
	)
	(segment
		(start 68.986908 -74.039984)
		(end 69.719444 -74.039984)
		(width 0.1143)
		(layer "In2.Cu")
		(net "XDP_CPU_NODE1_VISA16")
	)
	(segment
		(start 73.739756 -75.14082)
		(end 74.288142 -74.592434)
		(width 0.1143)
		(layer "In2.Cu")
		(net "XDP_CPU_NODE1_VISA16")
	)
	(segment
		(start 180.010562 -122.36577)
		(end 180.48732 -122.842528)
		(width 0.1016)
		(layer "F.Cu")
		(net "PWRGD_NODE1_P3V3_PG")
	)
	(segment
		(start 182.414418 -122.842528)
		(end 182.481474 -122.775472)
		(width 0.1016)
		(layer "F.Cu")
		(net "PWRGD_NODE1_P3V3_PG")
	)
	(segment
		(start 67.924934 -3.813048)
		(end 67.924934 -3.344164)
		(width 0.254)
		(layer "F.Cu")
		(net "PWRGD_NODE1_P3V3_PG")
	)
	(segment
		(start 68.940934 -4.158996)
		(end 69.347334 -4.565396)
		(width 0.254)
		(layer "F.Cu")
		(net "PWRGD_NODE1_P3V3_PG")
	)
	(segment
		(start 68.940934 -3.344164)
		(end 68.940934 -4.158996)
		(width 0.254)
		(layer "F.Cu")
		(net "PWRGD_NODE1_P3V3_PG")
	)
	(segment
		(start 68.277486 -4.1656)
		(end 67.924934 -3.813048)
		(width 0.254)
		(layer "F.Cu")
		(net "PWRGD_NODE1_P3V3_PG")
	)
	(segment
		(start 67.924934 -3.344164)
		(end 68.940934 -3.344164)
		(width 0.254)
		(layer "F.Cu")
		(net "PWRGD_NODE1_P3V3_PG")
	)
	(segment
		(start 69.347334 -4.565396)
		(end 69.347334 -4.971288)
		(width 0.254)
		(layer "F.Cu")
		(net "PWRGD_NODE1_P3V3_PG")
	)
	(segment
		(start 180.48732 -122.842528)
		(end 182.414418 -122.842528)
		(width 0.1016)
		(layer "F.Cu")
		(net "PWRGD_NODE1_P3V3_PG")
	)
	(via
		(at 182.481474 -122.775472)
		(size 0.508)
		(drill 0.254)
		(layers "F.Cu" "B.Cu")
		(net "PWRGD_NODE1_P3V3_PG")
	)
	(via
		(at 68.277486 -4.1656)
		(size 0.508)
		(drill 0.254)
		(layers "F.Cu" "B.Cu")
		(net "PWRGD_NODE1_P3V3_PG")
	)
	(segment
		(start 70.952106 -1.49098)
		(end 68.277486 -4.1656)
		(width 0.1143)
		(layer "In6.Cu")
		(net "PWRGD_NODE1_P3V3_PG")
	)
	(segment
		(start 129.159 -15.0622)
		(end 128.8542 -15.367)
		(width 0.1143)
		(layer "In6.Cu")
		(net "PWRGD_NODE1_P3V3_PG")
	)
	(segment
		(start 164.86378 -49.665128)
		(end 162.82416 -47.625508)
		(width 0.1143)
		(layer "In6.Cu")
		(net "PWRGD_NODE1_P3V3_PG")
	)
	(segment
		(start 156.9974 -15.0622)
		(end 129.159 -15.0622)
		(width 0.1143)
		(layer "In6.Cu")
		(net "PWRGD_NODE1_P3V3_PG")
	)
	(segment
		(start 183.197754 -122.53468)
		(end 186.25693 -119.475504)
		(width 0.1143)
		(layer "In6.Cu")
		(net "PWRGD_NODE1_P3V3_PG")
	)
	(segment
		(start 108.345986 -1.49098)
		(end 70.952106 -1.49098)
		(width 0.1143)
		(layer "In6.Cu")
		(net "PWRGD_NODE1_P3V3_PG")
	)
	(segment
		(start 162.82416 -20.88896)
		(end 156.9974 -15.0622)
		(width 0.1143)
		(layer "In6.Cu")
		(net "PWRGD_NODE1_P3V3_PG")
	)
	(segment
		(start 186.25693 -87.90813)
		(end 164.86378 -66.51498)
		(width 0.1143)
		(layer "In6.Cu")
		(net "PWRGD_NODE1_P3V3_PG")
	)
	(segment
		(start 126.776988 -15.367)
		(end 126.2634 -14.853412)
		(width 0.1143)
		(layer "In6.Cu")
		(net "PWRGD_NODE1_P3V3_PG")
	)
	(segment
		(start 186.25693 -119.475504)
		(end 186.25693 -87.90813)
		(width 0.1143)
		(layer "In6.Cu")
		(net "PWRGD_NODE1_P3V3_PG")
	)
	(segment
		(start 126.2634 -14.853412)
		(end 121.708418 -14.853412)
		(width 0.1143)
		(layer "In6.Cu")
		(net "PWRGD_NODE1_P3V3_PG")
	)
	(segment
		(start 182.722266 -122.53468)
		(end 183.197754 -122.53468)
		(width 0.1143)
		(layer "In6.Cu")
		(net "PWRGD_NODE1_P3V3_PG")
	)
	(segment
		(start 128.8542 -15.367)
		(end 126.776988 -15.367)
		(width 0.1143)
		(layer "In6.Cu")
		(net "PWRGD_NODE1_P3V3_PG")
	)
	(segment
		(start 164.86378 -66.51498)
		(end 164.86378 -49.665128)
		(width 0.1143)
		(layer "In6.Cu")
		(net "PWRGD_NODE1_P3V3_PG")
	)
	(segment
		(start 121.708418 -14.853412)
		(end 108.345986 -1.49098)
		(width 0.1143)
		(layer "In6.Cu")
		(net "PWRGD_NODE1_P3V3_PG")
	)
	(segment
		(start 162.82416 -47.625508)
		(end 162.82416 -20.88896)
		(width 0.1143)
		(layer "In6.Cu")
		(net "PWRGD_NODE1_P3V3_PG")
	)
	(segment
		(start 182.481474 -122.775472)
		(end 182.722266 -122.53468)
		(width 0.1143)
		(layer "In6.Cu")
		(net "PWRGD_NODE1_P3V3_PG")
	)
	(segment
		(start 101.088952 -62.37986)
		(end 102.555802 -62.37986)
		(width 0.1016)
		(layer "F.Cu")
		(net "SMB_CPU_NODE1_XDP_CLK")
	)
	(segment
		(start 102.555802 -62.37986)
		(end 103.582216 -63.406274)
		(width 0.1016)
		(layer "F.Cu")
		(net "SMB_CPU_NODE1_XDP_CLK")
	)
	(segment
		(start 98.157792 -65.31102)
		(end 101.088952 -62.37986)
		(width 0.1016)
		(layer "F.Cu")
		(net "SMB_CPU_NODE1_XDP_CLK")
	)
	(segment
		(start 103.582216 -63.406274)
		(end 104.73182 -63.406274)
		(width 0.1016)
		(layer "F.Cu")
		(net "SMB_CPU_NODE1_XDP_CLK")
	)
	(segment
		(start 98.157792 -74.855578)
		(end 98.157792 -65.31102)
		(width 0.1016)
		(layer "F.Cu")
		(net "SMB_CPU_NODE1_XDP_CLK")
	)
	(segment
		(start 103.83266 -80.530446)
		(end 98.157792 -74.855578)
		(width 0.1016)
		(layer "F.Cu")
		(net "SMB_CPU_NODE1_XDP_CLK")
	)
	(via
		(at 103.83266 -80.530446)
		(size 0.508)
		(drill 0.254)
		(layers "F.Cu" "B.Cu")
		(net "SMB_CPU_NODE1_XDP_CLK")
	)
	(via
		(at 94.30004 -104.871266)
		(size 0.508)
		(drill 0.254)
		(layers "F.Cu" "B.Cu")
		(net "SMB_CPU_NODE1_XDP_CLK")
	)
	(via
		(at 40.865044 -96.594676)
		(size 0.508)
		(drill 0.254)
		(layers "F.Cu" "B.Cu")
		(net "SMB_CPU_NODE1_XDP_CLK")
	)
	(segment
		(start 41.58869 -94.882462)
		(end 41.58869 -96.594676)
		(width 0.1016)
		(layer "B.Cu")
		(net "SMB_CPU_NODE1_XDP_CLK")
	)
	(segment
		(start 41.58869 -96.594676)
		(end 40.865044 -96.594676)
		(width 0.1016)
		(layer "B.Cu")
		(net "SMB_CPU_NODE1_XDP_CLK")
	)
	(segment
		(start 41.670732 -94.80042)
		(end 41.58869 -94.882462)
		(width 0.1016)
		(layer "B.Cu")
		(net "SMB_CPU_NODE1_XDP_CLK")
	)
	(segment
		(start 95.377 -102.66045)
		(end 95.377 -101.5365)
		(width 0.1143)
		(layer "In2.Cu")
		(net "SMB_CPU_NODE1_XDP_CLK")
	)
	(segment
		(start 95.7834 -86.538054)
		(end 99.408234 -82.91322)
		(width 0.1143)
		(layer "In2.Cu")
		(net "SMB_CPU_NODE1_XDP_CLK")
	)
	(segment
		(start 95.7834 -101.1301)
		(end 95.7834 -86.538054)
		(width 0.1143)
		(layer "In2.Cu")
		(net "SMB_CPU_NODE1_XDP_CLK")
	)
	(segment
		(start 94.30004 -103.73741)
		(end 95.377 -102.66045)
		(width 0.1143)
		(layer "In2.Cu")
		(net "SMB_CPU_NODE1_XDP_CLK")
	)
	(segment
		(start 95.377 -101.5365)
		(end 95.7834 -101.1301)
		(width 0.1143)
		(layer "In2.Cu")
		(net "SMB_CPU_NODE1_XDP_CLK")
	)
	(segment
		(start 101.449886 -82.91322)
		(end 103.83266 -80.530446)
		(width 0.1143)
		(layer "In2.Cu")
		(net "SMB_CPU_NODE1_XDP_CLK")
	)
	(segment
		(start 99.408234 -82.91322)
		(end 101.449886 -82.91322)
		(width 0.1143)
		(layer "In2.Cu")
		(net "SMB_CPU_NODE1_XDP_CLK")
	)
	(segment
		(start 94.30004 -104.871266)
		(end 94.30004 -103.73741)
		(width 0.1143)
		(layer "In2.Cu")
		(net "SMB_CPU_NODE1_XDP_CLK")
	)
	(segment
		(start 48.641 -100.9269)
		(end 49.38014 -101.66604)
		(width 0.1143)
		(layer "In7.Cu")
		(net "SMB_CPU_NODE1_XDP_CLK")
	)
	(segment
		(start 82.204814 -105.866184)
		(end 84.409534 -105.866184)
		(width 0.1143)
		(layer "In7.Cu")
		(net "SMB_CPU_NODE1_XDP_CLK")
	)
	(segment
		(start 49.38014 -102.547166)
		(end 49.7078 -102.874826)
		(width 0.1143)
		(layer "In7.Cu")
		(net "SMB_CPU_NODE1_XDP_CLK")
	)
	(segment
		(start 84.409534 -105.866184)
		(end 85.01253 -105.263188)
		(width 0.1143)
		(layer "In7.Cu")
		(net "SMB_CPU_NODE1_XDP_CLK")
	)
	(segment
		(start 49.38014 -101.66604)
		(end 49.38014 -102.547166)
		(width 0.1143)
		(layer "In7.Cu")
		(net "SMB_CPU_NODE1_XDP_CLK")
	)
	(segment
		(start 48.641 -97.636076)
		(end 48.641 -100.9269)
		(width 0.1143)
		(layer "In7.Cu")
		(net "SMB_CPU_NODE1_XDP_CLK")
	)
	(segment
		(start 87.838026 -104.871266)
		(end 94.30004 -104.871266)
		(width 0.1143)
		(layer "In7.Cu")
		(net "SMB_CPU_NODE1_XDP_CLK")
	)
	(segment
		(start 72.385682 -103.048054)
		(end 75.95489 -106.617262)
		(width 0.1143)
		(layer "In7.Cu")
		(net "SMB_CPU_NODE1_XDP_CLK")
	)
	(segment
		(start 81.453736 -106.617262)
		(end 82.204814 -105.866184)
		(width 0.1143)
		(layer "In7.Cu")
		(net "SMB_CPU_NODE1_XDP_CLK")
	)
	(segment
		(start 58.568082 -102.874826)
		(end 59.77636 -101.666548)
		(width 0.1143)
		(layer "In7.Cu")
		(net "SMB_CPU_NODE1_XDP_CLK")
	)
	(segment
		(start 49.7078 -102.874826)
		(end 58.568082 -102.874826)
		(width 0.1143)
		(layer "In7.Cu")
		(net "SMB_CPU_NODE1_XDP_CLK")
	)
	(segment
		(start 64.262762 -101.666548)
		(end 65.644268 -103.048054)
		(width 0.1143)
		(layer "In7.Cu")
		(net "SMB_CPU_NODE1_XDP_CLK")
	)
	(segment
		(start 75.95489 -106.617262)
		(end 81.453736 -106.617262)
		(width 0.1143)
		(layer "In7.Cu")
		(net "SMB_CPU_NODE1_XDP_CLK")
	)
	(segment
		(start 85.01253 -105.263188)
		(end 87.446104 -105.263188)
		(width 0.1143)
		(layer "In7.Cu")
		(net "SMB_CPU_NODE1_XDP_CLK")
	)
	(segment
		(start 87.446104 -105.263188)
		(end 87.838026 -104.871266)
		(width 0.1143)
		(layer "In7.Cu")
		(net "SMB_CPU_NODE1_XDP_CLK")
	)
	(segment
		(start 41.25087 -96.209104)
		(end 47.214028 -96.209104)
		(width 0.1143)
		(layer "In7.Cu")
		(net "SMB_CPU_NODE1_XDP_CLK")
	)
	(segment
		(start 47.214028 -96.209104)
		(end 48.641 -97.636076)
		(width 0.1143)
		(layer "In7.Cu")
		(net "SMB_CPU_NODE1_XDP_CLK")
	)
	(segment
		(start 59.77636 -101.666548)
		(end 64.262762 -101.666548)
		(width 0.1143)
		(layer "In7.Cu")
		(net "SMB_CPU_NODE1_XDP_CLK")
	)
	(segment
		(start 65.644268 -103.048054)
		(end 72.385682 -103.048054)
		(width 0.1143)
		(layer "In7.Cu")
		(net "SMB_CPU_NODE1_XDP_CLK")
	)
	(segment
		(start 40.865044 -96.594676)
		(end 41.25087 -96.209104)
		(width 0.1143)
		(layer "In7.Cu")
		(net "SMB_CPU_NODE1_XDP_CLK")
	)
	(segment
		(start 46.942248 -80.002126)
		(end 46.942248 -80.121506)
		(width 0.1016)
		(layer "F.Cu")
		(net "SMB_CPU_NODE1_XDP_CLK_R")
	)
	(segment
		(start 46.942248 -80.121506)
		(end 46.539912 -80.523842)
		(width 0.1016)
		(layer "F.Cu")
		(net "SMB_CPU_NODE1_XDP_CLK_R")
	)
	(via
		(at 46.539912 -80.523842)
		(size 0.508)
		(drill 0.254)
		(layers "F.Cu" "B.Cu")
		(net "SMB_CPU_NODE1_XDP_CLK_R")
	)
	(segment
		(start 40.654732 -94.00032)
		(end 40.654732 -93.518482)
		(width 0.1016)
		(layer "B.Cu")
		(net "SMB_CPU_NODE1_XDP_CLK_R")
	)
	(segment
		(start 43.991022 -84.363814)
		(end 46.539912 -81.814924)
		(width 0.1016)
		(layer "B.Cu")
		(net "SMB_CPU_NODE1_XDP_CLK_R")
	)
	(segment
		(start 41.670732 -94.00032)
		(end 40.654732 -94.00032)
		(width 0.1016)
		(layer "B.Cu")
		(net "SMB_CPU_NODE1_XDP_CLK_R")
	)
	(segment
		(start 46.539912 -81.814924)
		(end 46.539912 -80.523842)
		(width 0.1016)
		(layer "B.Cu")
		(net "SMB_CPU_NODE1_XDP_CLK_R")
	)
	(segment
		(start 43.991022 -90.182192)
		(end 43.991022 -84.363814)
		(width 0.1016)
		(layer "B.Cu")
		(net "SMB_CPU_NODE1_XDP_CLK_R")
	)
	(segment
		(start 40.654732 -93.518482)
		(end 43.991022 -90.182192)
		(width 0.1016)
		(layer "B.Cu")
		(net "SMB_CPU_NODE1_XDP_CLK_R")
	)
	(segment
		(start 70.77964 -2.558542)
		(end 70.614794 -2.723388)
		(width 0.1016)
		(layer "F.Cu")
		(net "FM_CPLD_NODE1_P3V3_EN")
	)
	(segment
		(start 70.77964 -1.687322)
		(end 70.777862 -1.685544)
		(width 0.1016)
		(layer "F.Cu")
		(net "FM_CPLD_NODE1_P3V3_EN")
	)
	(segment
		(start 70.614794 -2.723388)
		(end 69.842888 -2.723388)
		(width 0.1016)
		(layer "F.Cu")
		(net "FM_CPLD_NODE1_P3V3_EN")
	)
	(segment
		(start 170.968924 -116.365528)
		(end 170.73626 -116.132864)
		(width 0.1016)
		(layer "F.Cu")
		(net "FM_CPLD_NODE1_P3V3_EN")
	)
	(segment
		(start 70.77964 -1.687322)
		(end 70.77964 -2.558542)
		(width 0.1016)
		(layer "F.Cu")
		(net "FM_CPLD_NODE1_P3V3_EN")
	)
	(segment
		(start 172.010324 -116.365528)
		(end 170.968924 -116.365528)
		(width 0.1016)
		(layer "F.Cu")
		(net "FM_CPLD_NODE1_P3V3_EN")
	)
	(segment
		(start 70.786498 -1.69418)
		(end 70.77964 -1.687322)
		(width 0.1016)
		(layer "F.Cu")
		(net "FM_CPLD_NODE1_P3V3_EN")
	)
	(segment
		(start 71.768462 -1.69418)
		(end 70.786498 -1.69418)
		(width 0.1016)
		(layer "F.Cu")
		(net "FM_CPLD_NODE1_P3V3_EN")
	)
	(via
		(at 116.36248 -11.359134)
		(size 0.508)
		(drill 0.254)
		(layers "F.Cu" "B.Cu")
		(net "FM_CPLD_NODE1_P3V3_EN")
	)
	(via
		(at 70.77964 -2.558542)
		(size 0.508)
		(drill 0.254)
		(layers "F.Cu" "B.Cu")
		(net "FM_CPLD_NODE1_P3V3_EN")
	)
	(via
		(at 130.33248 -18.305526)
		(size 0.508)
		(drill 0.254)
		(layers "F.Cu" "B.Cu")
		(net "FM_CPLD_NODE1_P3V3_EN")
	)
	(via
		(at 170.73626 -116.132864)
		(size 0.508)
		(drill 0.254)
		(layers "F.Cu" "B.Cu")
		(net "FM_CPLD_NODE1_P3V3_EN")
	)
	(segment
		(start 116.36248 -11.359134)
		(end 116.36248 -11.360658)
		(width 0.1143)
		(layer "In2.Cu")
		(net "FM_CPLD_NODE1_P3V3_EN")
	)
	(segment
		(start 129.895854 -18.305526)
		(end 130.33248 -18.305526)
		(width 0.1143)
		(layer "In2.Cu")
		(net "FM_CPLD_NODE1_P3V3_EN")
	)
	(segment
		(start 116.93398 -11.932158)
		(end 119.017796 -11.932158)
		(width 0.1143)
		(layer "In2.Cu")
		(net "FM_CPLD_NODE1_P3V3_EN")
	)
	(segment
		(start 119.017796 -11.932158)
		(end 119.9261 -12.840462)
		(width 0.1143)
		(layer "In2.Cu")
		(net "FM_CPLD_NODE1_P3V3_EN")
	)
	(segment
		(start 116.36248 -11.360658)
		(end 116.93398 -11.932158)
		(width 0.1143)
		(layer "In2.Cu")
		(net "FM_CPLD_NODE1_P3V3_EN")
	)
	(segment
		(start 124.43079 -12.840462)
		(end 129.895854 -18.305526)
		(width 0.1143)
		(layer "In2.Cu")
		(net "FM_CPLD_NODE1_P3V3_EN")
	)
	(segment
		(start 119.9261 -12.840462)
		(end 124.43079 -12.840462)
		(width 0.1143)
		(layer "In2.Cu")
		(net "FM_CPLD_NODE1_P3V3_EN")
	)
	(segment
		(start 116.36248 -11.35888)
		(end 106.76128 -1.75768)
		(width 0.1143)
		(layer "In6.Cu")
		(net "FM_CPLD_NODE1_P3V3_EN")
	)
	(segment
		(start 71.580502 -1.75768)
		(end 70.77964 -2.558542)
		(width 0.1143)
		(layer "In6.Cu")
		(net "FM_CPLD_NODE1_P3V3_EN")
	)
	(segment
		(start 178.68773 -82.54873)
		(end 178.68773 -105.1814)
		(width 0.1143)
		(layer "In6.Cu")
		(net "FM_CPLD_NODE1_P3V3_EN")
	)
	(segment
		(start 178.68773 -105.1814)
		(end 170.69181 -113.17732)
		(width 0.1143)
		(layer "In6.Cu")
		(net "FM_CPLD_NODE1_P3V3_EN")
	)
	(segment
		(start 160.4772 -47.879508)
		(end 163.339526 -50.741834)
		(width 0.1143)
		(layer "In6.Cu")
		(net "FM_CPLD_NODE1_P3V3_EN")
	)
	(segment
		(start 130.710432 -18.683478)
		(end 157.42539 -18.683478)
		(width 0.1143)
		(layer "In6.Cu")
		(net "FM_CPLD_NODE1_P3V3_EN")
	)
	(segment
		(start 163.339526 -50.741834)
		(end 163.339526 -67.200526)
		(width 0.1143)
		(layer "In6.Cu")
		(net "FM_CPLD_NODE1_P3V3_EN")
	)
	(segment
		(start 130.33248 -18.305526)
		(end 130.710432 -18.683478)
		(width 0.1143)
		(layer "In6.Cu")
		(net "FM_CPLD_NODE1_P3V3_EN")
	)
	(segment
		(start 163.339526 -67.200526)
		(end 178.68773 -82.54873)
		(width 0.1143)
		(layer "In6.Cu")
		(net "FM_CPLD_NODE1_P3V3_EN")
	)
	(segment
		(start 106.76128 -1.75768)
		(end 71.580502 -1.75768)
		(width 0.1143)
		(layer "In6.Cu")
		(net "FM_CPLD_NODE1_P3V3_EN")
	)
	(segment
		(start 157.42539 -18.683478)
		(end 160.4772 -21.735288)
		(width 0.1143)
		(layer "In6.Cu")
		(net "FM_CPLD_NODE1_P3V3_EN")
	)
	(segment
		(start 170.69181 -113.17732)
		(end 170.69181 -116.088414)
		(width 0.1143)
		(layer "In6.Cu")
		(net "FM_CPLD_NODE1_P3V3_EN")
	)
	(segment
		(start 116.36248 -11.359134)
		(end 116.36248 -11.35888)
		(width 0.1143)
		(layer "In6.Cu")
		(net "FM_CPLD_NODE1_P3V3_EN")
	)
	(segment
		(start 160.4772 -21.735288)
		(end 160.4772 -47.879508)
		(width 0.1143)
		(layer "In6.Cu")
		(net "FM_CPLD_NODE1_P3V3_EN")
	)
	(segment
		(start 170.69181 -116.088414)
		(end 170.73626 -116.132864)
		(width 0.1143)
		(layer "In6.Cu")
		(net "FM_CPLD_NODE1_P3V3_EN")
	)
	(segment
		(start 108.81487 -67.906138)
		(end 108.74248 -67.833748)
		(width 0.1016)
		(layer "F.Cu")
		(net "XDP_CPU_NODE1_VISA17")
	)
	(segment
		(start 70.202044 -70.310502)
		(end 70.204076 -70.310502)
		(width 0.1016)
		(layer "F.Cu")
		(net "XDP_CPU_NODE1_VISA17")
	)
	(segment
		(start 108.74248 -67.833748)
		(end 108.28909 -67.833748)
		(width 0.1016)
		(layer "F.Cu")
		(net "XDP_CPU_NODE1_VISA17")
	)
	(segment
		(start 70.204076 -70.310502)
		(end 70.597776 -70.704202)
		(width 0.1016)
		(layer "F.Cu")
		(net "XDP_CPU_NODE1_VISA17")
	)
	(segment
		(start 110.460028 -67.906138)
		(end 108.81487 -67.906138)
		(width 0.1016)
		(layer "F.Cu")
		(net "XDP_CPU_NODE1_VISA17")
	)
	(via
		(at 70.597776 -70.704202)
		(size 0.508)
		(drill 0.254)
		(layers "F.Cu" "B.Cu")
		(net "XDP_CPU_NODE1_VISA17")
	)
	(via
		(at 108.28909 -67.833748)
		(size 0.508)
		(drill 0.254)
		(layers "F.Cu" "B.Cu")
		(net "XDP_CPU_NODE1_VISA17")
	)
	(segment
		(start 96.200468 -58.933842)
		(end 96.018096 -58.75147)
		(width 0.1143)
		(layer "In2.Cu")
		(net "XDP_CPU_NODE1_VISA17")
	)
	(segment
		(start 76.773786 -68.107814)
		(end 76.4667 -68.4149)
		(width 0.1143)
		(layer "In2.Cu")
		(net "XDP_CPU_NODE1_VISA17")
	)
	(segment
		(start 107.515152 -67.000374)
		(end 107.515152 -66.121534)
		(width 0.1143)
		(layer "In2.Cu")
		(net "XDP_CPU_NODE1_VISA17")
	)
	(segment
		(start 96.640396 -59.213496)
		(end 96.38284 -59.213496)
		(width 0.1143)
		(layer "In2.Cu")
		(net "XDP_CPU_NODE1_VISA17")
	)
	(segment
		(start 77.439266 -68.107814)
		(end 76.773786 -68.107814)
		(width 0.1143)
		(layer "In2.Cu")
		(net "XDP_CPU_NODE1_VISA17")
	)
	(segment
		(start 94.333568 -58.933842)
		(end 94.333568 -59.031124)
		(width 0.1143)
		(layer "In2.Cu")
		(net "XDP_CPU_NODE1_VISA17")
	)
	(segment
		(start 106.631232 -65.771014)
		(end 106.613452 -65.771014)
		(width 0.1143)
		(layer "In2.Cu")
		(net "XDP_CPU_NODE1_VISA17")
	)
	(segment
		(start 96.38284 -59.213496)
		(end 96.200468 -59.031124)
		(width 0.1143)
		(layer "In2.Cu")
		(net "XDP_CPU_NODE1_VISA17")
	)
	(segment
		(start 98.067368 -59.031124)
		(end 97.884996 -59.213496)
		(width 0.1143)
		(layer "In2.Cu")
		(net "XDP_CPU_NODE1_VISA17")
	)
	(segment
		(start 97.262696 -58.75147)
		(end 97.00514 -58.75147)
		(width 0.1143)
		(layer "In2.Cu")
		(net "XDP_CPU_NODE1_VISA17")
	)
	(segment
		(start 92.906596 -59.213496)
		(end 92.64904 -59.213496)
		(width 0.1143)
		(layer "In2.Cu")
		(net "XDP_CPU_NODE1_VISA17")
	)
	(segment
		(start 97.445068 -59.031124)
		(end 97.445068 -58.933842)
		(width 0.1143)
		(layer "In2.Cu")
		(net "XDP_CPU_NODE1_VISA17")
	)
	(segment
		(start 96.018096 -58.75147)
		(end 95.76054 -58.75147)
		(width 0.1143)
		(layer "In2.Cu")
		(net "XDP_CPU_NODE1_VISA17")
	)
	(segment
		(start 93.711268 -58.933842)
		(end 93.528896 -58.75147)
		(width 0.1143)
		(layer "In2.Cu")
		(net "XDP_CPU_NODE1_VISA17")
	)
	(segment
		(start 97.884996 -59.213496)
		(end 97.62744 -59.213496)
		(width 0.1143)
		(layer "In2.Cu")
		(net "XDP_CPU_NODE1_VISA17")
	)
	(segment
		(start 104.924098 -62.105286)
		(end 104.666542 -62.105286)
		(width 0.1143)
		(layer "In2.Cu")
		(net "XDP_CPU_NODE1_VISA17")
	)
	(segment
		(start 92.466668 -59.031124)
		(end 92.466668 -58.933842)
		(width 0.1143)
		(layer "In2.Cu")
		(net "XDP_CPU_NODE1_VISA17")
	)
	(segment
		(start 96.200468 -59.031124)
		(end 96.200468 -58.933842)
		(width 0.1143)
		(layer "In2.Cu")
		(net "XDP_CPU_NODE1_VISA17")
	)
	(segment
		(start 94.151196 -59.213496)
		(end 93.89364 -59.213496)
		(width 0.1143)
		(layer "In2.Cu")
		(net "XDP_CPU_NODE1_VISA17")
	)
	(segment
		(start 103.847392 -61.803788)
		(end 100.795074 -58.75147)
		(width 0.1143)
		(layer "In2.Cu")
		(net "XDP_CPU_NODE1_VISA17")
	)
	(segment
		(start 108.28909 -67.833748)
		(end 108.28909 -67.774312)
		(width 0.1143)
		(layer "In2.Cu")
		(net "XDP_CPU_NODE1_VISA17")
	)
	(segment
		(start 106.106976 -65.814194)
		(end 105.10647 -64.813688)
		(width 0.1143)
		(layer "In2.Cu")
		(net "XDP_CPU_NODE1_VISA17")
	)
	(segment
		(start 97.62744 -59.213496)
		(end 97.445068 -59.031124)
		(width 0.1143)
		(layer "In2.Cu")
		(net "XDP_CPU_NODE1_VISA17")
	)
	(segment
		(start 78.405736 -67.141344)
		(end 77.439266 -68.107814)
		(width 0.1143)
		(layer "In2.Cu")
		(net "XDP_CPU_NODE1_VISA17")
	)
	(segment
		(start 93.088968 -59.031124)
		(end 92.906596 -59.213496)
		(width 0.1143)
		(layer "In2.Cu")
		(net "XDP_CPU_NODE1_VISA17")
	)
	(segment
		(start 106.613452 -65.771014)
		(end 106.570272 -65.814194)
		(width 0.1143)
		(layer "In2.Cu")
		(net "XDP_CPU_NODE1_VISA17")
	)
	(segment
		(start 95.395796 -59.213496)
		(end 95.13824 -59.213496)
		(width 0.1143)
		(layer "In2.Cu")
		(net "XDP_CPU_NODE1_VISA17")
	)
	(segment
		(start 70.597776 -70.539356)
		(end 70.597776 -70.704202)
		(width 0.1143)
		(layer "In2.Cu")
		(net "XDP_CPU_NODE1_VISA17")
	)
	(segment
		(start 95.13824 -59.213496)
		(end 94.955868 -59.031124)
		(width 0.1143)
		(layer "In2.Cu")
		(net "XDP_CPU_NODE1_VISA17")
	)
	(segment
		(start 93.711268 -59.031124)
		(end 93.711268 -58.933842)
		(width 0.1143)
		(layer "In2.Cu")
		(net "XDP_CPU_NODE1_VISA17")
	)
	(segment
		(start 93.088968 -58.933842)
		(end 93.088968 -59.031124)
		(width 0.1143)
		(layer "In2.Cu")
		(net "XDP_CPU_NODE1_VISA17")
	)
	(segment
		(start 105.10647 -62.287658)
		(end 104.924098 -62.105286)
		(width 0.1143)
		(layer "In2.Cu")
		(net "XDP_CPU_NODE1_VISA17")
	)
	(segment
		(start 104.297734 -64.94272)
		(end 104.033828 -64.94272)
		(width 0.1143)
		(layer "In2.Cu")
		(net "XDP_CPU_NODE1_VISA17")
	)
	(segment
		(start 96.822768 -58.933842)
		(end 96.822768 -59.031124)
		(width 0.1143)
		(layer "In2.Cu")
		(net "XDP_CPU_NODE1_VISA17")
	)
	(segment
		(start 106.641392 -65.760854)
		(end 106.631232 -65.771014)
		(width 0.1143)
		(layer "In2.Cu")
		(net "XDP_CPU_NODE1_VISA17")
	)
	(segment
		(start 92.64904 -59.213496)
		(end 92.466668 -59.031124)
		(width 0.1143)
		(layer "In2.Cu")
		(net "XDP_CPU_NODE1_VISA17")
	)
	(segment
		(start 107.515152 -66.121534)
		(end 107.154472 -65.760854)
		(width 0.1143)
		(layer "In2.Cu")
		(net "XDP_CPU_NODE1_VISA17")
	)
	(segment
		(start 93.89364 -59.213496)
		(end 93.711268 -59.031124)
		(width 0.1143)
		(layer "In2.Cu")
		(net "XDP_CPU_NODE1_VISA17")
	)
	(segment
		(start 103.847392 -64.756284)
		(end 103.847392 -61.803788)
		(width 0.1143)
		(layer "In2.Cu")
		(net "XDP_CPU_NODE1_VISA17")
	)
	(segment
		(start 80.166464 -67.141344)
		(end 78.405736 -67.141344)
		(width 0.1143)
		(layer "In2.Cu")
		(net "XDP_CPU_NODE1_VISA17")
	)
	(segment
		(start 104.48417 -62.287658)
		(end 104.48417 -64.756284)
		(width 0.1143)
		(layer "In2.Cu")
		(net "XDP_CPU_NODE1_VISA17")
	)
	(segment
		(start 93.27134 -58.75147)
		(end 93.088968 -58.933842)
		(width 0.1143)
		(layer "In2.Cu")
		(net "XDP_CPU_NODE1_VISA17")
	)
	(segment
		(start 104.666542 -62.105286)
		(end 104.48417 -62.287658)
		(width 0.1143)
		(layer "In2.Cu")
		(net "XDP_CPU_NODE1_VISA17")
	)
	(segment
		(start 94.51594 -58.75147)
		(end 94.333568 -58.933842)
		(width 0.1143)
		(layer "In2.Cu")
		(net "XDP_CPU_NODE1_VISA17")
	)
	(segment
		(start 95.578168 -59.031124)
		(end 95.395796 -59.213496)
		(width 0.1143)
		(layer "In2.Cu")
		(net "XDP_CPU_NODE1_VISA17")
	)
	(segment
		(start 94.773496 -58.75147)
		(end 94.51594 -58.75147)
		(width 0.1143)
		(layer "In2.Cu")
		(net "XDP_CPU_NODE1_VISA17")
	)
	(segment
		(start 88.556338 -58.75147)
		(end 80.166464 -67.141344)
		(width 0.1143)
		(layer "In2.Cu")
		(net "XDP_CPU_NODE1_VISA17")
	)
	(segment
		(start 97.00514 -58.75147)
		(end 96.822768 -58.933842)
		(width 0.1143)
		(layer "In2.Cu")
		(net "XDP_CPU_NODE1_VISA17")
	)
	(segment
		(start 98.067368 -58.933842)
		(end 98.067368 -59.031124)
		(width 0.1143)
		(layer "In2.Cu")
		(net "XDP_CPU_NODE1_VISA17")
	)
	(segment
		(start 93.528896 -58.75147)
		(end 93.27134 -58.75147)
		(width 0.1143)
		(layer "In2.Cu")
		(net "XDP_CPU_NODE1_VISA17")
	)
	(segment
		(start 107.154472 -65.760854)
		(end 106.641392 -65.760854)
		(width 0.1143)
		(layer "In2.Cu")
		(net "XDP_CPU_NODE1_VISA17")
	)
	(segment
		(start 95.578168 -58.933842)
		(end 95.578168 -59.031124)
		(width 0.1143)
		(layer "In2.Cu")
		(net "XDP_CPU_NODE1_VISA17")
	)
	(segment
		(start 71.418704 -70.133718)
		(end 71.003414 -70.133718)
		(width 0.1143)
		(layer "In2.Cu")
		(net "XDP_CPU_NODE1_VISA17")
	)
	(segment
		(start 104.033828 -64.94272)
		(end 103.847392 -64.756284)
		(width 0.1143)
		(layer "In2.Cu")
		(net "XDP_CPU_NODE1_VISA17")
	)
	(segment
		(start 71.003414 -70.133718)
		(end 70.597776 -70.539356)
		(width 0.1143)
		(layer "In2.Cu")
		(net "XDP_CPU_NODE1_VISA17")
	)
	(segment
		(start 92.466668 -58.933842)
		(end 92.284296 -58.75147)
		(width 0.1143)
		(layer "In2.Cu")
		(net "XDP_CPU_NODE1_VISA17")
	)
	(segment
		(start 94.333568 -59.031124)
		(end 94.151196 -59.213496)
		(width 0.1143)
		(layer "In2.Cu")
		(net "XDP_CPU_NODE1_VISA17")
	)
	(segment
		(start 76.4667 -68.4149)
		(end 73.137522 -68.4149)
		(width 0.1143)
		(layer "In2.Cu")
		(net "XDP_CPU_NODE1_VISA17")
	)
	(segment
		(start 106.570272 -65.814194)
		(end 106.106976 -65.814194)
		(width 0.1143)
		(layer "In2.Cu")
		(net "XDP_CPU_NODE1_VISA17")
	)
	(segment
		(start 92.284296 -58.75147)
		(end 88.556338 -58.75147)
		(width 0.1143)
		(layer "In2.Cu")
		(net "XDP_CPU_NODE1_VISA17")
	)
	(segment
		(start 73.137522 -68.4149)
		(end 71.418704 -70.133718)
		(width 0.1143)
		(layer "In2.Cu")
		(net "XDP_CPU_NODE1_VISA17")
	)
	(segment
		(start 94.955868 -59.031124)
		(end 94.955868 -58.933842)
		(width 0.1143)
		(layer "In2.Cu")
		(net "XDP_CPU_NODE1_VISA17")
	)
	(segment
		(start 96.822768 -59.031124)
		(end 96.640396 -59.213496)
		(width 0.1143)
		(layer "In2.Cu")
		(net "XDP_CPU_NODE1_VISA17")
	)
	(segment
		(start 97.445068 -58.933842)
		(end 97.262696 -58.75147)
		(width 0.1143)
		(layer "In2.Cu")
		(net "XDP_CPU_NODE1_VISA17")
	)
	(segment
		(start 100.795074 -58.75147)
		(end 98.24974 -58.75147)
		(width 0.1143)
		(layer "In2.Cu")
		(net "XDP_CPU_NODE1_VISA17")
	)
	(segment
		(start 98.24974 -58.75147)
		(end 98.067368 -58.933842)
		(width 0.1143)
		(layer "In2.Cu")
		(net "XDP_CPU_NODE1_VISA17")
	)
	(segment
		(start 94.955868 -58.933842)
		(end 94.773496 -58.75147)
		(width 0.1143)
		(layer "In2.Cu")
		(net "XDP_CPU_NODE1_VISA17")
	)
	(segment
		(start 95.76054 -58.75147)
		(end 95.578168 -58.933842)
		(width 0.1143)
		(layer "In2.Cu")
		(net "XDP_CPU_NODE1_VISA17")
	)
	(segment
		(start 108.28909 -67.774312)
		(end 107.515152 -67.000374)
		(width 0.1143)
		(layer "In2.Cu")
		(net "XDP_CPU_NODE1_VISA17")
	)
	(segment
		(start 105.10647 -64.813688)
		(end 105.10647 -62.287658)
		(width 0.1143)
		(layer "In2.Cu")
		(net "XDP_CPU_NODE1_VISA17")
	)
	(segment
		(start 104.48417 -64.756284)
		(end 104.297734 -64.94272)
		(width 0.1143)
		(layer "In2.Cu")
		(net "XDP_CPU_NODE1_VISA17")
	)
	(segment
		(start 67.510406 -5.590032)
		(end 67.510406 -5.33146)
		(width 0.254)
		(layer "F.Cu")
		(net "P3V3_NODE1_SS")
	)
	(segment
		(start 68.622418 -6.19633)
		(end 68.116704 -6.19633)
		(width 0.254)
		(layer "F.Cu")
		(net "P3V3_NODE1_SS")
	)
	(segment
		(start 67.18046 -5.001514)
		(end 67.510406 -5.33146)
		(width 0.254)
		(layer "F.Cu")
		(net "P3V3_NODE1_SS")
	)
	(segment
		(start 68.116704 -6.19633)
		(end 67.510406 -5.590032)
		(width 0.254)
		(layer "F.Cu")
		(net "P3V3_NODE1_SS")
	)
	(segment
		(start 66.875406 -5.001514)
		(end 67.18046 -5.001514)
		(width 0.254)
		(layer "F.Cu")
		(net "P3V3_NODE1_SS")
	)
	(via
		(at 67.510406 -5.33146)
		(size 0.508)
		(drill 0.254)
		(layers "F.Cu" "B.Cu")
		(net "P3V3_NODE1_SS")
	)
	(segment
		(start 57.207912 -100.75926)
		(end 57.207912 -101.487986)
		(width 0.1016)
		(layer "F.Cu")
		(net "PU_TEMP1_NODE1_SYS_SHDN_L")
	)
	(segment
		(start 50.471832 -101.66477)
		(end 50.471832 -102.746048)
		(width 0.1016)
		(layer "F.Cu")
		(net "PU_TEMP1_NODE1_SYS_SHDN_L")
	)
	(segment
		(start 50.775616 -103.049832)
		(end 55.646066 -103.049832)
		(width 0.1016)
		(layer "F.Cu")
		(net "PU_TEMP1_NODE1_SYS_SHDN_L")
	)
	(segment
		(start 55.646066 -103.049832)
		(end 56.66359 -102.032308)
		(width 0.1016)
		(layer "F.Cu")
		(net "PU_TEMP1_NODE1_SYS_SHDN_L")
	)
	(segment
		(start 50.471832 -102.746048)
		(end 50.775616 -103.049832)
		(width 0.1016)
		(layer "F.Cu")
		(net "PU_TEMP1_NODE1_SYS_SHDN_L")
	)
	(segment
		(start 57.207912 -101.487986)
		(end 56.66359 -102.032308)
		(width 0.1016)
		(layer "F.Cu")
		(net "PU_TEMP1_NODE1_SYS_SHDN_L")
	)
	(via
		(at 56.66359 -102.032308)
		(size 0.508)
		(drill 0.254)
		(layers "F.Cu" "B.Cu")
		(net "PU_TEMP1_NODE1_SYS_SHDN_L")
	)
	(segment
		(start 66.054478 -75.569318)
		(end 66.411602 -75.212194)
		(width 0.1016)
		(layer "F.Cu")
		(net "TP_CPU0_NODE1_HFPLL")
	)
	(segment
		(start 66.011044 -75.569318)
		(end 66.054478 -75.569318)
		(width 0.1016)
		(layer "F.Cu")
		(net "TP_CPU0_NODE1_HFPLL")
	)
	(via
		(at 66.411602 -75.212194)
		(size 0.508)
		(drill 0.254)
		(layers "F.Cu" "B.Cu")
		(net "TP_CPU0_NODE1_HFPLL")
	)
	(segment
		(start 67.037458 -2.98069)
		(end 67.026282 -2.98069)
		(width 0.254)
		(layer "F.Cu")
		(net "P3V3_NODE1_VREG5")
	)
	(segment
		(start 66.181732 -5.14985)
		(end 66.86804 -5.836158)
		(width 0.254)
		(layer "F.Cu")
		(net "P3V3_NODE1_VREG5")
	)
	(segment
		(start 66.956686 -6.421374)
		(end 67.623436 -6.421374)
		(width 0.254)
		(layer "F.Cu")
		(net "P3V3_NODE1_VREG5")
	)
	(segment
		(start 66.86804 -6.332728)
		(end 66.956686 -6.421374)
		(width 0.254)
		(layer "F.Cu")
		(net "P3V3_NODE1_VREG5")
	)
	(segment
		(start 66.79057 -3.216402)
		(end 66.181732 -3.82524)
		(width 0.254)
		(layer "F.Cu")
		(net "P3V3_NODE1_VREG5")
	)
	(segment
		(start 67.898264 -6.696202)
		(end 68.622418 -6.696202)
		(width 0.254)
		(layer "F.Cu")
		(net "P3V3_NODE1_VREG5")
	)
	(segment
		(start 66.181732 -3.82524)
		(end 66.181732 -5.14985)
		(width 0.254)
		(layer "F.Cu")
		(net "P3V3_NODE1_VREG5")
	)
	(segment
		(start 66.86804 -5.836158)
		(end 66.86804 -6.332728)
		(width 0.254)
		(layer "F.Cu")
		(net "P3V3_NODE1_VREG5")
	)
	(segment
		(start 67.026282 -2.98069)
		(end 66.79057 -3.216402)
		(width 0.254)
		(layer "F.Cu")
		(net "P3V3_NODE1_VREG5")
	)
	(segment
		(start 67.474084 -2.544064)
		(end 67.037458 -2.98069)
		(width 0.254)
		(layer "F.Cu")
		(net "P3V3_NODE1_VREG5")
	)
	(segment
		(start 67.623436 -6.421374)
		(end 67.898264 -6.696202)
		(width 0.254)
		(layer "F.Cu")
		(net "P3V3_NODE1_VREG5")
	)
	(segment
		(start 67.924934 -2.544064)
		(end 67.474084 -2.544064)
		(width 0.254)
		(layer "F.Cu")
		(net "P3V3_NODE1_VREG5")
	)
	(via
		(at 66.79057 -3.216402)
		(size 0.508)
		(drill 0.254)
		(layers "F.Cu" "B.Cu")
		(net "P3V3_NODE1_VREG5")
	)
	(segment
		(start 48.307752 -102.916228)
		(end 49.337722 -102.916228)
		(width 0.1016)
		(layer "F.Cu")
		(net "SMB_TEMP1_NODE1_ALERT_R_L")
	)
	(segment
		(start 46.573694 -101.999034)
		(end 47.390558 -101.999034)
		(width 0.1016)
		(layer "F.Cu")
		(net "SMB_TEMP1_NODE1_ALERT_R_L")
	)
	(segment
		(start 47.390558 -101.999034)
		(end 48.307752 -102.916228)
		(width 0.1016)
		(layer "F.Cu")
		(net "SMB_TEMP1_NODE1_ALERT_R_L")
	)
	(segment
		(start 49.821846 -101.66477)
		(end 49.821846 -102.369112)
		(width 0.1016)
		(layer "F.Cu")
		(net "SMB_TEMP1_NODE1_ALERT_R_L")
	)
	(segment
		(start 45.557694 -101.999034)
		(end 46.573694 -101.999034)
		(width 0.1016)
		(layer "F.Cu")
		(net "SMB_TEMP1_NODE1_ALERT_R_L")
	)
	(segment
		(start 49.821846 -102.369112)
		(end 49.853342 -102.400608)
		(width 0.1016)
		(layer "F.Cu")
		(net "SMB_TEMP1_NODE1_ALERT_R_L")
	)
	(segment
		(start 49.337722 -102.916228)
		(end 49.853342 -102.400608)
		(width 0.1016)
		(layer "F.Cu")
		(net "SMB_TEMP1_NODE1_ALERT_R_L")
	)
	(via
		(at 49.853342 -102.400608)
		(size 0.508)
		(drill 0.254)
		(layers "F.Cu" "B.Cu")
		(net "SMB_TEMP1_NODE1_ALERT_R_L")
	)
	(segment
		(start 49.990248 -80.002126)
		(end 49.990248 -80.443324)
		(width 0.1016)
		(layer "F.Cu")
		(net "SMB_CPU_NODE1_XDP_DAT_R")
	)
	(segment
		(start 49.990248 -80.443324)
		(end 49.904904 -80.528668)
		(width 0.1016)
		(layer "F.Cu")
		(net "SMB_CPU_NODE1_XDP_DAT_R")
	)
	(via
		(at 49.904904 -80.528668)
		(size 0.508)
		(drill 0.254)
		(layers "F.Cu" "B.Cu")
		(net "SMB_CPU_NODE1_XDP_DAT_R")
	)
	(via
		(at 46.978062 -91.837002)
		(size 0.6604)
		(drill 0.3302)
		(layers "F.Cu" "B.Cu")
		(net "SMB_CPU_NODE1_XDP_DAT_R")
	)
	(segment
		(start 49.096422 -81.444084)
		(end 49.904904 -80.635602)
		(width 0.1016)
		(layer "B.Cu")
		(net "SMB_CPU_NODE1_XDP_DAT_R")
	)
	(segment
		(start 47.766732 -94.00032)
		(end 46.750732 -94.00032)
		(width 0.1016)
		(layer "B.Cu")
		(net "SMB_CPU_NODE1_XDP_DAT_R")
	)
	(segment
		(start 48.373284 -81.444084)
		(end 49.096422 -81.444084)
		(width 0.1016)
		(layer "B.Cu")
		(net "SMB_CPU_NODE1_XDP_DAT_R")
	)
	(segment
		(start 46.750732 -92.064332)
		(end 46.978062 -91.837002)
		(width 0.1016)
		(layer "B.Cu")
		(net "SMB_CPU_NODE1_XDP_DAT_R")
	)
	(segment
		(start 46.978062 -91.837002)
		(end 46.978062 -86.320122)
		(width 0.1016)
		(layer "B.Cu")
		(net "SMB_CPU_NODE1_XDP_DAT_R")
	)
	(segment
		(start 47.806102 -83.561174)
		(end 47.802546 -83.557618)
		(width 0.1016)
		(layer "B.Cu")
		(net "SMB_CPU_NODE1_XDP_DAT_R")
	)
	(segment
		(start 46.750732 -94.00032)
		(end 46.750732 -92.064332)
		(width 0.1016)
		(layer "B.Cu")
		(net "SMB_CPU_NODE1_XDP_DAT_R")
	)
	(segment
		(start 46.978062 -86.320122)
		(end 47.806102 -85.492082)
		(width 0.1016)
		(layer "B.Cu")
		(net "SMB_CPU_NODE1_XDP_DAT_R")
	)
	(segment
		(start 49.904904 -80.635602)
		(end 49.904904 -80.528668)
		(width 0.1016)
		(layer "B.Cu")
		(net "SMB_CPU_NODE1_XDP_DAT_R")
	)
	(segment
		(start 47.802546 -83.557618)
		(end 47.802546 -82.014822)
		(width 0.1016)
		(layer "B.Cu")
		(net "SMB_CPU_NODE1_XDP_DAT_R")
	)
	(segment
		(start 47.802546 -82.014822)
		(end 48.373284 -81.444084)
		(width 0.1016)
		(layer "B.Cu")
		(net "SMB_CPU_NODE1_XDP_DAT_R")
	)
	(segment
		(start 47.806102 -85.492082)
		(end 47.806102 -83.561174)
		(width 0.1016)
		(layer "B.Cu")
		(net "SMB_CPU_NODE1_XDP_DAT_R")
	)
	(segment
		(start 68.622418 -7.196328)
		(end 68.258182 -7.196328)
		(width 0.254)
		(layer "F.Cu")
		(net "P3V3_NODE1_FB")
	)
	(segment
		(start 66.091308 -9.506966)
		(end 66.091308 -8.501888)
		(width 0.254)
		(layer "F.Cu")
		(net "P3V3_NODE1_FB")
	)
	(segment
		(start 66.757042 -7.424166)
		(end 66.757042 -7.668768)
		(width 0.254)
		(layer "F.Cu")
		(net "P3V3_NODE1_FB")
	)
	(segment
		(start 66.757042 -7.668768)
		(end 66.091308 -8.334502)
		(width 0.254)
		(layer "F.Cu")
		(net "P3V3_NODE1_FB")
	)
	(segment
		(start 66.091308 -8.334502)
		(end 66.091308 -8.501888)
		(width 0.254)
		(layer "F.Cu")
		(net "P3V3_NODE1_FB")
	)
	(segment
		(start 68.030344 -7.424166)
		(end 67.592194 -7.424166)
		(width 0.254)
		(layer "F.Cu")
		(net "P3V3_NODE1_FB")
	)
	(segment
		(start 68.258182 -7.196328)
		(end 68.030344 -7.424166)
		(width 0.254)
		(layer "F.Cu")
		(net "P3V3_NODE1_FB")
	)
	(segment
		(start 67.592194 -7.424166)
		(end 66.757042 -7.424166)
		(width 0.254)
		(layer "F.Cu")
		(net "P3V3_NODE1_FB")
	)
	(via
		(at 67.592194 -7.424166)
		(size 0.508)
		(drill 0.254)
		(layers "F.Cu" "B.Cu")
		(net "P3V3_NODE1_FB")
	)
	(segment
		(start 49.17186 -98.144584)
		(end 49.17186 -97.379282)
		(width 0.1016)
		(layer "F.Cu")
		(net "TP_TEMP1_NODE1_3")
	)
	(via
		(at 49.17186 -97.379282)
		(size 0.508)
		(drill 0.254)
		(layers "F.Cu" "B.Cu")
		(net "TP_TEMP1_NODE1_3")
	)
	(segment
		(start 47.704248 -80.002126)
		(end 47.704248 -80.176116)
		(width 0.1016)
		(layer "F.Cu")
		(net "SMB_CPU_NODE1_MEM_ICS_DAT_R")
	)
	(segment
		(start 47.704248 -80.176116)
		(end 47.3329 -80.547464)
		(width 0.1016)
		(layer "F.Cu")
		(net "SMB_CPU_NODE1_MEM_ICS_DAT_R")
	)
	(via
		(at 47.3329 -80.547464)
		(size 0.508)
		(drill 0.254)
		(layers "F.Cu" "B.Cu")
		(net "SMB_CPU_NODE1_MEM_ICS_DAT_R")
	)
	(via
		(at 44.41444 -92.053664)
		(size 0.6604)
		(drill 0.3302)
		(layers "F.Cu" "B.Cu")
		(net "SMB_CPU_NODE1_MEM_ICS_DAT_R")
	)
	(segment
		(start 45.859954 -82.888836)
		(end 47.174912 -81.573878)
		(width 0.1016)
		(layer "B.Cu")
		(net "SMB_CPU_NODE1_MEM_ICS_DAT_R")
	)
	(segment
		(start 43.82262 -92.053664)
		(end 44.41444 -92.053664)
		(width 0.1016)
		(layer "B.Cu")
		(net "SMB_CPU_NODE1_MEM_ICS_DAT_R")
	)
	(segment
		(start 42.686732 -93.189552)
		(end 43.82262 -92.053664)
		(width 0.1016)
		(layer "B.Cu")
		(net "SMB_CPU_NODE1_MEM_ICS_DAT_R")
	)
	(segment
		(start 47.174912 -81.573878)
		(end 47.174912 -80.704944)
		(width 0.1016)
		(layer "B.Cu")
		(net "SMB_CPU_NODE1_MEM_ICS_DAT_R")
	)
	(segment
		(start 43.702732 -94.00032)
		(end 42.686732 -94.00032)
		(width 0.1016)
		(layer "B.Cu")
		(net "SMB_CPU_NODE1_MEM_ICS_DAT_R")
	)
	(segment
		(start 44.874942 -91.593162)
		(end 45.356018 -91.593162)
		(width 0.1016)
		(layer "B.Cu")
		(net "SMB_CPU_NODE1_MEM_ICS_DAT_R")
	)
	(segment
		(start 45.859954 -91.089226)
		(end 45.859954 -82.888836)
		(width 0.1016)
		(layer "B.Cu")
		(net "SMB_CPU_NODE1_MEM_ICS_DAT_R")
	)
	(segment
		(start 47.332392 -80.547464)
		(end 47.3329 -80.547464)
		(width 0.1016)
		(layer "B.Cu")
		(net "SMB_CPU_NODE1_MEM_ICS_DAT_R")
	)
	(segment
		(start 45.356018 -91.593162)
		(end 45.859954 -91.089226)
		(width 0.1016)
		(layer "B.Cu")
		(net "SMB_CPU_NODE1_MEM_ICS_DAT_R")
	)
	(segment
		(start 42.686732 -94.00032)
		(end 42.686732 -93.189552)
		(width 0.1016)
		(layer "B.Cu")
		(net "SMB_CPU_NODE1_MEM_ICS_DAT_R")
	)
	(segment
		(start 47.174912 -80.704944)
		(end 47.332392 -80.547464)
		(width 0.1016)
		(layer "B.Cu")
		(net "SMB_CPU_NODE1_MEM_ICS_DAT_R")
	)
	(segment
		(start 44.41444 -92.053664)
		(end 44.874942 -91.593162)
		(width 0.1016)
		(layer "B.Cu")
		(net "SMB_CPU_NODE1_MEM_ICS_DAT_R")
	)
	(via
		(at 84.431632 -138.200638)
		(size 0.508)
		(drill 0.254)
		(layers "F.Cu" "B.Cu")
		(net "P1V26_BMC_NODE1_ADJ")
	)
	(segment
		(start 81.978754 -136.763252)
		(end 83.83524 -136.763252)
		(width 0.254)
		(layer "B.Cu")
		(net "P1V26_BMC_NODE1_ADJ")
	)
	(segment
		(start 84.431632 -137.359644)
		(end 84.431632 -138.200638)
		(width 0.254)
		(layer "B.Cu")
		(net "P1V26_BMC_NODE1_ADJ")
	)
	(segment
		(start 81.784698 -136.957308)
		(end 81.978754 -136.763252)
		(width 0.254)
		(layer "B.Cu")
		(net "P1V26_BMC_NODE1_ADJ")
	)
	(segment
		(start 83.83524 -136.763252)
		(end 84.431632 -137.359644)
		(width 0.254)
		(layer "B.Cu")
		(net "P1V26_BMC_NODE1_ADJ")
	)
	(segment
		(start 181.01056 -116.365528)
		(end 181.439312 -116.365528)
		(width 0.1016)
		(layer "F.Cu")
		(net "FM_CPLD_NODE1_P5V_EN")
	)
	(segment
		(start 59.519566 -162.015424)
		(end 59.519566 -162.88893)
		(width 0.1016)
		(layer "F.Cu")
		(net "FM_CPLD_NODE1_P5V_EN")
	)
	(segment
		(start 59.563 -161.97199)
		(end 59.519566 -162.015424)
		(width 0.1016)
		(layer "F.Cu")
		(net "FM_CPLD_NODE1_P5V_EN")
	)
	(segment
		(start 59.519566 -163.12007)
		(end 60.312554 -163.913058)
		(width 0.1016)
		(layer "F.Cu")
		(net "FM_CPLD_NODE1_P5V_EN")
	)
	(segment
		(start 59.330336 -164.134546)
		(end 60.312554 -164.134546)
		(width 0.1016)
		(layer "F.Cu")
		(net "FM_CPLD_NODE1_P5V_EN")
	)
	(segment
		(start 181.439312 -116.365528)
		(end 181.744112 -116.670328)
		(width 0.1016)
		(layer "F.Cu")
		(net "FM_CPLD_NODE1_P5V_EN")
	)
	(segment
		(start 60.312554 -163.913058)
		(end 60.312554 -164.134546)
		(width 0.1016)
		(layer "F.Cu")
		(net "FM_CPLD_NODE1_P5V_EN")
	)
	(segment
		(start 58.314336 -164.134546)
		(end 59.330336 -164.134546)
		(width 0.1016)
		(layer "F.Cu")
		(net "FM_CPLD_NODE1_P5V_EN")
	)
	(segment
		(start 59.519566 -162.88893)
		(end 59.519566 -163.12007)
		(width 0.1016)
		(layer "F.Cu")
		(net "FM_CPLD_NODE1_P5V_EN")
	)
	(via
		(at 129.1336 -156.921962)
		(size 0.508)
		(drill 0.254)
		(layers "F.Cu" "B.Cu")
		(net "FM_CPLD_NODE1_P5V_EN")
	)
	(via
		(at 59.563 -161.97199)
		(size 0.508)
		(drill 0.254)
		(layers "F.Cu" "B.Cu")
		(net "FM_CPLD_NODE1_P5V_EN")
	)
	(via
		(at 181.744112 -116.670328)
		(size 0.508)
		(drill 0.254)
		(layers "F.Cu" "B.Cu")
		(net "FM_CPLD_NODE1_P5V_EN")
	)
	(via
		(at 158.9786 -117.289326)
		(size 0.508)
		(drill 0.254)
		(layers "F.Cu" "B.Cu")
		(net "FM_CPLD_NODE1_P5V_EN")
	)
	(segment
		(start 132.749544 -156.746448)
		(end 129.309114 -156.746448)
		(width 0.1143)
		(layer "In2.Cu")
		(net "FM_CPLD_NODE1_P5V_EN")
	)
	(segment
		(start 141.71041 -155.415488)
		(end 134.080504 -155.415488)
		(width 0.1143)
		(layer "In2.Cu")
		(net "FM_CPLD_NODE1_P5V_EN")
	)
	(segment
		(start 158.80715 -117.460776)
		(end 158.80715 -127.27051)
		(width 0.1143)
		(layer "In2.Cu")
		(net "FM_CPLD_NODE1_P5V_EN")
	)
	(segment
		(start 158.80715 -127.27051)
		(end 157.600396 -128.477264)
		(width 0.1143)
		(layer "In2.Cu")
		(net "FM_CPLD_NODE1_P5V_EN")
	)
	(segment
		(start 148.155152 -139.58189)
		(end 148.656802 -140.08354)
		(width 0.1143)
		(layer "In2.Cu")
		(net "FM_CPLD_NODE1_P5V_EN")
	)
	(segment
		(start 157.600396 -128.51003)
		(end 151.136604 -134.973822)
		(width 0.1143)
		(layer "In2.Cu")
		(net "FM_CPLD_NODE1_P5V_EN")
	)
	(segment
		(start 134.080504 -155.415488)
		(end 132.749544 -156.746448)
		(width 0.1143)
		(layer "In2.Cu")
		(net "FM_CPLD_NODE1_P5V_EN")
	)
	(segment
		(start 151.136604 -134.973822)
		(end 148.155152 -137.955528)
		(width 0.1143)
		(layer "In2.Cu")
		(net "FM_CPLD_NODE1_P5V_EN")
	)
	(segment
		(start 148.271992 -145.277078)
		(end 147.66036 -145.88871)
		(width 0.1143)
		(layer "In2.Cu")
		(net "FM_CPLD_NODE1_P5V_EN")
	)
	(segment
		(start 129.309114 -156.746448)
		(end 129.1336 -156.921962)
		(width 0.1143)
		(layer "In2.Cu")
		(net "FM_CPLD_NODE1_P5V_EN")
	)
	(segment
		(start 147.66036 -145.88871)
		(end 147.66036 -149.465538)
		(width 0.1143)
		(layer "In2.Cu")
		(net "FM_CPLD_NODE1_P5V_EN")
	)
	(segment
		(start 148.155152 -137.955528)
		(end 148.155152 -139.58189)
		(width 0.1143)
		(layer "In2.Cu")
		(net "FM_CPLD_NODE1_P5V_EN")
	)
	(segment
		(start 148.656802 -140.44676)
		(end 148.002752 -141.10081)
		(width 0.1143)
		(layer "In2.Cu")
		(net "FM_CPLD_NODE1_P5V_EN")
	)
	(segment
		(start 148.002752 -144.644618)
		(end 148.271992 -144.913858)
		(width 0.1143)
		(layer "In2.Cu")
		(net "FM_CPLD_NODE1_P5V_EN")
	)
	(segment
		(start 158.9786 -117.289326)
		(end 158.80715 -117.460776)
		(width 0.1143)
		(layer "In2.Cu")
		(net "FM_CPLD_NODE1_P5V_EN")
	)
	(segment
		(start 148.002752 -141.10081)
		(end 148.002752 -144.644618)
		(width 0.1143)
		(layer "In2.Cu")
		(net "FM_CPLD_NODE1_P5V_EN")
	)
	(segment
		(start 157.600396 -128.477264)
		(end 157.600396 -128.51003)
		(width 0.1143)
		(layer "In2.Cu")
		(net "FM_CPLD_NODE1_P5V_EN")
	)
	(segment
		(start 147.66036 -149.465538)
		(end 141.71041 -155.415488)
		(width 0.1143)
		(layer "In2.Cu")
		(net "FM_CPLD_NODE1_P5V_EN")
	)
	(segment
		(start 148.656802 -140.08354)
		(end 148.656802 -140.44676)
		(width 0.1143)
		(layer "In2.Cu")
		(net "FM_CPLD_NODE1_P5V_EN")
	)
	(segment
		(start 148.271992 -144.913858)
		(end 148.271992 -145.277078)
		(width 0.1143)
		(layer "In2.Cu")
		(net "FM_CPLD_NODE1_P5V_EN")
	)
	(segment
		(start 128.535938 -156.921962)
		(end 128.4478 -157.0101)
		(width 0.1143)
		(layer "In7.Cu")
		(net "FM_CPLD_NODE1_P5V_EN")
	)
	(segment
		(start 70.83298 -163.440618)
		(end 70.83298 -163.44138)
		(width 0.1143)
		(layer "In7.Cu")
		(net "FM_CPLD_NODE1_P5V_EN")
	)
	(segment
		(start 112.563402 -160.60547)
		(end 111.761524 -159.803592)
		(width 0.1143)
		(layer "In7.Cu")
		(net "FM_CPLD_NODE1_P5V_EN")
	)
	(segment
		(start 120.250712 -159.709358)
		(end 117.532658 -159.709358)
		(width 0.1143)
		(layer "In7.Cu")
		(net "FM_CPLD_NODE1_P5V_EN")
	)
	(segment
		(start 160.517332 -117.289326)
		(end 160.925256 -116.881402)
		(width 0.1143)
		(layer "In7.Cu")
		(net "FM_CPLD_NODE1_P5V_EN")
	)
	(segment
		(start 74.685652 -159.587946)
		(end 70.83298 -163.440618)
		(width 0.1143)
		(layer "In7.Cu")
		(net "FM_CPLD_NODE1_P5V_EN")
	)
	(segment
		(start 103.136192 -160.052004)
		(end 102.96652 -160.052004)
		(width 0.1143)
		(layer "In7.Cu")
		(net "FM_CPLD_NODE1_P5V_EN")
	)
	(segment
		(start 120.5611 -159.39897)
		(end 120.250712 -159.709358)
		(width 0.1143)
		(layer "In7.Cu")
		(net "FM_CPLD_NODE1_P5V_EN")
	)
	(segment
		(start 168.853104 -114.658902)
		(end 169.678858 -113.833148)
		(width 0.1143)
		(layer "In7.Cu")
		(net "FM_CPLD_NODE1_P5V_EN")
	)
	(segment
		(start 124.32919 -157.0101)
		(end 121.94032 -159.39897)
		(width 0.1143)
		(layer "In7.Cu")
		(net "FM_CPLD_NODE1_P5V_EN")
	)
	(segment
		(start 103.384604 -159.803592)
		(end 103.136192 -160.052004)
		(width 0.1143)
		(layer "In7.Cu")
		(net "FM_CPLD_NODE1_P5V_EN")
	)
	(segment
		(start 121.94032 -159.39897)
		(end 120.5611 -159.39897)
		(width 0.1143)
		(layer "In7.Cu")
		(net "FM_CPLD_NODE1_P5V_EN")
	)
	(segment
		(start 181.079648 -116.670328)
		(end 181.744112 -116.670328)
		(width 0.1143)
		(layer "In7.Cu")
		(net "FM_CPLD_NODE1_P5V_EN")
	)
	(segment
		(start 59.55792 -163.68903)
		(end 59.55792 -161.97707)
		(width 0.1143)
		(layer "In7.Cu")
		(net "FM_CPLD_NODE1_P5V_EN")
	)
	(segment
		(start 78.8035 -159.587946)
		(end 74.685652 -159.587946)
		(width 0.1143)
		(layer "In7.Cu")
		(net "FM_CPLD_NODE1_P5V_EN")
	)
	(segment
		(start 102.96652 -160.052004)
		(end 102.83317 -160.185354)
		(width 0.1143)
		(layer "In7.Cu")
		(net "FM_CPLD_NODE1_P5V_EN")
	)
	(segment
		(start 98.138742 -159.487108)
		(end 91.148916 -159.487108)
		(width 0.1143)
		(layer "In7.Cu")
		(net "FM_CPLD_NODE1_P5V_EN")
	)
	(segment
		(start 129.1336 -156.921962)
		(end 128.535938 -156.921962)
		(width 0.1143)
		(layer "In7.Cu")
		(net "FM_CPLD_NODE1_P5V_EN")
	)
	(segment
		(start 79.515208 -158.876238)
		(end 78.8035 -159.587946)
		(width 0.1143)
		(layer "In7.Cu")
		(net "FM_CPLD_NODE1_P5V_EN")
	)
	(segment
		(start 158.9786 -117.289326)
		(end 160.517332 -117.289326)
		(width 0.1143)
		(layer "In7.Cu")
		(net "FM_CPLD_NODE1_P5V_EN")
	)
	(segment
		(start 91.148916 -159.487108)
		(end 91.027504 -159.365696)
		(width 0.1143)
		(layer "In7.Cu")
		(net "FM_CPLD_NODE1_P5V_EN")
	)
	(segment
		(start 70.592696 -163.681664)
		(end 67.27444 -163.681664)
		(width 0.1143)
		(layer "In7.Cu")
		(net "FM_CPLD_NODE1_P5V_EN")
	)
	(segment
		(start 111.761524 -159.803592)
		(end 103.384604 -159.803592)
		(width 0.1143)
		(layer "In7.Cu")
		(net "FM_CPLD_NODE1_P5V_EN")
	)
	(segment
		(start 67.27444 -163.681664)
		(end 65.600326 -165.355778)
		(width 0.1143)
		(layer "In7.Cu")
		(net "FM_CPLD_NODE1_P5V_EN")
	)
	(segment
		(start 91.027504 -159.365696)
		(end 80.659478 -159.365696)
		(width 0.1143)
		(layer "In7.Cu")
		(net "FM_CPLD_NODE1_P5V_EN")
	)
	(segment
		(start 98.836988 -160.185354)
		(end 98.138742 -159.487108)
		(width 0.1143)
		(layer "In7.Cu")
		(net "FM_CPLD_NODE1_P5V_EN")
	)
	(segment
		(start 117.532658 -159.709358)
		(end 116.636546 -160.60547)
		(width 0.1143)
		(layer "In7.Cu")
		(net "FM_CPLD_NODE1_P5V_EN")
	)
	(segment
		(start 160.925256 -116.881402)
		(end 161.963862 -116.881402)
		(width 0.1143)
		(layer "In7.Cu")
		(net "FM_CPLD_NODE1_P5V_EN")
	)
	(segment
		(start 80.17002 -158.876238)
		(end 79.515208 -158.876238)
		(width 0.1143)
		(layer "In7.Cu")
		(net "FM_CPLD_NODE1_P5V_EN")
	)
	(segment
		(start 61.955934 -165.355778)
		(end 61.033914 -164.433758)
		(width 0.1143)
		(layer "In7.Cu")
		(net "FM_CPLD_NODE1_P5V_EN")
	)
	(segment
		(start 128.4478 -157.0101)
		(end 124.32919 -157.0101)
		(width 0.1143)
		(layer "In7.Cu")
		(net "FM_CPLD_NODE1_P5V_EN")
	)
	(segment
		(start 102.83317 -160.185354)
		(end 98.836988 -160.185354)
		(width 0.1143)
		(layer "In7.Cu")
		(net "FM_CPLD_NODE1_P5V_EN")
	)
	(segment
		(start 70.83298 -163.44138)
		(end 70.592696 -163.681664)
		(width 0.1143)
		(layer "In7.Cu")
		(net "FM_CPLD_NODE1_P5V_EN")
	)
	(segment
		(start 116.636546 -160.60547)
		(end 112.563402 -160.60547)
		(width 0.1143)
		(layer "In7.Cu")
		(net "FM_CPLD_NODE1_P5V_EN")
	)
	(segment
		(start 61.033914 -164.433758)
		(end 60.302648 -164.433758)
		(width 0.1143)
		(layer "In7.Cu")
		(net "FM_CPLD_NODE1_P5V_EN")
	)
	(segment
		(start 164.186362 -114.658902)
		(end 168.853104 -114.658902)
		(width 0.1143)
		(layer "In7.Cu")
		(net "FM_CPLD_NODE1_P5V_EN")
	)
	(segment
		(start 59.55792 -161.97707)
		(end 59.563 -161.97199)
		(width 0.1143)
		(layer "In7.Cu")
		(net "FM_CPLD_NODE1_P5V_EN")
	)
	(segment
		(start 80.659478 -159.365696)
		(end 80.17002 -158.876238)
		(width 0.1143)
		(layer "In7.Cu")
		(net "FM_CPLD_NODE1_P5V_EN")
	)
	(segment
		(start 161.963862 -116.881402)
		(end 164.186362 -114.658902)
		(width 0.1143)
		(layer "In7.Cu")
		(net "FM_CPLD_NODE1_P5V_EN")
	)
	(segment
		(start 60.302648 -164.433758)
		(end 59.55792 -163.68903)
		(width 0.1143)
		(layer "In7.Cu")
		(net "FM_CPLD_NODE1_P5V_EN")
	)
	(segment
		(start 178.242468 -113.833148)
		(end 181.079648 -116.670328)
		(width 0.1143)
		(layer "In7.Cu")
		(net "FM_CPLD_NODE1_P5V_EN")
	)
	(segment
		(start 169.678858 -113.833148)
		(end 178.242468 -113.833148)
		(width 0.1143)
		(layer "In7.Cu")
		(net "FM_CPLD_NODE1_P5V_EN")
	)
	(segment
		(start 65.600326 -165.355778)
		(end 61.955934 -165.355778)
		(width 0.1143)
		(layer "In7.Cu")
		(net "FM_CPLD_NODE1_P5V_EN")
	)
	(segment
		(start 51.479704 -102.795832)
		(end 51.121818 -102.437946)
		(width 0.1016)
		(layer "F.Cu")
		(net "PU_EMC1428_NODE1_TRIP")
	)
	(segment
		(start 56.191912 -100.75926)
		(end 56.191912 -101.525578)
		(width 0.1016)
		(layer "F.Cu")
		(net "PU_EMC1428_NODE1_TRIP")
	)
	(segment
		(start 56.191912 -101.525578)
		(end 54.921658 -102.795832)
		(width 0.1016)
		(layer "F.Cu")
		(net "PU_EMC1428_NODE1_TRIP")
	)
	(segment
		(start 51.121818 -102.437946)
		(end 51.121818 -102.436676)
		(width 0.1016)
		(layer "F.Cu")
		(net "PU_EMC1428_NODE1_TRIP")
	)
	(segment
		(start 51.121818 -101.66477)
		(end 51.121818 -102.436676)
		(width 0.1016)
		(layer "F.Cu")
		(net "PU_EMC1428_NODE1_TRIP")
	)
	(segment
		(start 54.921658 -102.795832)
		(end 51.479704 -102.795832)
		(width 0.1016)
		(layer "F.Cu")
		(net "PU_EMC1428_NODE1_TRIP")
	)
	(via
		(at 51.121818 -102.436676)
		(size 0.508)
		(drill 0.254)
		(layers "F.Cu" "B.Cu")
		(net "PU_EMC1428_NODE1_TRIP")
	)
	(segment
		(start 52.27193 -82.04073)
		(end 52.832 -82.6008)
		(width 0.1016)
		(layer "F.Cu")
		(net "A_CPU_NODE1_SOC_THERMREFNPAD")
	)
	(segment
		(start 52.27193 -81.952846)
		(end 52.27193 -82.04073)
		(width 0.1016)
		(layer "F.Cu")
		(net "A_CPU_NODE1_SOC_THERMREFNPAD")
	)
	(via
		(at 52.832 -82.6008)
		(size 0.508)
		(drill 0.254)
		(layers "F.Cu" "B.Cu")
		(net "A_CPU_NODE1_SOC_THERMREFNPAD")
	)
	(segment
		(start 52.735226 -82.504026)
		(end 52.832 -82.6008)
		(width 0.1016)
		(layer "B.Cu")
		(net "A_CPU_NODE1_SOC_THERMREFNPAD")
	)
	(segment
		(start 51.69408 -82.504026)
		(end 52.735226 -82.504026)
		(width 0.1016)
		(layer "B.Cu")
		(net "A_CPU_NODE1_SOC_THERMREFNPAD")
	)
	(segment
		(start 51.69662 -81.4832)
		(end 51.69662 -82.501486)
		(width 0.1016)
		(layer "B.Cu")
		(net "A_CPU_NODE1_SOC_THERMREFNPAD")
	)
	(segment
		(start 51.69662 -82.501486)
		(end 51.69408 -82.504026)
		(width 0.1016)
		(layer "B.Cu")
		(net "A_CPU_NODE1_SOC_THERMREFNPAD")
	)
	(segment
		(start 60.55868 -163.505134)
		(end 60.55868 -163.105592)
		(width 0.1016)
		(layer "F.Cu")
		(net "FM_CPLD_NODE1_P5V_NODE1_EN_G")
	)
	(segment
		(start 60.775342 -162.88893)
		(end 60.55868 -163.105592)
		(width 0.1016)
		(layer "F.Cu")
		(net "FM_CPLD_NODE1_P5V_NODE1_EN_G")
	)
	(segment
		(start 61.163708 -164.110162)
		(end 60.55868 -163.505134)
		(width 0.1016)
		(layer "F.Cu")
		(net "FM_CPLD_NODE1_P5V_NODE1_EN_G")
	)
	(segment
		(start 61.419486 -162.88893)
		(end 60.775342 -162.88893)
		(width 0.1016)
		(layer "F.Cu")
		(net "FM_CPLD_NODE1_P5V_NODE1_EN_G")
	)
	(segment
		(start 61.38418 -164.110162)
		(end 61.163708 -164.110162)
		(width 0.1016)
		(layer "F.Cu")
		(net "FM_CPLD_NODE1_P5V_NODE1_EN_G")
	)
	(via
		(at 60.55868 -163.105592)
		(size 0.508)
		(drill 0.254)
		(layers "F.Cu" "B.Cu")
		(net "FM_CPLD_NODE1_P5V_NODE1_EN_G")
	)
	(segment
		(start 66.141854 -130.457194)
		(end 66.540888 -130.05816)
		(width 0.3048)
		(layer "F.Cu")
		(net "P1V26_BMC_NODE1")
	)
	(segment
		(start 70.142354 -132.059426)
		(end 70.54215 -132.459222)
		(width 0.3048)
		(layer "F.Cu")
		(net "P1V26_BMC_NODE1")
	)
	(segment
		(start 63.741808 -130.458972)
		(end 63.340996 -130.05816)
		(width 0.3048)
		(layer "F.Cu")
		(net "P1V26_BMC_NODE1")
	)
	(segment
		(start 66.939668 -139.259564)
		(end 66.540888 -139.658344)
		(width 0.3048)
		(layer "F.Cu")
		(net "P1V26_BMC_NODE1")
	)
	(segment
		(start 58.941716 -129.659126)
		(end 58.540904 -129.258314)
		(width 0.381)
		(layer "F.Cu")
		(net "P1V26_BMC_NODE1")
	)
	(segment
		(start 63.741808 -139.259564)
		(end 63.739522 -139.259564)
		(width 0.3048)
		(layer "F.Cu")
		(net "P1V26_BMC_NODE1")
	)
	(segment
		(start 61.341762 -133.659118)
		(end 60.94095 -133.258306)
		(width 0.3048)
		(layer "F.Cu")
		(net "P1V26_BMC_NODE1")
	)
	(segment
		(start 62.941708 -130.458972)
		(end 62.540896 -130.05816)
		(width 0.3048)
		(layer "F.Cu")
		(net "P1V26_BMC_NODE1")
	)
	(segment
		(start 66.9417 -130.457448)
		(end 67.340988 -130.05816)
		(width 0.3048)
		(layer "F.Cu")
		(net "P1V26_BMC_NODE1")
	)
	(segment
		(start 58.941716 -129.659634)
		(end 58.941716 -129.659126)
		(width 0.381)
		(layer "F.Cu")
		(net "P1V26_BMC_NODE1")
	)
	(segment
		(start 61.339476 -133.659626)
		(end 60.94095 -134.058152)
		(width 0.3048)
		(layer "F.Cu")
		(net "P1V26_BMC_NODE1")
	)
	(segment
		(start 66.142108 -139.259564)
		(end 66.540888 -139.658344)
		(width 0.3048)
		(layer "F.Cu")
		(net "P1V26_BMC_NODE1")
	)
	(segment
		(start 66.9417 -130.45948)
		(end 66.9417 -130.457448)
		(width 0.3048)
		(layer "F.Cu")
		(net "P1V26_BMC_NODE1")
	)
	(segment
		(start 66.942208 -139.259564)
		(end 66.9417 -139.259564)
		(width 0.3048)
		(layer "F.Cu")
		(net "P1V26_BMC_NODE1")
	)
	(segment
		(start 61.341762 -134.458964)
		(end 60.94095 -134.058152)
		(width 0.3048)
		(layer "F.Cu")
		(net "P1V26_BMC_NODE1")
	)
	(segment
		(start 66.141854 -139.259564)
		(end 66.142108 -139.259564)
		(width 0.3048)
		(layer "F.Cu")
		(net "P1V26_BMC_NODE1")
	)
	(segment
		(start 62.941708 -130.45948)
		(end 62.941708 -130.458972)
		(width 0.3048)
		(layer "F.Cu")
		(net "P1V26_BMC_NODE1")
	)
	(segment
		(start 66.942208 -139.259564)
		(end 67.340988 -139.658344)
		(width 0.3048)
		(layer "F.Cu")
		(net "P1V26_BMC_NODE1")
	)
	(segment
		(start 70.141846 -132.059426)
		(end 70.142354 -132.059426)
		(width 0.3048)
		(layer "F.Cu")
		(net "P1V26_BMC_NODE1")
	)
	(segment
		(start 63.741808 -130.45948)
		(end 63.741808 -130.458972)
		(width 0.3048)
		(layer "F.Cu")
		(net "P1V26_BMC_NODE1")
	)
	(segment
		(start 70.141846 -132.859526)
		(end 70.54215 -132.459222)
		(width 0.3048)
		(layer "F.Cu")
		(net "P1V26_BMC_NODE1")
	)
	(segment
		(start 66.141854 -130.45948)
		(end 66.141854 -130.457194)
		(width 0.3048)
		(layer "F.Cu")
		(net "P1V26_BMC_NODE1")
	)
	(segment
		(start 61.341762 -133.659626)
		(end 61.341762 -133.659118)
		(width 0.3048)
		(layer "F.Cu")
		(net "P1V26_BMC_NODE1")
	)
	(segment
		(start 61.341762 -134.459472)
		(end 61.341762 -134.458964)
		(width 0.3048)
		(layer "F.Cu")
		(net "P1V26_BMC_NODE1")
	)
	(segment
		(start 63.739522 -139.259564)
		(end 63.340996 -139.65809)
		(width 0.3048)
		(layer "F.Cu")
		(net "P1V26_BMC_NODE1")
	)
	(segment
		(start 66.9417 -139.259564)
		(end 66.939668 -139.259564)
		(width 0.3048)
		(layer "F.Cu")
		(net "P1V26_BMC_NODE1")
	)
	(segment
		(start 61.341762 -133.659626)
		(end 61.339476 -133.659626)
		(width 0.3048)
		(layer "F.Cu")
		(net "P1V26_BMC_NODE1")
	)
	(segment
		(start 62.94247 -139.259564)
		(end 63.340996 -139.65809)
		(width 0.3048)
		(layer "F.Cu")
		(net "P1V26_BMC_NODE1")
	)
	(segment
		(start 62.941708 -139.259564)
		(end 62.94247 -139.259564)
		(width 0.3048)
		(layer "F.Cu")
		(net "P1V26_BMC_NODE1")
	)
	(via
		(at 58.540904 -129.258314)
		(size 0.49022)
		(drill 0.254)
		(layers "F.Cu" "B.Cu")
		(net "P1V26_BMC_NODE1")
	)
	(via
		(at 62.540896 -130.05816)
		(size 0.49022)
		(drill 0.254)
		(layers "F.Cu" "B.Cu")
		(net "P1V26_BMC_NODE1")
	)
	(via
		(at 67.340988 -139.658344)
		(size 0.49022)
		(drill 0.254)
		(layers "F.Cu" "B.Cu")
		(net "P1V26_BMC_NODE1")
	)
	(via
		(at 83.462368 -137.451084)
		(size 0.508)
		(drill 0.254)
		(layers "F.Cu" "B.Cu")
		(net "P1V26_BMC_NODE1")
	)
	(via
		(at 66.540888 -139.658344)
		(size 0.49022)
		(drill 0.254)
		(layers "F.Cu" "B.Cu")
		(net "P1V26_BMC_NODE1")
	)
	(via
		(at 83.401408 -138.534648)
		(size 0.508)
		(drill 0.254)
		(layers "F.Cu" "B.Cu")
		(net "P1V26_BMC_NODE1")
	)
	(via
		(at 82.699352 -137.527538)
		(size 0.508)
		(drill 0.254)
		(layers "F.Cu" "B.Cu")
		(net "P1V26_BMC_NODE1")
	)
	(via
		(at 66.540888 -130.05816)
		(size 0.49022)
		(drill 0.254)
		(layers "F.Cu" "B.Cu")
		(net "P1V26_BMC_NODE1")
	)
	(via
		(at 80.944212 -137.405364)
		(size 0.508)
		(drill 0.254)
		(layers "F.Cu" "B.Cu")
		(net "P1V26_BMC_NODE1")
	)
	(via
		(at 81.744312 -137.587228)
		(size 0.508)
		(drill 0.254)
		(layers "F.Cu" "B.Cu")
		(net "P1V26_BMC_NODE1")
	)
	(via
		(at 50.916586 -123.762262)
		(size 0.508)
		(drill 0.254)
		(layers "F.Cu" "B.Cu")
		(net "P1V26_BMC_NODE1")
	)
	(via
		(at 63.340996 -139.65809)
		(size 0.49022)
		(drill 0.254)
		(layers "F.Cu" "B.Cu")
		(net "P1V26_BMC_NODE1")
	)
	(via
		(at 60.94095 -134.058152)
		(size 0.49022)
		(drill 0.254)
		(layers "F.Cu" "B.Cu")
		(net "P1V26_BMC_NODE1")
	)
	(via
		(at 63.340996 -130.05816)
		(size 0.49022)
		(drill 0.254)
		(layers "F.Cu" "B.Cu")
		(net "P1V26_BMC_NODE1")
	)
	(via
		(at 67.340988 -130.05816)
		(size 0.49022)
		(drill 0.254)
		(layers "F.Cu" "B.Cu")
		(net "P1V26_BMC_NODE1")
	)
	(via
		(at 50.197512 -124.420122)
		(size 0.6604)
		(drill 0.3302)
		(layers "F.Cu" "B.Cu")
		(net "P1V26_BMC_NODE1")
	)
	(via
		(at 70.54215 -132.459222)
		(size 0.49022)
		(drill 0.254)
		(layers "F.Cu" "B.Cu")
		(net "P1V26_BMC_NODE1")
	)
	(via
		(at 60.94095 -133.258306)
		(size 0.49022)
		(drill 0.254)
		(layers "F.Cu" "B.Cu")
		(net "P1V26_BMC_NODE1")
	)
	(via
		(at 82.531458 -138.687302)
		(size 0.508)
		(drill 0.254)
		(layers "F.Cu" "B.Cu")
		(net "P1V26_BMC_NODE1")
	)
	(segment
		(start 57.990994 -129.830322)
		(end 58.313066 -129.50825)
		(width 0.3556)
		(layer "B.Cu")
		(net "P1V26_BMC_NODE1")
	)
	(segment
		(start 58.434732 -129.50825)
		(end 58.540904 -129.402078)
		(width 0.3556)
		(layer "B.Cu")
		(net "P1V26_BMC_NODE1")
	)
	(segment
		(start 57.990994 -129.853182)
		(end 57.990994 -129.830322)
		(width 0.3556)
		(layer "B.Cu")
		(net "P1V26_BMC_NODE1")
	)
	(segment
		(start 58.540904 -129.402078)
		(end 58.540904 -129.258314)
		(width 0.3556)
		(layer "B.Cu")
		(net "P1V26_BMC_NODE1")
	)
	(segment
		(start 58.313066 -129.50825)
		(end 58.434732 -129.50825)
		(width 0.3556)
		(layer "B.Cu")
		(net "P1V26_BMC_NODE1")
	)
	(segment
		(start 57.830466 -130.01371)
		(end 57.990994 -129.853182)
		(width 0.3556)
		(layer "B.Cu")
		(net "P1V26_BMC_NODE1")
	)
	(segment
		(start 60.813696 -75.799442)
		(end 61.201046 -75.412092)
		(width 0.254)
		(layer "F.Cu")
		(net "A_CPU1_NODE1_THERMDA")
	)
	(segment
		(start 51.906932 -100.22967)
		(end 52.924964 -100.22967)
		(width 0.254)
		(layer "F.Cu")
		(net "A_CPU1_NODE1_THERMDA")
	)
	(segment
		(start 52.924964 -100.22967)
		(end 53.1622 -100.466906)
		(width 0.254)
		(layer "F.Cu")
		(net "A_CPU1_NODE1_THERMDA")
	)
	(segment
		(start 61.201046 -75.412092)
		(end 61.201046 -75.399392)
		(width 0.254)
		(layer "F.Cu")
		(net "A_CPU1_NODE1_THERMDA")
	)
	(segment
		(start 53.1622 -100.466906)
		(end 53.7718 -100.466906)
		(width 0.254)
		(layer "F.Cu")
		(net "A_CPU1_NODE1_THERMDA")
	)
	(segment
		(start 53.7718 -100.466906)
		(end 54.459124 -100.466906)
		(width 0.254)
		(layer "F.Cu")
		(net "A_CPU1_NODE1_THERMDA")
	)
	(segment
		(start 60.800996 -75.799442)
		(end 60.813696 -75.799442)
		(width 0.254)
		(layer "F.Cu")
		(net "A_CPU1_NODE1_THERMDA")
	)
	(via
		(at 61.201046 -75.399392)
		(size 0.508)
		(drill 0.254)
		(layers "F.Cu" "B.Cu")
		(net "A_CPU1_NODE1_THERMDA")
	)
	(via
		(at 54.459124 -100.466906)
		(size 0.508)
		(drill 0.254)
		(layers "F.Cu" "B.Cu")
		(net "A_CPU1_NODE1_THERMDA")
	)
	(segment
		(start 55.266844 -92.436442)
		(end 55.266844 -89.655396)
		(width 0.254)
		(layer "In2.Cu")
		(net "A_CPU1_NODE1_THERMDA")
	)
	(segment
		(start 59.986418 -75.702668)
		(end 60.89777 -75.702668)
		(width 0.254)
		(layer "In2.Cu")
		(net "A_CPU1_NODE1_THERMDA")
	)
	(segment
		(start 54.459124 -100.466906)
		(end 53.256688 -99.26447)
		(width 0.254)
		(layer "In2.Cu")
		(net "A_CPU1_NODE1_THERMDA")
	)
	(segment
		(start 57.76595 -80.37957)
		(end 58.310018 -79.835502)
		(width 0.254)
		(layer "In2.Cu")
		(net "A_CPU1_NODE1_THERMDA")
	)
	(segment
		(start 57.76595 -87.15629)
		(end 57.76595 -80.37957)
		(width 0.254)
		(layer "In2.Cu")
		(net "A_CPU1_NODE1_THERMDA")
	)
	(segment
		(start 53.256688 -99.26447)
		(end 53.256688 -94.446598)
		(width 0.254)
		(layer "In2.Cu")
		(net "A_CPU1_NODE1_THERMDA")
	)
	(segment
		(start 58.310018 -77.379068)
		(end 59.986418 -75.702668)
		(width 0.254)
		(layer "In2.Cu")
		(net "A_CPU1_NODE1_THERMDA")
	)
	(segment
		(start 55.266844 -89.655396)
		(end 57.76595 -87.15629)
		(width 0.254)
		(layer "In2.Cu")
		(net "A_CPU1_NODE1_THERMDA")
	)
	(segment
		(start 58.310018 -79.835502)
		(end 58.310018 -77.379068)
		(width 0.254)
		(layer "In2.Cu")
		(net "A_CPU1_NODE1_THERMDA")
	)
	(segment
		(start 60.89777 -75.702668)
		(end 61.201046 -75.399392)
		(width 0.254)
		(layer "In2.Cu")
		(net "A_CPU1_NODE1_THERMDA")
	)
	(segment
		(start 53.256688 -94.446598)
		(end 55.266844 -92.436442)
		(width 0.254)
		(layer "In2.Cu")
		(net "A_CPU1_NODE1_THERMDA")
	)
	(via
		(at 61.898022 -160.592516)
		(size 0.508)
		(drill 0.254)
		(layers "F.Cu" "B.Cu")
		(net "FM_CPLD_NODE1_P5V_EN_LV")
	)
	(segment
		(start 84.350352 -135.659622)
		(end 84.175092 -135.484362)
		(width 0.254)
		(layer "F.Cu")
		(net "P1V26_STB_NODE1_ADJ_S")
	)
	(segment
		(start 84.350352 -136.633712)
		(end 84.350352 -135.659622)
		(width 0.254)
		(layer "F.Cu")
		(net "P1V26_STB_NODE1_ADJ_S")
	)
	(segment
		(start 83.425792 -135.712962)
		(end 83.654392 -135.484362)
		(width 0.254)
		(layer "F.Cu")
		(net "P1V26_STB_NODE1_ADJ_S")
	)
	(segment
		(start 84.175092 -135.484362)
		(end 83.654392 -135.484362)
		(width 0.254)
		(layer "F.Cu")
		(net "P1V26_STB_NODE1_ADJ_S")
	)
	(segment
		(start 83.425792 -136.337294)
		(end 83.425792 -135.712962)
		(width 0.254)
		(layer "F.Cu")
		(net "P1V26_STB_NODE1_ADJ_S")
	)
	(via
		(at 83.654392 -135.484362)
		(size 0.508)
		(drill 0.254)
		(layers "F.Cu" "B.Cu")
		(net "P1V26_STB_NODE1_ADJ_S")
	)
	(segment
		(start 46.588426 -100.919026)
		(end 46.588426 -100.917756)
		(width 0.3048)
		(layer "F.Cu")
		(net "A_SOC_NODE1_THERMDC")
	)
	(segment
		(start 45.83176 -101.103938)
		(end 46.016672 -100.919026)
		(width 0.3048)
		(layer "F.Cu")
		(net "A_SOC_NODE1_THERMDC")
	)
	(segment
		(start 45.83176 -101.106224)
		(end 45.83176 -101.103938)
		(width 0.3048)
		(layer "F.Cu")
		(net "A_SOC_NODE1_THERMDC")
	)
	(segment
		(start 51.571906 -82.714846)
		(end 51.200812 -82.343752)
		(width 0.254)
		(layer "F.Cu")
		(net "A_SOC_NODE1_THERMDC")
	)
	(segment
		(start 46.016672 -100.919026)
		(end 46.588426 -100.919026)
		(width 0.3048)
		(layer "F.Cu")
		(net "A_SOC_NODE1_THERMDC")
	)
	(segment
		(start 47.385224 -100.879656)
		(end 48.387 -100.879656)
		(width 0.3048)
		(layer "F.Cu")
		(net "A_SOC_NODE1_THERMDC")
	)
	(segment
		(start 47.347124 -100.917756)
		(end 47.385224 -100.879656)
		(width 0.3048)
		(layer "F.Cu")
		(net "A_SOC_NODE1_THERMDC")
	)
	(segment
		(start 51.01336 -82.343752)
		(end 50.945288 -82.27568)
		(width 0.254)
		(layer "F.Cu")
		(net "A_SOC_NODE1_THERMDC")
	)
	(segment
		(start 51.200812 -82.343752)
		(end 51.01336 -82.343752)
		(width 0.254)
		(layer "F.Cu")
		(net "A_SOC_NODE1_THERMDC")
	)
	(segment
		(start 46.588426 -100.917756)
		(end 47.347124 -100.917756)
		(width 0.3048)
		(layer "F.Cu")
		(net "A_SOC_NODE1_THERMDC")
	)
	(via
		(at 50.945288 -82.27568)
		(size 0.508)
		(drill 0.254)
		(layers "F.Cu" "B.Cu")
		(net "A_SOC_NODE1_THERMDC")
	)
	(via
		(at 45.83176 -101.106224)
		(size 0.508)
		(drill 0.254)
		(layers "F.Cu" "B.Cu")
		(net "A_SOC_NODE1_THERMDC")
	)
	(segment
		(start 46.252384 -100.684838)
		(end 45.83176 -101.105462)
		(width 0.254)
		(layer "In2.Cu")
		(net "A_SOC_NODE1_THERMDC")
	)
	(segment
		(start 49.609502 -88.763856)
		(end 49.840134 -88.994488)
		(width 0.254)
		(layer "In2.Cu")
		(net "A_SOC_NODE1_THERMDC")
	)
	(segment
		(start 46.925738 -100.684838)
		(end 46.252384 -100.684838)
		(width 0.254)
		(layer "In2.Cu")
		(net "A_SOC_NODE1_THERMDC")
	)
	(segment
		(start 50.728118 -82.27568)
		(end 49.907444 -83.096354)
		(width 0.254)
		(layer "In2.Cu")
		(net "A_SOC_NODE1_THERMDC")
	)
	(segment
		(start 49.609502 -87.104982)
		(end 49.609502 -88.763856)
		(width 0.254)
		(layer "In2.Cu")
		(net "A_SOC_NODE1_THERMDC")
	)
	(segment
		(start 49.840134 -91.231212)
		(end 48.132238 -92.939108)
		(width 0.254)
		(layer "In2.Cu")
		(net "A_SOC_NODE1_THERMDC")
	)
	(segment
		(start 48.132238 -92.939108)
		(end 48.132238 -99.478338)
		(width 0.254)
		(layer "In2.Cu")
		(net "A_SOC_NODE1_THERMDC")
	)
	(segment
		(start 49.840134 -88.994488)
		(end 49.840134 -91.231212)
		(width 0.254)
		(layer "In2.Cu")
		(net "A_SOC_NODE1_THERMDC")
	)
	(segment
		(start 49.907444 -83.096354)
		(end 49.907444 -86.80704)
		(width 0.254)
		(layer "In2.Cu")
		(net "A_SOC_NODE1_THERMDC")
	)
	(segment
		(start 45.83176 -101.105462)
		(end 45.83176 -101.106224)
		(width 0.254)
		(layer "In2.Cu")
		(net "A_SOC_NODE1_THERMDC")
	)
	(segment
		(start 50.945288 -82.27568)
		(end 50.728118 -82.27568)
		(width 0.254)
		(layer "In2.Cu")
		(net "A_SOC_NODE1_THERMDC")
	)
	(segment
		(start 49.907444 -86.80704)
		(end 49.609502 -87.104982)
		(width 0.254)
		(layer "In2.Cu")
		(net "A_SOC_NODE1_THERMDC")
	)
	(segment
		(start 48.132238 -99.478338)
		(end 46.925738 -100.684838)
		(width 0.254)
		(layer "In2.Cu")
		(net "A_SOC_NODE1_THERMDC")
	)
	(segment
		(start 46.940216 -79.302102)
		(end 46.546516 -78.908402)
		(width 0.1016)
		(layer "F.Cu")
		(net "SMB_CPU_NODE1_MEM_ICS_CLK_R")
	)
	(segment
		(start 46.942248 -79.302102)
		(end 46.940216 -79.302102)
		(width 0.1016)
		(layer "F.Cu")
		(net "SMB_CPU_NODE1_MEM_ICS_CLK_R")
	)
	(via
		(at 46.546516 -78.908402)
		(size 0.508)
		(drill 0.254)
		(layers "F.Cu" "B.Cu")
		(net "SMB_CPU_NODE1_MEM_ICS_CLK_R")
	)
	(segment
		(start 43.09237 -87.701374)
		(end 43.09237 -81.689956)
		(width 0.1016)
		(layer "B.Cu")
		(net "SMB_CPU_NODE1_MEM_ICS_CLK_R")
	)
	(segment
		(start 45.235622 -79.546704)
		(end 45.908214 -79.546704)
		(width 0.1016)
		(layer "B.Cu")
		(net "SMB_CPU_NODE1_MEM_ICS_CLK_R")
	)
	(segment
		(start 36.590732 -94.00032)
		(end 36.590732 -93.347032)
		(width 0.1016)
		(layer "B.Cu")
		(net "SMB_CPU_NODE1_MEM_ICS_CLK_R")
	)
	(segment
		(start 39.371524 -91.42222)
		(end 43.09237 -87.701374)
		(width 0.1016)
		(layer "B.Cu")
		(net "SMB_CPU_NODE1_MEM_ICS_CLK_R")
	)
	(segment
		(start 43.09237 -81.689956)
		(end 45.235622 -79.546704)
		(width 0.1016)
		(layer "B.Cu")
		(net "SMB_CPU_NODE1_MEM_ICS_CLK_R")
	)
	(segment
		(start 45.908214 -79.546704)
		(end 46.546516 -78.908402)
		(width 0.1016)
		(layer "B.Cu")
		(net "SMB_CPU_NODE1_MEM_ICS_CLK_R")
	)
	(segment
		(start 36.590732 -93.347032)
		(end 38.515544 -91.42222)
		(width 0.1016)
		(layer "B.Cu")
		(net "SMB_CPU_NODE1_MEM_ICS_CLK_R")
	)
	(segment
		(start 37.606732 -94.00032)
		(end 36.590732 -94.00032)
		(width 0.1016)
		(layer "B.Cu")
		(net "SMB_CPU_NODE1_MEM_ICS_CLK_R")
	)
	(segment
		(start 38.515544 -91.42222)
		(end 39.371524 -91.42222)
		(width 0.1016)
		(layer "B.Cu")
		(net "SMB_CPU_NODE1_MEM_ICS_CLK_R")
	)
	(segment
		(start 45.82922 -99.814126)
		(end 45.82922 -99.815396)
		(width 0.3048)
		(layer "F.Cu")
		(net "A_SOC_NODE1_THERMDA")
	)
	(segment
		(start 47.409862 -100.117656)
		(end 46.588426 -100.117656)
		(width 0.3048)
		(layer "F.Cu")
		(net "A_SOC_NODE1_THERMDA")
	)
	(segment
		(start 51.325526 -81.706466)
		(end 50.912776 -81.706466)
		(width 0.254)
		(layer "F.Cu")
		(net "A_SOC_NODE1_THERMDA")
	)
	(segment
		(start 46.04004 -100.026216)
		(end 46.496986 -100.026216)
		(width 0.3048)
		(layer "F.Cu")
		(net "A_SOC_NODE1_THERMDA")
	)
	(segment
		(start 48.387 -100.22967)
		(end 47.521876 -100.22967)
		(width 0.3048)
		(layer "F.Cu")
		(net "A_SOC_NODE1_THERMDA")
	)
	(segment
		(start 50.912776 -81.706466)
		(end 50.853594 -81.647284)
		(width 0.254)
		(layer "F.Cu")
		(net "A_SOC_NODE1_THERMDA")
	)
	(segment
		(start 45.82922 -99.815396)
		(end 46.04004 -100.026216)
		(width 0.3048)
		(layer "F.Cu")
		(net "A_SOC_NODE1_THERMDA")
	)
	(segment
		(start 47.521876 -100.22967)
		(end 47.409862 -100.117656)
		(width 0.3048)
		(layer "F.Cu")
		(net "A_SOC_NODE1_THERMDA")
	)
	(segment
		(start 46.496986 -100.026216)
		(end 46.588426 -100.117656)
		(width 0.3048)
		(layer "F.Cu")
		(net "A_SOC_NODE1_THERMDA")
	)
	(segment
		(start 51.571906 -81.952846)
		(end 51.325526 -81.706466)
		(width 0.254)
		(layer "F.Cu")
		(net "A_SOC_NODE1_THERMDA")
	)
	(via
		(at 50.853594 -81.647284)
		(size 0.508)
		(drill 0.254)
		(layers "F.Cu" "B.Cu")
		(net "A_SOC_NODE1_THERMDA")
	)
	(via
		(at 45.82922 -99.814126)
		(size 0.508)
		(drill 0.254)
		(layers "F.Cu" "B.Cu")
		(net "A_SOC_NODE1_THERMDA")
	)
	(segment
		(start 45.82922 -99.835716)
		(end 46.226476 -100.232972)
		(width 0.254)
		(layer "In2.Cu")
		(net "A_SOC_NODE1_THERMDA")
	)
	(segment
		(start 49.551844 -82.949034)
		(end 50.853594 -81.647284)
		(width 0.254)
		(layer "In2.Cu")
		(net "A_SOC_NODE1_THERMDA")
	)
	(segment
		(start 45.82922 -99.814126)
		(end 45.82922 -99.835716)
		(width 0.254)
		(layer "In2.Cu")
		(net "A_SOC_NODE1_THERMDA")
	)
	(segment
		(start 47.725838 -92.770706)
		(end 49.433734 -91.06281)
		(width 0.254)
		(layer "In2.Cu")
		(net "A_SOC_NODE1_THERMDA")
	)
	(segment
		(start 49.433734 -89.091008)
		(end 49.253902 -88.911176)
		(width 0.254)
		(layer "In2.Cu")
		(net "A_SOC_NODE1_THERMDA")
	)
	(segment
		(start 46.742858 -100.232972)
		(end 47.725838 -99.249992)
		(width 0.254)
		(layer "In2.Cu")
		(net "A_SOC_NODE1_THERMDA")
	)
	(segment
		(start 49.253902 -86.957662)
		(end 49.551844 -86.65972)
		(width 0.254)
		(layer "In2.Cu")
		(net "A_SOC_NODE1_THERMDA")
	)
	(segment
		(start 46.226476 -100.232972)
		(end 46.742858 -100.232972)
		(width 0.254)
		(layer "In2.Cu")
		(net "A_SOC_NODE1_THERMDA")
	)
	(segment
		(start 49.551844 -86.65972)
		(end 49.551844 -82.949034)
		(width 0.254)
		(layer "In2.Cu")
		(net "A_SOC_NODE1_THERMDA")
	)
	(segment
		(start 49.253902 -88.911176)
		(end 49.253902 -86.957662)
		(width 0.254)
		(layer "In2.Cu")
		(net "A_SOC_NODE1_THERMDA")
	)
	(segment
		(start 49.433734 -91.06281)
		(end 49.433734 -89.091008)
		(width 0.254)
		(layer "In2.Cu")
		(net "A_SOC_NODE1_THERMDA")
	)
	(segment
		(start 47.725838 -99.249992)
		(end 47.725838 -92.770706)
		(width 0.254)
		(layer "In2.Cu")
		(net "A_SOC_NODE1_THERMDA")
	)
	(segment
		(start 30.15742 -131.833874)
		(end 30.149038 -131.842256)
		(width 0.254)
		(layer "F.Cu")
		(net "P1V538_BMC_NODE1_ADJ")
	)
	(segment
		(start 30.15742 -130.538474)
		(end 30.18282 -130.513074)
		(width 0.254)
		(layer "F.Cu")
		(net "P1V538_BMC_NODE1_ADJ")
	)
	(segment
		(start 30.18282 -129.925318)
		(end 30.003496 -129.745994)
		(width 0.254)
		(layer "F.Cu")
		(net "P1V538_BMC_NODE1_ADJ")
	)
	(segment
		(start 30.141164 -128.354582)
		(end 30.141164 -129.608326)
		(width 0.2032)
		(layer "F.Cu")
		(net "P1V538_BMC_NODE1_ADJ")
	)
	(segment
		(start 30.18282 -130.513074)
		(end 30.18282 -129.925318)
		(width 0.254)
		(layer "F.Cu")
		(net "P1V538_BMC_NODE1_ADJ")
	)
	(segment
		(start 30.15742 -131.833874)
		(end 30.15742 -130.538474)
		(width 0.254)
		(layer "F.Cu")
		(net "P1V538_BMC_NODE1_ADJ")
	)
	(segment
		(start 30.149038 -131.842256)
		(end 30.149038 -132.850382)
		(width 0.254)
		(layer "F.Cu")
		(net "P1V538_BMC_NODE1_ADJ")
	)
	(segment
		(start 30.141164 -129.608326)
		(end 30.003496 -129.745994)
		(width 0.2032)
		(layer "F.Cu")
		(net "P1V538_BMC_NODE1_ADJ")
	)
	(via
		(at 30.003496 -129.745994)
		(size 0.508)
		(drill 0.254)
		(layers "F.Cu" "B.Cu")
		(net "P1V538_BMC_NODE1_ADJ")
	)
	(segment
		(start 49.821846 -96.865948)
		(end 48.940974 -95.985076)
		(width 0.1016)
		(layer "F.Cu")
		(net "TP_TEMP1_NODE1_2")
	)
	(segment
		(start 48.940974 -95.985076)
		(end 48.940974 -95.898716)
		(width 0.1016)
		(layer "F.Cu")
		(net "TP_TEMP1_NODE1_2")
	)
	(segment
		(start 49.821846 -98.144584)
		(end 49.821846 -96.865948)
		(width 0.1016)
		(layer "F.Cu")
		(net "TP_TEMP1_NODE1_2")
	)
	(via
		(at 48.940974 -95.898716)
		(size 0.508)
		(drill 0.254)
		(layers "F.Cu" "B.Cu")
		(net "TP_TEMP1_NODE1_2")
	)
	(segment
		(start 31.566358 -133.018022)
		(end 31.566866 -133.017514)
		(width 0.254)
		(layer "F.Cu")
		(net "P1V538_STB_NODE1_ADJ_S")
	)
	(segment
		(start 30.949138 -132.850382)
		(end 30.955488 -132.844032)
		(width 0.254)
		(layer "F.Cu")
		(net "P1V538_STB_NODE1_ADJ_S")
	)
	(segment
		(start 30.955488 -132.844032)
		(end 31.392368 -132.844032)
		(width 0.254)
		(layer "F.Cu")
		(net "P1V538_STB_NODE1_ADJ_S")
	)
	(segment
		(start 31.76905 -132.81533)
		(end 31.566866 -133.017514)
		(width 0.254)
		(layer "F.Cu")
		(net "P1V538_STB_NODE1_ADJ_S")
	)
	(segment
		(start 32.359346 -132.81533)
		(end 31.76905 -132.81533)
		(width 0.254)
		(layer "F.Cu")
		(net "P1V538_STB_NODE1_ADJ_S")
	)
	(segment
		(start 30.95752 -131.833874)
		(end 30.949138 -131.842256)
		(width 0.254)
		(layer "F.Cu")
		(net "P1V538_STB_NODE1_ADJ_S")
	)
	(segment
		(start 31.392368 -132.844032)
		(end 31.566358 -133.018022)
		(width 0.254)
		(layer "F.Cu")
		(net "P1V538_STB_NODE1_ADJ_S")
	)
	(segment
		(start 30.949138 -131.842256)
		(end 30.949138 -132.850382)
		(width 0.254)
		(layer "F.Cu")
		(net "P1V538_STB_NODE1_ADJ_S")
	)
	(via
		(at 31.566866 -133.017514)
		(size 0.508)
		(drill 0.254)
		(layers "F.Cu" "B.Cu")
		(net "P1V538_STB_NODE1_ADJ_S")
	)
	(segment
		(start 47.704248 -79.302102)
		(end 47.702216 -79.302102)
		(width 0.1016)
		(layer "F.Cu")
		(net "SMB_CPU_NODE1_BMC_CLK_RR")
	)
	(segment
		(start 47.702216 -79.302102)
		(end 47.308516 -78.908402)
		(width 0.1016)
		(layer "F.Cu")
		(net "SMB_CPU_NODE1_BMC_CLK_RR")
	)
	(via
		(at 40.28567 -92.59951)
		(size 0.6604)
		(drill 0.3302)
		(layers "F.Cu" "B.Cu")
		(net "SMB_CPU_NODE1_BMC_CLK_RR")
	)
	(via
		(at 47.308516 -78.908402)
		(size 0.508)
		(drill 0.254)
		(layers "F.Cu" "B.Cu")
		(net "SMB_CPU_NODE1_BMC_CLK_RR")
	)
	(segment
		(start 43.568874 -89.316306)
		(end 43.568874 -83.329018)
		(width 0.1016)
		(layer "B.Cu")
		(net "SMB_CPU_NODE1_BMC_CLK_RR")
	)
	(segment
		(start 38.622732 -94.00032)
		(end 38.622732 -93.359732)
		(width 0.1016)
		(layer "B.Cu")
		(net "SMB_CPU_NODE1_BMC_CLK_RR")
	)
	(segment
		(start 45.400468 -80.056736)
		(end 45.62602 -79.831184)
		(width 0.1016)
		(layer "B.Cu")
		(net "SMB_CPU_NODE1_BMC_CLK_RR")
	)
	(segment
		(start 39.638732 -94.00032)
		(end 38.622732 -94.00032)
		(width 0.1016)
		(layer "B.Cu")
		(net "SMB_CPU_NODE1_BMC_CLK_RR")
	)
	(segment
		(start 38.622732 -93.359732)
		(end 39.382954 -92.59951)
		(width 0.1016)
		(layer "B.Cu")
		(net "SMB_CPU_NODE1_BMC_CLK_RR")
	)
	(segment
		(start 43.568874 -83.329018)
		(end 45.400468 -81.497424)
		(width 0.1016)
		(layer "B.Cu")
		(net "SMB_CPU_NODE1_BMC_CLK_RR")
	)
	(segment
		(start 47.308516 -79.062326)
		(end 47.308516 -78.908402)
		(width 0.1016)
		(layer "B.Cu")
		(net "SMB_CPU_NODE1_BMC_CLK_RR")
	)
	(segment
		(start 45.62602 -79.831184)
		(end 46.539658 -79.831184)
		(width 0.1016)
		(layer "B.Cu")
		(net "SMB_CPU_NODE1_BMC_CLK_RR")
	)
	(segment
		(start 40.28567 -92.59951)
		(end 43.568874 -89.316306)
		(width 0.1016)
		(layer "B.Cu")
		(net "SMB_CPU_NODE1_BMC_CLK_RR")
	)
	(segment
		(start 46.539658 -79.831184)
		(end 47.308516 -79.062326)
		(width 0.1016)
		(layer "B.Cu")
		(net "SMB_CPU_NODE1_BMC_CLK_RR")
	)
	(segment
		(start 45.400468 -81.497424)
		(end 45.400468 -80.056736)
		(width 0.1016)
		(layer "B.Cu")
		(net "SMB_CPU_NODE1_BMC_CLK_RR")
	)
	(segment
		(start 39.382954 -92.59951)
		(end 40.28567 -92.59951)
		(width 0.1016)
		(layer "B.Cu")
		(net "SMB_CPU_NODE1_BMC_CLK_RR")
	)
	(segment
		(start 60.000896 -78.199742)
		(end 60.400946 -77.799692)
		(width 0.254)
		(layer "F.Cu")
		(net "A_CPU0_NODE1_THERMDC")
	)
	(segment
		(start 52.73421 -99.505262)
		(end 53.76164 -99.505262)
		(width 0.254)
		(layer "F.Cu")
		(net "A_CPU0_NODE1_THERMDC")
	)
	(segment
		(start 55.39486 -99.286314)
		(end 55.175912 -99.505262)
		(width 0.254)
		(layer "F.Cu")
		(net "A_CPU0_NODE1_THERMDC")
	)
	(segment
		(start 51.906932 -99.579684)
		(end 52.385976 -99.579684)
		(width 0.254)
		(layer "F.Cu")
		(net "A_CPU0_NODE1_THERMDC")
	)
	(segment
		(start 52.385976 -99.579684)
		(end 52.73421 -99.505262)
		(width 0.254)
		(layer "F.Cu")
		(net "A_CPU0_NODE1_THERMDC")
	)
	(segment
		(start 55.175912 -99.505262)
		(end 53.76164 -99.505262)
		(width 0.254)
		(layer "F.Cu")
		(net "A_CPU0_NODE1_THERMDC")
	)
	(via
		(at 60.400946 -77.799692)
		(size 0.508)
		(drill 0.254)
		(layers "F.Cu" "B.Cu")
		(net "A_CPU0_NODE1_THERMDC")
	)
	(via
		(at 55.39486 -99.286314)
		(size 0.508)
		(drill 0.254)
		(layers "F.Cu" "B.Cu")
		(net "A_CPU0_NODE1_THERMDC")
	)
	(segment
		(start 56.254904 -98.115882)
		(end 56.254904 -94.224094)
		(width 0.254)
		(layer "In2.Cu")
		(net "A_CPU0_NODE1_THERMDC")
	)
	(segment
		(start 55.39486 -99.286314)
		(end 55.578756 -99.102418)
		(width 0.254)
		(layer "In2.Cu")
		(net "A_CPU0_NODE1_THERMDC")
	)
	(segment
		(start 58.137806 -92.341192)
		(end 58.137806 -91.612466)
		(width 0.254)
		(layer "In2.Cu")
		(net "A_CPU0_NODE1_THERMDC")
	)
	(segment
		(start 60.883546 -79.097632)
		(end 60.400946 -78.615032)
		(width 0.254)
		(layer "In2.Cu")
		(net "A_CPU0_NODE1_THERMDC")
	)
	(segment
		(start 60.400946 -78.615032)
		(end 60.400946 -77.799692)
		(width 0.254)
		(layer "In2.Cu")
		(net "A_CPU0_NODE1_THERMDC")
	)
	(segment
		(start 60.10783 -85.574886)
		(end 60.10783 -81.65211)
		(width 0.254)
		(layer "In2.Cu")
		(net "A_CPU0_NODE1_THERMDC")
	)
	(segment
		(start 60.55995 -81.19999)
		(end 60.55995 -79.92364)
		(width 0.254)
		(layer "In2.Cu")
		(net "A_CPU0_NODE1_THERMDC")
	)
	(segment
		(start 55.578756 -99.102418)
		(end 55.578756 -98.79203)
		(width 0.254)
		(layer "In2.Cu")
		(net "A_CPU0_NODE1_THERMDC")
	)
	(segment
		(start 58.650886 -88.918542)
		(end 60.116974 -87.452454)
		(width 0.254)
		(layer "In2.Cu")
		(net "A_CPU0_NODE1_THERMDC")
	)
	(segment
		(start 55.578756 -98.79203)
		(end 56.254904 -98.115882)
		(width 0.254)
		(layer "In2.Cu")
		(net "A_CPU0_NODE1_THERMDC")
	)
	(segment
		(start 60.10783 -81.65211)
		(end 60.55995 -81.19999)
		(width 0.254)
		(layer "In2.Cu")
		(net "A_CPU0_NODE1_THERMDC")
	)
	(segment
		(start 60.116974 -85.58403)
		(end 60.10783 -85.574886)
		(width 0.254)
		(layer "In2.Cu")
		(net "A_CPU0_NODE1_THERMDC")
	)
	(segment
		(start 60.116974 -87.452454)
		(end 60.116974 -85.58403)
		(width 0.254)
		(layer "In2.Cu")
		(net "A_CPU0_NODE1_THERMDC")
	)
	(segment
		(start 58.650886 -91.099386)
		(end 58.650886 -88.918542)
		(width 0.254)
		(layer "In2.Cu")
		(net "A_CPU0_NODE1_THERMDC")
	)
	(segment
		(start 60.55995 -79.92364)
		(end 60.883546 -79.600044)
		(width 0.254)
		(layer "In2.Cu")
		(net "A_CPU0_NODE1_THERMDC")
	)
	(segment
		(start 56.254904 -94.224094)
		(end 58.137806 -92.341192)
		(width 0.254)
		(layer "In2.Cu")
		(net "A_CPU0_NODE1_THERMDC")
	)
	(segment
		(start 58.137806 -91.612466)
		(end 58.650886 -91.099386)
		(width 0.254)
		(layer "In2.Cu")
		(net "A_CPU0_NODE1_THERMDC")
	)
	(segment
		(start 60.883546 -79.600044)
		(end 60.883546 -79.097632)
		(width 0.254)
		(layer "In2.Cu")
		(net "A_CPU0_NODE1_THERMDC")
	)
	(segment
		(start 50.471832 -96.908366)
		(end 49.63668 -96.073214)
		(width 0.1016)
		(layer "F.Cu")
		(net "TP_TEMP1_NODE1_1")
	)
	(segment
		(start 49.63668 -96.073214)
		(end 49.63668 -94.591124)
		(width 0.1016)
		(layer "F.Cu")
		(net "TP_TEMP1_NODE1_1")
	)
	(segment
		(start 50.471832 -98.144584)
		(end 50.471832 -96.908366)
		(width 0.1016)
		(layer "F.Cu")
		(net "TP_TEMP1_NODE1_1")
	)
	(via
		(at 49.63668 -94.591124)
		(size 0.508)
		(drill 0.254)
		(layers "F.Cu" "B.Cu")
		(net "TP_TEMP1_NODE1_1")
	)
	(segment
		(start 64.93002 -78.255622)
		(end 64.995298 -78.255622)
		(width 0.254)
		(layer "F.Cu")
		(net "A_CPU_NODE1_LV_GPIO_RCOMP")
	)
	(segment
		(start 65.292478 -78.552802)
		(end 65.292478 -78.647544)
		(width 0.254)
		(layer "F.Cu")
		(net "A_CPU_NODE1_LV_GPIO_RCOMP")
	)
	(segment
		(start 64.995298 -78.255622)
		(end 65.292478 -78.552802)
		(width 0.254)
		(layer "F.Cu")
		(net "A_CPU_NODE1_LV_GPIO_RCOMP")
	)
	(via
		(at 65.292478 -78.647544)
		(size 0.508)
		(drill 0.254)
		(layers "F.Cu" "B.Cu")
		(net "A_CPU_NODE1_LV_GPIO_RCOMP")
	)
	(via
		(at 68.147946 -77.975968)
		(size 0.6604)
		(drill 0.3302)
		(layers "F.Cu" "B.Cu")
		(net "A_CPU_NODE1_LV_GPIO_RCOMP")
	)
	(segment
		(start 65.760854 -77.974698)
		(end 66.025522 -77.974698)
		(width 0.381)
		(layer "B.Cu")
		(net "A_CPU_NODE1_LV_GPIO_RCOMP")
	)
	(segment
		(start 67.710304 -77.975968)
		(end 68.147946 -77.975968)
		(width 0.1016)
		(layer "B.Cu")
		(net "A_CPU_NODE1_LV_GPIO_RCOMP")
	)
	(segment
		(start 65.292478 -78.647544)
		(end 65.292478 -78.443074)
		(width 0.381)
		(layer "B.Cu")
		(net "A_CPU_NODE1_LV_GPIO_RCOMP")
	)
	(segment
		(start 66.49085 -77.50937)
		(end 67.243706 -77.50937)
		(width 0.1016)
		(layer "B.Cu")
		(net "A_CPU_NODE1_LV_GPIO_RCOMP")
	)
	(segment
		(start 66.025522 -77.974698)
		(end 66.49085 -77.50937)
		(width 0.1016)
		(layer "B.Cu")
		(net "A_CPU_NODE1_LV_GPIO_RCOMP")
	)
	(segment
		(start 67.243706 -77.50937)
		(end 67.710304 -77.975968)
		(width 0.1016)
		(layer "B.Cu")
		(net "A_CPU_NODE1_LV_GPIO_RCOMP")
	)
	(segment
		(start 65.292478 -78.443074)
		(end 65.760854 -77.974698)
		(width 0.381)
		(layer "B.Cu")
		(net "A_CPU_NODE1_LV_GPIO_RCOMP")
	)
	(segment
		(start 72.915018 -102.198932)
		(end 72.260968 -102.852982)
		(width 0.1016)
		(layer "F.Cu")
		(net "FM_CPLD_NODE1_P1V8_SUS_EN")
	)
	(segment
		(start 169.426636 -116.828316)
		(end 172.473112 -116.828316)
		(width 0.1016)
		(layer "F.Cu")
		(net "FM_CPLD_NODE1_P1V8_SUS_EN")
	)
	(segment
		(start 165.95344 -113.35512)
		(end 169.426636 -116.828316)
		(width 0.1016)
		(layer "F.Cu")
		(net "FM_CPLD_NODE1_P1V8_SUS_EN")
	)
	(segment
		(start 68.265294 -102.41026)
		(end 69.751448 -102.41026)
		(width 0.1016)
		(layer "F.Cu")
		(net "FM_CPLD_NODE1_P1V8_SUS_EN")
	)
	(segment
		(start 69.751448 -102.41026)
		(end 69.75475 -102.413562)
		(width 0.1016)
		(layer "F.Cu")
		(net "FM_CPLD_NODE1_P1V8_SUS_EN")
	)
	(segment
		(start 72.82434 -101.29139)
		(end 72.915018 -101.382068)
		(width 0.1016)
		(layer "F.Cu")
		(net "FM_CPLD_NODE1_P1V8_SUS_EN")
	)
	(segment
		(start 71.096886 -102.852728)
		(end 70.193916 -102.852728)
		(width 0.1016)
		(layer "F.Cu")
		(net "FM_CPLD_NODE1_P1V8_SUS_EN")
	)
	(segment
		(start 71.09714 -102.852982)
		(end 71.096886 -102.852728)
		(width 0.1016)
		(layer "F.Cu")
		(net "FM_CPLD_NODE1_P1V8_SUS_EN")
	)
	(segment
		(start 70.193916 -102.852728)
		(end 69.75475 -102.413562)
		(width 0.1016)
		(layer "F.Cu")
		(net "FM_CPLD_NODE1_P1V8_SUS_EN")
	)
	(segment
		(start 172.473112 -116.828316)
		(end 173.010322 -117.365526)
		(width 0.1016)
		(layer "F.Cu")
		(net "FM_CPLD_NODE1_P1V8_SUS_EN")
	)
	(segment
		(start 72.915018 -101.382068)
		(end 72.915018 -102.198932)
		(width 0.1016)
		(layer "F.Cu")
		(net "FM_CPLD_NODE1_P1V8_SUS_EN")
	)
	(segment
		(start 69.75475 -101.397562)
		(end 69.75475 -102.413562)
		(width 0.1016)
		(layer "F.Cu")
		(net "FM_CPLD_NODE1_P1V8_SUS_EN")
	)
	(segment
		(start 72.260968 -102.852982)
		(end 71.09714 -102.852982)
		(width 0.1016)
		(layer "F.Cu")
		(net "FM_CPLD_NODE1_P1V8_SUS_EN")
	)
	(via
		(at 99.91598 -104.550972)
		(size 0.508)
		(drill 0.254)
		(layers "F.Cu" "B.Cu")
		(net "FM_CPLD_NODE1_P1V8_SUS_EN")
	)
	(via
		(at 72.915018 -102.198932)
		(size 0.508)
		(drill 0.254)
		(layers "F.Cu" "B.Cu")
		(net "FM_CPLD_NODE1_P1V8_SUS_EN")
	)
	(via
		(at 120.69826 -86.109302)
		(size 0.508)
		(drill 0.254)
		(layers "F.Cu" "B.Cu")
		(net "FM_CPLD_NODE1_P1V8_SUS_EN")
	)
	(via
		(at 165.95344 -113.35512)
		(size 0.508)
		(drill 0.254)
		(layers "F.Cu" "B.Cu")
		(net "FM_CPLD_NODE1_P1V8_SUS_EN")
	)
	(segment
		(start 99.82835 -103.882444)
		(end 99.82708 -103.881174)
		(width 0.1143)
		(layer "In2.Cu")
		(net "FM_CPLD_NODE1_P1V8_SUS_EN")
	)
	(segment
		(start 99.82708 -103.881174)
		(end 99.82708 -103.517954)
		(width 0.1143)
		(layer "In2.Cu")
		(net "FM_CPLD_NODE1_P1V8_SUS_EN")
	)
	(segment
		(start 100.08362 -103.261414)
		(end 100.086414 -103.261414)
		(width 0.1143)
		(layer "In2.Cu")
		(net "FM_CPLD_NODE1_P1V8_SUS_EN")
	)
	(segment
		(start 101.231192 -102.116636)
		(end 107.08894 -102.116636)
		(width 0.1143)
		(layer "In2.Cu")
		(net "FM_CPLD_NODE1_P1V8_SUS_EN")
	)
	(segment
		(start 107.08894 -102.116636)
		(end 112.9284 -96.277176)
		(width 0.1143)
		(layer "In2.Cu")
		(net "FM_CPLD_NODE1_P1V8_SUS_EN")
	)
	(segment
		(start 100.086414 -103.261414)
		(end 101.231192 -102.116636)
		(width 0.1143)
		(layer "In2.Cu")
		(net "FM_CPLD_NODE1_P1V8_SUS_EN")
	)
	(segment
		(start 99.82708 -103.517954)
		(end 100.08362 -103.261414)
		(width 0.1143)
		(layer "In2.Cu")
		(net "FM_CPLD_NODE1_P1V8_SUS_EN")
	)
	(segment
		(start 99.91598 -104.550972)
		(end 99.82835 -104.463342)
		(width 0.1143)
		(layer "In2.Cu")
		(net "FM_CPLD_NODE1_P1V8_SUS_EN")
	)
	(segment
		(start 99.82835 -104.463342)
		(end 99.82835 -103.882444)
		(width 0.1143)
		(layer "In2.Cu")
		(net "FM_CPLD_NODE1_P1V8_SUS_EN")
	)
	(segment
		(start 112.9284 -96.277176)
		(end 112.9284 -93.879162)
		(width 0.1143)
		(layer "In2.Cu")
		(net "FM_CPLD_NODE1_P1V8_SUS_EN")
	)
	(segment
		(start 112.9284 -93.879162)
		(end 120.69826 -86.109302)
		(width 0.1143)
		(layer "In2.Cu")
		(net "FM_CPLD_NODE1_P1V8_SUS_EN")
	)
	(segment
		(start 99.70135 -104.336342)
		(end 96.092772 -104.336342)
		(width 0.1143)
		(layer "In7.Cu")
		(net "FM_CPLD_NODE1_P1V8_SUS_EN")
	)
	(segment
		(start 73.619868 -102.198932)
		(end 72.915018 -102.198932)
		(width 0.1143)
		(layer "In7.Cu")
		(net "FM_CPLD_NODE1_P1V8_SUS_EN")
	)
	(segment
		(start 130.03276 -95.4532)
		(end 120.69826 -86.1187)
		(width 0.1143)
		(layer "In7.Cu")
		(net "FM_CPLD_NODE1_P1V8_SUS_EN")
	)
	(segment
		(start 96.092772 -104.336342)
		(end 95.83801 -104.08158)
		(width 0.1143)
		(layer "In7.Cu")
		(net "FM_CPLD_NODE1_P1V8_SUS_EN")
	)
	(segment
		(start 165.95344 -113.35512)
		(end 163.65728 -111.05896)
		(width 0.1143)
		(layer "In7.Cu")
		(net "FM_CPLD_NODE1_P1V8_SUS_EN")
	)
	(segment
		(start 163.65728 -111.05896)
		(end 157.45587 -111.05896)
		(width 0.1143)
		(layer "In7.Cu")
		(net "FM_CPLD_NODE1_P1V8_SUS_EN")
	)
	(segment
		(start 95.83801 -104.08158)
		(end 94.74581 -104.08158)
		(width 0.1143)
		(layer "In7.Cu")
		(net "FM_CPLD_NODE1_P1V8_SUS_EN")
	)
	(segment
		(start 93.66885 -103.00462)
		(end 74.425556 -103.00462)
		(width 0.1143)
		(layer "In7.Cu")
		(net "FM_CPLD_NODE1_P1V8_SUS_EN")
	)
	(segment
		(start 99.91598 -104.550972)
		(end 99.70135 -104.336342)
		(width 0.1143)
		(layer "In7.Cu")
		(net "FM_CPLD_NODE1_P1V8_SUS_EN")
	)
	(segment
		(start 120.69826 -86.1187)
		(end 120.69826 -86.109302)
		(width 0.1143)
		(layer "In7.Cu")
		(net "FM_CPLD_NODE1_P1V8_SUS_EN")
	)
	(segment
		(start 157.45587 -111.05896)
		(end 141.85011 -95.4532)
		(width 0.1143)
		(layer "In7.Cu")
		(net "FM_CPLD_NODE1_P1V8_SUS_EN")
	)
	(segment
		(start 141.85011 -95.4532)
		(end 130.03276 -95.4532)
		(width 0.1143)
		(layer "In7.Cu")
		(net "FM_CPLD_NODE1_P1V8_SUS_EN")
	)
	(segment
		(start 74.425556 -103.00462)
		(end 73.619868 -102.198932)
		(width 0.1143)
		(layer "In7.Cu")
		(net "FM_CPLD_NODE1_P1V8_SUS_EN")
	)
	(segment
		(start 94.74581 -104.08158)
		(end 93.66885 -103.00462)
		(width 0.1143)
		(layer "In7.Cu")
		(net "FM_CPLD_NODE1_P1V8_SUS_EN")
	)
	(segment
		(start 123.504452 -144.30375)
		(end 123.098052 -144.30375)
		(width 0.127)
		(layer "F.Cu")
		(net "P2E_CPU_PCIE_SW_NODE1_RX_C_DN")
	)
	(segment
		(start 124.763276 -146.222974)
		(end 123.910852 -145.37055)
		(width 0.127)
		(layer "F.Cu")
		(net "P2E_CPU_PCIE_SW_NODE1_RX_C_DN")
	)
	(segment
		(start 123.098052 -144.30375)
		(end 122.894852 -144.10055)
		(width 0.127)
		(layer "F.Cu")
		(net "P2E_CPU_PCIE_SW_NODE1_RX_C_DN")
	)
	(segment
		(start 125.031754 -146.222974)
		(end 124.763276 -146.222974)
		(width 0.127)
		(layer "F.Cu")
		(net "P2E_CPU_PCIE_SW_NODE1_RX_C_DN")
	)
	(segment
		(start 125.787912 -146.175476)
		(end 125.079252 -146.175476)
		(width 0.127)
		(layer "F.Cu")
		(net "P2E_CPU_PCIE_SW_NODE1_RX_C_DN")
	)
	(segment
		(start 125.079252 -146.175476)
		(end 125.031754 -146.222974)
		(width 0.127)
		(layer "F.Cu")
		(net "P2E_CPU_PCIE_SW_NODE1_RX_C_DN")
	)
	(segment
		(start 123.910852 -144.71015)
		(end 123.504452 -144.30375)
		(width 0.127)
		(layer "F.Cu")
		(net "P2E_CPU_PCIE_SW_NODE1_RX_C_DN")
	)
	(segment
		(start 123.910852 -145.37055)
		(end 123.910852 -144.71015)
		(width 0.127)
		(layer "F.Cu")
		(net "P2E_CPU_PCIE_SW_NODE1_RX_C_DN")
	)
	(segment
		(start 122.894852 -144.10055)
		(end 122.894852 -143.813276)
		(width 0.127)
		(layer "F.Cu")
		(net "P2E_CPU_PCIE_SW_NODE1_RX_C_DN")
	)
	(via
		(at 122.894852 -143.813276)
		(size 0.508)
		(drill 0.254)
		(layers "F.Cu" "B.Cu")
		(net "P2E_CPU_PCIE_SW_NODE1_RX_C_DN")
	)
	(segment
		(start 122.15749 -144.295876)
		(end 122.412252 -144.295876)
		(width 0.127)
		(layer "B.Cu")
		(net "P2E_CPU_PCIE_SW_NODE1_RX_C_DN")
	)
	(segment
		(start 122.412252 -144.295876)
		(end 122.894852 -143.813276)
		(width 0.127)
		(layer "B.Cu")
		(net "P2E_CPU_PCIE_SW_NODE1_RX_C_DN")
	)
	(segment
		(start 121.80189 -143.940276)
		(end 122.15749 -144.295876)
		(width 0.127)
		(layer "B.Cu")
		(net "P2E_CPU_PCIE_SW_NODE1_RX_C_DN")
	)
	(segment
		(start 54.64048 -101.510846)
		(end 54.39664 -101.267006)
		(width 0.254)
		(layer "F.Cu")
		(net "A_CPU1_NODE1_THERMDC")
	)
	(segment
		(start 53.137308 -101.267006)
		(end 53.7718 -101.267006)
		(width 0.254)
		(layer "F.Cu")
		(net "A_CPU1_NODE1_THERMDC")
	)
	(segment
		(start 52.749958 -100.879656)
		(end 53.137308 -101.267006)
		(width 0.254)
		(layer "F.Cu")
		(net "A_CPU1_NODE1_THERMDC")
	)
	(segment
		(start 54.64048 -101.512116)
		(end 54.64048 -101.510846)
		(width 0.254)
		(layer "F.Cu")
		(net "A_CPU1_NODE1_THERMDC")
	)
	(segment
		(start 60.000896 -76.599542)
		(end 59.600846 -76.999592)
		(width 0.254)
		(layer "F.Cu")
		(net "A_CPU1_NODE1_THERMDC")
	)
	(segment
		(start 51.906932 -100.879656)
		(end 52.749958 -100.879656)
		(width 0.254)
		(layer "F.Cu")
		(net "A_CPU1_NODE1_THERMDC")
	)
	(segment
		(start 54.39664 -101.267006)
		(end 53.7718 -101.267006)
		(width 0.254)
		(layer "F.Cu")
		(net "A_CPU1_NODE1_THERMDC")
	)
	(via
		(at 54.64048 -101.512116)
		(size 0.508)
		(drill 0.254)
		(layers "F.Cu" "B.Cu")
		(net "A_CPU1_NODE1_THERMDC")
	)
	(via
		(at 59.600846 -76.999592)
		(size 0.508)
		(drill 0.254)
		(layers "F.Cu" "B.Cu")
		(net "A_CPU1_NODE1_THERMDC")
	)
	(segment
		(start 58.12155 -80.557116)
		(end 58.796174 -79.882492)
		(width 0.254)
		(layer "In2.Cu")
		(net "A_CPU1_NODE1_THERMDC")
	)
	(segment
		(start 59.402218 -77.19822)
		(end 59.600846 -76.999592)
		(width 0.254)
		(layer "In2.Cu")
		(net "A_CPU1_NODE1_THERMDC")
	)
	(segment
		(start 55.09514 -100.25634)
		(end 53.84546 -99.00666)
		(width 0.254)
		(layer "In2.Cu")
		(net "A_CPU1_NODE1_THERMDC")
	)
	(segment
		(start 59.000898 -79.882492)
		(end 59.402218 -79.481172)
		(width 0.254)
		(layer "In2.Cu")
		(net "A_CPU1_NODE1_THERMDC")
	)
	(segment
		(start 53.84546 -99.00666)
		(end 53.84546 -94.713552)
		(width 0.254)
		(layer "In2.Cu")
		(net "A_CPU1_NODE1_THERMDC")
	)
	(segment
		(start 55.865522 -89.559638)
		(end 58.12155 -87.30361)
		(width 0.254)
		(layer "In2.Cu")
		(net "A_CPU1_NODE1_THERMDC")
	)
	(segment
		(start 55.865522 -92.69349)
		(end 55.865522 -89.559638)
		(width 0.254)
		(layer "In2.Cu")
		(net "A_CPU1_NODE1_THERMDC")
	)
	(segment
		(start 58.12155 -87.30361)
		(end 58.12155 -80.557116)
		(width 0.254)
		(layer "In2.Cu")
		(net "A_CPU1_NODE1_THERMDC")
	)
	(segment
		(start 59.402218 -79.481172)
		(end 59.402218 -77.19822)
		(width 0.254)
		(layer "In2.Cu")
		(net "A_CPU1_NODE1_THERMDC")
	)
	(segment
		(start 54.7497 -101.512116)
		(end 55.09514 -101.166676)
		(width 0.254)
		(layer "In2.Cu")
		(net "A_CPU1_NODE1_THERMDC")
	)
	(segment
		(start 53.84546 -94.713552)
		(end 55.865522 -92.69349)
		(width 0.254)
		(layer "In2.Cu")
		(net "A_CPU1_NODE1_THERMDC")
	)
	(segment
		(start 55.09514 -101.166676)
		(end 55.09514 -100.25634)
		(width 0.254)
		(layer "In2.Cu")
		(net "A_CPU1_NODE1_THERMDC")
	)
	(segment
		(start 58.796174 -79.882492)
		(end 59.000898 -79.882492)
		(width 0.254)
		(layer "In2.Cu")
		(net "A_CPU1_NODE1_THERMDC")
	)
	(segment
		(start 54.64048 -101.512116)
		(end 54.7497 -101.512116)
		(width 0.254)
		(layer "In2.Cu")
		(net "A_CPU1_NODE1_THERMDC")
	)
	(segment
		(start 52.799996 -78.999842)
		(end 53.200046 -79.399892)
		(width 0.381)
		(layer "F.Cu")
		(net "PD_NODE1_NTB_RCOMP")
	)
	(via
		(at 50.495454 -80.956658)
		(size 0.6604)
		(drill 0.3302)
		(layers "F.Cu" "B.Cu")
		(net "PD_NODE1_NTB_RCOMP")
	)
	(via
		(at 53.200046 -79.399892)
		(size 0.508)
		(drill 0.254)
		(layers "F.Cu" "B.Cu")
		(net "PD_NODE1_NTB_RCOMP")
	)
	(segment
		(start 53.200046 -80.295496)
		(end 53.200046 -79.399892)
		(width 0.381)
		(layer "B.Cu")
		(net "PD_NODE1_NTB_RCOMP")
	)
	(segment
		(start 50.701194 -80.750918)
		(end 52.744624 -80.750918)
		(width 0.381)
		(layer "B.Cu")
		(net "PD_NODE1_NTB_RCOMP")
	)
	(segment
		(start 52.744624 -80.750918)
		(end 53.200046 -80.295496)
		(width 0.381)
		(layer "B.Cu")
		(net "PD_NODE1_NTB_RCOMP")
	)
	(segment
		(start 50.495454 -80.956658)
		(end 50.701194 -80.750918)
		(width 0.381)
		(layer "B.Cu")
		(net "PD_NODE1_NTB_RCOMP")
	)
	(segment
		(start 50.009298 -81.442814)
		(end 50.495454 -80.956658)
		(width 0.381)
		(layer "B.Cu")
		(net "PD_NODE1_NTB_RCOMP")
	)
	(segment
		(start 50.009298 -82.161888)
		(end 50.009298 -81.442814)
		(width 0.381)
		(layer "B.Cu")
		(net "PD_NODE1_NTB_RCOMP")
	)
	(segment
		(start 123.37796 -144.60855)
		(end 123.098052 -144.60855)
		(width 0.127)
		(layer "F.Cu")
		(net "P2E_CPU_PCIE_SW_NODE1_RX_C_DP")
	)
	(segment
		(start 123.606052 -145.497042)
		(end 123.606052 -144.836642)
		(width 0.127)
		(layer "F.Cu")
		(net "P2E_CPU_PCIE_SW_NODE1_RX_C_DP")
	)
	(segment
		(start 123.606052 -144.836642)
		(end 123.37796 -144.60855)
		(width 0.127)
		(layer "F.Cu")
		(net "P2E_CPU_PCIE_SW_NODE1_RX_C_DP")
	)
	(segment
		(start 125.079252 -146.575526)
		(end 125.0315 -146.527774)
		(width 0.127)
		(layer "F.Cu")
		(net "P2E_CPU_PCIE_SW_NODE1_RX_C_DP")
	)
	(segment
		(start 125.0315 -146.527774)
		(end 124.636784 -146.527774)
		(width 0.127)
		(layer "F.Cu")
		(net "P2E_CPU_PCIE_SW_NODE1_RX_C_DP")
	)
	(segment
		(start 125.787912 -146.575526)
		(end 125.079252 -146.575526)
		(width 0.127)
		(layer "F.Cu")
		(net "P2E_CPU_PCIE_SW_NODE1_RX_C_DP")
	)
	(segment
		(start 124.636784 -146.527774)
		(end 123.606052 -145.497042)
		(width 0.127)
		(layer "F.Cu")
		(net "P2E_CPU_PCIE_SW_NODE1_RX_C_DP")
	)
	(segment
		(start 122.894852 -144.81175)
		(end 122.894852 -145.083276)
		(width 0.127)
		(layer "F.Cu")
		(net "P2E_CPU_PCIE_SW_NODE1_RX_C_DP")
	)
	(segment
		(start 123.098052 -144.60855)
		(end 122.894852 -144.81175)
		(width 0.127)
		(layer "F.Cu")
		(net "P2E_CPU_PCIE_SW_NODE1_RX_C_DP")
	)
	(via
		(at 122.894852 -145.083276)
		(size 0.508)
		(drill 0.254)
		(layers "F.Cu" "B.Cu")
		(net "P2E_CPU_PCIE_SW_NODE1_RX_C_DP")
	)
	(segment
		(start 122.15749 -144.600676)
		(end 122.412252 -144.600676)
		(width 0.127)
		(layer "B.Cu")
		(net "P2E_CPU_PCIE_SW_NODE1_RX_C_DP")
	)
	(segment
		(start 121.80189 -144.956276)
		(end 122.15749 -144.600676)
		(width 0.127)
		(layer "B.Cu")
		(net "P2E_CPU_PCIE_SW_NODE1_RX_C_DP")
	)
	(segment
		(start 122.412252 -144.600676)
		(end 122.894852 -145.083276)
		(width 0.127)
		(layer "B.Cu")
		(net "P2E_CPU_PCIE_SW_NODE1_RX_C_DP")
	)
	(segment
		(start 61.503306 -83.10753)
		(end 61.054996 -83.55584)
		(width 0.3048)
		(layer "F.Cu")
		(net "P1V8_SUS_NODE1")
	)
	(segment
		(start 61.357002 -83.857846)
		(end 61.054996 -83.55584)
		(width 0.3048)
		(layer "F.Cu")
		(net "P1V8_SUS_NODE1")
	)
	(segment
		(start 61.503306 -82.333846)
		(end 61.437266 -82.333846)
		(width 0.3048)
		(layer "F.Cu")
		(net "P1V8_SUS_NODE1")
	)
	(segment
		(start 61.503306 -83.857846)
		(end 61.357002 -83.857846)
		(width 0.3048)
		(layer "F.Cu")
		(net "P1V8_SUS_NODE1")
	)
	(segment
		(start 61.437266 -82.333846)
		(end 61.089794 -82.681318)
		(width 0.3048)
		(layer "F.Cu")
		(net "P1V8_SUS_NODE1")
	)
	(segment
		(start 61.503306 -83.09483)
		(end 61.089794 -82.681318)
		(width 0.3048)
		(layer "F.Cu")
		(net "P1V8_SUS_NODE1")
	)
	(segment
		(start 61.503306 -83.095846)
		(end 61.503306 -83.10753)
		(width 0.3048)
		(layer "F.Cu")
		(net "P1V8_SUS_NODE1")
	)
	(segment
		(start 61.503306 -83.095846)
		(end 61.503306 -83.09483)
		(width 0.3048)
		(layer "F.Cu")
		(net "P1V8_SUS_NODE1")
	)
	(via
		(at 61.054996 -83.55584)
		(size 0.508)
		(drill 0.254)
		(layers "F.Cu" "B.Cu")
		(net "P1V8_SUS_NODE1")
	)
	(via
		(at 62.114684 -97.87001)
		(size 0.508)
		(drill 0.254)
		(layers "F.Cu" "B.Cu")
		(net "P1V8_SUS_NODE1")
	)
	(via
		(at 63.806578 -83.731354)
		(size 0.6604)
		(drill 0.3302)
		(layers "F.Cu" "B.Cu")
		(net "P1V8_SUS_NODE1")
	)
	(via
		(at 62.75451 -97.891092)
		(size 0.508)
		(drill 0.254)
		(layers "F.Cu" "B.Cu")
		(net "P1V8_SUS_NODE1")
	)
	(via
		(at 61.089794 -82.681318)
		(size 0.508)
		(drill 0.254)
		(layers "F.Cu" "B.Cu")
		(net "P1V8_SUS_NODE1")
	)
	(segment
		(start 51.906932 -98.929698)
		(end 52.855622 -98.929698)
		(width 0.254)
		(layer "F.Cu")
		(net "A_CPU0_NODE1_THERMDA")
	)
	(segment
		(start 60.800996 -77.399642)
		(end 60.400946 -76.999592)
		(width 0.254)
		(layer "F.Cu")
		(net "A_CPU0_NODE1_THERMDA")
	)
	(segment
		(start 54.555644 -98.705162)
		(end 53.76164 -98.705162)
		(width 0.254)
		(layer "F.Cu")
		(net "A_CPU0_NODE1_THERMDA")
	)
	(segment
		(start 53.080158 -98.705162)
		(end 53.76164 -98.705162)
		(width 0.254)
		(layer "F.Cu")
		(net "A_CPU0_NODE1_THERMDA")
	)
	(segment
		(start 52.855622 -98.929698)
		(end 53.080158 -98.705162)
		(width 0.254)
		(layer "F.Cu")
		(net "A_CPU0_NODE1_THERMDA")
	)
	(via
		(at 60.400946 -76.999592)
		(size 0.508)
		(drill 0.254)
		(layers "F.Cu" "B.Cu")
		(net "A_CPU0_NODE1_THERMDA")
	)
	(via
		(at 54.555644 -98.705162)
		(size 0.508)
		(drill 0.254)
		(layers "F.Cu" "B.Cu")
		(net "A_CPU0_NODE1_THERMDA")
	)
	(segment
		(start 57.368186 -89.156794)
		(end 57.368186 -92.291916)
		(width 0.254)
		(layer "In2.Cu")
		(net "A_CPU0_NODE1_THERMDA")
	)
	(segment
		(start 57.368186 -92.291916)
		(end 55.554372 -94.10573)
		(width 0.254)
		(layer "In2.Cu")
		(net "A_CPU0_NODE1_THERMDA")
	)
	(segment
		(start 55.554372 -98.017076)
		(end 54.866286 -98.705162)
		(width 0.254)
		(layer "In2.Cu")
		(net "A_CPU0_NODE1_THERMDA")
	)
	(segment
		(start 59.918346 -81.338674)
		(end 59.75223 -81.50479)
		(width 0.254)
		(layer "In2.Cu")
		(net "A_CPU0_NODE1_THERMDA")
	)
	(segment
		(start 54.866286 -98.705162)
		(end 54.555644 -98.705162)
		(width 0.254)
		(layer "In2.Cu")
		(net "A_CPU0_NODE1_THERMDA")
	)
	(segment
		(start 55.554372 -94.10573)
		(end 55.554372 -98.017076)
		(width 0.254)
		(layer "In2.Cu")
		(net "A_CPU0_NODE1_THERMDA")
	)
	(segment
		(start 59.918346 -77.482192)
		(end 59.918346 -81.338674)
		(width 0.254)
		(layer "In2.Cu")
		(net "A_CPU0_NODE1_THERMDA")
	)
	(segment
		(start 60.400946 -76.999592)
		(end 59.918346 -77.482192)
		(width 0.254)
		(layer "In2.Cu")
		(net "A_CPU0_NODE1_THERMDA")
	)
	(segment
		(start 59.75223 -86.77275)
		(end 57.368186 -89.156794)
		(width 0.254)
		(layer "In2.Cu")
		(net "A_CPU0_NODE1_THERMDA")
	)
	(segment
		(start 59.75223 -81.50479)
		(end 59.75223 -86.77275)
		(width 0.254)
		(layer "In2.Cu")
		(net "A_CPU0_NODE1_THERMDA")
	)
	(segment
		(start 69.499226 -100.510086)
		(end 68.265548 -100.510086)
		(width 0.1016)
		(layer "F.Cu")
		(net "FM_CPLD_NODE1_P1V8_SUS_EN_G")
	)
	(segment
		(start 68.265294 -100.51034)
		(end 68.265294 -101.068378)
		(width 0.1016)
		(layer "F.Cu")
		(net "FM_CPLD_NODE1_P1V8_SUS_EN_G")
	)
	(segment
		(start 69.138038 -101.941122)
		(end 69.14388 -101.941122)
		(width 0.1016)
		(layer "F.Cu")
		(net "FM_CPLD_NODE1_P1V8_SUS_EN_G")
	)
	(segment
		(start 69.75475 -100.254562)
		(end 69.499226 -100.510086)
		(width 0.1016)
		(layer "F.Cu")
		(net "FM_CPLD_NODE1_P1V8_SUS_EN_G")
	)
	(segment
		(start 68.265294 -101.068378)
		(end 69.138038 -101.941122)
		(width 0.1016)
		(layer "F.Cu")
		(net "FM_CPLD_NODE1_P1V8_SUS_EN_G")
	)
	(segment
		(start 68.265548 -100.510086)
		(end 68.265294 -100.51034)
		(width 0.1016)
		(layer "F.Cu")
		(net "FM_CPLD_NODE1_P1V8_SUS_EN_G")
	)
	(via
		(at 69.14388 -101.941122)
		(size 0.508)
		(drill 0.254)
		(layers "F.Cu" "B.Cu")
		(net "FM_CPLD_NODE1_P1V8_SUS_EN_G")
	)
	(segment
		(start 40.350186 -20.94992)
		(end 40.350186 -22.243034)
		(width 0.254)
		(layer "F.Cu")
		(net "P1V5_NODE1_DDR3_VREF0_D")
	)
	(segment
		(start 39.585646 -22.243796)
		(end 38.510972 -21.169122)
		(width 0.254)
		(layer "F.Cu")
		(net "P1V5_NODE1_DDR3_VREF0_D")
	)
	(segment
		(start 39.585646 -22.24532)
		(end 39.585646 -22.243796)
		(width 0.254)
		(layer "F.Cu")
		(net "P1V5_NODE1_DDR3_VREF0_D")
	)
	(segment
		(start 37.13607 -21.169122)
		(end 38.510972 -21.169122)
		(width 0.254)
		(layer "F.Cu")
		(net "P1V5_NODE1_DDR3_VREF0_D")
	)
	(segment
		(start 35.693858 -19.72691)
		(end 37.13607 -21.169122)
		(width 0.254)
		(layer "F.Cu")
		(net "P1V5_NODE1_DDR3_VREF0_D")
	)
	(segment
		(start 35.693858 -19.453352)
		(end 35.693858 -19.72691)
		(width 0.254)
		(layer "F.Cu")
		(net "P1V5_NODE1_DDR3_VREF0_D")
	)
	(segment
		(start 34.719006 -19.453352)
		(end 35.693858 -19.453352)
		(width 0.254)
		(layer "F.Cu")
		(net "P1V5_NODE1_DDR3_VREF0_D")
	)
	(segment
		(start 40.350186 -22.243034)
		(end 40.124888 -22.468332)
		(width 0.254)
		(layer "F.Cu")
		(net "P1V5_NODE1_DDR3_VREF0_D")
	)
	(segment
		(start 40.124888 -22.468332)
		(end 40.125142 -22.46884)
		(width 0.254)
		(layer "F.Cu")
		(net "P1V5_NODE1_DDR3_VREF0_D")
	)
	(segment
		(start 39.809166 -22.46884)
		(end 39.585646 -22.24532)
		(width 0.254)
		(layer "F.Cu")
		(net "P1V5_NODE1_DDR3_VREF0_D")
	)
	(segment
		(start 40.125142 -22.46884)
		(end 39.809166 -22.46884)
		(width 0.254)
		(layer "F.Cu")
		(net "P1V5_NODE1_DDR3_VREF0_D")
	)
	(via
		(at 38.510972 -21.169122)
		(size 0.508)
		(drill 0.254)
		(layers "F.Cu" "B.Cu")
		(net "P1V5_NODE1_DDR3_VREF0_D")
	)
	(segment
		(start 64.613282 -99.107498)
		(end 65.177924 -98.542856)
		(width 0.1016)
		(layer "F.Cu")
		(net "FM_CPLD_NODE1_P1V8_SUS_EN_LV")
	)
	(segment
		(start 66.858134 -101.4603)
		(end 67.351148 -101.953314)
		(width 0.1016)
		(layer "F.Cu")
		(net "FM_CPLD_NODE1_P1V8_SUS_EN_LV")
	)
	(segment
		(start 64.613282 -99.685856)
		(end 64.613282 -99.107498)
		(width 0.1016)
		(layer "F.Cu")
		(net "FM_CPLD_NODE1_P1V8_SUS_EN_LV")
	)
	(segment
		(start 66.221102 -99.545648)
		(end 66.221102 -101.049836)
		(width 0.1016)
		(layer "F.Cu")
		(net "FM_CPLD_NODE1_P1V8_SUS_EN_LV")
	)
	(segment
		(start 65.177924 -98.542856)
		(end 65.747138 -98.542856)
		(width 0.1016)
		(layer "F.Cu")
		(net "FM_CPLD_NODE1_P1V8_SUS_EN_LV")
	)
	(segment
		(start 66.265298 -101.094032)
		(end 66.265298 -101.4603)
		(width 0.1016)
		(layer "F.Cu")
		(net "FM_CPLD_NODE1_P1V8_SUS_EN_LV")
	)
	(segment
		(start 65.747138 -98.542856)
		(end 66.485516 -99.281234)
		(width 0.1016)
		(layer "F.Cu")
		(net "FM_CPLD_NODE1_P1V8_SUS_EN_LV")
	)
	(segment
		(start 66.221102 -101.049836)
		(end 66.265298 -101.094032)
		(width 0.1016)
		(layer "F.Cu")
		(net "FM_CPLD_NODE1_P1V8_SUS_EN_LV")
	)
	(segment
		(start 66.265298 -101.4603)
		(end 66.858134 -101.4603)
		(width 0.1016)
		(layer "F.Cu")
		(net "FM_CPLD_NODE1_P1V8_SUS_EN_LV")
	)
	(segment
		(start 66.485516 -99.281234)
		(end 66.221102 -99.545648)
		(width 0.1016)
		(layer "F.Cu")
		(net "FM_CPLD_NODE1_P1V8_SUS_EN_LV")
	)
	(via
		(at 67.351148 -101.953314)
		(size 0.508)
		(drill 0.254)
		(layers "F.Cu" "B.Cu")
		(net "FM_CPLD_NODE1_P1V8_SUS_EN_LV")
	)
	(segment
		(start 34.224468 -105.325164)
		(end 33.569656 -105.979976)
		(width 0.1016)
		(layer "F.Cu")
		(net "PWRGD_NODE1_P1V5_SUS_PG")
	)
	(segment
		(start 35.121088 -107.687618)
		(end 35.40633 -107.97286)
		(width 0.1016)
		(layer "F.Cu")
		(net "PWRGD_NODE1_P1V5_SUS_PG")
	)
	(segment
		(start 33.573212 -107.527598)
		(end 33.733232 -107.687618)
		(width 0.1016)
		(layer "F.Cu")
		(net "PWRGD_NODE1_P1V5_SUS_PG")
	)
	(segment
		(start 181.01056 -121.365518)
		(end 182.784496 -121.365518)
		(width 0.1016)
		(layer "F.Cu")
		(net "PWRGD_NODE1_P1V5_SUS_PG")
	)
	(segment
		(start 33.569656 -105.979976)
		(end 33.569656 -106.210608)
		(width 0.1016)
		(layer "F.Cu")
		(net "PWRGD_NODE1_P1V5_SUS_PG")
	)
	(segment
		(start 34.224468 -104.40797)
		(end 34.224468 -105.325164)
		(width 0.1016)
		(layer "F.Cu")
		(net "PWRGD_NODE1_P1V5_SUS_PG")
	)
	(segment
		(start 33.569656 -106.210608)
		(end 33.569656 -107.265724)
		(width 0.1016)
		(layer "F.Cu")
		(net "PWRGD_NODE1_P1V5_SUS_PG")
	)
	(segment
		(start 33.573212 -107.26928)
		(end 33.573212 -107.527598)
		(width 0.1016)
		(layer "F.Cu")
		(net "PWRGD_NODE1_P1V5_SUS_PG")
	)
	(segment
		(start 33.569656 -107.265724)
		(end 33.573212 -107.26928)
		(width 0.1016)
		(layer "F.Cu")
		(net "PWRGD_NODE1_P1V5_SUS_PG")
	)
	(segment
		(start 34.031428 -104.21493)
		(end 34.224468 -104.40797)
		(width 0.1016)
		(layer "F.Cu")
		(net "PWRGD_NODE1_P1V5_SUS_PG")
	)
	(segment
		(start 182.784496 -121.365518)
		(end 182.91556 -121.496582)
		(width 0.1016)
		(layer "F.Cu")
		(net "PWRGD_NODE1_P1V5_SUS_PG")
	)
	(segment
		(start 33.33623 -104.21493)
		(end 34.031428 -104.21493)
		(width 0.1016)
		(layer "F.Cu")
		(net "PWRGD_NODE1_P1V5_SUS_PG")
	)
	(segment
		(start 33.733232 -107.687618)
		(end 35.121088 -107.687618)
		(width 0.1016)
		(layer "F.Cu")
		(net "PWRGD_NODE1_P1V5_SUS_PG")
	)
	(via
		(at 35.40633 -107.97286)
		(size 0.508)
		(drill 0.254)
		(layers "F.Cu" "B.Cu")
		(net "PWRGD_NODE1_P1V5_SUS_PG")
	)
	(via
		(at 164.82568 -116.294154)
		(size 0.508)
		(drill 0.254)
		(layers "F.Cu" "B.Cu")
		(net "PWRGD_NODE1_P1V5_SUS_PG")
	)
	(via
		(at 43.590464 -118.822216)
		(size 0.508)
		(drill 0.254)
		(layers "F.Cu" "B.Cu")
		(net "PWRGD_NODE1_P1V5_SUS_PG")
	)
	(via
		(at 182.91556 -121.496582)
		(size 0.508)
		(drill 0.254)
		(layers "F.Cu" "B.Cu")
		(net "PWRGD_NODE1_P1V5_SUS_PG")
	)
	(segment
		(start 45.90669 -117.843808)
		(end 44.568872 -117.843808)
		(width 0.1143)
		(layer "In6.Cu")
		(net "PWRGD_NODE1_P1V5_SUS_PG")
	)
	(segment
		(start 101.365304 -109.096048)
		(end 94.564454 -115.896898)
		(width 0.1143)
		(layer "In6.Cu")
		(net "PWRGD_NODE1_P1V5_SUS_PG")
	)
	(segment
		(start 48.49876 -115.251738)
		(end 45.90669 -117.843808)
		(width 0.1143)
		(layer "In6.Cu")
		(net "PWRGD_NODE1_P1V5_SUS_PG")
	)
	(segment
		(start 164.82568 -116.294154)
		(end 163.108132 -116.294154)
		(width 0.1143)
		(layer "In6.Cu")
		(net "PWRGD_NODE1_P1V5_SUS_PG")
	)
	(segment
		(start 94.564454 -115.896898)
		(end 87.655654 -115.896898)
		(width 0.1143)
		(layer "In6.Cu")
		(net "PWRGD_NODE1_P1V5_SUS_PG")
	)
	(segment
		(start 44.568872 -117.843808)
		(end 43.590464 -118.822216)
		(width 0.1143)
		(layer "In6.Cu")
		(net "PWRGD_NODE1_P1V5_SUS_PG")
	)
	(segment
		(start 158.603696 -116.296694)
		(end 156.867098 -114.560096)
		(width 0.1143)
		(layer "In6.Cu")
		(net "PWRGD_NODE1_P1V5_SUS_PG")
	)
	(segment
		(start 145.68424 -110.881414)
		(end 132.176266 -110.881414)
		(width 0.1143)
		(layer "In6.Cu")
		(net "PWRGD_NODE1_P1V5_SUS_PG")
	)
	(segment
		(start 48.49876 -114.596164)
		(end 48.49876 -115.251738)
		(width 0.1143)
		(layer "In6.Cu")
		(net "PWRGD_NODE1_P1V5_SUS_PG")
	)
	(segment
		(start 82.524854 -114.245644)
		(end 53.475128 -114.245644)
		(width 0.1143)
		(layer "In6.Cu")
		(net "PWRGD_NODE1_P1V5_SUS_PG")
	)
	(segment
		(start 132.176266 -110.881414)
		(end 131.878324 -111.179356)
		(width 0.1143)
		(layer "In6.Cu")
		(net "PWRGD_NODE1_P1V5_SUS_PG")
	)
	(segment
		(start 83.12658 -114.84737)
		(end 82.524854 -114.245644)
		(width 0.1143)
		(layer "In6.Cu")
		(net "PWRGD_NODE1_P1V5_SUS_PG")
	)
	(segment
		(start 125.207014 -111.3663)
		(end 122.936762 -109.096048)
		(width 0.1143)
		(layer "In6.Cu")
		(net "PWRGD_NODE1_P1V5_SUS_PG")
	)
	(segment
		(start 122.936762 -109.096048)
		(end 101.365304 -109.096048)
		(width 0.1143)
		(layer "In6.Cu")
		(net "PWRGD_NODE1_P1V5_SUS_PG")
	)
	(segment
		(start 156.867098 -114.560096)
		(end 153.472896 -114.560096)
		(width 0.1143)
		(layer "In6.Cu")
		(net "PWRGD_NODE1_P1V5_SUS_PG")
	)
	(segment
		(start 87.655654 -115.896898)
		(end 86.606126 -114.84737)
		(width 0.1143)
		(layer "In6.Cu")
		(net "PWRGD_NODE1_P1V5_SUS_PG")
	)
	(segment
		(start 52.011834 -112.78235)
		(end 50.312574 -112.78235)
		(width 0.1143)
		(layer "In6.Cu")
		(net "PWRGD_NODE1_P1V5_SUS_PG")
	)
	(segment
		(start 128.002284 -111.179356)
		(end 127.81534 -111.3663)
		(width 0.1143)
		(layer "In6.Cu")
		(net "PWRGD_NODE1_P1V5_SUS_PG")
	)
	(segment
		(start 86.606126 -114.84737)
		(end 83.12658 -114.84737)
		(width 0.1143)
		(layer "In6.Cu")
		(net "PWRGD_NODE1_P1V5_SUS_PG")
	)
	(segment
		(start 163.105592 -116.296694)
		(end 158.603696 -116.296694)
		(width 0.1143)
		(layer "In6.Cu")
		(net "PWRGD_NODE1_P1V5_SUS_PG")
	)
	(segment
		(start 131.878324 -111.179356)
		(end 128.002284 -111.179356)
		(width 0.1143)
		(layer "In6.Cu")
		(net "PWRGD_NODE1_P1V5_SUS_PG")
	)
	(segment
		(start 50.312574 -112.78235)
		(end 48.49876 -114.596164)
		(width 0.1143)
		(layer "In6.Cu")
		(net "PWRGD_NODE1_P1V5_SUS_PG")
	)
	(segment
		(start 53.475128 -114.245644)
		(end 52.011834 -112.78235)
		(width 0.1143)
		(layer "In6.Cu")
		(net "PWRGD_NODE1_P1V5_SUS_PG")
	)
	(segment
		(start 127.81534 -111.3663)
		(end 125.207014 -111.3663)
		(width 0.1143)
		(layer "In6.Cu")
		(net "PWRGD_NODE1_P1V5_SUS_PG")
	)
	(segment
		(start 149.573488 -114.770662)
		(end 145.68424 -110.881414)
		(width 0.1143)
		(layer "In6.Cu")
		(net "PWRGD_NODE1_P1V5_SUS_PG")
	)
	(segment
		(start 153.472896 -114.560096)
		(end 153.26233 -114.770662)
		(width 0.1143)
		(layer "In6.Cu")
		(net "PWRGD_NODE1_P1V5_SUS_PG")
	)
	(segment
		(start 153.26233 -114.770662)
		(end 149.573488 -114.770662)
		(width 0.1143)
		(layer "In6.Cu")
		(net "PWRGD_NODE1_P1V5_SUS_PG")
	)
	(segment
		(start 163.108132 -116.294154)
		(end 163.105592 -116.296694)
		(width 0.1143)
		(layer "In6.Cu")
		(net "PWRGD_NODE1_P1V5_SUS_PG")
	)
	(segment
		(start 169.054018 -116.294154)
		(end 164.82568 -116.294154)
		(width 0.1143)
		(layer "In7.Cu")
		(net "PWRGD_NODE1_P1V5_SUS_PG")
	)
	(segment
		(start 172.70349 -116.549932)
		(end 171.848272 -115.694714)
		(width 0.1143)
		(layer "In7.Cu")
		(net "PWRGD_NODE1_P1V5_SUS_PG")
	)
	(segment
		(start 35.879532 -107.97286)
		(end 35.40633 -107.97286)
		(width 0.1143)
		(layer "In7.Cu")
		(net "PWRGD_NODE1_P1V5_SUS_PG")
	)
	(segment
		(start 178.684174 -117.265196)
		(end 178.212242 -117.265196)
		(width 0.1143)
		(layer "In7.Cu")
		(net "PWRGD_NODE1_P1V5_SUS_PG")
	)
	(segment
		(start 177.496724 -116.549932)
		(end 172.70349 -116.549932)
		(width 0.1143)
		(layer "In7.Cu")
		(net "PWRGD_NODE1_P1V5_SUS_PG")
	)
	(segment
		(start 41.271952 -118.822216)
		(end 36.87572 -114.425984)
		(width 0.1143)
		(layer "In7.Cu")
		(net "PWRGD_NODE1_P1V5_SUS_PG")
	)
	(segment
		(start 169.39514 -115.954302)
		(end 169.054018 -116.294154)
		(width 0.1143)
		(layer "In7.Cu")
		(net "PWRGD_NODE1_P1V5_SUS_PG")
	)
	(segment
		(start 171.848272 -115.694714)
		(end 169.654728 -115.694714)
		(width 0.1143)
		(layer "In7.Cu")
		(net "PWRGD_NODE1_P1V5_SUS_PG")
	)
	(segment
		(start 169.654728 -115.694714)
		(end 169.39514 -115.954302)
		(width 0.1143)
		(layer "In7.Cu")
		(net "PWRGD_NODE1_P1V5_SUS_PG")
	)
	(segment
		(start 36.87572 -114.425984)
		(end 36.87572 -108.969048)
		(width 0.1143)
		(layer "In7.Cu")
		(net "PWRGD_NODE1_P1V5_SUS_PG")
	)
	(segment
		(start 43.590464 -118.822216)
		(end 41.271952 -118.822216)
		(width 0.1143)
		(layer "In7.Cu")
		(net "PWRGD_NODE1_P1V5_SUS_PG")
	)
	(segment
		(start 36.87572 -108.969048)
		(end 35.879532 -107.97286)
		(width 0.1143)
		(layer "In7.Cu")
		(net "PWRGD_NODE1_P1V5_SUS_PG")
	)
	(segment
		(start 182.91556 -121.496582)
		(end 178.684174 -117.265196)
		(width 0.1143)
		(layer "In7.Cu")
		(net "PWRGD_NODE1_P1V5_SUS_PG")
	)
	(segment
		(start 178.212242 -117.265196)
		(end 177.496724 -116.549932)
		(width 0.1143)
		(layer "In7.Cu")
		(net "PWRGD_NODE1_P1V5_SUS_PG")
	)
	(segment
		(start 55.375048 -152.25395)
		(end 55.86984 -152.748742)
		(width 0.127)
		(layer "F.Cu")
		(net "P2E_CPU_NIC1_NODE1_RX_DP")
	)
	(segment
		(start 42.702734 -66.089276)
		(end 42.595292 -66.196718)
		(width 0.127)
		(layer "F.Cu")
		(net "P2E_CPU_NIC1_NODE1_RX_DP")
	)
	(segment
		(start 42.702734 -65.481708)
		(end 42.702734 -66.089276)
		(width 0.127)
		(layer "F.Cu")
		(net "P2E_CPU_NIC1_NODE1_RX_DP")
	)
	(segment
		(start 55.13324 -152.25395)
		(end 55.375048 -152.25395)
		(width 0.127)
		(layer "F.Cu")
		(net "P2E_CPU_NIC1_NODE1_RX_DP")
	)
	(segment
		(start 54.744112 -152.643078)
		(end 55.13324 -152.25395)
		(width 0.127)
		(layer "F.Cu")
		(net "P2E_CPU_NIC1_NODE1_RX_DP")
	)
	(via
		(at 42.595292 -66.196718)
		(size 0.508)
		(drill 0.254)
		(layers "F.Cu" "B.Cu")
		(net "P2E_CPU_NIC1_NODE1_RX_DP")
	)
	(via
		(at 55.86984 -152.748742)
		(size 0.508)
		(drill 0.254)
		(layers "F.Cu" "B.Cu")
		(net "P2E_CPU_NIC1_NODE1_RX_DP")
	)
	(segment
		(start 10.369296 -106.541062)
		(end 10.30224 -104.523286)
		(width 0.127)
		(layer "In7.Cu")
		(net "P2E_CPU_NIC1_NODE1_RX_DP")
	)
	(segment
		(start 27.855418 -77.62367)
		(end 29.21508 -72.585072)
		(width 0.127)
		(layer "In7.Cu")
		(net "P2E_CPU_NIC1_NODE1_RX_DP")
	)
	(segment
		(start 11.212068 -103.399082)
		(end 12.761214 -103.215948)
		(width 0.127)
		(layer "In7.Cu")
		(net "P2E_CPU_NIC1_NODE1_RX_DP")
	)
	(segment
		(start 41.92524 -151.13762)
		(end 38.599618 -150.980902)
		(width 0.127)
		(layer "In7.Cu")
		(net "P2E_CPU_NIC1_NODE1_RX_DP")
	)
	(segment
		(start 33.69056 -66.664332)
		(end 38.96614 -67.151758)
		(width 0.127)
		(layer "In7.Cu")
		(net "P2E_CPU_NIC1_NODE1_RX_DP")
	)
	(segment
		(start 18.554192 -90.25763)
		(end 26.411682 -80.59928)
		(width 0.127)
		(layer "In7.Cu")
		(net "P2E_CPU_NIC1_NODE1_RX_DP")
	)
	(segment
		(start 52.326286 -152.259792)
		(end 50.462434 -152.958292)
		(width 0.127)
		(layer "In7.Cu")
		(net "P2E_CPU_NIC1_NODE1_RX_DP")
	)
	(segment
		(start 50.462434 -152.958292)
		(end 49.449482 -152.958292)
		(width 0.127)
		(layer "In7.Cu")
		(net "P2E_CPU_NIC1_NODE1_RX_DP")
	)
	(segment
		(start 29.21508 -72.585072)
		(end 31.00832 -67.90055)
		(width 0.127)
		(layer "In7.Cu")
		(net "P2E_CPU_NIC1_NODE1_RX_DP")
	)
	(segment
		(start 43.20032 -66.048636)
		(end 42.892472 -65.740788)
		(width 0.127)
		(layer "In7.Cu")
		(net "P2E_CPU_NIC1_NODE1_RX_DP")
	)
	(segment
		(start 55.86984 -152.748742)
		(end 55.86984 -152.386792)
		(width 0.127)
		(layer "In7.Cu")
		(net "P2E_CPU_NIC1_NODE1_RX_DP")
	)
	(segment
		(start 10.56894 -112.541812)
		(end 10.540746 -111.697516)
		(width 0.127)
		(layer "In7.Cu")
		(net "P2E_CPU_NIC1_NODE1_RX_DP")
	)
	(segment
		(start 43.20032 -66.66357)
		(end 43.20032 -66.048636)
		(width 0.127)
		(layer "In7.Cu")
		(net "P2E_CPU_NIC1_NODE1_RX_DP")
	)
	(segment
		(start 38.599618 -150.980902)
		(end 32.891222 -150.518876)
		(width 0.127)
		(layer "In7.Cu")
		(net "P2E_CPU_NIC1_NODE1_RX_DP")
	)
	(segment
		(start 47.628556 -151.664924)
		(end 41.92524 -151.13762)
		(width 0.127)
		(layer "In7.Cu")
		(net "P2E_CPU_NIC1_NODE1_RX_DP")
	)
	(segment
		(start 10.30224 -104.523286)
		(end 11.212068 -103.399082)
		(width 0.127)
		(layer "In7.Cu")
		(net "P2E_CPU_NIC1_NODE1_RX_DP")
	)
	(segment
		(start 22.41423 -139.883388)
		(end 19.344386 -139.166854)
		(width 0.127)
		(layer "In7.Cu")
		(net "P2E_CPU_NIC1_NODE1_RX_DP")
	)
	(segment
		(start 10.369296 -106.806238)
		(end 10.369296 -106.541062)
		(width 0.127)
		(layer "In7.Cu")
		(net "P2E_CPU_NIC1_NODE1_RX_DP")
	)
	(segment
		(start 12.761214 -103.215948)
		(end 15.635986 -100.662232)
		(width 0.127)
		(layer "In7.Cu")
		(net "P2E_CPU_NIC1_NODE1_RX_DP")
	)
	(segment
		(start 15.635986 -100.662232)
		(end 18.554192 -90.25763)
		(width 0.127)
		(layer "In7.Cu")
		(net "P2E_CPU_NIC1_NODE1_RX_DP")
	)
	(segment
		(start 42.568876 -65.863978)
		(end 42.595292 -66.196718)
		(width 0.127)
		(layer "In7.Cu")
		(net "P2E_CPU_NIC1_NODE1_RX_DP")
	)
	(segment
		(start 55.74284 -152.259792)
		(end 52.326286 -152.259792)
		(width 0.127)
		(layer "In7.Cu")
		(net "P2E_CPU_NIC1_NODE1_RX_DP")
	)
	(segment
		(start 32.891222 -150.518876)
		(end 24.522684 -141.570456)
		(width 0.127)
		(layer "In7.Cu")
		(net "P2E_CPU_NIC1_NODE1_RX_DP")
	)
	(segment
		(start 49.449482 -152.958292)
		(end 47.628556 -151.664924)
		(width 0.127)
		(layer "In7.Cu")
		(net "P2E_CPU_NIC1_NODE1_RX_DP")
	)
	(segment
		(start 10.540746 -111.697516)
		(end 9.988296 -109.36351)
		(width 0.127)
		(layer "In7.Cu")
		(net "P2E_CPU_NIC1_NODE1_RX_DP")
	)
	(segment
		(start 26.411682 -80.59928)
		(end 27.855418 -77.62367)
		(width 0.127)
		(layer "In7.Cu")
		(net "P2E_CPU_NIC1_NODE1_RX_DP")
	)
	(segment
		(start 42.892472 -65.740788)
		(end 42.674032 -65.740788)
		(width 0.127)
		(layer "In7.Cu")
		(net "P2E_CPU_NIC1_NODE1_RX_DP")
	)
	(segment
		(start 55.86984 -152.386792)
		(end 55.74284 -152.259792)
		(width 0.127)
		(layer "In7.Cu")
		(net "P2E_CPU_NIC1_NODE1_RX_DP")
	)
	(segment
		(start 9.988296 -109.36351)
		(end 10.369296 -106.806238)
		(width 0.127)
		(layer "In7.Cu")
		(net "P2E_CPU_NIC1_NODE1_RX_DP")
	)
	(segment
		(start 42.674032 -65.740788)
		(end 42.568876 -65.863978)
		(width 0.127)
		(layer "In7.Cu")
		(net "P2E_CPU_NIC1_NODE1_RX_DP")
	)
	(segment
		(start 18.404332 -138.947906)
		(end 17.16532 -138.08583)
		(width 0.127)
		(layer "In7.Cu")
		(net "P2E_CPU_NIC1_NODE1_RX_DP")
	)
	(segment
		(start 31.00832 -67.90055)
		(end 33.69056 -66.664332)
		(width 0.127)
		(layer "In7.Cu")
		(net "P2E_CPU_NIC1_NODE1_RX_DP")
	)
	(segment
		(start 38.96614 -67.151758)
		(end 42.43324 -67.308476)
		(width 0.127)
		(layer "In7.Cu")
		(net "P2E_CPU_NIC1_NODE1_RX_DP")
	)
	(segment
		(start 12.3825 -135.426196)
		(end 10.968736 -133.16966)
		(width 0.127)
		(layer "In7.Cu")
		(net "P2E_CPU_NIC1_NODE1_RX_DP")
	)
	(segment
		(start 19.344386 -139.166854)
		(end 18.404332 -138.947906)
		(width 0.127)
		(layer "In7.Cu")
		(net "P2E_CPU_NIC1_NODE1_RX_DP")
	)
	(segment
		(start 42.43324 -67.308476)
		(end 43.20032 -66.66357)
		(width 0.127)
		(layer "In7.Cu")
		(net "P2E_CPU_NIC1_NODE1_RX_DP")
	)
	(segment
		(start 10.968736 -133.16966)
		(end 10.56894 -112.541812)
		(width 0.127)
		(layer "In7.Cu")
		(net "P2E_CPU_NIC1_NODE1_RX_DP")
	)
	(segment
		(start 17.16532 -138.08583)
		(end 12.3825 -135.426196)
		(width 0.127)
		(layer "In7.Cu")
		(net "P2E_CPU_NIC1_NODE1_RX_DP")
	)
	(segment
		(start 24.522684 -141.570456)
		(end 22.41423 -139.883388)
		(width 0.127)
		(layer "In7.Cu")
		(net "P2E_CPU_NIC1_NODE1_RX_DP")
	)
	(segment
		(start 27.091894 -102.461314)
		(end 27.78506 -103.15448)
		(width 0.1016)
		(layer "F.Cu")
		(net "FM_CPLD_NODE1_P1V5_SUS_EN")
	)
	(segment
		(start 27.772868 -103.234236)
		(end 27.772868 -104.228646)
		(width 0.1016)
		(layer "F.Cu")
		(net "FM_CPLD_NODE1_P1V5_SUS_EN")
	)
	(segment
		(start 160.34512 -113.285778)
		(end 161.693098 -111.9378)
		(width 0.1016)
		(layer "F.Cu")
		(net "FM_CPLD_NODE1_P1V5_SUS_EN")
	)
	(segment
		(start 27.88539 -100.498148)
		(end 26.882598 -101.50094)
		(width 0.1016)
		(layer "F.Cu")
		(net "FM_CPLD_NODE1_P1V5_SUS_EN")
	)
	(segment
		(start 27.78506 -103.221282)
		(end 27.785822 -103.221282)
		(width 0.1016)
		(layer "F.Cu")
		(net "FM_CPLD_NODE1_P1V5_SUS_EN")
	)
	(segment
		(start 80.105504 -106.682794)
		(end 79.034894 -106.682794)
		(width 0.1016)
		(layer "F.Cu")
		(net "FM_CPLD_NODE1_P1V5_SUS_EN")
	)
	(segment
		(start 29.055568 -104.21493)
		(end 29.041852 -104.228646)
		(width 0.1016)
		(layer "F.Cu")
		(net "FM_CPLD_NODE1_P1V5_SUS_EN")
	)
	(segment
		(start 42.001948 -104.90708)
		(end 36.73983 -99.644962)
		(width 0.1016)
		(layer "F.Cu")
		(net "FM_CPLD_NODE1_P1V5_SUS_EN")
	)
	(segment
		(start 79.034894 -106.682794)
		(end 77.25918 -104.90708)
		(width 0.1016)
		(layer "F.Cu")
		(net "FM_CPLD_NODE1_P1V5_SUS_EN")
	)
	(segment
		(start 173.574202 -112.498378)
		(end 176.01057 -114.934746)
		(width 0.1016)
		(layer "F.Cu")
		(net "FM_CPLD_NODE1_P1V5_SUS_EN")
	)
	(segment
		(start 27.090624 -102.461314)
		(end 27.091894 -102.461314)
		(width 0.1016)
		(layer "F.Cu")
		(net "FM_CPLD_NODE1_P1V5_SUS_EN")
	)
	(segment
		(start 30.75686 -99.644962)
		(end 29.88818 -100.513642)
		(width 0.1016)
		(layer "F.Cu")
		(net "FM_CPLD_NODE1_P1V5_SUS_EN")
	)
	(segment
		(start 29.512006 -100.498148)
		(end 27.88539 -100.498148)
		(width 0.1016)
		(layer "F.Cu")
		(net "FM_CPLD_NODE1_P1V5_SUS_EN")
	)
	(segment
		(start 176.01057 -114.934746)
		(end 176.01057 -116.365528)
		(width 0.1016)
		(layer "F.Cu")
		(net "FM_CPLD_NODE1_P1V5_SUS_EN")
	)
	(segment
		(start 26.882598 -101.50094)
		(end 26.882598 -102.253288)
		(width 0.1016)
		(layer "F.Cu")
		(net "FM_CPLD_NODE1_P1V5_SUS_EN")
	)
	(segment
		(start 36.73983 -99.644962)
		(end 30.75686 -99.644962)
		(width 0.1016)
		(layer "F.Cu")
		(net "FM_CPLD_NODE1_P1V5_SUS_EN")
	)
	(segment
		(start 30.235906 -104.21493)
		(end 29.055568 -104.21493)
		(width 0.1016)
		(layer "F.Cu")
		(net "FM_CPLD_NODE1_P1V5_SUS_EN")
	)
	(segment
		(start 29.041852 -104.228646)
		(end 27.772868 -104.228646)
		(width 0.1016)
		(layer "F.Cu")
		(net "FM_CPLD_NODE1_P1V5_SUS_EN")
	)
	(segment
		(start 29.5275 -100.513642)
		(end 29.512006 -100.498148)
		(width 0.1016)
		(layer "F.Cu")
		(net "FM_CPLD_NODE1_P1V5_SUS_EN")
	)
	(segment
		(start 161.693098 -111.9378)
		(end 170.094402 -111.9378)
		(width 0.1016)
		(layer "F.Cu")
		(net "FM_CPLD_NODE1_P1V5_SUS_EN")
	)
	(segment
		(start 27.78506 -103.15448)
		(end 27.78506 -103.221282)
		(width 0.1016)
		(layer "F.Cu")
		(net "FM_CPLD_NODE1_P1V5_SUS_EN")
	)
	(segment
		(start 170.094402 -111.9378)
		(end 170.65498 -112.498378)
		(width 0.1016)
		(layer "F.Cu")
		(net "FM_CPLD_NODE1_P1V5_SUS_EN")
	)
	(segment
		(start 29.88818 -100.513642)
		(end 29.5275 -100.513642)
		(width 0.1016)
		(layer "F.Cu")
		(net "FM_CPLD_NODE1_P1V5_SUS_EN")
	)
	(segment
		(start 80.55356 -107.13085)
		(end 80.105504 -106.682794)
		(width 0.1016)
		(layer "F.Cu")
		(net "FM_CPLD_NODE1_P1V5_SUS_EN")
	)
	(segment
		(start 27.785822 -103.221282)
		(end 27.772868 -103.234236)
		(width 0.1016)
		(layer "F.Cu")
		(net "FM_CPLD_NODE1_P1V5_SUS_EN")
	)
	(segment
		(start 26.882598 -102.253288)
		(end 27.090624 -102.461314)
		(width 0.1016)
		(layer "F.Cu")
		(net "FM_CPLD_NODE1_P1V5_SUS_EN")
	)
	(segment
		(start 170.65498 -112.498378)
		(end 173.574202 -112.498378)
		(width 0.1016)
		(layer "F.Cu")
		(net "FM_CPLD_NODE1_P1V5_SUS_EN")
	)
	(segment
		(start 77.25918 -104.90708)
		(end 42.001948 -104.90708)
		(width 0.1016)
		(layer "F.Cu")
		(net "FM_CPLD_NODE1_P1V5_SUS_EN")
	)
	(via
		(at 80.55356 -107.13085)
		(size 0.508)
		(drill 0.254)
		(layers "F.Cu" "B.Cu")
		(net "FM_CPLD_NODE1_P1V5_SUS_EN")
	)
	(via
		(at 160.34512 -113.285778)
		(size 0.508)
		(drill 0.254)
		(layers "F.Cu" "B.Cu")
		(net "FM_CPLD_NODE1_P1V5_SUS_EN")
	)
	(segment
		(start 160.34512 -113.285778)
		(end 160.31464 -113.255298)
		(width 0.1143)
		(layer "In6.Cu")
		(net "FM_CPLD_NODE1_P1V5_SUS_EN")
	)
	(segment
		(start 132.79628 -106.306366)
		(end 131.660646 -105.170732)
		(width 0.1143)
		(layer "In6.Cu")
		(net "FM_CPLD_NODE1_P1V5_SUS_EN")
	)
	(segment
		(start 89.984072 -113.847372)
		(end 89.789762 -113.847372)
		(width 0.1143)
		(layer "In6.Cu")
		(net "FM_CPLD_NODE1_P1V5_SUS_EN")
	)
	(segment
		(start 132.79628 -107.353862)
		(end 132.79628 -106.306366)
		(width 0.1143)
		(layer "In6.Cu")
		(net "FM_CPLD_NODE1_P1V5_SUS_EN")
	)
	(segment
		(start 90.77579 -114.63909)
		(end 89.984072 -113.847372)
		(width 0.1143)
		(layer "In6.Cu")
		(net "FM_CPLD_NODE1_P1V5_SUS_EN")
	)
	(segment
		(start 145.142204 -108.268262)
		(end 133.71068 -108.268262)
		(width 0.1143)
		(layer "In6.Cu")
		(net "FM_CPLD_NODE1_P1V5_SUS_EN")
	)
	(segment
		(start 121.74855 -105.170732)
		(end 119.527574 -107.391708)
		(width 0.1143)
		(layer "In6.Cu")
		(net "FM_CPLD_NODE1_P1V5_SUS_EN")
	)
	(segment
		(start 83.389216 -109.855254)
		(end 81.991962 -108.458)
		(width 0.1143)
		(layer "In6.Cu")
		(net "FM_CPLD_NODE1_P1V5_SUS_EN")
	)
	(segment
		(start 89.789762 -113.847372)
		(end 85.797644 -109.855254)
		(width 0.1143)
		(layer "In6.Cu")
		(net "FM_CPLD_NODE1_P1V5_SUS_EN")
	)
	(segment
		(start 150.12924 -113.255298)
		(end 145.142204 -108.268262)
		(width 0.1143)
		(layer "In6.Cu")
		(net "FM_CPLD_NODE1_P1V5_SUS_EN")
	)
	(segment
		(start 95.35668 -113.406174)
		(end 94.123764 -114.63909)
		(width 0.1143)
		(layer "In6.Cu")
		(net "FM_CPLD_NODE1_P1V5_SUS_EN")
	)
	(segment
		(start 100.473764 -107.391708)
		(end 95.35668 -112.508792)
		(width 0.1143)
		(layer "In6.Cu")
		(net "FM_CPLD_NODE1_P1V5_SUS_EN")
	)
	(segment
		(start 119.527574 -107.391708)
		(end 100.473764 -107.391708)
		(width 0.1143)
		(layer "In6.Cu")
		(net "FM_CPLD_NODE1_P1V5_SUS_EN")
	)
	(segment
		(start 81.991962 -108.397802)
		(end 81.32826 -107.733846)
		(width 0.1143)
		(layer "In6.Cu")
		(net "FM_CPLD_NODE1_P1V5_SUS_EN")
	)
	(segment
		(start 81.156556 -107.733846)
		(end 80.55356 -107.13085)
		(width 0.1143)
		(layer "In6.Cu")
		(net "FM_CPLD_NODE1_P1V5_SUS_EN")
	)
	(segment
		(start 95.35668 -112.508792)
		(end 95.35668 -113.406174)
		(width 0.1143)
		(layer "In6.Cu")
		(net "FM_CPLD_NODE1_P1V5_SUS_EN")
	)
	(segment
		(start 131.660646 -105.170732)
		(end 121.74855 -105.170732)
		(width 0.1143)
		(layer "In6.Cu")
		(net "FM_CPLD_NODE1_P1V5_SUS_EN")
	)
	(segment
		(start 94.123764 -114.63909)
		(end 90.77579 -114.63909)
		(width 0.1143)
		(layer "In6.Cu")
		(net "FM_CPLD_NODE1_P1V5_SUS_EN")
	)
	(segment
		(start 81.32826 -107.733846)
		(end 81.156556 -107.733846)
		(width 0.1143)
		(layer "In6.Cu")
		(net "FM_CPLD_NODE1_P1V5_SUS_EN")
	)
	(segment
		(start 133.71068 -108.268262)
		(end 132.79628 -107.353862)
		(width 0.1143)
		(layer "In6.Cu")
		(net "FM_CPLD_NODE1_P1V5_SUS_EN")
	)
	(segment
		(start 160.31464 -113.255298)
		(end 150.12924 -113.255298)
		(width 0.1143)
		(layer "In6.Cu")
		(net "FM_CPLD_NODE1_P1V5_SUS_EN")
	)
	(segment
		(start 85.797644 -109.855254)
		(end 83.389216 -109.855254)
		(width 0.1143)
		(layer "In6.Cu")
		(net "FM_CPLD_NODE1_P1V5_SUS_EN")
	)
	(segment
		(start 81.991962 -108.458)
		(end 81.991962 -108.397802)
		(width 0.1143)
		(layer "In6.Cu")
		(net "FM_CPLD_NODE1_P1V5_SUS_EN")
	)
	(segment
		(start 60.022486 -121.984262)
		(end 59.816238 -121.778014)
		(width 0.1016)
		(layer "F.Cu")
		(net "BMC_ROMA1")
	)
	(segment
		(start 59.816238 -121.778014)
		(end 59.816238 -119.04726)
		(width 0.1016)
		(layer "F.Cu")
		(net "BMC_ROMA1")
	)
	(segment
		(start 60.352686 -117.773704)
		(end 60.56122 -117.56517)
		(width 0.1016)
		(layer "F.Cu")
		(net "BMC_ROMA1")
	)
	(segment
		(start 60.352686 -118.510812)
		(end 60.352686 -117.773704)
		(width 0.1016)
		(layer "F.Cu")
		(net "BMC_ROMA1")
	)
	(segment
		(start 62.941708 -127.259588)
		(end 62.941708 -127.068072)
		(width 0.1016)
		(layer "F.Cu")
		(net "BMC_ROMA1")
	)
	(segment
		(start 61.944504 -125.63348)
		(end 61.944504 -125.474222)
		(width 0.1016)
		(layer "F.Cu")
		(net "BMC_ROMA1")
	)
	(segment
		(start 62.576964 -126.703328)
		(end 62.576964 -126.26594)
		(width 0.1016)
		(layer "F.Cu")
		(net "BMC_ROMA1")
	)
	(segment
		(start 62.941708 -127.068072)
		(end 62.576964 -126.703328)
		(width 0.1016)
		(layer "F.Cu")
		(net "BMC_ROMA1")
	)
	(segment
		(start 60.56122 -117.56517)
		(end 60.56122 -116.925852)
		(width 0.1016)
		(layer "F.Cu")
		(net "BMC_ROMA1")
	)
	(segment
		(start 62.576964 -126.26594)
		(end 61.944504 -125.63348)
		(width 0.1016)
		(layer "F.Cu")
		(net "BMC_ROMA1")
	)
	(segment
		(start 60.022486 -122.670062)
		(end 60.022486 -121.984262)
		(width 0.1016)
		(layer "F.Cu")
		(net "BMC_ROMA1")
	)
	(segment
		(start 61.597286 -124.244862)
		(end 60.022486 -122.670062)
		(width 0.1016)
		(layer "F.Cu")
		(net "BMC_ROMA1")
	)
	(segment
		(start 61.597286 -125.127004)
		(end 61.597286 -124.244862)
		(width 0.1016)
		(layer "F.Cu")
		(net "BMC_ROMA1")
	)
	(segment
		(start 61.944504 -125.474222)
		(end 61.597286 -125.127004)
		(width 0.1016)
		(layer "F.Cu")
		(net "BMC_ROMA1")
	)
	(segment
		(start 59.816238 -119.04726)
		(end 60.352686 -118.510812)
		(width 0.1016)
		(layer "F.Cu")
		(net "BMC_ROMA1")
	)
	(via
		(at 60.56122 -116.925852)
		(size 0.508)
		(drill 0.254)
		(layers "F.Cu" "B.Cu")
		(net "BMC_ROMA1")
	)
	(segment
		(start 61.571124 -89.716864)
		(end 61.429392 -89.858596)
		(width 0.3048)
		(layer "F.Cu")
		(net "A_CPU_NODE1_NTB_CROSSLK_MODE")
	)
	(segment
		(start 61.429392 -89.858596)
		(end 61.429392 -93.257116)
		(width 0.508)
		(layer "F.Cu")
		(net "A_CPU_NODE1_NTB_CROSSLK_MODE")
	)
	(segment
		(start 63.177166 -95.960438)
		(end 61.741812 -94.525084)
		(width 0.508)
		(layer "F.Cu")
		(net "A_CPU_NODE1_NTB_CROSSLK_MODE")
	)
	(segment
		(start 63.177166 -96.309942)
		(end 63.177166 -95.960438)
		(width 0.508)
		(layer "F.Cu")
		(net "A_CPU_NODE1_NTB_CROSSLK_MODE")
	)
	(segment
		(start 61.571124 -88.683338)
		(end 61.571124 -89.716864)
		(width 0.3048)
		(layer "F.Cu")
		(net "A_CPU_NODE1_NTB_CROSSLK_MODE")
	)
	(segment
		(start 61.64072 -88.613742)
		(end 61.571124 -88.683338)
		(width 0.3048)
		(layer "F.Cu")
		(net "A_CPU_NODE1_NTB_CROSSLK_MODE")
	)
	(segment
		(start 61.429392 -93.257116)
		(end 61.741812 -93.569536)
		(width 0.508)
		(layer "F.Cu")
		(net "A_CPU_NODE1_NTB_CROSSLK_MODE")
	)
	(segment
		(start 61.64072 -88.605106)
		(end 61.64072 -88.613742)
		(width 0.3048)
		(layer "F.Cu")
		(net "A_CPU_NODE1_NTB_CROSSLK_MODE")
	)
	(segment
		(start 61.741812 -94.525084)
		(end 61.741812 -93.569536)
		(width 0.508)
		(layer "F.Cu")
		(net "A_CPU_NODE1_NTB_CROSSLK_MODE")
	)
	(via
		(at 61.741812 -93.569536)
		(size 0.508)
		(drill 0.254)
		(layers "F.Cu" "B.Cu")
		(net "A_CPU_NODE1_NTB_CROSSLK_MODE")
	)
	(segment
		(start 55.066184 -151.94915)
		(end 55.399432 -151.94915)
		(width 0.127)
		(layer "F.Cu")
		(net "P2E_CPU_NIC1_NODE1_RX_DN")
	)
	(segment
		(start 42.591228 -64.89573)
		(end 42.499788 -64.98717)
		(width 0.127)
		(layer "F.Cu")
		(net "P2E_CPU_NIC1_NODE1_RX_DN")
	)
	(segment
		(start 55.399432 -151.94915)
		(end 55.86984 -151.478742)
		(width 0.127)
		(layer "F.Cu")
		(net "P2E_CPU_NIC1_NODE1_RX_DN")
	)
	(segment
		(start 54.744112 -151.627078)
		(end 55.066184 -151.94915)
		(width 0.127)
		(layer "F.Cu")
		(net "P2E_CPU_NIC1_NODE1_RX_DN")
	)
	(segment
		(start 43.099736 -64.89573)
		(end 42.591228 -64.89573)
		(width 0.127)
		(layer "F.Cu")
		(net "P2E_CPU_NIC1_NODE1_RX_DN")
	)
	(via
		(at 42.499788 -64.98717)
		(size 0.508)
		(drill 0.254)
		(layers "F.Cu" "B.Cu")
		(net "P2E_CPU_NIC1_NODE1_RX_DN")
	)
	(via
		(at 55.86984 -151.478742)
		(size 0.508)
		(drill 0.254)
		(layers "F.Cu" "B.Cu")
		(net "P2E_CPU_NIC1_NODE1_RX_DN")
	)
	(segment
		(start 47.733712 -151.381206)
		(end 41.94556 -150.846028)
		(width 0.127)
		(layer "In7.Cu")
		(net "P2E_CPU_NIC1_NODE1_RX_DN")
	)
	(segment
		(start 10.597896 -104.622346)
		(end 11.364468 -103.675434)
		(width 0.127)
		(layer "In7.Cu")
		(net "P2E_CPU_NIC1_NODE1_RX_DN")
	)
	(segment
		(start 41.94556 -150.846028)
		(end 38.61816 -150.68931)
		(width 0.127)
		(layer "In7.Cu")
		(net "P2E_CPU_NIC1_NODE1_RX_DN")
	)
	(segment
		(start 55.74284 -151.967692)
		(end 52.2732 -151.967692)
		(width 0.127)
		(layer "In7.Cu")
		(net "P2E_CPU_NIC1_NODE1_RX_DN")
	)
	(segment
		(start 11.259312 -133.083046)
		(end 10.86104 -112.534192)
		(width 0.127)
		(layer "In7.Cu")
		(net "P2E_CPU_NIC1_NODE1_RX_DN")
	)
	(segment
		(start 42.526204 -65.319656)
		(end 42.499788 -64.98717)
		(width 0.127)
		(layer "In7.Cu")
		(net "P2E_CPU_NIC1_NODE1_RX_DN")
	)
	(segment
		(start 26.65984 -80.757522)
		(end 28.1305 -77.72654)
		(width 0.127)
		(layer "In7.Cu")
		(net "P2E_CPU_NIC1_NODE1_RX_DN")
	)
	(segment
		(start 38.946074 -67.44335)
		(end 42.534078 -67.605656)
		(width 0.127)
		(layer "In7.Cu")
		(net "P2E_CPU_NIC1_NODE1_RX_DN")
	)
	(segment
		(start 33.02762 -150.236682)
		(end 24.72182 -141.355318)
		(width 0.127)
		(layer "In7.Cu")
		(net "P2E_CPU_NIC1_NODE1_RX_DN")
	)
	(segment
		(start 28.1305 -77.72654)
		(end 29.493464 -72.67575)
		(width 0.127)
		(layer "In7.Cu")
		(net "P2E_CPU_NIC1_NODE1_RX_DN")
	)
	(segment
		(start 24.72182 -141.355318)
		(end 22.54504 -139.613894)
		(width 0.127)
		(layer "In7.Cu")
		(net "P2E_CPU_NIC1_NODE1_RX_DN")
	)
	(segment
		(start 10.86104 -112.534192)
		(end 10.83183 -111.658654)
		(width 0.127)
		(layer "In7.Cu")
		(net "P2E_CPU_NIC1_NODE1_RX_DN")
	)
	(segment
		(start 18.819368 -90.395044)
		(end 26.65984 -80.757522)
		(width 0.127)
		(layer "In7.Cu")
		(net "P2E_CPU_NIC1_NODE1_RX_DN")
	)
	(segment
		(start 42.677842 -65.448688)
		(end 42.526204 -65.319656)
		(width 0.127)
		(layer "In7.Cu")
		(net "P2E_CPU_NIC1_NODE1_RX_DN")
	)
	(segment
		(start 12.88669 -103.495348)
		(end 15.89405 -100.823776)
		(width 0.127)
		(layer "In7.Cu")
		(net "P2E_CPU_NIC1_NODE1_RX_DN")
	)
	(segment
		(start 33.741614 -66.962528)
		(end 38.946074 -67.44335)
		(width 0.127)
		(layer "In7.Cu")
		(net "P2E_CPU_NIC1_NODE1_RX_DN")
	)
	(segment
		(start 19.41068 -138.882374)
		(end 18.525236 -138.676126)
		(width 0.127)
		(layer "In7.Cu")
		(net "P2E_CPU_NIC1_NODE1_RX_DN")
	)
	(segment
		(start 43.01363 -65.448688)
		(end 42.677842 -65.448688)
		(width 0.127)
		(layer "In7.Cu")
		(net "P2E_CPU_NIC1_NODE1_RX_DN")
	)
	(segment
		(start 10.661396 -106.535982)
		(end 10.597896 -104.622346)
		(width 0.127)
		(layer "In7.Cu")
		(net "P2E_CPU_NIC1_NODE1_RX_DN")
	)
	(segment
		(start 22.54504 -139.613894)
		(end 19.41068 -138.882374)
		(width 0.127)
		(layer "In7.Cu")
		(net "P2E_CPU_NIC1_NODE1_RX_DN")
	)
	(segment
		(start 49.5427 -152.666192)
		(end 47.733712 -151.381206)
		(width 0.127)
		(layer "In7.Cu")
		(net "P2E_CPU_NIC1_NODE1_RX_DN")
	)
	(segment
		(start 55.86984 -151.478742)
		(end 55.86984 -151.840692)
		(width 0.127)
		(layer "In7.Cu")
		(net "P2E_CPU_NIC1_NODE1_RX_DN")
	)
	(segment
		(start 10.83183 -111.658654)
		(end 10.28573 -109.35081)
		(width 0.127)
		(layer "In7.Cu")
		(net "P2E_CPU_NIC1_NODE1_RX_DN")
	)
	(segment
		(start 10.28573 -109.35081)
		(end 10.661396 -106.828082)
		(width 0.127)
		(layer "In7.Cu")
		(net "P2E_CPU_NIC1_NODE1_RX_DN")
	)
	(segment
		(start 55.86984 -151.840692)
		(end 55.74284 -151.967692)
		(width 0.127)
		(layer "In7.Cu")
		(net "P2E_CPU_NIC1_NODE1_RX_DN")
	)
	(segment
		(start 42.534078 -67.605656)
		(end 43.49242 -66.799714)
		(width 0.127)
		(layer "In7.Cu")
		(net "P2E_CPU_NIC1_NODE1_RX_DN")
	)
	(segment
		(start 43.49242 -66.799714)
		(end 43.49242 -65.927478)
		(width 0.127)
		(layer "In7.Cu")
		(net "P2E_CPU_NIC1_NODE1_RX_DN")
	)
	(segment
		(start 18.525236 -138.676126)
		(end 17.32026 -137.837418)
		(width 0.127)
		(layer "In7.Cu")
		(net "P2E_CPU_NIC1_NODE1_RX_DN")
	)
	(segment
		(start 17.32026 -137.837418)
		(end 12.590272 -135.207248)
		(width 0.127)
		(layer "In7.Cu")
		(net "P2E_CPU_NIC1_NODE1_RX_DN")
	)
	(segment
		(start 31.238698 -68.116196)
		(end 33.741614 -66.962528)
		(width 0.127)
		(layer "In7.Cu")
		(net "P2E_CPU_NIC1_NODE1_RX_DN")
	)
	(segment
		(start 29.493464 -72.67575)
		(end 31.238698 -68.116196)
		(width 0.127)
		(layer "In7.Cu")
		(net "P2E_CPU_NIC1_NODE1_RX_DN")
	)
	(segment
		(start 15.89405 -100.823776)
		(end 18.819368 -90.395044)
		(width 0.127)
		(layer "In7.Cu")
		(net "P2E_CPU_NIC1_NODE1_RX_DN")
	)
	(segment
		(start 12.590272 -135.207248)
		(end 11.259312 -133.083046)
		(width 0.127)
		(layer "In7.Cu")
		(net "P2E_CPU_NIC1_NODE1_RX_DN")
	)
	(segment
		(start 43.49242 -65.927478)
		(end 43.01363 -65.448688)
		(width 0.127)
		(layer "In7.Cu")
		(net "P2E_CPU_NIC1_NODE1_RX_DN")
	)
	(segment
		(start 50.409348 -152.666192)
		(end 49.5427 -152.666192)
		(width 0.127)
		(layer "In7.Cu")
		(net "P2E_CPU_NIC1_NODE1_RX_DN")
	)
	(segment
		(start 11.364468 -103.675434)
		(end 12.88669 -103.495348)
		(width 0.127)
		(layer "In7.Cu")
		(net "P2E_CPU_NIC1_NODE1_RX_DN")
	)
	(segment
		(start 38.61816 -150.68931)
		(end 33.02762 -150.236682)
		(width 0.127)
		(layer "In7.Cu")
		(net "P2E_CPU_NIC1_NODE1_RX_DN")
	)
	(segment
		(start 10.661396 -106.828082)
		(end 10.661396 -106.535982)
		(width 0.127)
		(layer "In7.Cu")
		(net "P2E_CPU_NIC1_NODE1_RX_DN")
	)
	(segment
		(start 52.2732 -151.967692)
		(end 50.409348 -152.666192)
		(width 0.127)
		(layer "In7.Cu")
		(net "P2E_CPU_NIC1_NODE1_RX_DN")
	)
	(segment
		(start 35.94354 -104.502712)
		(end 35.94354 -107.090718)
		(width 0.1016)
		(layer "F.Cu")
		(net "P1V5_SUS_NODE1_ADJ")
	)
	(segment
		(start 35.94354 -107.090718)
		(end 36.128706 -107.275884)
		(width 0.1016)
		(layer "F.Cu")
		(net "P1V5_SUS_NODE1_ADJ")
	)
	(via
		(at 36.128706 -107.275884)
		(size 0.508)
		(drill 0.254)
		(layers "F.Cu" "B.Cu")
		(net "P1V5_SUS_NODE1_ADJ")
	)
	(segment
		(start 64.541908 -129.659126)
		(end 64.141096 -129.258314)
		(width 0.1016)
		(layer "F.Cu")
		(net "BMC_ROMA17")
	)
	(segment
		(start 64.541908 -129.659634)
		(end 64.541908 -129.659126)
		(width 0.1016)
		(layer "F.Cu")
		(net "BMC_ROMA17")
	)
	(via
		(at 64.141096 -129.258314)
		(size 0.49022)
		(drill 0.254)
		(layers "F.Cu" "B.Cu")
		(net "BMC_ROMA17")
	)
	(via
		(at 64.769746 -123.383802)
		(size 0.6604)
		(drill 0.3302)
		(layers "F.Cu" "B.Cu")
		(net "BMC_ROMA17")
	)
	(segment
		(start 64.086486 -125.083062)
		(end 64.340486 -125.337062)
		(width 0.1016)
		(layer "B.Cu")
		(net "BMC_ROMA17")
	)
	(segment
		(start 66.194686 -118.358412)
		(end 65.686686 -118.866412)
		(width 0.1016)
		(layer "B.Cu")
		(net "BMC_ROMA17")
	)
	(segment
		(start 64.538606 -127.313182)
		(end 64.538606 -128.860804)
		(width 0.1016)
		(layer "B.Cu")
		(net "BMC_ROMA17")
	)
	(segment
		(start 64.538606 -128.860804)
		(end 64.141096 -129.258314)
		(width 0.1016)
		(layer "B.Cu")
		(net "BMC_ROMA17")
	)
	(segment
		(start 65.686686 -122.187462)
		(end 64.769746 -123.104402)
		(width 0.1016)
		(layer "B.Cu")
		(net "BMC_ROMA17")
	)
	(segment
		(start 64.769746 -123.383802)
		(end 64.086486 -124.067062)
		(width 0.1016)
		(layer "B.Cu")
		(net "BMC_ROMA17")
	)
	(segment
		(start 64.086486 -124.067062)
		(end 64.086486 -125.083062)
		(width 0.1016)
		(layer "B.Cu")
		(net "BMC_ROMA17")
	)
	(segment
		(start 64.769746 -123.104402)
		(end 64.769746 -123.383802)
		(width 0.1016)
		(layer "B.Cu")
		(net "BMC_ROMA17")
	)
	(segment
		(start 64.340486 -125.337062)
		(end 64.340486 -127.115062)
		(width 0.1016)
		(layer "B.Cu")
		(net "BMC_ROMA17")
	)
	(segment
		(start 64.340486 -127.115062)
		(end 64.538606 -127.313182)
		(width 0.1016)
		(layer "B.Cu")
		(net "BMC_ROMA17")
	)
	(segment
		(start 65.686686 -118.866412)
		(end 65.686686 -122.187462)
		(width 0.1016)
		(layer "B.Cu")
		(net "BMC_ROMA17")
	)
	(segment
		(start 57.586372 -22.70379)
		(end 57.56148 -22.70379)
		(width 0.1016)
		(layer "F.Cu")
		(net "PD_NODE1_DM3")
	)
	(segment
		(start 57.750202 -20.94992)
		(end 57.750202 -22.53996)
		(width 0.1016)
		(layer "F.Cu")
		(net "PD_NODE1_DM3")
	)
	(segment
		(start 57.750202 -22.53996)
		(end 57.586372 -22.70379)
		(width 0.1016)
		(layer "F.Cu")
		(net "PD_NODE1_DM3")
	)
	(via
		(at 57.56148 -22.70379)
		(size 0.508)
		(drill 0.254)
		(layers "F.Cu" "B.Cu")
		(net "PD_NODE1_DM3")
	)
	(segment
		(start 57.08396 -22.22627)
		(end 57.56148 -22.70379)
		(width 0.1016)
		(layer "B.Cu")
		(net "PD_NODE1_DM3")
	)
	(segment
		(start 57.08396 -21.495766)
		(end 57.08396 -22.22627)
		(width 0.1016)
		(layer "B.Cu")
		(net "PD_NODE1_DM3")
	)
	(segment
		(start 38.672008 -67.690238)
		(end 38.82009 -67.582796)
		(width 0.127)
		(layer "F.Cu")
		(net "P2E_CPU_NIC2_NODE1_RX_DP")
	)
	(segment
		(start 40.322246 -67.611244)
		(end 40.3225 -67.611498)
		(width 0.127)
		(layer "F.Cu")
		(net "P2E_CPU_NIC2_NODE1_RX_DP")
	)
	(segment
		(start 38.188392 -67.480688)
		(end 38.295326 -67.62877)
		(width 0.127)
		(layer "F.Cu")
		(net "P2E_CPU_NIC2_NODE1_RX_DP")
	)
	(segment
		(start 34.722816 -69.175122)
		(end 34.957004 -68.873878)
		(width 0.127)
		(layer "F.Cu")
		(net "P2E_CPU_NIC2_NODE1_RX_DP")
	)
	(segment
		(start 38.99408 -67.611244)
		(end 39.321486 -67.611244)
		(width 0.127)
		(layer "F.Cu")
		(net "P2E_CPU_NIC2_NODE1_RX_DP")
	)
	(segment
		(start 39.836598 -67.74561)
		(end 39.97071 -67.611244)
		(width 0.127)
		(layer "F.Cu")
		(net "P2E_CPU_NIC2_NODE1_RX_DP")
	)
	(segment
		(start 34.506916 -69.201792)
		(end 34.722816 -69.175122)
		(width 0.127)
		(layer "F.Cu")
		(net "P2E_CPU_NIC2_NODE1_RX_DP")
	)
	(segment
		(start 36.393374 -67.285362)
		(end 36.985956 -67.285362)
		(width 0.127)
		(layer "F.Cu")
		(net "P2E_CPU_NIC2_NODE1_RX_DP")
	)
	(segment
		(start 35.898582 -67.83324)
		(end 36.20135 -67.60083)
		(width 0.127)
		(layer "F.Cu")
		(net "P2E_CPU_NIC2_NODE1_RX_DP")
	)
	(segment
		(start 33.314132 -69.723254)
		(end 33.883092 -69.723254)
		(width 0.127)
		(layer "F.Cu")
		(net "P2E_CPU_NIC2_NODE1_RX_DP")
	)
	(segment
		(start 33.883092 -69.723254)
		(end 34.378138 -69.367654)
		(width 0.127)
		(layer "F.Cu")
		(net "P2E_CPU_NIC2_NODE1_RX_DP")
	)
	(segment
		(start 36.985956 -67.285362)
		(end 37.180012 -67.317112)
		(width 0.127)
		(layer "F.Cu")
		(net "P2E_CPU_NIC2_NODE1_RX_DP")
	)
	(segment
		(start 34.378138 -69.367654)
		(end 34.506916 -69.201792)
		(width 0.127)
		(layer "F.Cu")
		(net "P2E_CPU_NIC2_NODE1_RX_DP")
	)
	(segment
		(start 36.22548 -67.414394)
		(end 36.393374 -67.285362)
		(width 0.127)
		(layer "F.Cu")
		(net "P2E_CPU_NIC2_NODE1_RX_DP")
	)
	(segment
		(start 40.3225 -67.611498)
		(end 41.69791 -67.611498)
		(width 0.127)
		(layer "F.Cu")
		(net "P2E_CPU_NIC2_NODE1_RX_DP")
	)
	(segment
		(start 39.455598 -67.74561)
		(end 39.836598 -67.74561)
		(width 0.127)
		(layer "F.Cu")
		(net "P2E_CPU_NIC2_NODE1_RX_DP")
	)
	(segment
		(start 42.219372 -67.38239)
		(end 42.248328 -67.411346)
		(width 0.127)
		(layer "F.Cu")
		(net "P2E_CPU_NIC2_NODE1_RX_DP")
	)
	(segment
		(start 39.97071 -67.611244)
		(end 40.322246 -67.611244)
		(width 0.127)
		(layer "F.Cu")
		(net "P2E_CPU_NIC2_NODE1_RX_DP")
	)
	(segment
		(start 38.295326 -67.62877)
		(end 38.672008 -67.690238)
		(width 0.127)
		(layer "F.Cu")
		(net "P2E_CPU_NIC2_NODE1_RX_DP")
	)
	(segment
		(start 37.180012 -67.317112)
		(end 37.286946 -67.465194)
		(width 0.127)
		(layer "F.Cu")
		(net "P2E_CPU_NIC2_NODE1_RX_DP")
	)
	(segment
		(start 150.369778 -155.6766)
		(end 150.713948 -155.33243)
		(width 0.127)
		(layer "F.Cu")
		(net "P2E_CPU_NIC2_NODE1_RX_DP")
	)
	(segment
		(start 34.957004 -68.873878)
		(end 34.929318 -68.657724)
		(width 0.127)
		(layer "F.Cu")
		(net "P2E_CPU_NIC2_NODE1_RX_DP")
	)
	(segment
		(start 41.69791 -67.611498)
		(end 41.927018 -67.38239)
		(width 0.127)
		(layer "F.Cu")
		(net "P2E_CPU_NIC2_NODE1_RX_DP")
	)
	(segment
		(start 38.82009 -67.582796)
		(end 38.99408 -67.611244)
		(width 0.127)
		(layer "F.Cu")
		(net "P2E_CPU_NIC2_NODE1_RX_DP")
	)
	(segment
		(start 33.102296 -70.382384)
		(end 33.102296 -69.93509)
		(width 0.127)
		(layer "F.Cu")
		(net "P2E_CPU_NIC2_NODE1_RX_DP")
	)
	(segment
		(start 149.55012 -155.208224)
		(end 150.018496 -155.6766)
		(width 0.127)
		(layer "F.Cu")
		(net "P2E_CPU_NIC2_NODE1_RX_DP")
	)
	(segment
		(start 34.929318 -68.657724)
		(end 35.406076 -68.043298)
		(width 0.127)
		(layer "F.Cu")
		(net "P2E_CPU_NIC2_NODE1_RX_DP")
	)
	(segment
		(start 37.81171 -67.41922)
		(end 38.188392 -67.480688)
		(width 0.127)
		(layer "F.Cu")
		(net "P2E_CPU_NIC2_NODE1_RX_DP")
	)
	(segment
		(start 150.018496 -155.6766)
		(end 150.369778 -155.6766)
		(width 0.127)
		(layer "F.Cu")
		(net "P2E_CPU_NIC2_NODE1_RX_DP")
	)
	(segment
		(start 35.406076 -68.043298)
		(end 35.7124 -67.808348)
		(width 0.127)
		(layer "F.Cu")
		(net "P2E_CPU_NIC2_NODE1_RX_DP")
	)
	(segment
		(start 33.102296 -69.93509)
		(end 33.314132 -69.723254)
		(width 0.127)
		(layer "F.Cu")
		(net "P2E_CPU_NIC2_NODE1_RX_DP")
	)
	(segment
		(start 35.7124 -67.808348)
		(end 35.898582 -67.83324)
		(width 0.127)
		(layer "F.Cu")
		(net "P2E_CPU_NIC2_NODE1_RX_DP")
	)
	(segment
		(start 39.321486 -67.611244)
		(end 39.455598 -67.74561)
		(width 0.127)
		(layer "F.Cu")
		(net "P2E_CPU_NIC2_NODE1_RX_DP")
	)
	(segment
		(start 41.927018 -67.38239)
		(end 42.219372 -67.38239)
		(width 0.127)
		(layer "F.Cu")
		(net "P2E_CPU_NIC2_NODE1_RX_DP")
	)
	(segment
		(start 37.286946 -67.465194)
		(end 37.663628 -67.526662)
		(width 0.127)
		(layer "F.Cu")
		(net "P2E_CPU_NIC2_NODE1_RX_DP")
	)
	(segment
		(start 37.663628 -67.526662)
		(end 37.81171 -67.41922)
		(width 0.127)
		(layer "F.Cu")
		(net "P2E_CPU_NIC2_NODE1_RX_DP")
	)
	(segment
		(start 36.20135 -67.60083)
		(end 36.22548 -67.414394)
		(width 0.127)
		(layer "F.Cu")
		(net "P2E_CPU_NIC2_NODE1_RX_DP")
	)
	(via
		(at 149.55012 -155.208224)
		(size 0.508)
		(drill 0.254)
		(layers "F.Cu" "B.Cu")
		(net "P2E_CPU_NIC2_NODE1_RX_DP")
	)
	(via
		(at 33.102296 -70.382384)
		(size 0.508)
		(drill 0.254)
		(layers "F.Cu" "B.Cu")
		(net "P2E_CPU_NIC2_NODE1_RX_DP")
	)
	(segment
		(start 49.162208 -115.289838)
		(end 49.82464 -113.714784)
		(width 0.127)
		(layer "In7.Cu")
		(net "P2E_CPU_NIC2_NODE1_RX_DP")
	)
	(segment
		(start 33.453578 -74.163682)
		(end 33.274254 -74.258424)
		(width 0.127)
		(layer "In7.Cu")
		(net "P2E_CPU_NIC2_NODE1_RX_DP")
	)
	(segment
		(start 137.317734 -128.436624)
		(end 139.159234 -128.436624)
		(width 0.127)
		(layer "In7.Cu")
		(net "P2E_CPU_NIC2_NODE1_RX_DP")
	)
	(segment
		(start 136.892538 -128.42494)
		(end 137.317734 -128.436624)
		(width 0.127)
		(layer "In7.Cu")
		(net "P2E_CPU_NIC2_NODE1_RX_DP")
	)
	(segment
		(start 99.947476 -107.83189)
		(end 100.24745 -107.83189)
		(width 0.127)
		(layer "In7.Cu")
		(net "P2E_CPU_NIC2_NODE1_RX_DP")
	)
	(segment
		(start 49.82464 -113.714784)
		(end 50.46091 -113.32337)
		(width 0.127)
		(layer "In7.Cu")
		(net "P2E_CPU_NIC2_NODE1_RX_DP")
	)
	(segment
		(start 45.84192 -116.768626)
		(end 47.916338 -116.494306)
		(width 0.127)
		(layer "In7.Cu")
		(net "P2E_CPU_NIC2_NODE1_RX_DP")
	)
	(segment
		(start 130.929126 -129.09042)
		(end 131.338574 -129.029968)
		(width 0.127)
		(layer "In7.Cu")
		(net "P2E_CPU_NIC2_NODE1_RX_DP")
	)
	(segment
		(start 100.24745 -107.83189)
		(end 101.459284 -107.50804)
		(width 0.127)
		(layer "In7.Cu")
		(net "P2E_CPU_NIC2_NODE1_RX_DP")
	)
	(segment
		(start 154.661362 -137.23366)
		(end 156.356304 -138.150854)
		(width 0.127)
		(layer "In7.Cu")
		(net "P2E_CPU_NIC2_NODE1_RX_DP")
	)
	(segment
		(start 40.43807 -106.744262)
		(end 41.758362 -109.761274)
		(width 0.127)
		(layer "In7.Cu")
		(net "P2E_CPU_NIC2_NODE1_RX_DP")
	)
	(segment
		(start 127.57658 -124.078746)
		(end 127.293878 -126.547118)
		(width 0.127)
		(layer "In7.Cu")
		(net "P2E_CPU_NIC2_NODE1_RX_DP")
	)
	(segment
		(start 136.515348 -128.466088)
		(end 136.892538 -128.42494)
		(width 0.127)
		(layer "In7.Cu")
		(net "P2E_CPU_NIC2_NODE1_RX_DP")
	)
	(segment
		(start 54.43982 -113.557812)
		(end 54.55666 -113.70056)
		(width 0.127)
		(layer "In7.Cu")
		(net "P2E_CPU_NIC2_NODE1_RX_DP")
	)
	(segment
		(start 42.017188 -113.500154)
		(end 42.041572 -113.597944)
		(width 0.127)
		(layer "In7.Cu")
		(net "P2E_CPU_NIC2_NODE1_RX_DP")
	)
	(segment
		(start 33.257744 -74.801984)
		(end 33.25749 -74.802746)
		(width 0.127)
		(layer "In7.Cu")
		(net "P2E_CPU_NIC2_NODE1_RX_DP")
	)
	(segment
		(start 53.42128 -113.458752)
		(end 53.53812 -113.6015)
		(width 0.127)
		(layer "In7.Cu")
		(net "P2E_CPU_NIC2_NODE1_RX_DP")
	)
	(segment
		(start 154.542744 -154.9273)
		(end 154.185112 -155.467304)
		(width 0.127)
		(layer "In7.Cu")
		(net "P2E_CPU_NIC2_NODE1_RX_DP")
	)
	(segment
		(start 130.926586 -129.090928)
		(end 130.929126 -129.09042)
		(width 0.127)
		(layer "In7.Cu")
		(net "P2E_CPU_NIC2_NODE1_RX_DP")
	)
	(segment
		(start 52.023264 -113.322608)
		(end 52.40274 -113.359692)
		(width 0.127)
		(layer "In7.Cu")
		(net "P2E_CPU_NIC2_NODE1_RX_DP")
	)
	(segment
		(start 53.91785 -113.638838)
		(end 54.060344 -113.520728)
		(width 0.127)
		(layer "In7.Cu")
		(net "P2E_CPU_NIC2_NODE1_RX_DP")
	)
	(segment
		(start 141.772894 -130.466592)
		(end 144.745456 -131.03606)
		(width 0.127)
		(layer "In7.Cu")
		(net "P2E_CPU_NIC2_NODE1_RX_DP")
	)
	(segment
		(start 154.52217 -154.410156)
		(end 154.542744 -154.9273)
		(width 0.127)
		(layer "In7.Cu")
		(net "P2E_CPU_NIC2_NODE1_RX_DP")
	)
	(segment
		(start 33.06826 -83.965034)
		(end 33.198562 -86.597744)
		(width 0.127)
		(layer "In7.Cu")
		(net "P2E_CPU_NIC2_NODE1_RX_DP")
	)
	(segment
		(start 101.459284 -107.50804)
		(end 103.51516 -107.0864)
		(width 0.127)
		(layer "In7.Cu")
		(net "P2E_CPU_NIC2_NODE1_RX_DP")
	)
	(segment
		(start 122.63628 -111.759238)
		(end 125.37948 -117.340634)
		(width 0.127)
		(layer "In7.Cu")
		(net "P2E_CPU_NIC2_NODE1_RX_DP")
	)
	(segment
		(start 136.003284 -128.672844)
		(end 136.382506 -128.631442)
		(width 0.127)
		(layer "In7.Cu")
		(net "P2E_CPU_NIC2_NODE1_RX_DP")
	)
	(segment
		(start 85.628734 -109.993684)
		(end 89.350342 -109.992922)
		(width 0.127)
		(layer "In7.Cu")
		(net "P2E_CPU_NIC2_NODE1_RX_DP")
	)
	(segment
		(start 152.3492 -155.431998)
		(end 150.540974 -155.697174)
		(width 0.127)
		(layer "In7.Cu")
		(net "P2E_CPU_NIC2_NODE1_RX_DP")
	)
	(segment
		(start 56.097424 -113.718848)
		(end 56.83504 -113.788698)
		(width 0.127)
		(layer "In7.Cu")
		(net "P2E_CPU_NIC2_NODE1_RX_DP")
	)
	(segment
		(start 127.293878 -126.547118)
		(end 127.59055 -128.082294)
		(width 0.127)
		(layer "In7.Cu")
		(net "P2E_CPU_NIC2_NODE1_RX_DP")
	)
	(segment
		(start 144.745456 -131.03606)
		(end 146.257518 -131.161028)
		(width 0.127)
		(layer "In7.Cu")
		(net "P2E_CPU_NIC2_NODE1_RX_DP")
	)
	(segment
		(start 52.89931 -113.539778)
		(end 53.041804 -113.421668)
		(width 0.127)
		(layer "In7.Cu")
		(net "P2E_CPU_NIC2_NODE1_RX_DP")
	)
	(segment
		(start 54.060344 -113.520728)
		(end 54.43982 -113.557812)
		(width 0.127)
		(layer "In7.Cu")
		(net "P2E_CPU_NIC2_NODE1_RX_DP")
	)
	(segment
		(start 146.257518 -131.161028)
		(end 148.615146 -132.324856)
		(width 0.127)
		(layer "In7.Cu")
		(net "P2E_CPU_NIC2_NODE1_RX_DP")
	)
	(segment
		(start 42.964608 -115.690142)
		(end 43.756072 -116.493798)
		(width 0.127)
		(layer "In7.Cu")
		(net "P2E_CPU_NIC2_NODE1_RX_DP")
	)
	(segment
		(start 33.161986 -74.623168)
		(end 33.257744 -74.801984)
		(width 0.127)
		(layer "In7.Cu")
		(net "P2E_CPU_NIC2_NODE1_RX_DP")
	)
	(segment
		(start 56.83504 -113.788698)
		(end 62.4713 -113.030508)
		(width 0.127)
		(layer "In7.Cu")
		(net "P2E_CPU_NIC2_NODE1_RX_DP")
	)
	(segment
		(start 135.838692 -128.540002)
		(end 136.003284 -128.672844)
		(width 0.127)
		(layer "In7.Cu")
		(net "P2E_CPU_NIC2_NODE1_RX_DP")
	)
	(segment
		(start 33.745678 -69.893434)
		(end 34.110168 -70.257924)
		(width 0.127)
		(layer "In7.Cu")
		(net "P2E_CPU_NIC2_NODE1_RX_DP")
	)
	(segment
		(start 32.99714 -75.652376)
		(end 33.06826 -83.965034)
		(width 0.127)
		(layer "In7.Cu")
		(net "P2E_CPU_NIC2_NODE1_RX_DP")
	)
	(segment
		(start 42.041572 -113.597944)
		(end 42.964608 -115.690142)
		(width 0.127)
		(layer "In7.Cu")
		(net "P2E_CPU_NIC2_NODE1_RX_DP")
	)
	(segment
		(start 34.110168 -70.257924)
		(end 34.205418 -71.533258)
		(width 0.127)
		(layer "In7.Cu")
		(net "P2E_CPU_NIC2_NODE1_RX_DP")
	)
	(segment
		(start 155.96743 -152.482804)
		(end 155.13939 -153.378662)
		(width 0.127)
		(layer "In7.Cu")
		(net "P2E_CPU_NIC2_NODE1_RX_DP")
	)
	(segment
		(start 51.50104 -113.40338)
		(end 51.88077 -113.440718)
		(width 0.127)
		(layer "In7.Cu")
		(net "P2E_CPU_NIC2_NODE1_RX_DP")
	)
	(segment
		(start 134.94766 -128.78816)
		(end 135.326882 -128.746758)
		(width 0.127)
		(layer "In7.Cu")
		(net "P2E_CPU_NIC2_NODE1_RX_DP")
	)
	(segment
		(start 54.55666 -113.70056)
		(end 54.93639 -113.737898)
		(width 0.127)
		(layer "In7.Cu")
		(net "P2E_CPU_NIC2_NODE1_RX_DP")
	)
	(segment
		(start 125.37948 -117.340634)
		(end 125.5014 -119.351806)
		(width 0.127)
		(layer "In7.Cu")
		(net "P2E_CPU_NIC2_NODE1_RX_DP")
	)
	(segment
		(start 33.102296 -70.020434)
		(end 33.229296 -69.893434)
		(width 0.127)
		(layer "In7.Cu")
		(net "P2E_CPU_NIC2_NODE1_RX_DP")
	)
	(segment
		(start 131.338574 -129.029968)
		(end 134.783068 -128.655064)
		(width 0.127)
		(layer "In7.Cu")
		(net "P2E_CPU_NIC2_NODE1_RX_DP")
	)
	(segment
		(start 66.079116 -114.340132)
		(end 68.21424 -114.172746)
		(width 0.127)
		(layer "In7.Cu")
		(net "P2E_CPU_NIC2_NODE1_RX_DP")
	)
	(segment
		(start 157.551374 -147.180046)
		(end 157.458664 -148.28774)
		(width 0.127)
		(layer "In7.Cu")
		(net "P2E_CPU_NIC2_NODE1_RX_DP")
	)
	(segment
		(start 139.159234 -128.436624)
		(end 140.574268 -129.166112)
		(width 0.127)
		(layer "In7.Cu")
		(net "P2E_CPU_NIC2_NODE1_RX_DP")
	)
	(segment
		(start 55.5752 -113.79962)
		(end 55.95493 -113.836958)
		(width 0.127)
		(layer "In7.Cu")
		(net "P2E_CPU_NIC2_NODE1_RX_DP")
	)
	(segment
		(start 114.699796 -107.762294)
		(end 119.193056 -108.08462)
		(width 0.127)
		(layer "In7.Cu")
		(net "P2E_CPU_NIC2_NODE1_RX_DP")
	)
	(segment
		(start 83.539838 -110.363508)
		(end 85.628734 -109.993684)
		(width 0.127)
		(layer "In7.Cu")
		(net "P2E_CPU_NIC2_NODE1_RX_DP")
	)
	(segment
		(start 33.574228 -73.274428)
		(end 33.662366 -73.43267)
		(width 0.127)
		(layer "In7.Cu")
		(net "P2E_CPU_NIC2_NODE1_RX_DP")
	)
	(segment
		(start 33.942274 -72.453754)
		(end 33.837372 -72.820276)
		(width 0.127)
		(layer "In7.Cu")
		(net "P2E_CPU_NIC2_NODE1_RX_DP")
	)
	(segment
		(start 121.375678 -109.40669)
		(end 121.477024 -109.644688)
		(width 0.127)
		(layer "In7.Cu")
		(net "P2E_CPU_NIC2_NODE1_RX_DP")
	)
	(segment
		(start 134.783068 -128.655064)
		(end 134.94766 -128.78816)
		(width 0.127)
		(layer "In7.Cu")
		(net "P2E_CPU_NIC2_NODE1_RX_DP")
	)
	(segment
		(start 154.690826 -153.864056)
		(end 154.52217 -154.410156)
		(width 0.127)
		(layer "In7.Cu")
		(net "P2E_CPU_NIC2_NODE1_RX_DP")
	)
	(segment
		(start 130.925062 -129.093214)
		(end 130.926586 -129.090928)
		(width 0.127)
		(layer "In7.Cu")
		(net "P2E_CPU_NIC2_NODE1_RX_DP")
	)
	(segment
		(start 33.662366 -73.43267)
		(end 33.453578 -74.163682)
		(width 0.127)
		(layer "In7.Cu")
		(net "P2E_CPU_NIC2_NODE1_RX_DP")
	)
	(segment
		(start 33.274254 -74.258424)
		(end 33.161986 -74.623168)
		(width 0.127)
		(layer "In7.Cu")
		(net "P2E_CPU_NIC2_NODE1_RX_DP")
	)
	(segment
		(start 107.113324 -107.185714)
		(end 109.104684 -107.712764)
		(width 0.127)
		(layer "In7.Cu")
		(net "P2E_CPU_NIC2_NODE1_RX_DP")
	)
	(segment
		(start 94.093792 -108.270548)
		(end 96.124522 -108.139738)
		(width 0.127)
		(layer "In7.Cu")
		(net "P2E_CPU_NIC2_NODE1_RX_DP")
	)
	(segment
		(start 135.326882 -128.746758)
		(end 135.459724 -128.581404)
		(width 0.127)
		(layer "In7.Cu")
		(net "P2E_CPU_NIC2_NODE1_RX_DP")
	)
	(segment
		(start 140.574268 -129.166112)
		(end 141.772894 -130.466592)
		(width 0.127)
		(layer "In7.Cu")
		(net "P2E_CPU_NIC2_NODE1_RX_DP")
	)
	(segment
		(start 50.46091 -113.32337)
		(end 51.03495 -113.22685)
		(width 0.127)
		(layer "In7.Cu")
		(net "P2E_CPU_NIC2_NODE1_RX_DP")
	)
	(segment
		(start 105.54462 -107.215432)
		(end 107.113324 -107.185714)
		(width 0.127)
		(layer "In7.Cu")
		(net "P2E_CPU_NIC2_NODE1_RX_DP")
	)
	(segment
		(start 82.31632 -111.931704)
		(end 83.539838 -110.363508)
		(width 0.127)
		(layer "In7.Cu")
		(net "P2E_CPU_NIC2_NODE1_RX_DP")
	)
	(segment
		(start 153.83002 -155.592526)
		(end 152.871424 -155.466034)
		(width 0.127)
		(layer "In7.Cu")
		(net "P2E_CPU_NIC2_NODE1_RX_DP")
	)
	(segment
		(start 119.193056 -108.08462)
		(end 121.375678 -109.40669)
		(width 0.127)
		(layer "In7.Cu")
		(net "P2E_CPU_NIC2_NODE1_RX_DP")
	)
	(segment
		(start 54.93639 -113.737898)
		(end 55.078884 -113.619788)
		(width 0.127)
		(layer "In7.Cu")
		(net "P2E_CPU_NIC2_NODE1_RX_DP")
	)
	(segment
		(start 33.229296 -69.893434)
		(end 33.745678 -69.893434)
		(width 0.127)
		(layer "In7.Cu")
		(net "P2E_CPU_NIC2_NODE1_RX_DP")
	)
	(segment
		(start 52.40274 -113.359692)
		(end 52.51958 -113.50244)
		(width 0.127)
		(layer "In7.Cu")
		(net "P2E_CPU_NIC2_NODE1_RX_DP")
	)
	(segment
		(start 39.302436 -100.406708)
		(end 40.43807 -106.744262)
		(width 0.127)
		(layer "In7.Cu")
		(net "P2E_CPU_NIC2_NODE1_RX_DP")
	)
	(segment
		(start 33.25749 -74.802746)
		(end 32.99714 -75.652376)
		(width 0.127)
		(layer "In7.Cu")
		(net "P2E_CPU_NIC2_NODE1_RX_DP")
	)
	(segment
		(start 156.786072 -139.035536)
		(end 156.927042 -143.450818)
		(width 0.127)
		(layer "In7.Cu")
		(net "P2E_CPU_NIC2_NODE1_RX_DP")
	)
	(segment
		(start 72.926956 -114.668554)
		(end 78.64348 -113.922048)
		(width 0.127)
		(layer "In7.Cu")
		(net "P2E_CPU_NIC2_NODE1_RX_DP")
	)
	(segment
		(start 55.45836 -113.656872)
		(end 55.5752 -113.79962)
		(width 0.127)
		(layer "In7.Cu")
		(net "P2E_CPU_NIC2_NODE1_RX_DP")
	)
	(segment
		(start 155.13939 -153.378662)
		(end 154.690826 -153.864056)
		(width 0.127)
		(layer "In7.Cu")
		(net "P2E_CPU_NIC2_NODE1_RX_DP")
	)
	(segment
		(start 96.124522 -108.139738)
		(end 99.290632 -107.93857)
		(width 0.127)
		(layer "In7.Cu")
		(net "P2E_CPU_NIC2_NODE1_RX_DP")
	)
	(segment
		(start 125.5014 -119.351806)
		(end 125.678946 -119.905272)
		(width 0.127)
		(layer "In7.Cu")
		(net "P2E_CPU_NIC2_NODE1_RX_DP")
	)
	(segment
		(start 127.59055 -128.082294)
		(end 128.616456 -129.013204)
		(width 0.127)
		(layer "In7.Cu")
		(net "P2E_CPU_NIC2_NODE1_RX_DP")
	)
	(segment
		(start 53.53812 -113.6015)
		(end 53.91785 -113.638838)
		(width 0.127)
		(layer "In7.Cu")
		(net "P2E_CPU_NIC2_NODE1_RX_DP")
	)
	(segment
		(start 157.458664 -148.28774)
		(end 155.96743 -152.482804)
		(width 0.127)
		(layer "In7.Cu")
		(net "P2E_CPU_NIC2_NODE1_RX_DP")
	)
	(segment
		(start 35.593528 -96.21139)
		(end 39.302436 -100.406708)
		(width 0.127)
		(layer "In7.Cu")
		(net "P2E_CPU_NIC2_NODE1_RX_DP")
	)
	(segment
		(start 128.616456 -129.013204)
		(end 130.9243 -129.093468)
		(width 0.127)
		(layer "In7.Cu")
		(net "P2E_CPU_NIC2_NODE1_RX_DP")
	)
	(segment
		(start 127.602742 -122.23115)
		(end 127.57658 -124.078746)
		(width 0.127)
		(layer "In7.Cu")
		(net "P2E_CPU_NIC2_NODE1_RX_DP")
	)
	(segment
		(start 154.185112 -155.467304)
		(end 153.83002 -155.592526)
		(width 0.127)
		(layer "In7.Cu")
		(net "P2E_CPU_NIC2_NODE1_RX_DP")
	)
	(segment
		(start 55.078884 -113.619788)
		(end 55.45836 -113.656872)
		(width 0.127)
		(layer "In7.Cu")
		(net "P2E_CPU_NIC2_NODE1_RX_DP")
	)
	(segment
		(start 33.837372 -72.820276)
		(end 33.67913 -72.907906)
		(width 0.127)
		(layer "In7.Cu")
		(net "P2E_CPU_NIC2_NODE1_RX_DP")
	)
	(segment
		(start 43.756072 -116.493798)
		(end 45.84192 -116.768626)
		(width 0.127)
		(layer "In7.Cu")
		(net "P2E_CPU_NIC2_NODE1_RX_DP")
	)
	(segment
		(start 125.678946 -119.905272)
		(end 127.602742 -122.23115)
		(width 0.127)
		(layer "In7.Cu")
		(net "P2E_CPU_NIC2_NODE1_RX_DP")
	)
	(segment
		(start 55.95493 -113.836958)
		(end 56.097424 -113.718848)
		(width 0.127)
		(layer "In7.Cu")
		(net "P2E_CPU_NIC2_NODE1_RX_DP")
	)
	(segment
		(start 41.897808 -111.78794)
		(end 42.017188 -113.500154)
		(width 0.127)
		(layer "In7.Cu")
		(net "P2E_CPU_NIC2_NODE1_RX_DP")
	)
	(segment
		(start 53.041804 -113.421668)
		(end 53.42128 -113.458752)
		(width 0.127)
		(layer "In7.Cu")
		(net "P2E_CPU_NIC2_NODE1_RX_DP")
	)
	(segment
		(start 68.21424 -114.172746)
		(end 72.926956 -114.668554)
		(width 0.127)
		(layer "In7.Cu")
		(net "P2E_CPU_NIC2_NODE1_RX_DP")
	)
	(segment
		(start 121.477024 -109.644688)
		(end 122.63628 -111.759238)
		(width 0.127)
		(layer "In7.Cu")
		(net "P2E_CPU_NIC2_NODE1_RX_DP")
	)
	(segment
		(start 130.9243 -129.093468)
		(end 130.925062 -129.093214)
		(width 0.127)
		(layer "In7.Cu")
		(net "P2E_CPU_NIC2_NODE1_RX_DP")
	)
	(segment
		(start 34.205418 -71.533258)
		(end 34.11728 -71.84136)
		(width 0.127)
		(layer "In7.Cu")
		(net "P2E_CPU_NIC2_NODE1_RX_DP")
	)
	(segment
		(start 33.959038 -71.92899)
		(end 33.854136 -72.295512)
		(width 0.127)
		(layer "In7.Cu")
		(net "P2E_CPU_NIC2_NODE1_RX_DP")
	)
	(segment
		(start 156.927042 -143.450818)
		(end 157.551374 -147.180046)
		(width 0.127)
		(layer "In7.Cu")
		(net "P2E_CPU_NIC2_NODE1_RX_DP")
	)
	(segment
		(start 51.03495 -113.22685)
		(end 51.3842 -113.260886)
		(width 0.127)
		(layer "In7.Cu")
		(net "P2E_CPU_NIC2_NODE1_RX_DP")
	)
	(segment
		(start 152.871424 -155.466034)
		(end 152.3492 -155.431998)
		(width 0.127)
		(layer "In7.Cu")
		(net "P2E_CPU_NIC2_NODE1_RX_DP")
	)
	(segment
		(start 99.290632 -107.93857)
		(end 99.947476 -107.83189)
		(width 0.127)
		(layer "In7.Cu")
		(net "P2E_CPU_NIC2_NODE1_RX_DP")
	)
	(segment
		(start 136.382506 -128.631442)
		(end 136.515348 -128.466088)
		(width 0.127)
		(layer "In7.Cu")
		(net "P2E_CPU_NIC2_NODE1_RX_DP")
	)
	(segment
		(start 52.51958 -113.50244)
		(end 52.89931 -113.539778)
		(width 0.127)
		(layer "In7.Cu")
		(net "P2E_CPU_NIC2_NODE1_RX_DP")
	)
	(segment
		(start 103.51516 -107.0864)
		(end 105.54462 -107.215432)
		(width 0.127)
		(layer "In7.Cu")
		(net "P2E_CPU_NIC2_NODE1_RX_DP")
	)
	(segment
		(start 47.916338 -116.494306)
		(end 49.162208 -115.289838)
		(width 0.127)
		(layer "In7.Cu")
		(net "P2E_CPU_NIC2_NODE1_RX_DP")
	)
	(segment
		(start 33.198562 -86.597744)
		(end 35.593528 -96.21139)
		(width 0.127)
		(layer "In7.Cu")
		(net "P2E_CPU_NIC2_NODE1_RX_DP")
	)
	(segment
		(start 51.88077 -113.440718)
		(end 52.023264 -113.322608)
		(width 0.127)
		(layer "In7.Cu")
		(net "P2E_CPU_NIC2_NODE1_RX_DP")
	)
	(segment
		(start 150.540974 -155.697174)
		(end 150.03907 -155.697174)
		(width 0.127)
		(layer "In7.Cu")
		(net "P2E_CPU_NIC2_NODE1_RX_DP")
	)
	(segment
		(start 34.11728 -71.84136)
		(end 33.959038 -71.92899)
		(width 0.127)
		(layer "In7.Cu")
		(net "P2E_CPU_NIC2_NODE1_RX_DP")
	)
	(segment
		(start 135.459724 -128.581404)
		(end 135.838692 -128.540002)
		(width 0.127)
		(layer "In7.Cu")
		(net "P2E_CPU_NIC2_NODE1_RX_DP")
	)
	(segment
		(start 152.20188 -134.661148)
		(end 154.661362 -137.23366)
		(width 0.127)
		(layer "In7.Cu")
		(net "P2E_CPU_NIC2_NODE1_RX_DP")
	)
	(segment
		(start 78.64348 -113.922048)
		(end 82.31632 -111.931704)
		(width 0.127)
		(layer "In7.Cu")
		(net "P2E_CPU_NIC2_NODE1_RX_DP")
	)
	(segment
		(start 109.104684 -107.712764)
		(end 114.699796 -107.762294)
		(width 0.127)
		(layer "In7.Cu")
		(net "P2E_CPU_NIC2_NODE1_RX_DP")
	)
	(segment
		(start 89.350342 -109.992922)
		(end 94.093792 -108.270548)
		(width 0.127)
		(layer "In7.Cu")
		(net "P2E_CPU_NIC2_NODE1_RX_DP")
	)
	(segment
		(start 33.67913 -72.907906)
		(end 33.574228 -73.274428)
		(width 0.127)
		(layer "In7.Cu")
		(net "P2E_CPU_NIC2_NODE1_RX_DP")
	)
	(segment
		(start 62.4713 -113.030508)
		(end 66.079116 -114.340132)
		(width 0.127)
		(layer "In7.Cu")
		(net "P2E_CPU_NIC2_NODE1_RX_DP")
	)
	(segment
		(start 51.3842 -113.260886)
		(end 51.50104 -113.40338)
		(width 0.127)
		(layer "In7.Cu")
		(net "P2E_CPU_NIC2_NODE1_RX_DP")
	)
	(segment
		(start 33.854136 -72.295512)
		(end 33.942274 -72.453754)
		(width 0.127)
		(layer "In7.Cu")
		(net "P2E_CPU_NIC2_NODE1_RX_DP")
	)
	(segment
		(start 41.758362 -109.761274)
		(end 41.897808 -111.78794)
		(width 0.127)
		(layer "In7.Cu")
		(net "P2E_CPU_NIC2_NODE1_RX_DP")
	)
	(segment
		(start 150.03907 -155.697174)
		(end 149.55012 -155.208224)
		(width 0.127)
		(layer "In7.Cu")
		(net "P2E_CPU_NIC2_NODE1_RX_DP")
	)
	(segment
		(start 156.356304 -138.150854)
		(end 156.786072 -139.035536)
		(width 0.127)
		(layer "In7.Cu")
		(net "P2E_CPU_NIC2_NODE1_RX_DP")
	)
	(segment
		(start 148.615146 -132.324856)
		(end 152.20188 -134.661148)
		(width 0.127)
		(layer "In7.Cu")
		(net "P2E_CPU_NIC2_NODE1_RX_DP")
	)
	(segment
		(start 33.102296 -70.382384)
		(end 33.102296 -70.020434)
		(width 0.127)
		(layer "In7.Cu")
		(net "P2E_CPU_NIC2_NODE1_RX_DP")
	)
	(segment
		(start 64.541908 -128.859026)
		(end 64.141096 -128.458214)
		(width 0.1016)
		(layer "F.Cu")
		(net "BMC_ROMA18")
	)
	(segment
		(start 64.541908 -128.859534)
		(end 64.541908 -128.859026)
		(width 0.1016)
		(layer "F.Cu")
		(net "BMC_ROMA18")
	)
	(via
		(at 63.146686 -126.581662)
		(size 0.6604)
		(drill 0.3302)
		(layers "F.Cu" "B.Cu")
		(net "BMC_ROMA18")
	)
	(via
		(at 64.141096 -128.458214)
		(size 0.49022)
		(drill 0.254)
		(layers "F.Cu" "B.Cu")
		(net "BMC_ROMA18")
	)
	(segment
		(start 64.899286 -118.358412)
		(end 64.391286 -118.866412)
		(width 0.1016)
		(layer "B.Cu")
		(net "BMC_ROMA18")
	)
	(segment
		(start 64.141096 -128.458214)
		(end 64.141096 -128.439672)
		(width 0.1016)
		(layer "B.Cu")
		(net "BMC_ROMA18")
	)
	(segment
		(start 63.045086 -126.480062)
		(end 63.146686 -126.581662)
		(width 0.1016)
		(layer "B.Cu")
		(net "BMC_ROMA18")
	)
	(segment
		(start 63.045086 -123.914662)
		(end 63.045086 -126.480062)
		(width 0.1016)
		(layer "B.Cu")
		(net "BMC_ROMA18")
	)
	(segment
		(start 64.141096 -128.439672)
		(end 63.738506 -128.037082)
		(width 0.1016)
		(layer "B.Cu")
		(net "BMC_ROMA18")
	)
	(segment
		(start 63.738506 -128.037082)
		(end 63.738506 -127.493268)
		(width 0.1016)
		(layer "B.Cu")
		(net "BMC_ROMA18")
	)
	(segment
		(start 64.391286 -118.866412)
		(end 64.391286 -122.568462)
		(width 0.1016)
		(layer "B.Cu")
		(net "BMC_ROMA18")
	)
	(segment
		(start 63.738506 -127.493268)
		(end 63.146686 -126.901448)
		(width 0.1016)
		(layer "B.Cu")
		(net "BMC_ROMA18")
	)
	(segment
		(start 63.146686 -126.901448)
		(end 63.146686 -126.581662)
		(width 0.1016)
		(layer "B.Cu")
		(net "BMC_ROMA18")
	)
	(segment
		(start 64.391286 -122.568462)
		(end 63.045086 -123.914662)
		(width 0.1016)
		(layer "B.Cu")
		(net "BMC_ROMA18")
	)
	(segment
		(start 37.010594 -66.980562)
		(end 39.018718 -67.306444)
		(width 0.127)
		(layer "F.Cu")
		(net "P2E_CPU_NIC2_NODE1_RX_DN")
	)
	(segment
		(start 41.571418 -67.306698)
		(end 41.800526 -67.07759)
		(width 0.127)
		(layer "F.Cu")
		(net "P2E_CPU_NIC2_NODE1_RX_DN")
	)
	(segment
		(start 41.800526 -67.07759)
		(end 42.28338 -67.07759)
		(width 0.127)
		(layer "F.Cu")
		(net "P2E_CPU_NIC2_NODE1_RX_DN")
	)
	(segment
		(start 36.289742 -66.980562)
		(end 37.010594 -66.980562)
		(width 0.127)
		(layer "F.Cu")
		(net "P2E_CPU_NIC2_NODE1_RX_DN")
	)
	(segment
		(start 39.018718 -67.306444)
		(end 39.626286 -67.306444)
		(width 0.127)
		(layer "F.Cu")
		(net "P2E_CPU_NIC2_NODE1_RX_DN")
	)
	(segment
		(start 34.610802 -68.570856)
		(end 35.18916 -67.825366)
		(width 0.127)
		(layer "F.Cu")
		(net "P2E_CPU_NIC2_NODE1_RX_DN")
	)
	(segment
		(start 42.28338 -67.07759)
		(end 43.205908 -67.358514)
		(width 0.127)
		(layer "F.Cu")
		(net "P2E_CPU_NIC2_NODE1_RX_DN")
	)
	(segment
		(start 34.16427 -69.145658)
		(end 34.343848 -68.914772)
		(width 0.127)
		(layer "F.Cu")
		(net "P2E_CPU_NIC2_NODE1_RX_DN")
	)
	(segment
		(start 33.282128 -69.418454)
		(end 33.784794 -69.418454)
		(width 0.127)
		(layer "F.Cu")
		(net "P2E_CPU_NIC2_NODE1_RX_DN")
	)
	(segment
		(start 33.102296 -69.112384)
		(end 33.102296 -69.238622)
		(width 0.127)
		(layer "F.Cu")
		(net "P2E_CPU_NIC2_NODE1_RX_DN")
	)
	(segment
		(start 150.346918 -155.9814)
		(end 150.713948 -156.34843)
		(width 0.127)
		(layer "F.Cu")
		(net "P2E_CPU_NIC2_NODE1_RX_DN")
	)
	(segment
		(start 35.18916 -67.825366)
		(end 36.289742 -66.980562)
		(width 0.127)
		(layer "F.Cu")
		(net "P2E_CPU_NIC2_NODE1_RX_DN")
	)
	(segment
		(start 33.102296 -69.238622)
		(end 33.282128 -69.418454)
		(width 0.127)
		(layer "F.Cu")
		(net "P2E_CPU_NIC2_NODE1_RX_DN")
	)
	(segment
		(start 39.626286 -67.306444)
		(end 39.626286 -67.306698)
		(width 0.127)
		(layer "F.Cu")
		(net "P2E_CPU_NIC2_NODE1_RX_DN")
	)
	(segment
		(start 39.626286 -67.306698)
		(end 41.571418 -67.306698)
		(width 0.127)
		(layer "F.Cu")
		(net "P2E_CPU_NIC2_NODE1_RX_DN")
	)
	(segment
		(start 33.784794 -69.418454)
		(end 34.16427 -69.145658)
		(width 0.127)
		(layer "F.Cu")
		(net "P2E_CPU_NIC2_NODE1_RX_DN")
	)
	(segment
		(start 150.046944 -155.9814)
		(end 150.346918 -155.9814)
		(width 0.127)
		(layer "F.Cu")
		(net "P2E_CPU_NIC2_NODE1_RX_DN")
	)
	(segment
		(start 149.55012 -156.478224)
		(end 150.046944 -155.9814)
		(width 0.127)
		(layer "F.Cu")
		(net "P2E_CPU_NIC2_NODE1_RX_DN")
	)
	(segment
		(start 34.343848 -68.914772)
		(end 34.610802 -68.570856)
		(width 0.127)
		(layer "F.Cu")
		(net "P2E_CPU_NIC2_NODE1_RX_DN")
	)
	(via
		(at 33.102296 -69.112384)
		(size 0.508)
		(drill 0.254)
		(layers "F.Cu" "B.Cu")
		(net "P2E_CPU_NIC2_NODE1_RX_DN")
	)
	(via
		(at 149.55012 -156.478224)
		(size 0.508)
		(drill 0.254)
		(layers "F.Cu" "B.Cu")
		(net "P2E_CPU_NIC2_NODE1_RX_DN")
	)
	(segment
		(start 42.046398 -109.690662)
		(end 42.1894 -111.76762)
		(width 0.127)
		(layer "In7.Cu")
		(net "P2E_CPU_NIC2_NODE1_RX_DN")
	)
	(segment
		(start 150.56231 -155.989274)
		(end 150.03907 -155.989274)
		(width 0.127)
		(layer "In7.Cu")
		(net "P2E_CPU_NIC2_NODE1_RX_DN")
	)
	(segment
		(start 139.2301 -128.144524)
		(end 140.7541 -128.930146)
		(width 0.127)
		(layer "In7.Cu")
		(net "P2E_CPU_NIC2_NODE1_RX_DN")
	)
	(segment
		(start 35.85972 -96.071436)
		(end 39.57574 -100.274374)
		(width 0.127)
		(layer "In7.Cu")
		(net "P2E_CPU_NIC2_NODE1_RX_DN")
	)
	(segment
		(start 33.36036 -83.956652)
		(end 33.489138 -86.554818)
		(width 0.127)
		(layer "In7.Cu")
		(net "P2E_CPU_NIC2_NODE1_RX_DN")
	)
	(segment
		(start 100.208842 -107.53979)
		(end 101.122988 -107.295442)
		(width 0.127)
		(layer "In7.Cu")
		(net "P2E_CPU_NIC2_NODE1_RX_DN")
	)
	(segment
		(start 33.229296 -69.601334)
		(end 33.866836 -69.601334)
		(width 0.127)
		(layer "In7.Cu")
		(net "P2E_CPU_NIC2_NODE1_RX_DN")
	)
	(segment
		(start 157.84576 -147.167854)
		(end 157.7467 -148.34997)
		(width 0.127)
		(layer "In7.Cu")
		(net "P2E_CPU_NIC2_NODE1_RX_DN")
	)
	(segment
		(start 33.102296 -69.112384)
		(end 33.102296 -69.474334)
		(width 0.127)
		(layer "In7.Cu")
		(net "P2E_CPU_NIC2_NODE1_RX_DN")
	)
	(segment
		(start 39.57574 -100.274374)
		(end 40.719502 -106.658664)
		(width 0.127)
		(layer "In7.Cu")
		(net "P2E_CPU_NIC2_NODE1_RX_DN")
	)
	(segment
		(start 72.9234 -114.374422)
		(end 78.55204 -113.639346)
		(width 0.127)
		(layer "In7.Cu")
		(net "P2E_CPU_NIC2_NODE1_RX_DN")
	)
	(segment
		(start 156.5783 -137.93851)
		(end 157.07614 -138.963908)
		(width 0.127)
		(layer "In7.Cu")
		(net "P2E_CPU_NIC2_NODE1_RX_DN")
	)
	(segment
		(start 89.29878 -109.700568)
		(end 94.03334 -107.981496)
		(width 0.127)
		(layer "In7.Cu")
		(net "P2E_CPU_NIC2_NODE1_RX_DN")
	)
	(segment
		(start 127.896366 -122.127772)
		(end 127.86868 -124.097542)
		(width 0.127)
		(layer "In7.Cu")
		(net "P2E_CPU_NIC2_NODE1_RX_DN")
	)
	(segment
		(start 34.393632 -70.127876)
		(end 34.50082 -71.563484)
		(width 0.127)
		(layer "In7.Cu")
		(net "P2E_CPU_NIC2_NODE1_RX_DN")
	)
	(segment
		(start 33.489138 -86.554818)
		(end 35.85972 -96.071436)
		(width 0.127)
		(layer "In7.Cu")
		(net "P2E_CPU_NIC2_NODE1_RX_DN")
	)
	(segment
		(start 153.861262 -155.891484)
		(end 152.842722 -155.757118)
		(width 0.127)
		(layer "In7.Cu")
		(net "P2E_CPU_NIC2_NODE1_RX_DN")
	)
	(segment
		(start 127.58928 -126.535688)
		(end 127.859028 -127.931164)
		(width 0.127)
		(layer "In7.Cu")
		(net "P2E_CPU_NIC2_NODE1_RX_DN")
	)
	(segment
		(start 154.816048 -154.44851)
		(end 154.8384 -155.00985)
		(width 0.127)
		(layer "In7.Cu")
		(net "P2E_CPU_NIC2_NODE1_RX_DN")
	)
	(segment
		(start 99.923854 -107.53979)
		(end 100.208842 -107.53979)
		(width 0.127)
		(layer "In7.Cu")
		(net "P2E_CPU_NIC2_NODE1_RX_DN")
	)
	(segment
		(start 42.1894 -111.76762)
		(end 42.30878 -113.479834)
		(width 0.127)
		(layer "In7.Cu")
		(net "P2E_CPU_NIC2_NODE1_RX_DN")
	)
	(segment
		(start 62.503558 -112.731296)
		(end 66.119248 -114.043714)
		(width 0.127)
		(layer "In7.Cu")
		(net "P2E_CPU_NIC2_NODE1_RX_DN")
	)
	(segment
		(start 152.361138 -155.725622)
		(end 150.56231 -155.989274)
		(width 0.127)
		(layer "In7.Cu")
		(net "P2E_CPU_NIC2_NODE1_RX_DN")
	)
	(segment
		(start 33.537144 -74.88809)
		(end 33.289748 -75.695048)
		(width 0.127)
		(layer "In7.Cu")
		(net "P2E_CPU_NIC2_NODE1_RX_DN")
	)
	(segment
		(start 40.719502 -106.658664)
		(end 42.046398 -109.690662)
		(width 0.127)
		(layer "In7.Cu")
		(net "P2E_CPU_NIC2_NODE1_RX_DN")
	)
	(segment
		(start 109.144054 -107.420918)
		(end 114.71148 -107.470194)
		(width 0.127)
		(layer "In7.Cu")
		(net "P2E_CPU_NIC2_NODE1_RX_DN")
	)
	(segment
		(start 130.88112 -128.79959)
		(end 130.884168 -128.801876)
		(width 0.127)
		(layer "In7.Cu")
		(net "P2E_CPU_NIC2_NODE1_RX_DN")
	)
	(segment
		(start 103.494586 -106.792268)
		(end 105.551224 -106.923078)
		(width 0.127)
		(layer "In7.Cu")
		(net "P2E_CPU_NIC2_NODE1_RX_DN")
	)
	(segment
		(start 33.818576 -73.950322)
		(end 33.73374 -74.24674)
		(width 0.127)
		(layer "In7.Cu")
		(net "P2E_CPU_NIC2_NODE1_RX_DN")
	)
	(segment
		(start 94.03334 -107.981496)
		(end 96.10598 -107.848146)
		(width 0.127)
		(layer "In7.Cu")
		(net "P2E_CPU_NIC2_NODE1_RX_DN")
	)
	(segment
		(start 156.2227 -152.636982)
		(end 155.35402 -153.577036)
		(width 0.127)
		(layer "In7.Cu")
		(net "P2E_CPU_NIC2_NODE1_RX_DN")
	)
	(segment
		(start 150.03907 -155.989274)
		(end 149.55012 -156.478224)
		(width 0.127)
		(layer "In7.Cu")
		(net "P2E_CPU_NIC2_NODE1_RX_DN")
	)
	(segment
		(start 66.119248 -114.043714)
		(end 68.21805 -113.879376)
		(width 0.127)
		(layer "In7.Cu")
		(net "P2E_CPU_NIC2_NODE1_RX_DN")
	)
	(segment
		(start 144.78508 -130.745992)
		(end 146.33702 -130.874262)
		(width 0.127)
		(layer "In7.Cu")
		(net "P2E_CPU_NIC2_NODE1_RX_DN")
	)
	(segment
		(start 157.21838 -143.421862)
		(end 157.84576 -147.167854)
		(width 0.127)
		(layer "In7.Cu")
		(net "P2E_CPU_NIC2_NODE1_RX_DN")
	)
	(segment
		(start 130.886708 -128.801368)
		(end 131.30149 -128.740154)
		(width 0.127)
		(layer "In7.Cu")
		(net "P2E_CPU_NIC2_NODE1_RX_DN")
	)
	(segment
		(start 154.84094 -136.998456)
		(end 156.5783 -137.93851)
		(width 0.127)
		(layer "In7.Cu")
		(net "P2E_CPU_NIC2_NODE1_RX_DN")
	)
	(segment
		(start 130.884168 -128.801876)
		(end 130.886708 -128.801368)
		(width 0.127)
		(layer "In7.Cu")
		(net "P2E_CPU_NIC2_NODE1_RX_DN")
	)
	(segment
		(start 127.859028 -127.931164)
		(end 128.73355 -128.724914)
		(width 0.127)
		(layer "In7.Cu")
		(net "P2E_CPU_NIC2_NODE1_RX_DN")
	)
	(segment
		(start 33.102296 -69.474334)
		(end 33.229296 -69.601334)
		(width 0.127)
		(layer "In7.Cu")
		(net "P2E_CPU_NIC2_NODE1_RX_DN")
	)
	(segment
		(start 96.10598 -107.848146)
		(end 99.257866 -107.64774)
		(width 0.127)
		(layer "In7.Cu")
		(net "P2E_CPU_NIC2_NODE1_RX_DN")
	)
	(segment
		(start 107.14863 -106.892852)
		(end 109.144054 -107.420918)
		(width 0.127)
		(layer "In7.Cu")
		(net "P2E_CPU_NIC2_NODE1_RX_DN")
	)
	(segment
		(start 68.21805 -113.879376)
		(end 72.9234 -114.374422)
		(width 0.127)
		(layer "In7.Cu")
		(net "P2E_CPU_NIC2_NODE1_RX_DN")
	)
	(segment
		(start 50.356262 -113.044732)
		(end 51.024536 -112.93221)
		(width 0.127)
		(layer "In7.Cu")
		(net "P2E_CPU_NIC2_NODE1_RX_DN")
	)
	(segment
		(start 49.591468 -113.514886)
		(end 50.356262 -113.044732)
		(width 0.127)
		(layer "In7.Cu")
		(net "P2E_CPU_NIC2_NODE1_RX_DN")
	)
	(segment
		(start 45.84192 -116.473732)
		(end 47.78248 -116.217192)
		(width 0.127)
		(layer "In7.Cu")
		(net "P2E_CPU_NIC2_NODE1_RX_DN")
	)
	(segment
		(start 99.257866 -107.64774)
		(end 99.923854 -107.53979)
		(width 0.127)
		(layer "In7.Cu")
		(net "P2E_CPU_NIC2_NODE1_RX_DN")
	)
	(segment
		(start 34.50082 -71.563484)
		(end 33.818576 -73.950322)
		(width 0.127)
		(layer "In7.Cu")
		(net "P2E_CPU_NIC2_NODE1_RX_DN")
	)
	(segment
		(start 125.79096 -119.29745)
		(end 125.940058 -119.76227)
		(width 0.127)
		(layer "In7.Cu")
		(net "P2E_CPU_NIC2_NODE1_RX_DN")
	)
	(segment
		(start 125.940058 -119.76227)
		(end 127.896366 -122.127772)
		(width 0.127)
		(layer "In7.Cu")
		(net "P2E_CPU_NIC2_NODE1_RX_DN")
	)
	(segment
		(start 154.8384 -155.00985)
		(end 154.37485 -155.710382)
		(width 0.127)
		(layer "In7.Cu")
		(net "P2E_CPU_NIC2_NODE1_RX_DN")
	)
	(segment
		(start 33.537398 -74.887328)
		(end 33.537144 -74.88809)
		(width 0.127)
		(layer "In7.Cu")
		(net "P2E_CPU_NIC2_NODE1_RX_DN")
	)
	(segment
		(start 48.916082 -115.121436)
		(end 49.591468 -113.514886)
		(width 0.127)
		(layer "In7.Cu")
		(net "P2E_CPU_NIC2_NODE1_RX_DN")
	)
	(segment
		(start 105.551224 -106.923078)
		(end 107.14863 -106.892852)
		(width 0.127)
		(layer "In7.Cu")
		(net "P2E_CPU_NIC2_NODE1_RX_DN")
	)
	(segment
		(start 121.60758 -109.205522)
		(end 121.740168 -109.516926)
		(width 0.127)
		(layer "In7.Cu")
		(net "P2E_CPU_NIC2_NODE1_RX_DN")
	)
	(segment
		(start 33.289748 -75.695048)
		(end 33.36036 -83.956652)
		(width 0.127)
		(layer "In7.Cu")
		(net "P2E_CPU_NIC2_NODE1_RX_DN")
	)
	(segment
		(start 122.895614 -111.624618)
		(end 125.667516 -117.264434)
		(width 0.127)
		(layer "In7.Cu")
		(net "P2E_CPU_NIC2_NODE1_RX_DN")
	)
	(segment
		(start 152.38984 -134.43458)
		(end 154.84094 -136.998456)
		(width 0.127)
		(layer "In7.Cu")
		(net "P2E_CPU_NIC2_NODE1_RX_DN")
	)
	(segment
		(start 121.740168 -109.516926)
		(end 122.895614 -111.624618)
		(width 0.127)
		(layer "In7.Cu")
		(net "P2E_CPU_NIC2_NODE1_RX_DN")
	)
	(segment
		(start 101.392228 -107.22356)
		(end 103.494586 -106.792268)
		(width 0.127)
		(layer "In7.Cu")
		(net "P2E_CPU_NIC2_NODE1_RX_DN")
	)
	(segment
		(start 137.321798 -128.144524)
		(end 139.2301 -128.144524)
		(width 0.127)
		(layer "In7.Cu")
		(net "P2E_CPU_NIC2_NODE1_RX_DN")
	)
	(segment
		(start 146.33702 -130.874262)
		(end 148.76018 -132.070348)
		(width 0.127)
		(layer "In7.Cu")
		(net "P2E_CPU_NIC2_NODE1_RX_DN")
	)
	(segment
		(start 42.30878 -113.479834)
		(end 43.21048 -115.523264)
		(width 0.127)
		(layer "In7.Cu")
		(net "P2E_CPU_NIC2_NODE1_RX_DN")
	)
	(segment
		(start 148.76018 -132.070348)
		(end 152.38984 -134.43458)
		(width 0.127)
		(layer "In7.Cu")
		(net "P2E_CPU_NIC2_NODE1_RX_DN")
	)
	(segment
		(start 33.866836 -69.601334)
		(end 34.393632 -70.127876)
		(width 0.127)
		(layer "In7.Cu")
		(net "P2E_CPU_NIC2_NODE1_RX_DN")
	)
	(segment
		(start 83.378294 -110.095284)
		(end 85.60308 -109.70133)
		(width 0.127)
		(layer "In7.Cu")
		(net "P2E_CPU_NIC2_NODE1_RX_DN")
	)
	(segment
		(start 128.73355 -128.724914)
		(end 130.88112 -128.79959)
		(width 0.127)
		(layer "In7.Cu")
		(net "P2E_CPU_NIC2_NODE1_RX_DN")
	)
	(segment
		(start 125.667516 -117.264434)
		(end 125.79096 -119.29745)
		(width 0.127)
		(layer "In7.Cu")
		(net "P2E_CPU_NIC2_NODE1_RX_DN")
	)
	(segment
		(start 154.950414 -154.013662)
		(end 154.816048 -154.44851)
		(width 0.127)
		(layer "In7.Cu")
		(net "P2E_CPU_NIC2_NODE1_RX_DN")
	)
	(segment
		(start 157.07614 -138.963908)
		(end 157.21838 -143.421862)
		(width 0.127)
		(layer "In7.Cu")
		(net "P2E_CPU_NIC2_NODE1_RX_DN")
	)
	(segment
		(start 85.60308 -109.70133)
		(end 89.29878 -109.700568)
		(width 0.127)
		(layer "In7.Cu")
		(net "P2E_CPU_NIC2_NODE1_RX_DN")
	)
	(segment
		(start 43.21048 -115.523264)
		(end 43.89374 -116.217192)
		(width 0.127)
		(layer "In7.Cu")
		(net "P2E_CPU_NIC2_NODE1_RX_DN")
	)
	(segment
		(start 157.7467 -148.34997)
		(end 156.2227 -152.636982)
		(width 0.127)
		(layer "In7.Cu")
		(net "P2E_CPU_NIC2_NODE1_RX_DN")
	)
	(segment
		(start 101.122988 -107.295442)
		(end 101.392228 -107.22356)
		(width 0.127)
		(layer "In7.Cu")
		(net "P2E_CPU_NIC2_NODE1_RX_DN")
	)
	(segment
		(start 119.284242 -107.798108)
		(end 121.60758 -109.205522)
		(width 0.127)
		(layer "In7.Cu")
		(net "P2E_CPU_NIC2_NODE1_RX_DN")
	)
	(segment
		(start 114.71148 -107.470194)
		(end 119.284242 -107.798108)
		(width 0.127)
		(layer "In7.Cu")
		(net "P2E_CPU_NIC2_NODE1_RX_DN")
	)
	(segment
		(start 131.30149 -128.740154)
		(end 136.8806 -128.132332)
		(width 0.127)
		(layer "In7.Cu")
		(net "P2E_CPU_NIC2_NODE1_RX_DN")
	)
	(segment
		(start 152.842722 -155.757118)
		(end 152.361138 -155.725622)
		(width 0.127)
		(layer "In7.Cu")
		(net "P2E_CPU_NIC2_NODE1_RX_DN")
	)
	(segment
		(start 127.86868 -124.097542)
		(end 127.58928 -126.535688)
		(width 0.127)
		(layer "In7.Cu")
		(net "P2E_CPU_NIC2_NODE1_RX_DN")
	)
	(segment
		(start 136.8806 -128.132332)
		(end 137.321798 -128.144524)
		(width 0.127)
		(layer "In7.Cu")
		(net "P2E_CPU_NIC2_NODE1_RX_DN")
	)
	(segment
		(start 56.829452 -113.494566)
		(end 62.503558 -112.731296)
		(width 0.127)
		(layer "In7.Cu")
		(net "P2E_CPU_NIC2_NODE1_RX_DN")
	)
	(segment
		(start 33.73374 -74.24674)
		(end 33.537398 -74.887328)
		(width 0.127)
		(layer "In7.Cu")
		(net "P2E_CPU_NIC2_NODE1_RX_DN")
	)
	(segment
		(start 78.55204 -113.639346)
		(end 82.123534 -111.703866)
		(width 0.127)
		(layer "In7.Cu")
		(net "P2E_CPU_NIC2_NODE1_RX_DN")
	)
	(segment
		(start 154.37485 -155.710382)
		(end 153.861262 -155.891484)
		(width 0.127)
		(layer "In7.Cu")
		(net "P2E_CPU_NIC2_NODE1_RX_DN")
	)
	(segment
		(start 47.78248 -116.217192)
		(end 48.916082 -115.121436)
		(width 0.127)
		(layer "In7.Cu")
		(net "P2E_CPU_NIC2_NODE1_RX_DN")
	)
	(segment
		(start 140.7541 -128.930146)
		(end 141.9225 -130.197606)
		(width 0.127)
		(layer "In7.Cu")
		(net "P2E_CPU_NIC2_NODE1_RX_DN")
	)
	(segment
		(start 141.9225 -130.197606)
		(end 144.78508 -130.745992)
		(width 0.127)
		(layer "In7.Cu")
		(net "P2E_CPU_NIC2_NODE1_RX_DN")
	)
	(segment
		(start 43.89374 -116.217192)
		(end 45.84192 -116.473732)
		(width 0.127)
		(layer "In7.Cu")
		(net "P2E_CPU_NIC2_NODE1_RX_DN")
	)
	(segment
		(start 82.123534 -111.703866)
		(end 83.378294 -110.095284)
		(width 0.127)
		(layer "In7.Cu")
		(net "P2E_CPU_NIC2_NODE1_RX_DN")
	)
	(segment
		(start 51.024536 -112.93221)
		(end 56.829452 -113.494566)
		(width 0.127)
		(layer "In7.Cu")
		(net "P2E_CPU_NIC2_NODE1_RX_DN")
	)
	(segment
		(start 155.35402 -153.577036)
		(end 154.950414 -154.013662)
		(width 0.127)
		(layer "In7.Cu")
		(net "P2E_CPU_NIC2_NODE1_RX_DN")
	)
	(segment
		(start 51.750214 -20.94992)
		(end 51.750214 -22.366986)
		(width 0.1651)
		(layer "F.Cu")
		(net "M1_DQ_NODE1_DQ17")
	)
	(segment
		(start 51.816762 -22.433026)
		(end 51.816762 -23.176738)
		(width 0.1651)
		(layer "F.Cu")
		(net "M1_DQ_NODE1_DQ17")
	)
	(segment
		(start 53.797962 -69.265038)
		(end 53.790342 -69.265038)
		(width 0.1016)
		(layer "F.Cu")
		(net "M1_DQ_NODE1_DQ17")
	)
	(segment
		(start 51.816254 -22.433026)
		(end 51.816762 -22.433026)
		(width 0.1651)
		(layer "F.Cu")
		(net "M1_DQ_NODE1_DQ17")
	)
	(segment
		(start 53.790342 -69.265038)
		(end 53.416962 -68.891658)
		(width 0.1016)
		(layer "F.Cu")
		(net "M1_DQ_NODE1_DQ17")
	)
	(segment
		(start 51.750214 -22.366986)
		(end 51.816254 -22.433026)
		(width 0.1651)
		(layer "F.Cu")
		(net "M1_DQ_NODE1_DQ17")
	)
	(via
		(at 53.416962 -68.891658)
		(size 0.508)
		(drill 0.254)
		(layers "F.Cu" "B.Cu")
		(net "M1_DQ_NODE1_DQ17")
	)
	(via
		(at 51.816762 -23.176738)
		(size 0.508)
		(drill 0.254)
		(layers "F.Cu" "B.Cu")
		(net "M1_DQ_NODE1_DQ17")
	)
	(segment
		(start 48.3489 -27.916886)
		(end 48.13046 -28.135326)
		(width 0.2032)
		(layer "In7.Cu")
		(net "M1_DQ_NODE1_DQ17")
	)
	(segment
		(start 49.86528 -60.964064)
		(end 49.96942 -61.068204)
		(width 0.2032)
		(layer "In7.Cu")
		(net "M1_DQ_NODE1_DQ17")
	)
	(segment
		(start 50.994056 -23.999444)
		(end 50.921158 -23.999444)
		(width 0.2032)
		(layer "In7.Cu")
		(net "M1_DQ_NODE1_DQ17")
	)
	(segment
		(start 49.11852 -59.398662)
		(end 49.86528 -60.145422)
		(width 0.2032)
		(layer "In7.Cu")
		(net "M1_DQ_NODE1_DQ17")
	)
	(segment
		(start 48.3489 -26.571702)
		(end 48.3489 -27.916886)
		(width 0.2032)
		(layer "In7.Cu")
		(net "M1_DQ_NODE1_DQ17")
	)
	(segment
		(start 47.85106 -31.729172)
		(end 47.85106 -34.058098)
		(width 0.2032)
		(layer "In7.Cu")
		(net "M1_DQ_NODE1_DQ17")
	)
	(segment
		(start 48.13046 -31.449772)
		(end 47.85106 -31.729172)
		(width 0.2032)
		(layer "In7.Cu")
		(net "M1_DQ_NODE1_DQ17")
	)
	(segment
		(start 51.816762 -23.176738)
		(end 50.994056 -23.999444)
		(width 0.2032)
		(layer "In7.Cu")
		(net "M1_DQ_NODE1_DQ17")
	)
	(segment
		(start 53.262022 -69.046598)
		(end 53.416962 -68.891658)
		(width 0.1016)
		(layer "In7.Cu")
		(net "M1_DQ_NODE1_DQ17")
	)
	(segment
		(start 48.13046 -28.135326)
		(end 48.13046 -31.449772)
		(width 0.2032)
		(layer "In7.Cu")
		(net "M1_DQ_NODE1_DQ17")
	)
	(segment
		(start 40.28313 -52.383944)
		(end 43.015916 -52.383944)
		(width 0.2032)
		(layer "In7.Cu")
		(net "M1_DQ_NODE1_DQ17")
	)
	(segment
		(start 49.96942 -62.085474)
		(end 51.596544 -63.712598)
		(width 0.1016)
		(layer "In7.Cu")
		(net "M1_DQ_NODE1_DQ17")
	)
	(segment
		(start 39.07282 -51.173634)
		(end 40.28313 -52.383944)
		(width 0.2032)
		(layer "In7.Cu")
		(net "M1_DQ_NODE1_DQ17")
	)
	(segment
		(start 49.96942 -61.643768)
		(end 49.96942 -62.085474)
		(width 0.1016)
		(layer "In7.Cu")
		(net "M1_DQ_NODE1_DQ17")
	)
	(segment
		(start 52.181252 -68.442586)
		(end 52.785264 -69.046598)
		(width 0.1016)
		(layer "In7.Cu")
		(net "M1_DQ_NODE1_DQ17")
	)
	(segment
		(start 49.86528 -60.145422)
		(end 49.86528 -60.964064)
		(width 0.2032)
		(layer "In7.Cu")
		(net "M1_DQ_NODE1_DQ17")
	)
	(segment
		(start 47.85106 -34.058098)
		(end 39.07282 -42.836338)
		(width 0.2032)
		(layer "In7.Cu")
		(net "M1_DQ_NODE1_DQ17")
	)
	(segment
		(start 50.921158 -23.999444)
		(end 48.3489 -26.571702)
		(width 0.2032)
		(layer "In7.Cu")
		(net "M1_DQ_NODE1_DQ17")
	)
	(segment
		(start 43.015916 -52.383944)
		(end 49.11852 -58.486548)
		(width 0.2032)
		(layer "In7.Cu")
		(net "M1_DQ_NODE1_DQ17")
	)
	(segment
		(start 49.11852 -58.486548)
		(end 49.11852 -59.398662)
		(width 0.2032)
		(layer "In7.Cu")
		(net "M1_DQ_NODE1_DQ17")
	)
	(segment
		(start 52.181252 -64.948054)
		(end 52.181252 -68.442586)
		(width 0.1016)
		(layer "In7.Cu")
		(net "M1_DQ_NODE1_DQ17")
	)
	(segment
		(start 51.596544 -63.712598)
		(end 51.596544 -64.363346)
		(width 0.1016)
		(layer "In7.Cu")
		(net "M1_DQ_NODE1_DQ17")
	)
	(segment
		(start 51.596544 -64.363346)
		(end 52.181252 -64.948054)
		(width 0.1016)
		(layer "In7.Cu")
		(net "M1_DQ_NODE1_DQ17")
	)
	(segment
		(start 39.07282 -42.836338)
		(end 39.07282 -51.173634)
		(width 0.2032)
		(layer "In7.Cu")
		(net "M1_DQ_NODE1_DQ17")
	)
	(segment
		(start 49.96942 -61.068204)
		(end 49.96942 -61.643768)
		(width 0.2032)
		(layer "In7.Cu")
		(net "M1_DQ_NODE1_DQ17")
	)
	(segment
		(start 52.785264 -69.046598)
		(end 53.262022 -69.046598)
		(width 0.1016)
		(layer "In7.Cu")
		(net "M1_DQ_NODE1_DQ17")
	)
	(segment
		(start 171.33697 -114.064288)
		(end 173.56836 -114.064288)
		(width 0.1016)
		(layer "F.Cu")
		(net "TP_FM_CPLD_NODE1_P1V0_STB_EN")
	)
	(segment
		(start 174.01032 -114.506248)
		(end 174.01032 -116.365528)
		(width 0.1016)
		(layer "F.Cu")
		(net "TP_FM_CPLD_NODE1_P1V0_STB_EN")
	)
	(segment
		(start 171.12996 -114.271298)
		(end 171.33697 -114.064288)
		(width 0.1016)
		(layer "F.Cu")
		(net "TP_FM_CPLD_NODE1_P1V0_STB_EN")
	)
	(segment
		(start 173.56836 -114.064288)
		(end 174.01032 -114.506248)
		(width 0.1016)
		(layer "F.Cu")
		(net "TP_FM_CPLD_NODE1_P1V0_STB_EN")
	)
	(via
		(at 171.12996 -114.271298)
		(size 0.508)
		(drill 0.254)
		(layers "F.Cu" "B.Cu")
		(net "TP_FM_CPLD_NODE1_P1V0_STB_EN")
	)
	(segment
		(start 63.741808 -128.058926)
		(end 63.340996 -127.658114)
		(width 0.1016)
		(layer "F.Cu")
		(net "BMC_ROMA5")
	)
	(segment
		(start 63.741808 -128.059434)
		(end 63.741808 -128.058926)
		(width 0.1016)
		(layer "F.Cu")
		(net "BMC_ROMA5")
	)
	(via
		(at 62.613286 -123.635262)
		(size 0.6604)
		(drill 0.3302)
		(layers "F.Cu" "B.Cu")
		(net "BMC_ROMA5")
	)
	(via
		(at 63.340996 -127.658114)
		(size 0.49022)
		(drill 0.254)
		(layers "F.Cu" "B.Cu")
		(net "BMC_ROMA5")
	)
	(segment
		(start 63.832486 -122.289062)
		(end 62.613286 -123.508262)
		(width 0.1016)
		(layer "B.Cu")
		(net "BMC_ROMA5")
	)
	(segment
		(start 62.613286 -123.508262)
		(end 62.613286 -123.635262)
		(width 0.1016)
		(layer "B.Cu")
		(net "BMC_ROMA5")
	)
	(segment
		(start 63.340996 -127.512572)
		(end 62.613286 -126.784862)
		(width 0.1016)
		(layer "B.Cu")
		(net "BMC_ROMA5")
	)
	(segment
		(start 63.832486 -121.444512)
		(end 63.832486 -122.289062)
		(width 0.1016)
		(layer "B.Cu")
		(net "BMC_ROMA5")
	)
	(segment
		(start 62.613286 -126.784862)
		(end 62.613286 -123.635262)
		(width 0.1016)
		(layer "B.Cu")
		(net "BMC_ROMA5")
	)
	(segment
		(start 63.340996 -127.658114)
		(end 63.340996 -127.512572)
		(width 0.1016)
		(layer "B.Cu")
		(net "BMC_ROMA5")
	)
	(segment
		(start 86.31428 -27.435556)
		(end 85.65007 -28.099766)
		(width 0.1651)
		(layer "F.Cu")
		(net "M1_DQ_NODE1_DQ39")
	)
	(segment
		(start 85.01888 -25.957022)
		(end 85.463126 -25.957022)
		(width 0.1651)
		(layer "F.Cu")
		(net "M1_DQ_NODE1_DQ39")
	)
	(segment
		(start 85.01888 -25.954736)
		(end 85.01888 -25.957022)
		(width 0.1651)
		(layer "F.Cu")
		(net "M1_DQ_NODE1_DQ39")
	)
	(segment
		(start 85.65007 -28.099766)
		(end 85.65007 -29.149802)
		(width 0.1651)
		(layer "F.Cu")
		(net "M1_DQ_NODE1_DQ39")
	)
	(segment
		(start 68.292726 -64.111124)
		(end 68.392802 -64.2112)
		(width 0.1016)
		(layer "F.Cu")
		(net "M1_DQ_NODE1_DQ39")
	)
	(segment
		(start 68.292726 -63.552324)
		(end 68.292726 -64.111124)
		(width 0.1016)
		(layer "F.Cu")
		(net "M1_DQ_NODE1_DQ39")
	)
	(segment
		(start 86.31428 -26.808176)
		(end 86.31428 -27.435556)
		(width 0.1651)
		(layer "F.Cu")
		(net "M1_DQ_NODE1_DQ39")
	)
	(segment
		(start 85.463126 -25.957022)
		(end 86.31428 -26.808176)
		(width 0.1651)
		(layer "F.Cu")
		(net "M1_DQ_NODE1_DQ39")
	)
	(via
		(at 68.392802 -64.2112)
		(size 0.508)
		(drill 0.254)
		(layers "F.Cu" "B.Cu")
		(net "M1_DQ_NODE1_DQ39")
	)
	(via
		(at 85.01888 -25.954736)
		(size 0.508)
		(drill 0.254)
		(layers "F.Cu" "B.Cu")
		(net "M1_DQ_NODE1_DQ39")
	)
	(segment
		(start 72.121268 -62.577472)
		(end 71.867268 -62.831472)
		(width 0.1016)
		(layer "In7.Cu")
		(net "M1_DQ_NODE1_DQ39")
	)
	(segment
		(start 76.465684 -44.69511)
		(end 76.257404 -44.90339)
		(width 0.2032)
		(layer "In7.Cu")
		(net "M1_DQ_NODE1_DQ39")
	)
	(segment
		(start 69.555614 -63.452248)
		(end 68.730114 -63.452248)
		(width 0.1016)
		(layer "In7.Cu")
		(net "M1_DQ_NODE1_DQ39")
	)
	(segment
		(start 81.397094 -40.99052)
		(end 81.102454 -40.99052)
		(width 0.2032)
		(layer "In7.Cu")
		(net "M1_DQ_NODE1_DQ39")
	)
	(segment
		(start 80.599534 -41.49344)
		(end 80.599534 -41.78808)
		(width 0.2032)
		(layer "In7.Cu")
		(net "M1_DQ_NODE1_DQ39")
	)
	(segment
		(start 85.01888 -25.954736)
		(end 85.01888 -28.50134)
		(width 0.2032)
		(layer "In7.Cu")
		(net "M1_DQ_NODE1_DQ39")
	)
	(segment
		(start 77.653896 -43.577002)
		(end 77.359256 -43.577002)
		(width 0.2032)
		(layer "In7.Cu")
		(net "M1_DQ_NODE1_DQ39")
	)
	(segment
		(start 71.96582 -59.401456)
		(end 72.282812 -59.718448)
		(width 0.2032)
		(layer "In7.Cu")
		(net "M1_DQ_NODE1_DQ39")
	)
	(segment
		(start 84.143342 -29.376878)
		(end 84.143342 -30.397958)
		(width 0.2032)
		(layer "In7.Cu")
		(net "M1_DQ_NODE1_DQ39")
	)
	(segment
		(start 78.379574 -44.00804)
		(end 78.084934 -44.00804)
		(width 0.2032)
		(layer "In7.Cu")
		(net "M1_DQ_NODE1_DQ39")
	)
	(segment
		(start 71.867268 -62.831472)
		(end 70.17639 -62.831472)
		(width 0.1016)
		(layer "In7.Cu")
		(net "M1_DQ_NODE1_DQ39")
	)
	(segment
		(start 81.286604 -40.16883)
		(end 81.605374 -40.4876)
		(width 0.2032)
		(layer "In7.Cu")
		(net "M1_DQ_NODE1_DQ39")
	)
	(segment
		(start 80.280764 -40.88003)
		(end 80.280764 -41.17467)
		(width 0.2032)
		(layer "In7.Cu")
		(net "M1_DQ_NODE1_DQ39")
	)
	(segment
		(start 80.096614 -41.99636)
		(end 79.777844 -41.67759)
		(width 0.2032)
		(layer "In7.Cu")
		(net "M1_DQ_NODE1_DQ39")
	)
	(segment
		(start 80.783684 -40.67175)
		(end 80.489044 -40.67175)
		(width 0.2032)
		(layer "In7.Cu")
		(net "M1_DQ_NODE1_DQ39")
	)
	(segment
		(start 70.17639 -62.831472)
		(end 69.555614 -63.452248)
		(width 0.1016)
		(layer "In7.Cu")
		(net "M1_DQ_NODE1_DQ39")
	)
	(segment
		(start 80.391254 -41.99636)
		(end 80.096614 -41.99636)
		(width 0.2032)
		(layer "In7.Cu")
		(net "M1_DQ_NODE1_DQ39")
	)
	(segment
		(start 77.582014 -44.51096)
		(end 77.582014 -44.8056)
		(width 0.2032)
		(layer "In7.Cu")
		(net "M1_DQ_NODE1_DQ39")
	)
	(segment
		(start 78.084934 -44.00804)
		(end 77.653896 -43.577002)
		(width 0.2032)
		(layer "In7.Cu")
		(net "M1_DQ_NODE1_DQ39")
	)
	(segment
		(start 68.392802 -63.78956)
		(end 68.392802 -64.2112)
		(width 0.1016)
		(layer "In7.Cu")
		(net "M1_DQ_NODE1_DQ39")
	)
	(segment
		(start 76.257404 -44.90339)
		(end 76.257404 -45.19803)
		(width 0.2032)
		(layer "In7.Cu")
		(net "M1_DQ_NODE1_DQ39")
	)
	(segment
		(start 79.274924 -42.18051)
		(end 79.593694 -42.49928)
		(width 0.2032)
		(layer "In7.Cu")
		(net "M1_DQ_NODE1_DQ39")
	)
	(segment
		(start 76.257404 -45.19803)
		(end 76.576174 -45.5168)
		(width 0.2032)
		(layer "In7.Cu")
		(net "M1_DQ_NODE1_DQ39")
	)
	(segment
		(start 82.402934 -39.98468)
		(end 82.108294 -39.98468)
		(width 0.2032)
		(layer "In7.Cu")
		(net "M1_DQ_NODE1_DQ39")
	)
	(segment
		(start 78.017878 -42.935144)
		(end 78.587854 -43.50512)
		(width 0.2032)
		(layer "In7.Cu")
		(net "M1_DQ_NODE1_DQ39")
	)
	(segment
		(start 76.760324 -44.69511)
		(end 76.465684 -44.69511)
		(width 0.2032)
		(layer "In7.Cu")
		(net "M1_DQ_NODE1_DQ39")
	)
	(segment
		(start 77.150976 -43.785282)
		(end 77.150976 -44.079922)
		(width 0.2032)
		(layer "In7.Cu")
		(net "M1_DQ_NODE1_DQ39")
	)
	(segment
		(start 71.96582 -50.421794)
		(end 71.96582 -59.401456)
		(width 0.2032)
		(layer "In7.Cu")
		(net "M1_DQ_NODE1_DQ39")
	)
	(segment
		(start 84.143342 -30.397958)
		(end 83.927442 -30.613858)
		(width 0.2032)
		(layer "In7.Cu")
		(net "M1_DQ_NODE1_DQ39")
	)
	(segment
		(start 83.322922 -32.292798)
		(end 83.322922 -39.064692)
		(width 0.2032)
		(layer "In7.Cu")
		(net "M1_DQ_NODE1_DQ39")
	)
	(segment
		(start 72.282812 -61.516514)
		(end 72.121268 -61.678058)
		(width 0.2032)
		(layer "In7.Cu")
		(net "M1_DQ_NODE1_DQ39")
	)
	(segment
		(start 81.286604 -39.87419)
		(end 81.286604 -40.16883)
		(width 0.2032)
		(layer "In7.Cu")
		(net "M1_DQ_NODE1_DQ39")
	)
	(segment
		(start 76.576174 -45.81144)
		(end 71.96582 -50.421794)
		(width 0.2032)
		(layer "In7.Cu")
		(net "M1_DQ_NODE1_DQ39")
	)
	(segment
		(start 80.489044 -40.67175)
		(end 80.280764 -40.88003)
		(width 0.2032)
		(layer "In7.Cu")
		(net "M1_DQ_NODE1_DQ39")
	)
	(segment
		(start 79.385414 -43.0022)
		(end 79.090774 -43.0022)
		(width 0.2032)
		(layer "In7.Cu")
		(net "M1_DQ_NODE1_DQ39")
	)
	(segment
		(start 72.121268 -61.678058)
		(end 72.121268 -62.577472)
		(width 0.1016)
		(layer "In7.Cu")
		(net "M1_DQ_NODE1_DQ39")
	)
	(segment
		(start 72.282812 -59.718448)
		(end 72.282812 -61.516514)
		(width 0.2032)
		(layer "In7.Cu")
		(net "M1_DQ_NODE1_DQ39")
	)
	(segment
		(start 85.01888 -28.50134)
		(end 84.143342 -29.376878)
		(width 0.2032)
		(layer "In7.Cu")
		(net "M1_DQ_NODE1_DQ39")
	)
	(segment
		(start 82.108294 -39.98468)
		(end 81.789524 -39.66591)
		(width 0.2032)
		(layer "In7.Cu")
		(net "M1_DQ_NODE1_DQ39")
	)
	(segment
		(start 79.090774 -43.0022)
		(end 78.520798 -42.432224)
		(width 0.2032)
		(layer "In7.Cu")
		(net "M1_DQ_NODE1_DQ39")
	)
	(segment
		(start 79.593694 -42.79392)
		(end 79.385414 -43.0022)
		(width 0.2032)
		(layer "In7.Cu")
		(net "M1_DQ_NODE1_DQ39")
	)
	(segment
		(start 81.494884 -39.66591)
		(end 81.286604 -39.87419)
		(width 0.2032)
		(layer "In7.Cu")
		(net "M1_DQ_NODE1_DQ39")
	)
	(segment
		(start 83.927442 -30.613858)
		(end 83.927442 -31.688278)
		(width 0.2032)
		(layer "In7.Cu")
		(net "M1_DQ_NODE1_DQ39")
	)
	(segment
		(start 78.017878 -42.640504)
		(end 78.017878 -42.935144)
		(width 0.2032)
		(layer "In7.Cu")
		(net "M1_DQ_NODE1_DQ39")
	)
	(segment
		(start 80.280764 -41.17467)
		(end 80.599534 -41.49344)
		(width 0.2032)
		(layer "In7.Cu")
		(net "M1_DQ_NODE1_DQ39")
	)
	(segment
		(start 79.274924 -41.88587)
		(end 79.274924 -42.18051)
		(width 0.2032)
		(layer "In7.Cu")
		(net "M1_DQ_NODE1_DQ39")
	)
	(segment
		(start 78.587854 -43.50512)
		(end 78.587854 -43.79976)
		(width 0.2032)
		(layer "In7.Cu")
		(net "M1_DQ_NODE1_DQ39")
	)
	(segment
		(start 79.777844 -41.67759)
		(end 79.483204 -41.67759)
		(width 0.2032)
		(layer "In7.Cu")
		(net "M1_DQ_NODE1_DQ39")
	)
	(segment
		(start 81.102454 -40.99052)
		(end 80.783684 -40.67175)
		(width 0.2032)
		(layer "In7.Cu")
		(net "M1_DQ_NODE1_DQ39")
	)
	(segment
		(start 81.605374 -40.78224)
		(end 81.397094 -40.99052)
		(width 0.2032)
		(layer "In7.Cu")
		(net "M1_DQ_NODE1_DQ39")
	)
	(segment
		(start 80.599534 -41.78808)
		(end 80.391254 -41.99636)
		(width 0.2032)
		(layer "In7.Cu")
		(net "M1_DQ_NODE1_DQ39")
	)
	(segment
		(start 78.520798 -42.432224)
		(end 78.226158 -42.432224)
		(width 0.2032)
		(layer "In7.Cu")
		(net "M1_DQ_NODE1_DQ39")
	)
	(segment
		(start 77.079094 -45.01388)
		(end 76.760324 -44.69511)
		(width 0.2032)
		(layer "In7.Cu")
		(net "M1_DQ_NODE1_DQ39")
	)
	(segment
		(start 76.576174 -45.5168)
		(end 76.576174 -45.81144)
		(width 0.2032)
		(layer "In7.Cu")
		(net "M1_DQ_NODE1_DQ39")
	)
	(segment
		(start 79.593694 -42.49928)
		(end 79.593694 -42.79392)
		(width 0.2032)
		(layer "In7.Cu")
		(net "M1_DQ_NODE1_DQ39")
	)
	(segment
		(start 81.605374 -40.4876)
		(end 81.605374 -40.78224)
		(width 0.2032)
		(layer "In7.Cu")
		(net "M1_DQ_NODE1_DQ39")
	)
	(segment
		(start 83.322922 -39.064692)
		(end 82.402934 -39.98468)
		(width 0.2032)
		(layer "In7.Cu")
		(net "M1_DQ_NODE1_DQ39")
	)
	(segment
		(start 83.927442 -31.688278)
		(end 83.322922 -32.292798)
		(width 0.2032)
		(layer "In7.Cu")
		(net "M1_DQ_NODE1_DQ39")
	)
	(segment
		(start 77.150976 -44.079922)
		(end 77.582014 -44.51096)
		(width 0.2032)
		(layer "In7.Cu")
		(net "M1_DQ_NODE1_DQ39")
	)
	(segment
		(start 78.226158 -42.432224)
		(end 78.017878 -42.640504)
		(width 0.2032)
		(layer "In7.Cu")
		(net "M1_DQ_NODE1_DQ39")
	)
	(segment
		(start 68.730114 -63.452248)
		(end 68.392802 -63.78956)
		(width 0.1016)
		(layer "In7.Cu")
		(net "M1_DQ_NODE1_DQ39")
	)
	(segment
		(start 77.359256 -43.577002)
		(end 77.150976 -43.785282)
		(width 0.2032)
		(layer "In7.Cu")
		(net "M1_DQ_NODE1_DQ39")
	)
	(segment
		(start 77.373734 -45.01388)
		(end 77.079094 -45.01388)
		(width 0.2032)
		(layer "In7.Cu")
		(net "M1_DQ_NODE1_DQ39")
	)
	(segment
		(start 78.587854 -43.79976)
		(end 78.379574 -44.00804)
		(width 0.2032)
		(layer "In7.Cu")
		(net "M1_DQ_NODE1_DQ39")
	)
	(segment
		(start 79.483204 -41.67759)
		(end 79.274924 -41.88587)
		(width 0.2032)
		(layer "In7.Cu")
		(net "M1_DQ_NODE1_DQ39")
	)
	(segment
		(start 81.789524 -39.66591)
		(end 81.494884 -39.66591)
		(width 0.2032)
		(layer "In7.Cu")
		(net "M1_DQ_NODE1_DQ39")
	)
	(segment
		(start 77.582014 -44.8056)
		(end 77.373734 -45.01388)
		(width 0.2032)
		(layer "In7.Cu")
		(net "M1_DQ_NODE1_DQ39")
	)
	(segment
		(start 65.341754 -128.059434)
		(end 65.341754 -128.058926)
		(width 0.1016)
		(layer "F.Cu")
		(net "BMC_ROMA9")
	)
	(segment
		(start 65.341754 -128.058926)
		(end 64.940942 -127.658114)
		(width 0.1016)
		(layer "F.Cu")
		(net "BMC_ROMA9")
	)
	(via
		(at 64.940942 -127.658114)
		(size 0.49022)
		(drill 0.254)
		(layers "F.Cu" "B.Cu")
		(net "BMC_ROMA9")
	)
	(via
		(at 64.721486 -124.752862)
		(size 0.6604)
		(drill 0.3302)
		(layers "F.Cu" "B.Cu")
		(net "BMC_ROMA9")
	)
	(segment
		(start 64.940942 -127.165862)
		(end 64.670686 -126.895606)
		(width 0.1016)
		(layer "B.Cu")
		(net "BMC_ROMA9")
	)
	(segment
		(start 65.305686 -123.076462)
		(end 65.305686 -123.584462)
		(width 0.1016)
		(layer "B.Cu")
		(net "BMC_ROMA9")
	)
	(segment
		(start 66.194686 -122.187462)
		(end 65.305686 -123.076462)
		(width 0.1016)
		(layer "B.Cu")
		(net "BMC_ROMA9")
	)
	(segment
		(start 64.721486 -124.168662)
		(end 64.721486 -124.752862)
		(width 0.1016)
		(layer "B.Cu")
		(net "BMC_ROMA9")
	)
	(segment
		(start 64.670686 -124.803662)
		(end 64.721486 -124.752862)
		(width 0.1016)
		(layer "B.Cu")
		(net "BMC_ROMA9")
	)
	(segment
		(start 64.670686 -126.895606)
		(end 64.670686 -124.803662)
		(width 0.1016)
		(layer "B.Cu")
		(net "BMC_ROMA9")
	)
	(segment
		(start 64.940942 -127.658114)
		(end 64.940942 -127.165862)
		(width 0.1016)
		(layer "B.Cu")
		(net "BMC_ROMA9")
	)
	(segment
		(start 66.194686 -121.444512)
		(end 66.194686 -122.187462)
		(width 0.1016)
		(layer "B.Cu")
		(net "BMC_ROMA9")
	)
	(segment
		(start 65.305686 -123.584462)
		(end 64.721486 -124.168662)
		(width 0.1016)
		(layer "B.Cu")
		(net "BMC_ROMA9")
	)
	(segment
		(start 50.281078 -63.552324)
		(end 50.979324 -63.552324)
		(width 0.1016)
		(layer "F.Cu")
		(net "M1_DQ_NODE1_DQ11")
	)
	(segment
		(start 50.945034 -61.824362)
		(end 50.945034 -59.683396)
		(width 0.1016)
		(layer "F.Cu")
		(net "M1_DQ_NODE1_DQ11")
	)
	(segment
		(start 49.950116 -20.94992)
		(end 49.949862 -20.94992)
		(width 0.1651)
		(layer "F.Cu")
		(net "M1_DQ_NODE1_DQ11")
	)
	(segment
		(start 51.21783 -63.313818)
		(end 51.21783 -62.097158)
		(width 0.1016)
		(layer "F.Cu")
		(net "M1_DQ_NODE1_DQ11")
	)
	(segment
		(start 50.945034 -59.683396)
		(end 50.367184 -59.105546)
		(width 0.1016)
		(layer "F.Cu")
		(net "M1_DQ_NODE1_DQ11")
	)
	(segment
		(start 51.21783 -62.097158)
		(end 50.945034 -61.824362)
		(width 0.1016)
		(layer "F.Cu")
		(net "M1_DQ_NODE1_DQ11")
	)
	(segment
		(start 50.979324 -63.552324)
		(end 51.21783 -63.313818)
		(width 0.1016)
		(layer "F.Cu")
		(net "M1_DQ_NODE1_DQ11")
	)
	(segment
		(start 49.949862 -20.94992)
		(end 49.949862 -23.326598)
		(width 0.1651)
		(layer "F.Cu")
		(net "M1_DQ_NODE1_DQ11")
	)
	(via
		(at 49.949862 -23.326598)
		(size 0.508)
		(drill 0.254)
		(layers "F.Cu" "B.Cu")
		(net "M1_DQ_NODE1_DQ11")
	)
	(via
		(at 50.367184 -59.105546)
		(size 0.508)
		(drill 0.254)
		(layers "F.Cu" "B.Cu")
		(net "M1_DQ_NODE1_DQ11")
	)
	(segment
		(start 48.813466 -57.63006)
		(end 48.813466 -57.336944)
		(width 0.1016)
		(layer "In2.Cu")
		(net "M1_DQ_NODE1_DQ11")
	)
	(segment
		(start 39.89578 -48.415194)
		(end 39.54018 -48.059594)
		(width 0.2032)
		(layer "In2.Cu")
		(net "M1_DQ_NODE1_DQ11")
	)
	(segment
		(start 47.589186 -56.112664)
		(end 47.538386 -56.112664)
		(width 0.1016)
		(layer "In2.Cu")
		(net "M1_DQ_NODE1_DQ11")
	)
	(segment
		(start 46.101254 -38.932104)
		(end 52.18176 -32.851598)
		(width 0.2032)
		(layer "In2.Cu")
		(net "M1_DQ_NODE1_DQ11")
	)
	(segment
		(start 49.949862 -23.585678)
		(end 49.949862 -23.326598)
		(width 0.2032)
		(layer "In2.Cu")
		(net "M1_DQ_NODE1_DQ11")
	)
	(segment
		(start 50.366422 -59.104784)
		(end 50.28819 -59.104784)
		(width 0.1016)
		(layer "In2.Cu")
		(net "M1_DQ_NODE1_DQ11")
	)
	(segment
		(start 51.600862 -24.672798)
		(end 50.917602 -23.989538)
		(width 0.2032)
		(layer "In2.Cu")
		(net "M1_DQ_NODE1_DQ11")
	)
	(segment
		(start 42.013124 -41.006268)
		(end 44.087288 -38.932104)
		(width 0.2032)
		(layer "In2.Cu")
		(net "M1_DQ_NODE1_DQ11")
	)
	(segment
		(start 43.127168 -52.707286)
		(end 43.127168 -52.994814)
		(width 0.2032)
		(layer "In2.Cu")
		(net "M1_DQ_NODE1_DQ11")
	)
	(segment
		(start 50.28819 -59.104784)
		(end 48.813466 -57.63006)
		(width 0.1016)
		(layer "In2.Cu")
		(net "M1_DQ_NODE1_DQ11")
	)
	(segment
		(start 39.54018 -42.142918)
		(end 40.67683 -41.006268)
		(width 0.2032)
		(layer "In2.Cu")
		(net "M1_DQ_NODE1_DQ11")
	)
	(segment
		(start 44.087288 -38.932104)
		(end 46.101254 -38.932104)
		(width 0.2032)
		(layer "In2.Cu")
		(net "M1_DQ_NODE1_DQ11")
	)
	(segment
		(start 50.367184 -59.105546)
		(end 50.366422 -59.104784)
		(width 0.1016)
		(layer "In2.Cu")
		(net "M1_DQ_NODE1_DQ11")
	)
	(segment
		(start 40.558212 -49.42713)
		(end 40.349932 -49.63541)
		(width 0.2032)
		(layer "In2.Cu")
		(net "M1_DQ_NODE1_DQ11")
	)
	(segment
		(start 40.852852 -49.42713)
		(end 40.558212 -49.42713)
		(width 0.2032)
		(layer "In2.Cu")
		(net "M1_DQ_NODE1_DQ11")
	)
	(segment
		(start 48.813466 -57.336944)
		(end 47.589186 -56.112664)
		(width 0.1016)
		(layer "In2.Cu")
		(net "M1_DQ_NODE1_DQ11")
	)
	(segment
		(start 40.67683 -41.006268)
		(end 42.013124 -41.006268)
		(width 0.2032)
		(layer "In2.Cu")
		(net "M1_DQ_NODE1_DQ11")
	)
	(segment
		(start 39.54018 -50.126138)
		(end 39.54018 -49.104042)
		(width 0.2032)
		(layer "In2.Cu")
		(net "M1_DQ_NODE1_DQ11")
	)
	(segment
		(start 42.624248 -53.210206)
		(end 39.54018 -50.126138)
		(width 0.2032)
		(layer "In2.Cu")
		(net "M1_DQ_NODE1_DQ11")
	)
	(segment
		(start 39.54018 -49.104042)
		(end 39.89578 -48.748442)
		(width 0.2032)
		(layer "In2.Cu")
		(net "M1_DQ_NODE1_DQ11")
	)
	(segment
		(start 47.538386 -56.112664)
		(end 40.852852 -49.42713)
		(width 0.2032)
		(layer "In2.Cu")
		(net "M1_DQ_NODE1_DQ11")
	)
	(segment
		(start 50.353722 -23.989538)
		(end 49.949862 -23.585678)
		(width 0.2032)
		(layer "In2.Cu")
		(net "M1_DQ_NODE1_DQ11")
	)
	(segment
		(start 43.127168 -52.994814)
		(end 42.911776 -53.210206)
		(width 0.2032)
		(layer "In2.Cu")
		(net "M1_DQ_NODE1_DQ11")
	)
	(segment
		(start 52.18176 -32.851598)
		(end 52.18176 -26.813002)
		(width 0.2032)
		(layer "In2.Cu")
		(net "M1_DQ_NODE1_DQ11")
	)
	(segment
		(start 52.18176 -26.813002)
		(end 51.600862 -26.232104)
		(width 0.2032)
		(layer "In2.Cu")
		(net "M1_DQ_NODE1_DQ11")
	)
	(segment
		(start 50.917602 -23.989538)
		(end 50.353722 -23.989538)
		(width 0.2032)
		(layer "In2.Cu")
		(net "M1_DQ_NODE1_DQ11")
	)
	(segment
		(start 39.54018 -48.059594)
		(end 39.54018 -42.142918)
		(width 0.2032)
		(layer "In2.Cu")
		(net "M1_DQ_NODE1_DQ11")
	)
	(segment
		(start 40.349932 -49.63541)
		(end 40.349932 -49.93005)
		(width 0.2032)
		(layer "In2.Cu")
		(net "M1_DQ_NODE1_DQ11")
	)
	(segment
		(start 40.349932 -49.93005)
		(end 43.127168 -52.707286)
		(width 0.2032)
		(layer "In2.Cu")
		(net "M1_DQ_NODE1_DQ11")
	)
	(segment
		(start 39.89578 -48.748442)
		(end 39.89578 -48.415194)
		(width 0.2032)
		(layer "In2.Cu")
		(net "M1_DQ_NODE1_DQ11")
	)
	(segment
		(start 42.911776 -53.210206)
		(end 42.624248 -53.210206)
		(width 0.2032)
		(layer "In2.Cu")
		(net "M1_DQ_NODE1_DQ11")
	)
	(segment
		(start 51.600862 -26.232104)
		(end 51.600862 -24.672798)
		(width 0.2032)
		(layer "In2.Cu")
		(net "M1_DQ_NODE1_DQ11")
	)
	(segment
		(start 63.741808 -129.659634)
		(end 63.741808 -129.659126)
		(width 0.1016)
		(layer "F.Cu")
		(net "BMC_ROMA3")
	)
	(segment
		(start 63.741808 -129.659126)
		(end 63.340996 -129.258314)
		(width 0.1016)
		(layer "F.Cu")
		(net "BMC_ROMA3")
	)
	(via
		(at 60.174886 -125.591062)
		(size 0.6604)
		(drill 0.3302)
		(layers "F.Cu" "B.Cu")
		(net "BMC_ROMA3")
	)
	(via
		(at 63.340996 -129.258314)
		(size 0.49022)
		(drill 0.254)
		(layers "F.Cu" "B.Cu")
		(net "BMC_ROMA3")
	)
	(segment
		(start 60.174886 -123.387358)
		(end 60.847986 -122.714258)
		(width 0.1016)
		(layer "B.Cu")
		(net "BMC_ROMA3")
	)
	(segment
		(start 60.581286 -125.997462)
		(end 60.174886 -125.591062)
		(width 0.1016)
		(layer "B.Cu")
		(net "BMC_ROMA3")
	)
	(segment
		(start 60.174886 -125.591062)
		(end 60.174886 -123.387358)
		(width 0.1016)
		(layer "B.Cu")
		(net "BMC_ROMA3")
	)
	(segment
		(start 60.581286 -126.403862)
		(end 60.581286 -125.997462)
		(width 0.1016)
		(layer "B.Cu")
		(net "BMC_ROMA3")
	)
	(segment
		(start 61.33846 -127.161036)
		(end 60.581286 -126.403862)
		(width 0.1016)
		(layer "B.Cu")
		(net "BMC_ROMA3")
	)
	(segment
		(start 63.340996 -129.258314)
		(end 62.943486 -128.860804)
		(width 0.1016)
		(layer "B.Cu")
		(net "BMC_ROMA3")
	)
	(segment
		(start 61.581284 -128.860804)
		(end 61.33846 -128.61798)
		(width 0.1016)
		(layer "B.Cu")
		(net "BMC_ROMA3")
	)
	(segment
		(start 61.33846 -128.61798)
		(end 61.33846 -127.161036)
		(width 0.1016)
		(layer "B.Cu")
		(net "BMC_ROMA3")
	)
	(segment
		(start 60.847986 -122.714258)
		(end 60.847986 -119.125492)
		(width 0.1016)
		(layer "B.Cu")
		(net "BMC_ROMA3")
	)
	(segment
		(start 62.943486 -128.860804)
		(end 61.581284 -128.860804)
		(width 0.1016)
		(layer "B.Cu")
		(net "BMC_ROMA3")
	)
	(segment
		(start 60.847986 -119.125492)
		(end 61.462666 -118.510812)
		(width 0.1016)
		(layer "B.Cu")
		(net "BMC_ROMA3")
	)
	(segment
		(start 74.851768 -76.332334)
		(end 75.240642 -75.94346)
		(width 0.1016)
		(layer "F.Cu")
		(net "A_CPU_NODE1_AE64_PU")
	)
	(segment
		(start 73.247758 -77.085952)
		(end 73.247758 -76.753974)
		(width 0.1016)
		(layer "F.Cu")
		(net "A_CPU_NODE1_AE64_PU")
	)
	(segment
		(start 73.247758 -76.753974)
		(end 73.669398 -76.332334)
		(width 0.1016)
		(layer "F.Cu")
		(net "A_CPU_NODE1_AE64_PU")
	)
	(segment
		(start 79.50581 -74.285094)
		(end 77.922628 -74.285094)
		(width 0.1016)
		(layer "F.Cu")
		(net "A_CPU_NODE1_AE64_PU")
	)
	(segment
		(start 75.240642 -75.94346)
		(end 76.146152 -75.94346)
		(width 0.1016)
		(layer "F.Cu")
		(net "A_CPU_NODE1_AE64_PU")
	)
	(segment
		(start 76.146152 -75.94346)
		(end 77.804518 -74.285094)
		(width 0.1016)
		(layer "F.Cu")
		(net "A_CPU_NODE1_AE64_PU")
	)
	(segment
		(start 79.784702 -74.285094)
		(end 79.781908 -74.287888)
		(width 0.1016)
		(layer "F.Cu")
		(net "A_CPU_NODE1_AE64_PU")
	)
	(segment
		(start 77.804518 -74.285094)
		(end 77.922628 -74.285094)
		(width 0.1016)
		(layer "F.Cu")
		(net "A_CPU_NODE1_AE64_PU")
	)
	(segment
		(start 79.508604 -74.287888)
		(end 79.50581 -74.285094)
		(width 0.1016)
		(layer "F.Cu")
		(net "A_CPU_NODE1_AE64_PU")
	)
	(segment
		(start 73.669398 -76.332334)
		(end 74.851768 -76.332334)
		(width 0.1016)
		(layer "F.Cu")
		(net "A_CPU_NODE1_AE64_PU")
	)
	(segment
		(start 79.781908 -74.287888)
		(end 79.508604 -74.287888)
		(width 0.1016)
		(layer "F.Cu")
		(net "A_CPU_NODE1_AE64_PU")
	)
	(segment
		(start 81.374996 -74.333862)
		(end 81.326228 -74.285094)
		(width 0.1016)
		(layer "F.Cu")
		(net "A_CPU_NODE1_AE64_PU")
	)
	(segment
		(start 81.326228 -74.285094)
		(end 79.784702 -74.285094)
		(width 0.1016)
		(layer "F.Cu")
		(net "A_CPU_NODE1_AE64_PU")
	)
	(via
		(at 77.922628 -74.285094)
		(size 0.762)
		(drill 0.381)
		(layers "F.Cu" "B.Cu")
		(net "A_CPU_NODE1_AE64_PU")
	)
	(segment
		(start 125.787912 -148.175472)
		(end 125.054614 -148.175472)
		(width 0.127)
		(layer "F.Cu")
		(net "P2E_CPU_PCIE_SW_NODE1_TX_DN")
	)
	(segment
		(start 125.054614 -148.175472)
		(end 125.006862 -148.12772)
		(width 0.127)
		(layer "F.Cu")
		(net "P2E_CPU_PCIE_SW_NODE1_TX_DN")
	)
	(segment
		(start 125.006862 -148.12772)
		(end 124.386594 -148.12772)
		(width 0.127)
		(layer "F.Cu")
		(net "P2E_CPU_PCIE_SW_NODE1_TX_DN")
	)
	(segment
		(start 123.910852 -148.603462)
		(end 123.910852 -148.90115)
		(width 0.127)
		(layer "F.Cu")
		(net "P2E_CPU_PCIE_SW_NODE1_TX_DN")
	)
	(segment
		(start 124.139452 -149.12975)
		(end 124.647452 -149.12975)
		(width 0.127)
		(layer "F.Cu")
		(net "P2E_CPU_PCIE_SW_NODE1_TX_DN")
	)
	(segment
		(start 124.386594 -148.12772)
		(end 123.910852 -148.603462)
		(width 0.127)
		(layer "F.Cu")
		(net "P2E_CPU_PCIE_SW_NODE1_TX_DN")
	)
	(segment
		(start 123.910852 -148.90115)
		(end 124.139452 -149.12975)
		(width 0.127)
		(layer "F.Cu")
		(net "P2E_CPU_PCIE_SW_NODE1_TX_DN")
	)
	(via
		(at 124.647452 -149.12975)
		(size 0.508)
		(drill 0.254)
		(layers "F.Cu" "B.Cu")
		(net "P2E_CPU_PCIE_SW_NODE1_TX_DN")
	)
	(segment
		(start 123.059952 -147.320762)
		(end 119.489728 -146.274536)
		(width 0.127)
		(layer "B.Cu")
		(net "P2E_CPU_PCIE_SW_NODE1_TX_DN")
	)
	(segment
		(start 33.975548 -73.32091)
		(end 34.05124 -72.947022)
		(width 0.127)
		(layer "B.Cu")
		(net "P2E_CPU_PCIE_SW_NODE1_TX_DN")
	)
	(segment
		(start 34.183828 -72.288654)
		(end 34.25952 -71.914766)
		(width 0.127)
		(layer "B.Cu")
		(net "P2E_CPU_PCIE_SW_NODE1_TX_DN")
	)
	(segment
		(start 37.558218 -68.521326)
		(end 38.2778 -68.543932)
		(width 0.127)
		(layer "B.Cu")
		(net "P2E_CPU_PCIE_SW_NODE1_TX_DN")
	)
	(segment
		(start 76.48321 -105.079038)
		(end 70.95363 -105.079038)
		(width 0.127)
		(layer "B.Cu")
		(net "P2E_CPU_PCIE_SW_NODE1_TX_DN")
	)
	(segment
		(start 43.3959 -104.310434)
		(end 43.39463 -104.31018)
		(width 0.127)
		(layer "B.Cu")
		(net "P2E_CPU_PCIE_SW_NODE1_TX_DN")
	)
	(segment
		(start 110.31474 -146.139154)
		(end 104.556814 -146.939)
		(width 0.127)
		(layer "B.Cu")
		(net "P2E_CPU_PCIE_SW_NODE1_TX_DN")
	)
	(segment
		(start 61.649864 -104.467914)
		(end 60.558426 -104.467914)
		(width 0.127)
		(layer "B.Cu")
		(net "P2E_CPU_PCIE_SW_NODE1_TX_DN")
	)
	(segment
		(start 70.95363 -105.079038)
		(end 64.391794 -105.045764)
		(width 0.127)
		(layer "B.Cu")
		(net "P2E_CPU_PCIE_SW_NODE1_TX_DN")
	)
	(segment
		(start 124.164852 -148.119846)
		(end 123.059952 -147.320762)
		(width 0.127)
		(layer "B.Cu")
		(net "P2E_CPU_PCIE_SW_NODE1_TX_DN")
	)
	(segment
		(start 33.288478 -95.108014)
		(end 33.177988 -94.743778)
		(width 0.127)
		(layer "B.Cu")
		(net "P2E_CPU_PCIE_SW_NODE1_TX_DN")
	)
	(segment
		(start 80.294226 -109.875066)
		(end 79.354426 -107.57154)
		(width 0.127)
		(layer "B.Cu")
		(net "P2E_CPU_PCIE_SW_NODE1_TX_DN")
	)
	(segment
		(start 119.489728 -146.274536)
		(end 110.31474 -146.139154)
		(width 0.127)
		(layer "B.Cu")
		(net "P2E_CPU_PCIE_SW_NODE1_TX_DN")
	)
	(segment
		(start 34.145474 -71.743824)
		(end 34.392362 -70.51548)
		(width 0.127)
		(layer "B.Cu")
		(net "P2E_CPU_PCIE_SW_NODE1_TX_DN")
	)
	(segment
		(start 89.36736 -115.053364)
		(end 88.40216 -111.658654)
		(width 0.127)
		(layer "B.Cu")
		(net "P2E_CPU_PCIE_SW_NODE1_TX_DN")
	)
	(segment
		(start 40.416734 -103.546402)
		(end 37.8714 -101.023166)
		(width 0.127)
		(layer "B.Cu")
		(net "P2E_CPU_PCIE_SW_NODE1_TX_DN")
	)
	(segment
		(start 64.391794 -105.045764)
		(end 62.5475 -104.488488)
		(width 0.127)
		(layer "B.Cu")
		(net "P2E_CPU_PCIE_SW_NODE1_TX_DN")
	)
	(segment
		(start 33.84296 -73.979278)
		(end 33.728914 -73.808336)
		(width 0.127)
		(layer "B.Cu")
		(net "P2E_CPU_PCIE_SW_NODE1_TX_DN")
	)
	(segment
		(start 43.39463 -104.31018)
		(end 43.379644 -104.308656)
		(width 0.127)
		(layer "B.Cu")
		(net "P2E_CPU_PCIE_SW_NODE1_TX_DN")
	)
	(segment
		(start 33.86582 -97.017586)
		(end 33.490916 -95.776542)
		(width 0.127)
		(layer "B.Cu")
		(net "P2E_CPU_PCIE_SW_NODE1_TX_DN")
	)
	(segment
		(start 91.057984 -124.64161)
		(end 91.165426 -123.065794)
		(width 0.127)
		(layer "B.Cu")
		(net "P2E_CPU_PCIE_SW_NODE1_TX_DN")
	)
	(segment
		(start 33.767268 -74.353166)
		(end 33.84296 -73.979278)
		(width 0.127)
		(layer "B.Cu")
		(net "P2E_CPU_PCIE_SW_NODE1_TX_DN")
	)
	(segment
		(start 34.924492 -69.9262)
		(end 36.215828 -69.71919)
		(width 0.127)
		(layer "B.Cu")
		(net "P2E_CPU_PCIE_SW_NODE1_TX_DN")
	)
	(segment
		(start 91.048332 -127.597662)
		(end 91.211908 -126.341124)
		(width 0.127)
		(layer "B.Cu")
		(net "P2E_CPU_PCIE_SW_NODE1_TX_DN")
	)
	(segment
		(start 33.433258 -75.275694)
		(end 33.596326 -74.466704)
		(width 0.127)
		(layer "B.Cu")
		(net "P2E_CPU_PCIE_SW_NODE1_TX_DN")
	)
	(segment
		(start 124.647452 -149.12975)
		(end 124.164852 -148.64715)
		(width 0.127)
		(layer "B.Cu")
		(net "P2E_CPU_PCIE_SW_NODE1_TX_DN")
	)
	(segment
		(start 33.177988 -94.743778)
		(end 32.975804 -94.076012)
		(width 0.127)
		(layer "B.Cu")
		(net "P2E_CPU_PCIE_SW_NODE1_TX_DN")
	)
	(segment
		(start 91.211908 -126.341124)
		(end 91.057984 -124.64161)
		(width 0.127)
		(layer "B.Cu")
		(net "P2E_CPU_PCIE_SW_NODE1_TX_DN")
	)
	(segment
		(start 62.5475 -104.488488)
		(end 61.789564 -104.471216)
		(width 0.127)
		(layer "B.Cu")
		(net "P2E_CPU_PCIE_SW_NODE1_TX_DN")
	)
	(segment
		(start 36.215828 -69.71919)
		(end 37.222176 -68.712842)
		(width 0.127)
		(layer "B.Cu")
		(net "P2E_CPU_PCIE_SW_NODE1_TX_DN")
	)
	(segment
		(start 37.8714 -101.023166)
		(end 33.86582 -97.017586)
		(width 0.127)
		(layer "B.Cu")
		(net "P2E_CPU_PCIE_SW_NODE1_TX_DN")
	)
	(segment
		(start 52.504594 -104.613202)
		(end 43.401488 -104.311196)
		(width 0.127)
		(layer "B.Cu")
		(net "P2E_CPU_PCIE_SW_NODE1_TX_DN")
	)
	(segment
		(start 90.103198 -135.808466)
		(end 91.048332 -127.597662)
		(width 0.127)
		(layer "B.Cu")
		(net "P2E_CPU_PCIE_SW_NODE1_TX_DN")
	)
	(segment
		(start 86.94674 -110.876842)
		(end 84.5312 -110.76432)
		(width 0.127)
		(layer "B.Cu")
		(net "P2E_CPU_PCIE_SW_NODE1_TX_DN")
	)
	(segment
		(start 33.288732 -95.108776)
		(end 33.288478 -95.108014)
		(width 0.127)
		(layer "B.Cu")
		(net "P2E_CPU_PCIE_SW_NODE1_TX_DN")
	)
	(segment
		(start 33.490916 -95.776542)
		(end 33.597342 -95.579184)
		(width 0.127)
		(layer "B.Cu")
		(net "P2E_CPU_PCIE_SW_NODE1_TX_DN")
	)
	(segment
		(start 41.532048 -103.978964)
		(end 41.301162 -103.937816)
		(width 0.127)
		(layer "B.Cu")
		(net "P2E_CPU_PCIE_SW_NODE1_TX_DN")
	)
	(segment
		(start 91.112086 -122.193304)
		(end 89.36736 -115.053364)
		(width 0.127)
		(layer "B.Cu")
		(net "P2E_CPU_PCIE_SW_NODE1_TX_DN")
	)
	(segment
		(start 34.392362 -70.51548)
		(end 34.924492 -69.9262)
		(width 0.127)
		(layer "B.Cu")
		(net "P2E_CPU_PCIE_SW_NODE1_TX_DN")
	)
	(segment
		(start 88.40216 -111.658654)
		(end 86.94674 -110.876842)
		(width 0.127)
		(layer "B.Cu")
		(net "P2E_CPU_PCIE_SW_NODE1_TX_DN")
	)
	(segment
		(start 104.556814 -146.939)
		(end 96.965516 -146.573748)
		(width 0.127)
		(layer "B.Cu")
		(net "P2E_CPU_PCIE_SW_NODE1_TX_DN")
	)
	(segment
		(start 32.562546 -92.711016)
		(end 32.315404 -77.399642)
		(width 0.127)
		(layer "B.Cu")
		(net "P2E_CPU_PCIE_SW_NODE1_TX_DN")
	)
	(segment
		(start 43.379644 -104.308656)
		(end 41.532048 -103.978964)
		(width 0.127)
		(layer "B.Cu")
		(net "P2E_CPU_PCIE_SW_NODE1_TX_DN")
	)
	(segment
		(start 77.805026 -105.851452)
		(end 76.48321 -105.079038)
		(width 0.127)
		(layer "B.Cu")
		(net "P2E_CPU_PCIE_SW_NODE1_TX_DN")
	)
	(segment
		(start 91.165426 -123.065794)
		(end 91.146884 -122.761248)
		(width 0.127)
		(layer "B.Cu")
		(net "P2E_CPU_PCIE_SW_NODE1_TX_DN")
	)
	(segment
		(start 79.354426 -107.57154)
		(end 77.805026 -105.851452)
		(width 0.127)
		(layer "B.Cu")
		(net "P2E_CPU_PCIE_SW_NODE1_TX_DN")
	)
	(segment
		(start 33.937194 -72.77608)
		(end 34.012886 -72.402192)
		(width 0.127)
		(layer "B.Cu")
		(net "P2E_CPU_PCIE_SW_NODE1_TX_DN")
	)
	(segment
		(start 32.315404 -77.399642)
		(end 33.433258 -75.275694)
		(width 0.127)
		(layer "B.Cu")
		(net "P2E_CPU_PCIE_SW_NODE1_TX_DN")
	)
	(segment
		(start 41.301162 -103.937816)
		(end 40.416734 -103.546402)
		(width 0.127)
		(layer "B.Cu")
		(net "P2E_CPU_PCIE_SW_NODE1_TX_DN")
	)
	(segment
		(start 90.133678 -139.600686)
		(end 90.103198 -135.808466)
		(width 0.127)
		(layer "B.Cu")
		(net "P2E_CPU_PCIE_SW_NODE1_TX_DN")
	)
	(segment
		(start 43.39971 -104.310942)
		(end 43.3959 -104.310434)
		(width 0.127)
		(layer "B.Cu")
		(net "P2E_CPU_PCIE_SW_NODE1_TX_DN")
	)
	(segment
		(start 38.2778 -68.543932)
		(end 38.720522 -68.957698)
		(width 0.127)
		(layer "B.Cu")
		(net "P2E_CPU_PCIE_SW_NODE1_TX_DN")
	)
	(segment
		(start 61.789564 -104.471216)
		(end 61.649864 -104.467914)
		(width 0.127)
		(layer "B.Cu")
		(net "P2E_CPU_PCIE_SW_NODE1_TX_DN")
	)
	(segment
		(start 43.401488 -104.311196)
		(end 43.39971 -104.310942)
		(width 0.127)
		(layer "B.Cu")
		(net "P2E_CPU_PCIE_SW_NODE1_TX_DN")
	)
	(segment
		(start 92.624148 -144.836896)
		(end 90.133678 -139.600686)
		(width 0.127)
		(layer "B.Cu")
		(net "P2E_CPU_PCIE_SW_NODE1_TX_DN")
	)
	(segment
		(start 33.597342 -95.579184)
		(end 33.486598 -95.214186)
		(width 0.127)
		(layer "B.Cu")
		(net "P2E_CPU_PCIE_SW_NODE1_TX_DN")
	)
	(segment
		(start 37.222176 -68.712842)
		(end 37.558218 -68.521326)
		(width 0.127)
		(layer "B.Cu")
		(net "P2E_CPU_PCIE_SW_NODE1_TX_DN")
	)
	(segment
		(start 91.146884 -122.761248)
		(end 91.112086 -122.193304)
		(width 0.127)
		(layer "B.Cu")
		(net "P2E_CPU_PCIE_SW_NODE1_TX_DN")
	)
	(segment
		(start 52.504594 -104.609646)
		(end 52.504594 -104.613202)
		(width 0.127)
		(layer "B.Cu")
		(net "P2E_CPU_PCIE_SW_NODE1_TX_DN")
	)
	(segment
		(start 84.5312 -110.76432)
		(end 82.36712 -111.096298)
		(width 0.127)
		(layer "B.Cu")
		(net "P2E_CPU_PCIE_SW_NODE1_TX_DN")
	)
	(segment
		(start 33.728914 -73.808336)
		(end 33.804606 -73.434448)
		(width 0.127)
		(layer "B.Cu")
		(net "P2E_CPU_PCIE_SW_NODE1_TX_DN")
	)
	(segment
		(start 34.012886 -72.402192)
		(end 34.183828 -72.288654)
		(width 0.127)
		(layer "B.Cu")
		(net "P2E_CPU_PCIE_SW_NODE1_TX_DN")
	)
	(segment
		(start 96.965516 -146.573748)
		(end 92.624148 -144.836896)
		(width 0.127)
		(layer "B.Cu")
		(net "P2E_CPU_PCIE_SW_NODE1_TX_DN")
	)
	(segment
		(start 32.975804 -94.076012)
		(end 32.562546 -92.711016)
		(width 0.127)
		(layer "B.Cu")
		(net "P2E_CPU_PCIE_SW_NODE1_TX_DN")
	)
	(segment
		(start 34.25952 -71.914766)
		(end 34.145474 -71.743824)
		(width 0.127)
		(layer "B.Cu")
		(net "P2E_CPU_PCIE_SW_NODE1_TX_DN")
	)
	(segment
		(start 33.486598 -95.214186)
		(end 33.288732 -95.108776)
		(width 0.127)
		(layer "B.Cu")
		(net "P2E_CPU_PCIE_SW_NODE1_TX_DN")
	)
	(segment
		(start 33.596326 -74.466704)
		(end 33.767268 -74.353166)
		(width 0.127)
		(layer "B.Cu")
		(net "P2E_CPU_PCIE_SW_NODE1_TX_DN")
	)
	(segment
		(start 82.36712 -111.096298)
		(end 80.93583 -110.68685)
		(width 0.127)
		(layer "B.Cu")
		(net "P2E_CPU_PCIE_SW_NODE1_TX_DN")
	)
	(segment
		(start 33.804606 -73.434448)
		(end 33.975548 -73.32091)
		(width 0.127)
		(layer "B.Cu")
		(net "P2E_CPU_PCIE_SW_NODE1_TX_DN")
	)
	(segment
		(start 34.05124 -72.947022)
		(end 33.937194 -72.77608)
		(width 0.127)
		(layer "B.Cu")
		(net "P2E_CPU_PCIE_SW_NODE1_TX_DN")
	)
	(segment
		(start 124.164852 -148.64715)
		(end 124.164852 -148.119846)
		(width 0.127)
		(layer "B.Cu")
		(net "P2E_CPU_PCIE_SW_NODE1_TX_DN")
	)
	(segment
		(start 60.558426 -104.467914)
		(end 52.504594 -104.609646)
		(width 0.127)
		(layer "B.Cu")
		(net "P2E_CPU_PCIE_SW_NODE1_TX_DN")
	)
	(segment
		(start 80.93583 -110.68685)
		(end 80.294226 -109.875066)
		(width 0.127)
		(layer "B.Cu")
		(net "P2E_CPU_PCIE_SW_NODE1_TX_DN")
	)
	(segment
		(start 67.789552 -63.640462)
		(end 67.611498 -63.462408)
		(width 0.1016)
		(layer "F.Cu")
		(net "M1_DQ_NODE1_DQ38")
	)
	(segment
		(start 67.789552 -64.047878)
		(end 67.789552 -63.640462)
		(width 0.1016)
		(layer "F.Cu")
		(net "M1_DQ_NODE1_DQ38")
	)
	(segment
		(start 85.050122 -27.622754)
		(end 85.673946 -26.99893)
		(width 0.1651)
		(layer "F.Cu")
		(net "M1_DQ_NODE1_DQ38")
	)
	(segment
		(start 85.75802 -26.99893)
		(end 85.75802 -27.001216)
		(width 0.1651)
		(layer "F.Cu")
		(net "M1_DQ_NODE1_DQ38")
	)
	(segment
		(start 85.050122 -29.149802)
		(end 85.050122 -27.622754)
		(width 0.1651)
		(layer "F.Cu")
		(net "M1_DQ_NODE1_DQ38")
	)
	(segment
		(start 85.673946 -26.99893)
		(end 85.75802 -26.99893)
		(width 0.1651)
		(layer "F.Cu")
		(net "M1_DQ_NODE1_DQ38")
	)
	(via
		(at 67.611498 -63.462408)
		(size 0.508)
		(drill 0.254)
		(layers "F.Cu" "B.Cu")
		(net "M1_DQ_NODE1_DQ38")
	)
	(via
		(at 85.75802 -27.001216)
		(size 0.508)
		(drill 0.254)
		(layers "F.Cu" "B.Cu")
		(net "M1_DQ_NODE1_DQ38")
	)
	(segment
		(start 68.209668 -64.650874)
		(end 68.782438 -64.650874)
		(width 0.1016)
		(layer "In7.Cu")
		(net "M1_DQ_NODE1_DQ38")
	)
	(segment
		(start 74.737976 -50.273712)
		(end 74.522076 -50.057812)
		(width 0.2032)
		(layer "In7.Cu")
		(net "M1_DQ_NODE1_DQ38")
	)
	(segment
		(start 67.61099 -63.462916)
		(end 67.61099 -64.052196)
		(width 0.1016)
		(layer "In7.Cu")
		(net "M1_DQ_NODE1_DQ38")
	)
	(segment
		(start 83.99018 -34.326068)
		(end 84.19846 -34.117788)
		(width 0.2032)
		(layer "In7.Cu")
		(net "M1_DQ_NODE1_DQ38")
	)
	(segment
		(start 84.77504 -34.117788)
		(end 84.98332 -33.909508)
		(width 0.2032)
		(layer "In7.Cu")
		(net "M1_DQ_NODE1_DQ38")
	)
	(segment
		(start 84.77504 -37.673788)
		(end 84.19846 -37.673788)
		(width 0.2032)
		(layer "In7.Cu")
		(net "M1_DQ_NODE1_DQ38")
	)
	(segment
		(start 83.99018 -34.620708)
		(end 83.99018 -34.326068)
		(width 0.2032)
		(layer "In7.Cu")
		(net "M1_DQ_NODE1_DQ38")
	)
	(segment
		(start 84.77504 -36.251388)
		(end 84.19846 -36.251388)
		(width 0.2032)
		(layer "In7.Cu")
		(net "M1_DQ_NODE1_DQ38")
	)
	(segment
		(start 72.60082 -59.28106)
		(end 72.60082 -52.697634)
		(width 0.2032)
		(layer "In7.Cu")
		(net "M1_DQ_NODE1_DQ38")
	)
	(segment
		(start 84.19846 -37.673788)
		(end 83.99018 -37.465508)
		(width 0.2032)
		(layer "In7.Cu")
		(net "M1_DQ_NODE1_DQ38")
	)
	(segment
		(start 72.924416 -59.604656)
		(end 72.60082 -59.28106)
		(width 0.2032)
		(layer "In7.Cu")
		(net "M1_DQ_NODE1_DQ38")
	)
	(segment
		(start 73.054464 -62.143894)
		(end 73.054464 -61.6966)
		(width 0.1016)
		(layer "In7.Cu")
		(net "M1_DQ_NODE1_DQ38")
	)
	(segment
		(start 84.98332 -38.302946)
		(end 84.98332 -37.882068)
		(width 0.2032)
		(layer "In7.Cu")
		(net "M1_DQ_NODE1_DQ38")
	)
	(segment
		(start 73.202546 -51.089814)
		(end 72.90816 -51.089814)
		(width 0.2032)
		(layer "In7.Cu")
		(net "M1_DQ_NODE1_DQ38")
	)
	(segment
		(start 83.99018 -37.465508)
		(end 83.99018 -37.170868)
		(width 0.2032)
		(layer "In7.Cu")
		(net "M1_DQ_NODE1_DQ38")
	)
	(segment
		(start 72.699372 -50.881026)
		(end 72.699372 -50.586894)
		(width 0.2032)
		(layer "In7.Cu")
		(net "M1_DQ_NODE1_DQ38")
	)
	(segment
		(start 84.19846 -35.540188)
		(end 84.77504 -35.540188)
		(width 0.2032)
		(layer "In7.Cu")
		(net "M1_DQ_NODE1_DQ38")
	)
	(segment
		(start 84.98332 -29.600652)
		(end 85.75802 -28.825952)
		(width 0.2032)
		(layer "In7.Cu")
		(net "M1_DQ_NODE1_DQ38")
	)
	(segment
		(start 84.19846 -36.962588)
		(end 84.77504 -36.962588)
		(width 0.2032)
		(layer "In7.Cu")
		(net "M1_DQ_NODE1_DQ38")
	)
	(segment
		(start 72.90816 -51.089814)
		(end 72.699372 -50.881026)
		(width 0.2032)
		(layer "In7.Cu")
		(net "M1_DQ_NODE1_DQ38")
	)
	(segment
		(start 83.99018 -37.170868)
		(end 84.19846 -36.962588)
		(width 0.2032)
		(layer "In7.Cu")
		(net "M1_DQ_NODE1_DQ38")
	)
	(segment
		(start 67.611498 -63.462408)
		(end 67.61099 -63.462916)
		(width 0.1016)
		(layer "In7.Cu")
		(net "M1_DQ_NODE1_DQ38")
	)
	(segment
		(start 84.19846 -36.251388)
		(end 83.99018 -36.043108)
		(width 0.2032)
		(layer "In7.Cu")
		(net "M1_DQ_NODE1_DQ38")
	)
	(segment
		(start 70.266052 -63.16726)
		(end 72.031098 -63.16726)
		(width 0.1016)
		(layer "In7.Cu")
		(net "M1_DQ_NODE1_DQ38")
	)
	(segment
		(start 85.75802 -28.825952)
		(end 85.75802 -27.001216)
		(width 0.2032)
		(layer "In7.Cu")
		(net "M1_DQ_NODE1_DQ38")
	)
	(segment
		(start 74.737976 -50.560732)
		(end 74.737976 -50.273712)
		(width 0.2032)
		(layer "In7.Cu")
		(net "M1_DQ_NODE1_DQ38")
	)
	(segment
		(start 67.61099 -64.052196)
		(end 68.209668 -64.650874)
		(width 0.1016)
		(layer "In7.Cu")
		(net "M1_DQ_NODE1_DQ38")
	)
	(segment
		(start 72.699372 -50.586894)
		(end 84.98332 -38.302946)
		(width 0.2032)
		(layer "In7.Cu")
		(net "M1_DQ_NODE1_DQ38")
	)
	(segment
		(start 72.924416 -61.566552)
		(end 72.924416 -59.604656)
		(width 0.2032)
		(layer "In7.Cu")
		(net "M1_DQ_NODE1_DQ38")
	)
	(segment
		(start 84.77504 -35.540188)
		(end 84.98332 -35.331908)
		(width 0.2032)
		(layer "In7.Cu")
		(net "M1_DQ_NODE1_DQ38")
	)
	(segment
		(start 84.77504 -36.962588)
		(end 84.98332 -36.754308)
		(width 0.2032)
		(layer "In7.Cu")
		(net "M1_DQ_NODE1_DQ38")
	)
	(segment
		(start 84.77504 -34.828988)
		(end 84.19846 -34.828988)
		(width 0.2032)
		(layer "In7.Cu")
		(net "M1_DQ_NODE1_DQ38")
	)
	(segment
		(start 84.98332 -37.882068)
		(end 84.77504 -37.673788)
		(width 0.2032)
		(layer "In7.Cu")
		(net "M1_DQ_NODE1_DQ38")
	)
	(segment
		(start 74.522076 -50.057812)
		(end 74.234548 -50.057812)
		(width 0.2032)
		(layer "In7.Cu")
		(net "M1_DQ_NODE1_DQ38")
	)
	(segment
		(start 72.60082 -52.697634)
		(end 74.737976 -50.560732)
		(width 0.2032)
		(layer "In7.Cu")
		(net "M1_DQ_NODE1_DQ38")
	)
	(segment
		(start 72.031098 -63.16726)
		(end 73.054464 -62.143894)
		(width 0.1016)
		(layer "In7.Cu")
		(net "M1_DQ_NODE1_DQ38")
	)
	(segment
		(start 84.98332 -36.754308)
		(end 84.98332 -36.459668)
		(width 0.2032)
		(layer "In7.Cu")
		(net "M1_DQ_NODE1_DQ38")
	)
	(segment
		(start 84.19846 -34.828988)
		(end 83.99018 -34.620708)
		(width 0.2032)
		(layer "In7.Cu")
		(net "M1_DQ_NODE1_DQ38")
	)
	(segment
		(start 84.98332 -36.459668)
		(end 84.77504 -36.251388)
		(width 0.2032)
		(layer "In7.Cu")
		(net "M1_DQ_NODE1_DQ38")
	)
	(segment
		(start 84.98332 -33.909508)
		(end 84.98332 -29.600652)
		(width 0.2032)
		(layer "In7.Cu")
		(net "M1_DQ_NODE1_DQ38")
	)
	(segment
		(start 83.99018 -35.748468)
		(end 84.19846 -35.540188)
		(width 0.2032)
		(layer "In7.Cu")
		(net "M1_DQ_NODE1_DQ38")
	)
	(segment
		(start 73.054464 -61.6966)
		(end 72.924416 -61.566552)
		(width 0.1016)
		(layer "In7.Cu")
		(net "M1_DQ_NODE1_DQ38")
	)
	(segment
		(start 84.98332 -35.331908)
		(end 84.98332 -35.037268)
		(width 0.2032)
		(layer "In7.Cu")
		(net "M1_DQ_NODE1_DQ38")
	)
	(segment
		(start 84.19846 -34.117788)
		(end 84.77504 -34.117788)
		(width 0.2032)
		(layer "In7.Cu")
		(net "M1_DQ_NODE1_DQ38")
	)
	(segment
		(start 83.99018 -36.043108)
		(end 83.99018 -35.748468)
		(width 0.2032)
		(layer "In7.Cu")
		(net "M1_DQ_NODE1_DQ38")
	)
	(segment
		(start 74.234548 -50.057812)
		(end 73.202546 -51.089814)
		(width 0.2032)
		(layer "In7.Cu")
		(net "M1_DQ_NODE1_DQ38")
	)
	(segment
		(start 68.782438 -64.650874)
		(end 70.266052 -63.16726)
		(width 0.1016)
		(layer "In7.Cu")
		(net "M1_DQ_NODE1_DQ38")
	)
	(segment
		(start 84.98332 -35.037268)
		(end 84.77504 -34.828988)
		(width 0.2032)
		(layer "In7.Cu")
		(net "M1_DQ_NODE1_DQ38")
	)
	(segment
		(start 66.141854 -128.859534)
		(end 66.141854 -128.857248)
		(width 0.1016)
		(layer "F.Cu")
		(net "BMC_ROMA13")
	)
	(segment
		(start 66.141854 -128.857248)
		(end 66.42989 -128.569466)
		(width 0.1016)
		(layer "F.Cu")
		(net "BMC_ROMA13")
	)
	(segment
		(start 66.42989 -128.569466)
		(end 66.540888 -128.458214)
		(width 0.1016)
		(layer "F.Cu")
		(net "BMC_ROMA13")
	)
	(via
		(at 66.540888 -128.458214)
		(size 0.49022)
		(drill 0.254)
		(layers "F.Cu" "B.Cu")
		(net "BMC_ROMA13")
	)
	(via
		(at 66.067686 -127.038862)
		(size 0.6604)
		(drill 0.3302)
		(layers "F.Cu" "B.Cu")
		(net "BMC_ROMA13")
	)
	(segment
		(start 67.826636 -118.910862)
		(end 67.826636 -121.814844)
		(width 0.1016)
		(layer "B.Cu")
		(net "BMC_ROMA13")
	)
	(segment
		(start 66.067686 -127.985012)
		(end 66.067686 -127.038862)
		(width 0.1016)
		(layer "B.Cu")
		(net "BMC_ROMA13")
	)
	(segment
		(start 67.826636 -121.814844)
		(end 66.905886 -122.735594)
		(width 0.1016)
		(layer "B.Cu")
		(net "BMC_ROMA13")
	)
	(segment
		(start 65.991486 -126.607062)
		(end 66.067686 -126.683262)
		(width 0.1016)
		(layer "B.Cu")
		(net "BMC_ROMA13")
	)
	(segment
		(start 65.991486 -124.455682)
		(end 65.991486 -126.607062)
		(width 0.1016)
		(layer "B.Cu")
		(net "BMC_ROMA13")
	)
	(segment
		(start 66.540888 -128.458214)
		(end 66.067686 -127.985012)
		(width 0.1016)
		(layer "B.Cu")
		(net "BMC_ROMA13")
	)
	(segment
		(start 66.067686 -126.683262)
		(end 66.067686 -127.038862)
		(width 0.1016)
		(layer "B.Cu")
		(net "BMC_ROMA13")
	)
	(segment
		(start 66.905886 -122.735594)
		(end 66.905886 -123.541282)
		(width 0.1016)
		(layer "B.Cu")
		(net "BMC_ROMA13")
	)
	(segment
		(start 66.905886 -123.541282)
		(end 65.991486 -124.455682)
		(width 0.1016)
		(layer "B.Cu")
		(net "BMC_ROMA13")
	)
	(segment
		(start 68.379086 -118.358412)
		(end 67.826636 -118.910862)
		(width 0.1016)
		(layer "B.Cu")
		(net "BMC_ROMA13")
	)
	(segment
		(start 53.250084 -29.149802)
		(end 53.250084 -30.555438)
		(width 0.1016)
		(layer "F.Cu")
		(net "PD_NODE1_DM2")
	)
	(segment
		(start 53.250084 -30.555438)
		(end 53.496464 -30.801818)
		(width 0.1016)
		(layer "F.Cu")
		(net "PD_NODE1_DM2")
	)
	(segment
		(start 53.496464 -30.801818)
		(end 53.498242 -30.801818)
		(width 0.1016)
		(layer "F.Cu")
		(net "PD_NODE1_DM2")
	)
	(via
		(at 53.498242 -30.801818)
		(size 0.508)
		(drill 0.254)
		(layers "F.Cu" "B.Cu")
		(net "PD_NODE1_DM2")
	)
	(segment
		(start 53.593492 -30.706568)
		(end 53.498242 -30.801818)
		(width 0.1016)
		(layer "B.Cu")
		(net "PD_NODE1_DM2")
	)
	(segment
		(start 53.593492 -29.199078)
		(end 53.593492 -30.706568)
		(width 0.1016)
		(layer "B.Cu")
		(net "PD_NODE1_DM2")
	)
	(segment
		(start 45.799248 -69.370702)
		(end 45.78223 -69.370702)
		(width 0.1016)
		(layer "F.Cu")
		(net "P2E_CPU_PCIE_SW_NODE1_TX_C_DN")
	)
	(segment
		(start 45.78223 -69.370702)
		(end 45.419772 -69.73316)
		(width 0.1016)
		(layer "F.Cu")
		(net "P2E_CPU_PCIE_SW_NODE1_TX_C_DN")
	)
	(via
		(at 45.419772 -69.73316)
		(size 0.49022)
		(drill 0.254)
		(layers "F.Cu" "B.Cu")
		(net "P2E_CPU_PCIE_SW_NODE1_TX_C_DN")
	)
	(via
		(at 42.633646 -68.641468)
		(size 0.4064)
		(drill 0.2032)
		(layers "F.Cu" "B.Cu")
		(net "P2E_CPU_PCIE_SW_NODE1_TX_C_DN")
	)
	(segment
		(start 45.104558 -69.248528)
		(end 45.573188 -69.248528)
		(width 0.1016)
		(layer "B.Cu")
		(net "P2E_CPU_PCIE_SW_NODE1_TX_C_DN")
	)
	(segment
		(start 42.984166 -68.641468)
		(end 43.103546 -68.522088)
		(width 0.127)
		(layer "B.Cu")
		(net "P2E_CPU_PCIE_SW_NODE1_TX_C_DN")
	)
	(segment
		(start 45.718984 -69.584062)
		(end 45.569886 -69.73316)
		(width 0.1016)
		(layer "B.Cu")
		(net "P2E_CPU_PCIE_SW_NODE1_TX_C_DN")
	)
	(segment
		(start 41.983406 -68.641468)
		(end 42.633646 -68.641468)
		(width 0.127)
		(layer "B.Cu")
		(net "P2E_CPU_PCIE_SW_NODE1_TX_C_DN")
	)
	(segment
		(start 45.573188 -69.248528)
		(end 45.718984 -69.394324)
		(width 0.1016)
		(layer "B.Cu")
		(net "P2E_CPU_PCIE_SW_NODE1_TX_C_DN")
	)
	(segment
		(start 39.74465 -68.746116)
		(end 39.849298 -68.641468)
		(width 0.127)
		(layer "B.Cu")
		(net "P2E_CPU_PCIE_SW_NODE1_TX_C_DN")
	)
	(segment
		(start 45.718984 -69.394324)
		(end 45.718984 -69.584062)
		(width 0.1016)
		(layer "B.Cu")
		(net "P2E_CPU_PCIE_SW_NODE1_TX_C_DN")
	)
	(segment
		(start 43.228768 -68.525136)
		(end 44.381166 -68.525136)
		(width 0.1016)
		(layer "B.Cu")
		(net "P2E_CPU_PCIE_SW_NODE1_TX_C_DN")
	)
	(segment
		(start 45.569886 -69.73316)
		(end 45.419772 -69.73316)
		(width 0.1016)
		(layer "B.Cu")
		(net "P2E_CPU_PCIE_SW_NODE1_TX_C_DN")
	)
	(segment
		(start 43.1165 -68.509134)
		(end 43.212258 -68.509134)
		(width 0.1016)
		(layer "B.Cu")
		(net "P2E_CPU_PCIE_SW_NODE1_TX_C_DN")
	)
	(segment
		(start 42.633646 -68.641468)
		(end 42.984166 -68.641468)
		(width 0.127)
		(layer "B.Cu")
		(net "P2E_CPU_PCIE_SW_NODE1_TX_C_DN")
	)
	(segment
		(start 39.732204 -68.746116)
		(end 39.74465 -68.746116)
		(width 0.127)
		(layer "B.Cu")
		(net "P2E_CPU_PCIE_SW_NODE1_TX_C_DN")
	)
	(segment
		(start 41.353994 -68.641468)
		(end 41.523666 -68.81114)
		(width 0.127)
		(layer "B.Cu")
		(net "P2E_CPU_PCIE_SW_NODE1_TX_C_DN")
	)
	(segment
		(start 43.103546 -68.522088)
		(end 43.1165 -68.509134)
		(width 0.1016)
		(layer "B.Cu")
		(net "P2E_CPU_PCIE_SW_NODE1_TX_C_DN")
	)
	(segment
		(start 41.813734 -68.81114)
		(end 41.983406 -68.641468)
		(width 0.127)
		(layer "B.Cu")
		(net "P2E_CPU_PCIE_SW_NODE1_TX_C_DN")
	)
	(segment
		(start 39.849298 -68.641468)
		(end 41.353994 -68.641468)
		(width 0.127)
		(layer "B.Cu")
		(net "P2E_CPU_PCIE_SW_NODE1_TX_C_DN")
	)
	(segment
		(start 39.520622 -68.957698)
		(end 39.732204 -68.746116)
		(width 0.127)
		(layer "B.Cu")
		(net "P2E_CPU_PCIE_SW_NODE1_TX_C_DN")
	)
	(segment
		(start 44.381166 -68.525136)
		(end 45.104558 -69.248528)
		(width 0.1016)
		(layer "B.Cu")
		(net "P2E_CPU_PCIE_SW_NODE1_TX_C_DN")
	)
	(segment
		(start 41.523666 -68.81114)
		(end 41.813734 -68.81114)
		(width 0.127)
		(layer "B.Cu")
		(net "P2E_CPU_PCIE_SW_NODE1_TX_C_DN")
	)
	(segment
		(start 43.212258 -68.509134)
		(end 43.228768 -68.525136)
		(width 0.1016)
		(layer "B.Cu")
		(net "P2E_CPU_PCIE_SW_NODE1_TX_C_DN")
	)
	(segment
		(start 65.426844 -117.228874)
		(end 65.422272 -117.224302)
		(width 0.1016)
		(layer "F.Cu")
		(net "BMC_ROMA15")
	)
	(segment
		(start 64.899286 -121.444512)
		(end 65.426844 -120.916954)
		(width 0.1016)
		(layer "F.Cu")
		(net "BMC_ROMA15")
	)
	(segment
		(start 65.702688 -125.480064)
		(end 65.702688 -122.247914)
		(width 0.1016)
		(layer "F.Cu")
		(net "BMC_ROMA15")
	)
	(segment
		(start 65.702688 -122.247914)
		(end 64.899286 -121.444512)
		(width 0.1016)
		(layer "F.Cu")
		(net "BMC_ROMA15")
	)
	(segment
		(start 66.148204 -127.259588)
		(end 66.524886 -126.882906)
		(width 0.1016)
		(layer "F.Cu")
		(net "BMC_ROMA15")
	)
	(segment
		(start 66.524886 -126.882906)
		(end 66.524886 -126.302262)
		(width 0.1016)
		(layer "F.Cu")
		(net "BMC_ROMA15")
	)
	(segment
		(start 65.426844 -120.916954)
		(end 65.426844 -117.228874)
		(width 0.1016)
		(layer "F.Cu")
		(net "BMC_ROMA15")
	)
	(segment
		(start 66.141854 -127.259588)
		(end 66.148204 -127.259588)
		(width 0.1016)
		(layer "F.Cu")
		(net "BMC_ROMA15")
	)
	(segment
		(start 66.524886 -126.302262)
		(end 65.702688 -125.480064)
		(width 0.1016)
		(layer "F.Cu")
		(net "BMC_ROMA15")
	)
	(via
		(at 65.422272 -117.224302)
		(size 0.508)
		(drill 0.254)
		(layers "F.Cu" "B.Cu")
		(net "BMC_ROMA15")
	)
	(segment
		(start 125.787912 -147.775422)
		(end 125.04674 -147.775422)
		(width 0.127)
		(layer "F.Cu")
		(net "P2E_CPU_PCIE_SW_NODE1_TX_DP")
	)
	(segment
		(start 125.04674 -147.775422)
		(end 124.999242 -147.82292)
		(width 0.127)
		(layer "F.Cu")
		(net "P2E_CPU_PCIE_SW_NODE1_TX_DP")
	)
	(segment
		(start 124.999242 -147.82292)
		(end 124.260102 -147.82292)
		(width 0.127)
		(layer "F.Cu")
		(net "P2E_CPU_PCIE_SW_NODE1_TX_DP")
	)
	(segment
		(start 124.260102 -147.82292)
		(end 123.606052 -148.47697)
		(width 0.127)
		(layer "F.Cu")
		(net "P2E_CPU_PCIE_SW_NODE1_TX_DP")
	)
	(segment
		(start 123.606052 -148.47697)
		(end 123.606052 -148.90115)
		(width 0.127)
		(layer "F.Cu")
		(net "P2E_CPU_PCIE_SW_NODE1_TX_DP")
	)
	(segment
		(start 123.606052 -148.90115)
		(end 123.377452 -149.12975)
		(width 0.127)
		(layer "F.Cu")
		(net "P2E_CPU_PCIE_SW_NODE1_TX_DP")
	)
	(via
		(at 123.377452 -149.12975)
		(size 0.508)
		(drill 0.254)
		(layers "F.Cu" "B.Cu")
		(net "P2E_CPU_PCIE_SW_NODE1_TX_DP")
	)
	(segment
		(start 64.34582 -105.350564)
		(end 62.498986 -104.792272)
		(width 0.127)
		(layer "B.Cu")
		(net "P2E_CPU_PCIE_SW_NODE1_TX_DP")
	)
	(segment
		(start 41.2115 -104.231694)
		(end 40.241982 -103.802434)
		(width 0.127)
		(layer "B.Cu")
		(net "P2E_CPU_PCIE_SW_NODE1_TX_DP")
	)
	(segment
		(start 92.40012 -145.075656)
		(end 89.829132 -139.67079)
		(width 0.127)
		(layer "B.Cu")
		(net "P2E_CPU_PCIE_SW_NODE1_TX_DP")
	)
	(segment
		(start 70.952614 -105.383838)
		(end 64.34582 -105.350564)
		(width 0.127)
		(layer "B.Cu")
		(net "P2E_CPU_PCIE_SW_NODE1_TX_DP")
	)
	(segment
		(start 123.860052 -148.275802)
		(end 122.923808 -147.598638)
		(width 0.127)
		(layer "B.Cu")
		(net "P2E_CPU_PCIE_SW_NODE1_TX_DP")
	)
	(segment
		(start 60.56122 -104.772714)
		(end 52.809394 -104.909366)
		(width 0.127)
		(layer "B.Cu")
		(net "P2E_CPU_PCIE_SW_NODE1_TX_DP")
	)
	(segment
		(start 89.829132 -139.67079)
		(end 89.798144 -135.79221)
		(width 0.127)
		(layer "B.Cu")
		(net "P2E_CPU_PCIE_SW_NODE1_TX_DP")
	)
	(segment
		(start 90.745564 -127.560578)
		(end 90.905076 -126.335028)
		(width 0.127)
		(layer "B.Cu")
		(net "P2E_CPU_PCIE_SW_NODE1_TX_DP")
	)
	(segment
		(start 76.40066 -105.383838)
		(end 70.952614 -105.383838)
		(width 0.127)
		(layer "B.Cu")
		(net "P2E_CPU_PCIE_SW_NODE1_TX_DP")
	)
	(segment
		(start 34.77006 -69.641974)
		(end 36.070032 -69.433694)
		(width 0.127)
		(layer "B.Cu")
		(net "P2E_CPU_PCIE_SW_NODE1_TX_DP")
	)
	(segment
		(start 80.85201 -110.979966)
		(end 80.696562 -110.875826)
		(width 0.127)
		(layer "B.Cu")
		(net "P2E_CPU_PCIE_SW_NODE1_TX_DP")
	)
	(segment
		(start 52.809394 -104.909366)
		(end 52.809394 -104.928416)
		(width 0.127)
		(layer "B.Cu")
		(net "P2E_CPU_PCIE_SW_NODE1_TX_DP")
	)
	(segment
		(start 61.646054 -104.772714)
		(end 60.56122 -104.772714)
		(width 0.127)
		(layer "B.Cu")
		(net "P2E_CPU_PCIE_SW_NODE1_TX_DP")
	)
	(segment
		(start 104.57053 -147.24507)
		(end 96.89973 -146.875754)
		(width 0.127)
		(layer "B.Cu")
		(net "P2E_CPU_PCIE_SW_NODE1_TX_DP")
	)
	(segment
		(start 40.241982 -103.802434)
		(end 37.656262 -101.23932)
		(width 0.127)
		(layer "B.Cu")
		(net "P2E_CPU_PCIE_SW_NODE1_TX_DP")
	)
	(segment
		(start 32.258254 -92.758514)
		(end 32.00908 -77.32649)
		(width 0.127)
		(layer "B.Cu")
		(net "P2E_CPU_PCIE_SW_NODE1_TX_DP")
	)
	(segment
		(start 123.860052 -148.64715)
		(end 123.860052 -148.275802)
		(width 0.127)
		(layer "B.Cu")
		(net "P2E_CPU_PCIE_SW_NODE1_TX_DP")
	)
	(segment
		(start 96.89973 -146.875754)
		(end 92.40012 -145.075656)
		(width 0.127)
		(layer "B.Cu")
		(net "P2E_CPU_PCIE_SW_NODE1_TX_DP")
	)
	(segment
		(start 43.364404 -104.613964)
		(end 43.361356 -104.613456)
		(width 0.127)
		(layer "B.Cu")
		(net "P2E_CPU_PCIE_SW_NODE1_TX_DP")
	)
	(segment
		(start 86.863428 -111.17834)
		(end 84.547456 -111.07039)
		(width 0.127)
		(layer "B.Cu")
		(net "P2E_CPU_PCIE_SW_NODE1_TX_DP")
	)
	(segment
		(start 34.10966 -70.373494)
		(end 34.77006 -69.641974)
		(width 0.127)
		(layer "B.Cu")
		(net "P2E_CPU_PCIE_SW_NODE1_TX_DP")
	)
	(segment
		(start 52.809394 -104.928416)
		(end 43.379644 -104.615488)
		(width 0.127)
		(layer "B.Cu")
		(net "P2E_CPU_PCIE_SW_NODE1_TX_DP")
	)
	(segment
		(start 80.696562 -110.875826)
		(end 80.028288 -110.03026)
		(width 0.127)
		(layer "B.Cu")
		(net "P2E_CPU_PCIE_SW_NODE1_TX_DP")
	)
	(segment
		(start 90.859864 -123.064778)
		(end 90.842592 -122.77979)
		(width 0.127)
		(layer "B.Cu")
		(net "P2E_CPU_PCIE_SW_NODE1_TX_DP")
	)
	(segment
		(start 89.798144 -135.79221)
		(end 90.745564 -127.560578)
		(width 0.127)
		(layer "B.Cu")
		(net "P2E_CPU_PCIE_SW_NODE1_TX_DP")
	)
	(segment
		(start 32.996378 -95.197676)
		(end 32.996124 -95.196914)
		(width 0.127)
		(layer "B.Cu")
		(net "P2E_CPU_PCIE_SW_NODE1_TX_DP")
	)
	(segment
		(start 43.361356 -104.613456)
		(end 43.335194 -104.610408)
		(width 0.127)
		(layer "B.Cu")
		(net "P2E_CPU_PCIE_SW_NODE1_TX_DP")
	)
	(segment
		(start 37.035486 -68.46824)
		(end 37.481764 -68.213732)
		(width 0.127)
		(layer "B.Cu")
		(net "P2E_CPU_PCIE_SW_NODE1_TX_DP")
	)
	(segment
		(start 61.782452 -104.776016)
		(end 61.646054 -104.772714)
		(width 0.127)
		(layer "B.Cu")
		(net "P2E_CPU_PCIE_SW_NODE1_TX_DP")
	)
	(segment
		(start 89.072466 -115.131342)
		(end 88.144096 -111.866172)
		(width 0.127)
		(layer "B.Cu")
		(net "P2E_CPU_PCIE_SW_NODE1_TX_DP")
	)
	(segment
		(start 82.347308 -111.407956)
		(end 80.85201 -110.979966)
		(width 0.127)
		(layer "B.Cu")
		(net "P2E_CPU_PCIE_SW_NODE1_TX_DP")
	)
	(segment
		(start 43.335194 -104.610408)
		(end 41.478454 -104.279192)
		(width 0.127)
		(layer "B.Cu")
		(net "P2E_CPU_PCIE_SW_NODE1_TX_DP")
	)
	(segment
		(start 90.809318 -122.239278)
		(end 89.072466 -115.131342)
		(width 0.127)
		(layer "B.Cu")
		(net "P2E_CPU_PCIE_SW_NODE1_TX_DP")
	)
	(segment
		(start 80.028288 -110.03026)
		(end 79.092044 -107.736132)
		(width 0.127)
		(layer "B.Cu")
		(net "P2E_CPU_PCIE_SW_NODE1_TX_DP")
	)
	(segment
		(start 33.153604 -75.119484)
		(end 33.15335 -75.118976)
		(width 0.127)
		(layer "B.Cu")
		(net "P2E_CPU_PCIE_SW_NODE1_TX_DP")
	)
	(segment
		(start 37.481764 -68.213732)
		(end 38.31971 -68.240148)
		(width 0.127)
		(layer "B.Cu")
		(net "P2E_CPU_PCIE_SW_NODE1_TX_DP")
	)
	(segment
		(start 110.333536 -146.444462)
		(end 104.57053 -147.24507)
		(width 0.127)
		(layer "B.Cu")
		(net "P2E_CPU_PCIE_SW_NODE1_TX_DP")
	)
	(segment
		(start 36.070032 -69.433694)
		(end 37.035486 -68.46824)
		(width 0.127)
		(layer "B.Cu")
		(net "P2E_CPU_PCIE_SW_NODE1_TX_DP")
	)
	(segment
		(start 43.379644 -104.615488)
		(end 43.364404 -104.613964)
		(width 0.127)
		(layer "B.Cu")
		(net "P2E_CPU_PCIE_SW_NODE1_TX_DP")
	)
	(segment
		(start 122.923808 -147.598638)
		(end 119.443754 -146.578828)
		(width 0.127)
		(layer "B.Cu")
		(net "P2E_CPU_PCIE_SW_NODE1_TX_DP")
	)
	(segment
		(start 77.610208 -106.09072)
		(end 76.40066 -105.383838)
		(width 0.127)
		(layer "B.Cu")
		(net "P2E_CPU_PCIE_SW_NODE1_TX_DP")
	)
	(segment
		(start 33.15335 -75.118976)
		(end 34.10966 -70.373494)
		(width 0.127)
		(layer "B.Cu")
		(net "P2E_CPU_PCIE_SW_NODE1_TX_DP")
	)
	(segment
		(start 88.144096 -111.866172)
		(end 86.863428 -111.17834)
		(width 0.127)
		(layer "B.Cu")
		(net "P2E_CPU_PCIE_SW_NODE1_TX_DP")
	)
	(segment
		(start 37.656262 -101.23932)
		(end 33.596072 -97.17913)
		(width 0.127)
		(layer "B.Cu")
		(net "P2E_CPU_PCIE_SW_NODE1_TX_DP")
	)
	(segment
		(start 62.498986 -104.792272)
		(end 61.782452 -104.776016)
		(width 0.127)
		(layer "B.Cu")
		(net "P2E_CPU_PCIE_SW_NODE1_TX_DP")
	)
	(segment
		(start 84.547456 -111.07039)
		(end 82.347308 -111.407956)
		(width 0.127)
		(layer "B.Cu")
		(net "P2E_CPU_PCIE_SW_NODE1_TX_DP")
	)
	(segment
		(start 119.443754 -146.578828)
		(end 110.333536 -146.444462)
		(width 0.127)
		(layer "B.Cu")
		(net "P2E_CPU_PCIE_SW_NODE1_TX_DP")
	)
	(segment
		(start 32.996124 -95.196914)
		(end 32.258254 -92.758514)
		(width 0.127)
		(layer "B.Cu")
		(net "P2E_CPU_PCIE_SW_NODE1_TX_DP")
	)
	(segment
		(start 33.142936 -75.172316)
		(end 33.153604 -75.119484)
		(width 0.127)
		(layer "B.Cu")
		(net "P2E_CPU_PCIE_SW_NODE1_TX_DP")
	)
	(segment
		(start 33.596072 -97.17913)
		(end 32.996378 -95.197676)
		(width 0.127)
		(layer "B.Cu")
		(net "P2E_CPU_PCIE_SW_NODE1_TX_DP")
	)
	(segment
		(start 32.00908 -77.32649)
		(end 33.142936 -75.172316)
		(width 0.127)
		(layer "B.Cu")
		(net "P2E_CPU_PCIE_SW_NODE1_TX_DP")
	)
	(segment
		(start 41.478454 -104.279192)
		(end 41.2115 -104.231694)
		(width 0.127)
		(layer "B.Cu")
		(net "P2E_CPU_PCIE_SW_NODE1_TX_DP")
	)
	(segment
		(start 38.31971 -68.240148)
		(end 38.720522 -67.941698)
		(width 0.127)
		(layer "B.Cu")
		(net "P2E_CPU_PCIE_SW_NODE1_TX_DP")
	)
	(segment
		(start 90.905076 -126.335028)
		(end 90.752168 -124.644912)
		(width 0.127)
		(layer "B.Cu")
		(net "P2E_CPU_PCIE_SW_NODE1_TX_DP")
	)
	(segment
		(start 123.377452 -149.12975)
		(end 123.860052 -148.64715)
		(width 0.127)
		(layer "B.Cu")
		(net "P2E_CPU_PCIE_SW_NODE1_TX_DP")
	)
	(segment
		(start 79.092044 -107.736132)
		(end 77.610208 -106.09072)
		(width 0.127)
		(layer "B.Cu")
		(net "P2E_CPU_PCIE_SW_NODE1_TX_DP")
	)
	(segment
		(start 90.842592 -122.77979)
		(end 90.809318 -122.239278)
		(width 0.127)
		(layer "B.Cu")
		(net "P2E_CPU_PCIE_SW_NODE1_TX_DP")
	)
	(segment
		(start 90.752168 -124.644912)
		(end 90.859864 -123.064778)
		(width 0.127)
		(layer "B.Cu")
		(net "P2E_CPU_PCIE_SW_NODE1_TX_DP")
	)
	(segment
		(start 73.998328 -66.33337)
		(end 74.3077 -66.33337)
		(width 0.1016)
		(layer "F.Cu")
		(net "M1_DQ_NODE1_DQ50")
	)
	(segment
		(start 95.54972 -23.784052)
		(end 95.54972 -22.985984)
		(width 0.1651)
		(layer "F.Cu")
		(net "M1_DQ_NODE1_DQ50")
	)
	(segment
		(start 74.555858 -66.085212)
		(end 74.555858 -63.194946)
		(width 0.1016)
		(layer "F.Cu")
		(net "M1_DQ_NODE1_DQ50")
	)
	(segment
		(start 95.54972 -22.985984)
		(end 95.550228 -22.985984)
		(width 0.1651)
		(layer "F.Cu")
		(net "M1_DQ_NODE1_DQ50")
	)
	(segment
		(start 95.550228 -22.985984)
		(end 95.550228 -20.94992)
		(width 0.1651)
		(layer "F.Cu")
		(net "M1_DQ_NODE1_DQ50")
	)
	(segment
		(start 74.555858 -63.194946)
		(end 74.94524 -62.805564)
		(width 0.1016)
		(layer "F.Cu")
		(net "M1_DQ_NODE1_DQ50")
	)
	(segment
		(start 78.542642 -62.276228)
		(end 79.06766 -62.801246)
		(width 0.1651)
		(layer "F.Cu")
		(net "M1_DQ_NODE1_DQ50")
	)
	(segment
		(start 73.485248 -66.84645)
		(end 73.998328 -66.33337)
		(width 0.1016)
		(layer "F.Cu")
		(net "M1_DQ_NODE1_DQ50")
	)
	(segment
		(start 75.474576 -62.276228)
		(end 78.542642 -62.276228)
		(width 0.1651)
		(layer "F.Cu")
		(net "M1_DQ_NODE1_DQ50")
	)
	(segment
		(start 95.68688 -23.921212)
		(end 95.54972 -23.784052)
		(width 0.1651)
		(layer "F.Cu")
		(net "M1_DQ_NODE1_DQ50")
	)
	(segment
		(start 74.94524 -62.805564)
		(end 75.474576 -62.276228)
		(width 0.1651)
		(layer "F.Cu")
		(net "M1_DQ_NODE1_DQ50")
	)
	(segment
		(start 95.687642 -23.921212)
		(end 95.68688 -23.921212)
		(width 0.1651)
		(layer "F.Cu")
		(net "M1_DQ_NODE1_DQ50")
	)
	(segment
		(start 74.3077 -66.33337)
		(end 74.555858 -66.085212)
		(width 0.1016)
		(layer "F.Cu")
		(net "M1_DQ_NODE1_DQ50")
	)
	(segment
		(start 73.305162 -66.84645)
		(end 73.485248 -66.84645)
		(width 0.1016)
		(layer "F.Cu")
		(net "M1_DQ_NODE1_DQ50")
	)
	(via
		(at 79.06766 -62.801246)
		(size 0.508)
		(drill 0.254)
		(layers "F.Cu" "B.Cu")
		(net "M1_DQ_NODE1_DQ50")
	)
	(via
		(at 95.687642 -23.921212)
		(size 0.508)
		(drill 0.254)
		(layers "F.Cu" "B.Cu")
		(net "M1_DQ_NODE1_DQ50")
	)
	(segment
		(start 83.476084 -54.285388)
		(end 83.161632 -54.59984)
		(width 0.2032)
		(layer "In7.Cu")
		(net "M1_DQ_NODE1_DQ50")
	)
	(segment
		(start 79.25308 -62.615826)
		(end 79.06766 -62.801246)
		(width 0.2032)
		(layer "In7.Cu")
		(net "M1_DQ_NODE1_DQ50")
	)
	(segment
		(start 83.645756 -55.388764)
		(end 83.645756 -55.693564)
		(width 0.2032)
		(layer "In7.Cu")
		(net "M1_DQ_NODE1_DQ50")
	)
	(segment
		(start 84.654136 -54.16296)
		(end 84.654136 -54.4576)
		(width 0.2032)
		(layer "In7.Cu")
		(net "M1_DQ_NODE1_DQ50")
	)
	(segment
		(start 81.56194 -57.47258)
		(end 81.56194 -57.990486)
		(width 0.2032)
		(layer "In7.Cu")
		(net "M1_DQ_NODE1_DQ50")
	)
	(segment
		(start 82.335878 -55.425594)
		(end 82.119724 -55.641748)
		(width 0.2032)
		(layer "In7.Cu")
		(net "M1_DQ_NODE1_DQ50")
	)
	(segment
		(start 83.770724 -54.285388)
		(end 83.476084 -54.285388)
		(width 0.2032)
		(layer "In7.Cu")
		(net "M1_DQ_NODE1_DQ50")
	)
	(segment
		(start 79.25308 -60.299346)
		(end 79.25308 -62.615826)
		(width 0.2032)
		(layer "In7.Cu")
		(net "M1_DQ_NODE1_DQ50")
	)
	(segment
		(start 82.082894 -56.951626)
		(end 81.59877 -56.467502)
		(width 0.2032)
		(layer "In7.Cu")
		(net "M1_DQ_NODE1_DQ50")
	)
	(segment
		(start 84.151216 -54.66588)
		(end 83.770724 -54.285388)
		(width 0.2032)
		(layer "In7.Cu")
		(net "M1_DQ_NODE1_DQ50")
	)
	(segment
		(start 84.273644 -53.782468)
		(end 84.654136 -54.16296)
		(width 0.2032)
		(layer "In7.Cu")
		(net "M1_DQ_NODE1_DQ50")
	)
	(segment
		(start 82.603848 -56.430672)
		(end 82.603848 -56.735472)
		(width 0.2032)
		(layer "In7.Cu")
		(net "M1_DQ_NODE1_DQ50")
	)
	(segment
		(start 94.02318 -27.17165)
		(end 94.02318 -37.620194)
		(width 0.2032)
		(layer "In7.Cu")
		(net "M1_DQ_NODE1_DQ50")
	)
	(segment
		(start 81.077816 -56.988456)
		(end 81.56194 -57.47258)
		(width 0.2032)
		(layer "In7.Cu")
		(net "M1_DQ_NODE1_DQ50")
	)
	(segment
		(start 84.445856 -54.66588)
		(end 84.151216 -54.66588)
		(width 0.2032)
		(layer "In7.Cu")
		(net "M1_DQ_NODE1_DQ50")
	)
	(segment
		(start 82.640678 -55.425594)
		(end 82.335878 -55.425594)
		(width 0.2032)
		(layer "In7.Cu")
		(net "M1_DQ_NODE1_DQ50")
	)
	(segment
		(start 94.5134 -38.110414)
		(end 94.5134 -43.248072)
		(width 0.2032)
		(layer "In7.Cu")
		(net "M1_DQ_NODE1_DQ50")
	)
	(segment
		(start 84.273644 -53.487828)
		(end 84.273644 -53.782468)
		(width 0.2032)
		(layer "In7.Cu")
		(net "M1_DQ_NODE1_DQ50")
	)
	(segment
		(start 83.645756 -55.693564)
		(end 83.429602 -55.909718)
		(width 0.2032)
		(layer "In7.Cu")
		(net "M1_DQ_NODE1_DQ50")
	)
	(segment
		(start 82.387694 -56.951626)
		(end 82.082894 -56.951626)
		(width 0.2032)
		(layer "In7.Cu")
		(net "M1_DQ_NODE1_DQ50")
	)
	(segment
		(start 94.688914 -25.715722)
		(end 94.688914 -26.505916)
		(width 0.2032)
		(layer "In7.Cu")
		(net "M1_DQ_NODE1_DQ50")
	)
	(segment
		(start 83.429602 -55.909718)
		(end 83.124802 -55.909718)
		(width 0.2032)
		(layer "In7.Cu")
		(net "M1_DQ_NODE1_DQ50")
	)
	(segment
		(start 94.688914 -26.505916)
		(end 94.02318 -27.17165)
		(width 0.2032)
		(layer "In7.Cu")
		(net "M1_DQ_NODE1_DQ50")
	)
	(segment
		(start 81.29397 -56.467502)
		(end 81.077816 -56.683656)
		(width 0.2032)
		(layer "In7.Cu")
		(net "M1_DQ_NODE1_DQ50")
	)
	(segment
		(start 83.161632 -54.59984)
		(end 83.161632 -54.90464)
		(width 0.2032)
		(layer "In7.Cu")
		(net "M1_DQ_NODE1_DQ50")
	)
	(segment
		(start 81.59877 -56.467502)
		(end 81.29397 -56.467502)
		(width 0.2032)
		(layer "In7.Cu")
		(net "M1_DQ_NODE1_DQ50")
	)
	(segment
		(start 82.603848 -56.735472)
		(end 82.387694 -56.951626)
		(width 0.2032)
		(layer "In7.Cu")
		(net "M1_DQ_NODE1_DQ50")
	)
	(segment
		(start 83.161632 -54.90464)
		(end 83.645756 -55.388764)
		(width 0.2032)
		(layer "In7.Cu")
		(net "M1_DQ_NODE1_DQ50")
	)
	(segment
		(start 81.56194 -57.990486)
		(end 79.25308 -60.299346)
		(width 0.2032)
		(layer "In7.Cu")
		(net "M1_DQ_NODE1_DQ50")
	)
	(segment
		(start 83.124802 -55.909718)
		(end 82.640678 -55.425594)
		(width 0.2032)
		(layer "In7.Cu")
		(net "M1_DQ_NODE1_DQ50")
	)
	(segment
		(start 94.5134 -43.248072)
		(end 84.273644 -53.487828)
		(width 0.2032)
		(layer "In7.Cu")
		(net "M1_DQ_NODE1_DQ50")
	)
	(segment
		(start 82.119724 -55.641748)
		(end 82.119724 -55.946548)
		(width 0.2032)
		(layer "In7.Cu")
		(net "M1_DQ_NODE1_DQ50")
	)
	(segment
		(start 95.68688 -24.717756)
		(end 94.688914 -25.715722)
		(width 0.2032)
		(layer "In7.Cu")
		(net "M1_DQ_NODE1_DQ50")
	)
	(segment
		(start 81.077816 -56.683656)
		(end 81.077816 -56.988456)
		(width 0.2032)
		(layer "In7.Cu")
		(net "M1_DQ_NODE1_DQ50")
	)
	(segment
		(start 84.654136 -54.4576)
		(end 84.445856 -54.66588)
		(width 0.2032)
		(layer "In7.Cu")
		(net "M1_DQ_NODE1_DQ50")
	)
	(segment
		(start 95.68688 -23.921974)
		(end 95.68688 -24.717756)
		(width 0.2032)
		(layer "In7.Cu")
		(net "M1_DQ_NODE1_DQ50")
	)
	(segment
		(start 94.02318 -37.620194)
		(end 94.5134 -38.110414)
		(width 0.2032)
		(layer "In7.Cu")
		(net "M1_DQ_NODE1_DQ50")
	)
	(segment
		(start 95.687642 -23.921212)
		(end 95.68688 -23.921974)
		(width 0.2032)
		(layer "In7.Cu")
		(net "M1_DQ_NODE1_DQ50")
	)
	(segment
		(start 82.119724 -55.946548)
		(end 82.603848 -56.430672)
		(width 0.2032)
		(layer "In7.Cu")
		(net "M1_DQ_NODE1_DQ50")
	)
	(segment
		(start 63.741808 -128.859026)
		(end 63.340996 -128.458214)
		(width 0.1016)
		(layer "F.Cu")
		(net "BMC_ROMA4")
	)
	(segment
		(start 63.741808 -128.859534)
		(end 63.741808 -128.859026)
		(width 0.1016)
		(layer "F.Cu")
		(net "BMC_ROMA4")
	)
	(via
		(at 63.340996 -128.458214)
		(size 0.49022)
		(drill 0.254)
		(layers "F.Cu" "B.Cu")
		(net "BMC_ROMA4")
	)
	(via
		(at 62.105286 -124.803662)
		(size 0.6604)
		(drill 0.3302)
		(layers "F.Cu" "B.Cu")
		(net "BMC_ROMA4")
	)
	(segment
		(start 63.197486 -122.273314)
		(end 62.105286 -123.365514)
		(width 0.1016)
		(layer "B.Cu")
		(net "BMC_ROMA4")
	)
	(segment
		(start 62.938406 -128.055624)
		(end 62.938406 -127.493268)
		(width 0.1016)
		(layer "B.Cu")
		(net "BMC_ROMA4")
	)
	(segment
		(start 62.938406 -127.493268)
		(end 62.308486 -126.863348)
		(width 0.1016)
		(layer "B.Cu")
		(net "BMC_ROMA4")
	)
	(segment
		(start 62.105286 -126.378462)
		(end 62.105286 -124.803662)
		(width 0.1016)
		(layer "B.Cu")
		(net "BMC_ROMA4")
	)
	(segment
		(start 62.308486 -126.581662)
		(end 62.105286 -126.378462)
		(width 0.1016)
		(layer "B.Cu")
		(net "BMC_ROMA4")
	)
	(segment
		(start 62.308486 -126.863348)
		(end 62.308486 -126.581662)
		(width 0.1016)
		(layer "B.Cu")
		(net "BMC_ROMA4")
	)
	(segment
		(start 62.105286 -123.365514)
		(end 62.105286 -124.803662)
		(width 0.1016)
		(layer "B.Cu")
		(net "BMC_ROMA4")
	)
	(segment
		(start 63.197486 -119.018812)
		(end 63.197486 -122.273314)
		(width 0.1016)
		(layer "B.Cu")
		(net "BMC_ROMA4")
	)
	(segment
		(start 63.340996 -128.458214)
		(end 62.938406 -128.055624)
		(width 0.1016)
		(layer "B.Cu")
		(net "BMC_ROMA4")
	)
	(segment
		(start 63.832486 -118.383812)
		(end 63.197486 -119.018812)
		(width 0.1016)
		(layer "B.Cu")
		(net "BMC_ROMA4")
	)
	(segment
		(start 46.54423 -69.370702)
		(end 46.181772 -69.73316)
		(width 0.1016)
		(layer "F.Cu")
		(net "P2E_CPU_PCIE_SW_NODE1_TX_C_DP")
	)
	(segment
		(start 46.561248 -69.370702)
		(end 46.54423 -69.370702)
		(width 0.1016)
		(layer "F.Cu")
		(net "P2E_CPU_PCIE_SW_NODE1_TX_C_DP")
	)
	(via
		(at 40.613076 -68.336668)
		(size 0.4064)
		(drill 0.2032)
		(layers "F.Cu" "B.Cu")
		(net "P2E_CPU_PCIE_SW_NODE1_TX_C_DP")
	)
	(via
		(at 46.181772 -69.73316)
		(size 0.49022)
		(drill 0.254)
		(layers "F.Cu" "B.Cu")
		(net "P2E_CPU_PCIE_SW_NODE1_TX_C_DP")
	)
	(segment
		(start 43.277536 -68.305934)
		(end 43.277282 -68.30568)
		(width 0.1016)
		(layer "B.Cu")
		(net "P2E_CPU_PCIE_SW_NODE1_TX_C_DP")
	)
	(segment
		(start 44.465494 -68.321936)
		(end 43.311318 -68.321936)
		(width 0.1016)
		(layer "B.Cu")
		(net "P2E_CPU_PCIE_SW_NODE1_TX_C_DP")
	)
	(segment
		(start 43.277282 -68.30568)
		(end 43.192954 -68.30568)
		(width 0.1016)
		(layer "B.Cu")
		(net "P2E_CPU_PCIE_SW_NODE1_TX_C_DP")
	)
	(segment
		(start 43.013884 -68.305934)
		(end 42.923714 -68.306188)
		(width 0.1016)
		(layer "B.Cu")
		(net "P2E_CPU_PCIE_SW_NODE1_TX_C_DP")
	)
	(segment
		(start 45.922184 -69.473572)
		(end 45.922184 -69.309996)
		(width 0.1016)
		(layer "B.Cu")
		(net "P2E_CPU_PCIE_SW_NODE1_TX_C_DP")
	)
	(segment
		(start 46.181772 -69.73316)
		(end 45.922184 -69.473572)
		(width 0.1016)
		(layer "B.Cu")
		(net "P2E_CPU_PCIE_SW_NODE1_TX_C_DP")
	)
	(segment
		(start 43.311318 -68.321936)
		(end 43.294808 -68.305934)
		(width 0.1016)
		(layer "B.Cu")
		(net "P2E_CPU_PCIE_SW_NODE1_TX_C_DP")
	)
	(segment
		(start 45.922184 -69.309996)
		(end 45.657516 -69.045328)
		(width 0.1016)
		(layer "B.Cu")
		(net "P2E_CPU_PCIE_SW_NODE1_TX_C_DP")
	)
	(segment
		(start 42.8879 -68.306442)
		(end 42.857674 -68.336668)
		(width 0.127)
		(layer "B.Cu")
		(net "P2E_CPU_PCIE_SW_NODE1_TX_C_DP")
	)
	(segment
		(start 39.915592 -68.336668)
		(end 40.613076 -68.336668)
		(width 0.127)
		(layer "B.Cu")
		(net "P2E_CPU_PCIE_SW_NODE1_TX_C_DP")
	)
	(segment
		(start 39.520622 -67.941698)
		(end 39.915592 -68.336668)
		(width 0.127)
		(layer "B.Cu")
		(net "P2E_CPU_PCIE_SW_NODE1_TX_C_DP")
	)
	(segment
		(start 42.857674 -68.336668)
		(end 40.613076 -68.336668)
		(width 0.127)
		(layer "B.Cu")
		(net "P2E_CPU_PCIE_SW_NODE1_TX_C_DP")
	)
	(segment
		(start 42.914824 -68.297298)
		(end 42.897044 -68.297298)
		(width 0.1016)
		(layer "B.Cu")
		(net "P2E_CPU_PCIE_SW_NODE1_TX_C_DP")
	)
	(segment
		(start 42.897044 -68.297298)
		(end 42.8879 -68.306442)
		(width 0.1016)
		(layer "B.Cu")
		(net "P2E_CPU_PCIE_SW_NODE1_TX_C_DP")
	)
	(segment
		(start 43.294808 -68.305934)
		(end 43.277536 -68.305934)
		(width 0.1016)
		(layer "B.Cu")
		(net "P2E_CPU_PCIE_SW_NODE1_TX_C_DP")
	)
	(segment
		(start 45.657516 -69.045328)
		(end 45.188886 -69.045328)
		(width 0.1016)
		(layer "B.Cu")
		(net "P2E_CPU_PCIE_SW_NODE1_TX_C_DP")
	)
	(segment
		(start 42.923714 -68.306188)
		(end 42.914824 -68.297298)
		(width 0.1016)
		(layer "B.Cu")
		(net "P2E_CPU_PCIE_SW_NODE1_TX_C_DP")
	)
	(segment
		(start 43.192954 -68.30568)
		(end 43.013884 -68.305934)
		(width 0.1016)
		(layer "B.Cu")
		(net "P2E_CPU_PCIE_SW_NODE1_TX_C_DP")
	)
	(segment
		(start 45.188886 -69.045328)
		(end 44.465494 -68.321936)
		(width 0.1016)
		(layer "B.Cu")
		(net "P2E_CPU_PCIE_SW_NODE1_TX_C_DP")
	)
	(segment
		(start 73.389998 -73.529952)
		(end 76.661772 -73.529952)
		(width 0.09906)
		(layer "F.Cu")
		(net "M_DDR3_NODE1_DQS7N")
	)
	(segment
		(start 100.333302 -32.13862)
		(end 100.333302 -31.867094)
		(width 0.1651)
		(layer "F.Cu")
		(net "M_DDR3_NODE1_DQS7N")
	)
	(segment
		(start 98.404172 -30.504892)
		(end 98.250248 -30.350968)
		(width 0.1651)
		(layer "F.Cu")
		(net "M_DDR3_NODE1_DQS7N")
	)
	(segment
		(start 100.333302 -31.867094)
		(end 99.956366 -31.490158)
		(width 0.1651)
		(layer "F.Cu")
		(net "M_DDR3_NODE1_DQS7N")
	)
	(segment
		(start 77.0382 -72.990964)
		(end 76.911454 -72.864218)
		(width 0.09906)
		(layer "F.Cu")
		(net "M_DDR3_NODE1_DQS7N")
	)
	(segment
		(start 99.097084 -31.490158)
		(end 98.404172 -30.797246)
		(width 0.1651)
		(layer "F.Cu")
		(net "M_DDR3_NODE1_DQS7N")
	)
	(segment
		(start 73.247758 -73.387712)
		(end 73.389998 -73.529952)
		(width 0.09906)
		(layer "F.Cu")
		(net "M_DDR3_NODE1_DQS7N")
	)
	(segment
		(start 76.661772 -73.529952)
		(end 77.0382 -73.153524)
		(width 0.09906)
		(layer "F.Cu")
		(net "M_DDR3_NODE1_DQS7N")
	)
	(segment
		(start 73.247758 -72.58304)
		(end 73.247758 -73.387712)
		(width 0.09906)
		(layer "F.Cu")
		(net "M_DDR3_NODE1_DQS7N")
	)
	(segment
		(start 98.404172 -30.797246)
		(end 98.404172 -30.504892)
		(width 0.1651)
		(layer "F.Cu")
		(net "M_DDR3_NODE1_DQS7N")
	)
	(segment
		(start 98.250248 -30.350968)
		(end 98.250248 -29.149802)
		(width 0.1651)
		(layer "F.Cu")
		(net "M_DDR3_NODE1_DQS7N")
	)
	(segment
		(start 99.956366 -31.490158)
		(end 99.097084 -31.490158)
		(width 0.1651)
		(layer "F.Cu")
		(net "M_DDR3_NODE1_DQS7N")
	)
	(segment
		(start 76.911454 -72.864218)
		(end 76.639928 -72.864218)
		(width 0.09906)
		(layer "F.Cu")
		(net "M_DDR3_NODE1_DQS7N")
	)
	(segment
		(start 77.0382 -73.153524)
		(end 77.0382 -72.990964)
		(width 0.09906)
		(layer "F.Cu")
		(net "M_DDR3_NODE1_DQS7N")
	)
	(segment
		(start 99.844352 -32.62757)
		(end 100.333302 -32.13862)
		(width 0.1651)
		(layer "F.Cu")
		(net "M_DDR3_NODE1_DQS7N")
	)
	(via
		(at 99.844352 -32.62757)
		(size 0.508)
		(drill 0.254)
		(layers "F.Cu" "B.Cu")
		(net "M_DDR3_NODE1_DQS7N")
	)
	(via
		(at 76.639928 -72.864218)
		(size 0.508)
		(drill 0.254)
		(layers "F.Cu" "B.Cu")
		(net "M_DDR3_NODE1_DQS7N")
	)
	(segment
		(start 102.51186 -35.97656)
		(end 102.303326 -35.768026)
		(width 0.2032)
		(layer "In7.Cu")
		(net "M_DDR3_NODE1_DQS7N")
	)
	(segment
		(start 100.337874 -38.562026)
		(end 101.12502 -38.562026)
		(width 0.2032)
		(layer "In7.Cu")
		(net "M_DDR3_NODE1_DQS7N")
	)
	(segment
		(start 96.0628 -53.984144)
		(end 96.0628 -53.862478)
		(width 0.2032)
		(layer "In7.Cu")
		(net "M_DDR3_NODE1_DQS7N")
	)
	(segment
		(start 93.26372 -59.887358)
		(end 93.472 -60.095638)
		(width 0.2032)
		(layer "In7.Cu")
		(net "M_DDR3_NODE1_DQS7N")
	)
	(segment
		(start 93.76664 -60.095638)
		(end 93.97492 -59.887358)
		(width 0.2032)
		(layer "In7.Cu")
		(net "M_DDR3_NODE1_DQS7N")
	)
	(segment
		(start 99.9363 -36.8808)
		(end 100.337874 -36.479226)
		(width 0.2032)
		(layer "In7.Cu")
		(net "M_DDR3_NODE1_DQS7N")
	)
	(segment
		(start 93.97492 -62.31509)
		(end 93.97492 -61.675518)
		(width 0.2032)
		(layer "In7.Cu")
		(net "M_DDR3_NODE1_DQS7N")
	)
	(segment
		(start 89.045288 -65.559178)
		(end 89.446862 -65.157604)
		(width 0.2032)
		(layer "In7.Cu")
		(net "M_DDR3_NODE1_DQS7N")
	)
	(segment
		(start 90.720926 -65.569084)
		(end 93.97492 -62.31509)
		(width 0.2032)
		(layer "In7.Cu")
		(net "M_DDR3_NODE1_DQS7N")
	)
	(segment
		(start 101.3333 -38.353746)
		(end 101.3333 -38.059106)
		(width 0.2032)
		(layer "In7.Cu")
		(net "M_DDR3_NODE1_DQS7N")
	)
	(segment
		(start 79.430118 -70.72757)
		(end 82.208624 -70.72757)
		(width 0.2032)
		(layer "In7.Cu")
		(net "M_DDR3_NODE1_DQS7N")
	)
	(segment
		(start 92.862146 -57.274206)
		(end 93.26372 -57.67578)
		(width 0.2032)
		(layer "In7.Cu")
		(net "M_DDR3_NODE1_DQS7N")
	)
	(segment
		(start 93.97492 -59.887358)
		(end 93.97492 -56.072024)
		(width 0.2032)
		(layer "In7.Cu")
		(net "M_DDR3_NODE1_DQS7N")
	)
	(segment
		(start 92.293694 -57.274206)
		(end 92.862146 -57.274206)
		(width 0.2032)
		(layer "In7.Cu")
		(net "M_DDR3_NODE1_DQS7N")
	)
	(segment
		(start 89.456768 -66.833242)
		(end 89.456768 -66.53911)
		(width 0.2032)
		(layer "In7.Cu")
		(net "M_DDR3_NODE1_DQS7N")
	)
	(segment
		(start 93.97492 -56.072024)
		(end 94.87662 -55.170324)
		(width 0.2032)
		(layer "In7.Cu")
		(net "M_DDR3_NODE1_DQS7N")
	)
	(segment
		(start 95.42907 -54.617874)
		(end 96.0628 -53.984144)
		(width 0.2032)
		(layer "In7.Cu")
		(net "M_DDR3_NODE1_DQS7N")
	)
	(segment
		(start 85.603588 -67.332606)
		(end 88.957404 -67.332606)
		(width 0.2032)
		(layer "In7.Cu")
		(net "M_DDR3_NODE1_DQS7N")
	)
	(segment
		(start 99.9363 -35.366452)
		(end 99.9363 -34.406586)
		(width 0.2032)
		(layer "In7.Cu")
		(net "M_DDR3_NODE1_DQS7N")
	)
	(segment
		(start 91.89212 -57.67578)
		(end 92.293694 -57.274206)
		(width 0.2032)
		(layer "In7.Cu")
		(net "M_DDR3_NODE1_DQS7N")
	)
	(segment
		(start 76.639928 -72.864218)
		(end 76.889356 -72.864218)
		(width 0.09906)
		(layer "In7.Cu")
		(net "M_DDR3_NODE1_DQS7N")
	)
	(segment
		(start 101.12502 -38.562026)
		(end 101.3333 -38.353746)
		(width 0.2032)
		(layer "In7.Cu")
		(net "M_DDR3_NODE1_DQS7N")
	)
	(segment
		(start 90.426794 -65.569084)
		(end 90.720926 -65.569084)
		(width 0.2032)
		(layer "In7.Cu")
		(net "M_DDR3_NODE1_DQS7N")
	)
	(segment
		(start 89.446862 -65.157604)
		(end 90.015314 -65.157604)
		(width 0.2032)
		(layer "In7.Cu")
		(net "M_DDR3_NODE1_DQS7N")
	)
	(segment
		(start 78.463648 -70.800468)
		(end 79.344012 -70.800468)
		(width 0.09906)
		(layer "In7.Cu")
		(net "M_DDR3_NODE1_DQS7N")
	)
	(segment
		(start 101.3333 -38.059106)
		(end 101.12502 -37.850826)
		(width 0.2032)
		(layer "In7.Cu")
		(net "M_DDR3_NODE1_DQS7N")
	)
	(segment
		(start 94.87662 -55.170324)
		(end 94.87662 -55.048658)
		(width 0.2032)
		(layer "In7.Cu")
		(net "M_DDR3_NODE1_DQS7N")
	)
	(segment
		(start 96.61525 -53.431694)
		(end 99.9363 -50.110644)
		(width 0.2032)
		(layer "In7.Cu")
		(net "M_DDR3_NODE1_DQS7N")
	)
	(segment
		(start 92.293694 -61.467238)
		(end 91.89212 -61.065664)
		(width 0.2032)
		(layer "In7.Cu")
		(net "M_DDR3_NODE1_DQS7N")
	)
	(segment
		(start 99.9363 -34.406586)
		(end 100.33762 -34.005266)
		(width 0.2032)
		(layer "In7.Cu")
		(net "M_DDR3_NODE1_DQS7N")
	)
	(segment
		(start 96.0628 -53.862478)
		(end 96.063054 -53.862478)
		(width 0.2032)
		(layer "In7.Cu")
		(net "M_DDR3_NODE1_DQS7N")
	)
	(segment
		(start 89.456768 -66.53911)
		(end 89.045288 -66.12763)
		(width 0.2032)
		(layer "In7.Cu")
		(net "M_DDR3_NODE1_DQS7N")
	)
	(segment
		(start 102.303326 -36.479226)
		(end 102.51186 -36.270692)
		(width 0.2032)
		(layer "In7.Cu")
		(net "M_DDR3_NODE1_DQS7N")
	)
	(segment
		(start 100.337874 -37.850826)
		(end 99.9363 -37.449252)
		(width 0.2032)
		(layer "In7.Cu")
		(net "M_DDR3_NODE1_DQS7N")
	)
	(segment
		(start 95.307658 -54.617874)
		(end 95.42907 -54.617874)
		(width 0.2032)
		(layer "In7.Cu")
		(net "M_DDR3_NODE1_DQS7N")
	)
	(segment
		(start 77.02042 -72.733154)
		(end 77.02042 -72.243696)
		(width 0.09906)
		(layer "In7.Cu")
		(net "M_DDR3_NODE1_DQS7N")
	)
	(segment
		(start 79.41691 -70.72757)
		(end 79.430118 -70.72757)
		(width 0.09906)
		(layer "In7.Cu")
		(net "M_DDR3_NODE1_DQS7N")
	)
	(segment
		(start 100.33762 -33.097216)
		(end 99.867974 -32.62757)
		(width 0.2032)
		(layer "In7.Cu")
		(net "M_DDR3_NODE1_DQS7N")
	)
	(segment
		(start 89.045288 -66.12763)
		(end 89.045288 -65.559178)
		(width 0.2032)
		(layer "In7.Cu")
		(net "M_DDR3_NODE1_DQS7N")
	)
	(segment
		(start 94.87662 -55.048658)
		(end 94.876874 -55.048658)
		(width 0.2032)
		(layer "In7.Cu")
		(net "M_DDR3_NODE1_DQS7N")
	)
	(segment
		(start 94.876874 -55.048658)
		(end 95.307658 -54.617874)
		(width 0.2032)
		(layer "In7.Cu")
		(net "M_DDR3_NODE1_DQS7N")
	)
	(segment
		(start 100.33762 -34.005266)
		(end 100.33762 -33.097216)
		(width 0.2032)
		(layer "In7.Cu")
		(net "M_DDR3_NODE1_DQS7N")
	)
	(segment
		(start 96.493838 -53.431694)
		(end 96.61525 -53.431694)
		(width 0.2032)
		(layer "In7.Cu")
		(net "M_DDR3_NODE1_DQS7N")
	)
	(segment
		(start 88.957404 -67.332606)
		(end 89.456768 -66.833242)
		(width 0.2032)
		(layer "In7.Cu")
		(net "M_DDR3_NODE1_DQS7N")
	)
	(segment
		(start 90.015314 -65.157604)
		(end 90.426794 -65.569084)
		(width 0.2032)
		(layer "In7.Cu")
		(net "M_DDR3_NODE1_DQS7N")
	)
	(segment
		(start 79.344012 -70.800468)
		(end 79.41691 -70.72757)
		(width 0.09906)
		(layer "In7.Cu")
		(net "M_DDR3_NODE1_DQS7N")
	)
	(segment
		(start 93.76664 -61.467238)
		(end 92.293694 -61.467238)
		(width 0.2032)
		(layer "In7.Cu")
		(net "M_DDR3_NODE1_DQS7N")
	)
	(segment
		(start 99.9363 -50.110644)
		(end 99.9363 -38.9636)
		(width 0.2032)
		(layer "In7.Cu")
		(net "M_DDR3_NODE1_DQS7N")
	)
	(segment
		(start 100.337874 -35.768026)
		(end 99.9363 -35.366452)
		(width 0.2032)
		(layer "In7.Cu")
		(net "M_DDR3_NODE1_DQS7N")
	)
	(segment
		(start 76.889356 -72.864218)
		(end 77.02042 -72.733154)
		(width 0.09906)
		(layer "In7.Cu")
		(net "M_DDR3_NODE1_DQS7N")
	)
	(segment
		(start 93.97492 -61.675518)
		(end 93.76664 -61.467238)
		(width 0.2032)
		(layer "In7.Cu")
		(net "M_DDR3_NODE1_DQS7N")
	)
	(segment
		(start 99.9363 -38.9636)
		(end 100.337874 -38.562026)
		(width 0.2032)
		(layer "In7.Cu")
		(net "M_DDR3_NODE1_DQS7N")
	)
	(segment
		(start 102.303326 -35.768026)
		(end 100.337874 -35.768026)
		(width 0.2032)
		(layer "In7.Cu")
		(net "M_DDR3_NODE1_DQS7N")
	)
	(segment
		(start 93.26372 -57.67578)
		(end 93.26372 -59.887358)
		(width 0.2032)
		(layer "In7.Cu")
		(net "M_DDR3_NODE1_DQS7N")
	)
	(segment
		(start 93.472 -60.095638)
		(end 93.76664 -60.095638)
		(width 0.2032)
		(layer "In7.Cu")
		(net "M_DDR3_NODE1_DQS7N")
	)
	(segment
		(start 102.51186 -36.270692)
		(end 102.51186 -35.97656)
		(width 0.2032)
		(layer "In7.Cu")
		(net "M_DDR3_NODE1_DQS7N")
	)
	(segment
		(start 91.89212 -61.065664)
		(end 91.89212 -57.67578)
		(width 0.2032)
		(layer "In7.Cu")
		(net "M_DDR3_NODE1_DQS7N")
	)
	(segment
		(start 77.02042 -72.243696)
		(end 78.463648 -70.800468)
		(width 0.09906)
		(layer "In7.Cu")
		(net "M_DDR3_NODE1_DQS7N")
	)
	(segment
		(start 96.063054 -53.862478)
		(end 96.493838 -53.431694)
		(width 0.2032)
		(layer "In7.Cu")
		(net "M_DDR3_NODE1_DQS7N")
	)
	(segment
		(start 99.867974 -32.62757)
		(end 99.844352 -32.62757)
		(width 0.2032)
		(layer "In7.Cu")
		(net "M_DDR3_NODE1_DQS7N")
	)
	(segment
		(start 99.9363 -37.449252)
		(end 99.9363 -36.8808)
		(width 0.2032)
		(layer "In7.Cu")
		(net "M_DDR3_NODE1_DQS7N")
	)
	(segment
		(start 100.337874 -36.479226)
		(end 102.303326 -36.479226)
		(width 0.2032)
		(layer "In7.Cu")
		(net "M_DDR3_NODE1_DQS7N")
	)
	(segment
		(start 82.208624 -70.72757)
		(end 85.603588 -67.332606)
		(width 0.2032)
		(layer "In7.Cu")
		(net "M_DDR3_NODE1_DQS7N")
	)
	(segment
		(start 101.12502 -37.850826)
		(end 100.337874 -37.850826)
		(width 0.2032)
		(layer "In7.Cu")
		(net "M_DDR3_NODE1_DQS7N")
	)
	(segment
		(start 60.352686 -121.444512)
		(end 60.352686 -122.187462)
		(width 0.1016)
		(layer "F.Cu")
		(net "BMC_ROMA2")
	)
	(segment
		(start 60.352686 -122.187462)
		(end 60.784486 -122.619262)
		(width 0.1016)
		(layer "F.Cu")
		(net "BMC_ROMA2")
	)
	(segment
		(start 62.941708 -126.249684)
		(end 62.198504 -125.50648)
		(width 0.1016)
		(layer "F.Cu")
		(net "BMC_ROMA2")
	)
	(segment
		(start 62.198504 -124.39777)
		(end 60.784486 -122.983752)
		(width 0.1016)
		(layer "F.Cu")
		(net "BMC_ROMA2")
	)
	(segment
		(start 60.784486 -122.983752)
		(end 60.784486 -122.619262)
		(width 0.1016)
		(layer "F.Cu")
		(net "BMC_ROMA2")
	)
	(segment
		(start 62.941708 -126.459488)
		(end 62.941708 -126.249684)
		(width 0.1016)
		(layer "F.Cu")
		(net "BMC_ROMA2")
	)
	(segment
		(start 62.198504 -125.50648)
		(end 62.198504 -124.39777)
		(width 0.1016)
		(layer "F.Cu")
		(net "BMC_ROMA2")
	)
	(via
		(at 60.784486 -122.619262)
		(size 0.762)
		(drill 0.381)
		(layers "F.Cu" "B.Cu")
		(net "BMC_ROMA2")
	)
	(segment
		(start 43.737784 -68.60159)
		(end 43.796204 -68.60159)
		(width 0.127)
		(layer "F.Cu")
		(net "P2E_CPU_PCIE_SW_NODE1_RX_DP")
	)
	(segment
		(start 43.390566 -68.948808)
		(end 43.737784 -68.60159)
		(width 0.127)
		(layer "F.Cu")
		(net "P2E_CPU_PCIE_SW_NODE1_RX_DP")
	)
	(via
		(at 43.390566 -68.948808)
		(size 0.508)
		(drill 0.254)
		(layers "F.Cu" "B.Cu")
		(net "P2E_CPU_PCIE_SW_NODE1_RX_DP")
	)
	(via
		(at 118.84152 -144.599152)
		(size 0.4064)
		(drill 0.2032)
		(layers "F.Cu" "B.Cu")
		(net "P2E_CPU_PCIE_SW_NODE1_RX_DP")
	)
	(segment
		(start 77.54366 -103.969312)
		(end 79.67726 -105.714038)
		(width 0.127)
		(layer "B.Cu")
		(net "P2E_CPU_PCIE_SW_NODE1_RX_DP")
	)
	(segment
		(start 91.845384 -140.564108)
		(end 94.573598 -144.25168)
		(width 0.127)
		(layer "B.Cu")
		(net "P2E_CPU_PCIE_SW_NODE1_RX_DP")
	)
	(segment
		(start 64.839088 -102.827328)
		(end 66.264028 -104.062022)
		(width 0.127)
		(layer "B.Cu")
		(net "P2E_CPU_PCIE_SW_NODE1_RX_DP")
	)
	(segment
		(start 43.32732 -70.47611)
		(end 43.30192 -70.47611)
		(width 0.1016)
		(layer "B.Cu")
		(net "P2E_CPU_PCIE_SW_NODE1_RX_DP")
	)
	(segment
		(start 92.289884 -121.691908)
		(end 91.89974 -132.624068)
		(width 0.127)
		(layer "B.Cu")
		(net "P2E_CPU_PCIE_SW_NODE1_RX_DP")
	)
	(segment
		(start 66.264028 -104.062022)
		(end 68.74383 -104.062022)
		(width 0.127)
		(layer "B.Cu")
		(net "P2E_CPU_PCIE_SW_NODE1_RX_DP")
	)
	(segment
		(start 84.357718 -109.847126)
		(end 86.626954 -109.821472)
		(width 0.127)
		(layer "B.Cu")
		(net "P2E_CPU_PCIE_SW_NODE1_RX_DP")
	)
	(segment
		(start 86.626954 -109.821472)
		(end 89.450926 -110.225332)
		(width 0.127)
		(layer "B.Cu")
		(net "P2E_CPU_PCIE_SW_NODE1_RX_DP")
	)
	(segment
		(start 43.87596 -70.409816)
		(end 43.758866 -70.52691)
		(width 0.1016)
		(layer "B.Cu")
		(net "P2E_CPU_PCIE_SW_NODE1_RX_DP")
	)
	(segment
		(start 120.642888 -144.599152)
		(end 118.84152 -144.599152)
		(width 0.127)
		(layer "B.Cu")
		(net "P2E_CPU_PCIE_SW_NODE1_RX_DP")
	)
	(segment
		(start 41.811702 -70.94982)
		(end 40.66159 -70.94982)
		(width 0.127)
		(layer "B.Cu")
		(net "P2E_CPU_PCIE_SW_NODE1_RX_DP")
	)
	(segment
		(start 40.005254 -101.524562)
		(end 45.170852 -102.106222)
		(width 0.127)
		(layer "B.Cu")
		(net "P2E_CPU_PCIE_SW_NODE1_RX_DP")
	)
	(segment
		(start 89.450926 -110.225332)
		(end 90.779092 -111.208566)
		(width 0.127)
		(layer "B.Cu")
		(net "P2E_CPU_PCIE_SW_NODE1_RX_DP")
	)
	(segment
		(start 48.927004 -103.316786)
		(end 50.596038 -103.567738)
		(width 0.127)
		(layer "B.Cu")
		(net "P2E_CPU_PCIE_SW_NODE1_RX_DP")
	)
	(segment
		(start 90.779092 -111.208566)
		(end 91.31046 -114.044222)
		(width 0.127)
		(layer "B.Cu")
		(net "P2E_CPU_PCIE_SW_NODE1_RX_DP")
	)
	(segment
		(start 94.573598 -144.25168)
		(end 98.981514 -145.620994)
		(width 0.127)
		(layer "B.Cu")
		(net "P2E_CPU_PCIE_SW_NODE1_RX_DP")
	)
	(segment
		(start 91.31046 -114.044222)
		(end 91.353894 -118.911624)
		(width 0.127)
		(layer "B.Cu")
		(net "P2E_CPU_PCIE_SW_NODE1_RX_DP")
	)
	(segment
		(start 36.335208 -75.022456)
		(end 35.66668 -77.526642)
		(width 0.127)
		(layer "B.Cu")
		(net "P2E_CPU_PCIE_SW_NODE1_RX_DP")
	)
	(segment
		(start 37.938456 -99.712272)
		(end 40.005254 -101.524562)
		(width 0.127)
		(layer "B.Cu")
		(net "P2E_CPU_PCIE_SW_NODE1_RX_DP")
	)
	(segment
		(start 82.841846 -108.603542)
		(end 83.386676 -109.607096)
		(width 0.127)
		(layer "B.Cu")
		(net "P2E_CPU_PCIE_SW_NODE1_RX_DP")
	)
	(segment
		(start 40.136064 -71.06412)
		(end 40.09263 -71.06412)
		(width 0.127)
		(layer "B.Cu")
		(net "P2E_CPU_PCIE_SW_NODE1_RX_DP")
	)
	(segment
		(start 43.704002 -69.788532)
		(end 43.87596 -69.96049)
		(width 0.1016)
		(layer "B.Cu")
		(net "P2E_CPU_PCIE_SW_NODE1_RX_DP")
	)
	(segment
		(start 42.9006 -70.47611)
		(end 41.811702 -70.94982)
		(width 0.127)
		(layer "B.Cu")
		(net "P2E_CPU_PCIE_SW_NODE1_RX_DP")
	)
	(segment
		(start 40.09263 -71.06412)
		(end 38.553644 -71.866506)
		(width 0.127)
		(layer "B.Cu")
		(net "P2E_CPU_PCIE_SW_NODE1_RX_DP")
	)
	(segment
		(start 83.386676 -109.607096)
		(end 84.357718 -109.847126)
		(width 0.127)
		(layer "B.Cu")
		(net "P2E_CPU_PCIE_SW_NODE1_RX_DP")
	)
	(segment
		(start 34.722816 -94.526608)
		(end 35.5981 -97.318068)
		(width 0.127)
		(layer "B.Cu")
		(net "P2E_CPU_PCIE_SW_NODE1_RX_DP")
	)
	(segment
		(start 50.596038 -103.567738)
		(end 56.485536 -103.567738)
		(width 0.127)
		(layer "B.Cu")
		(net "P2E_CPU_PCIE_SW_NODE1_RX_DP")
	)
	(segment
		(start 98.981514 -145.620994)
		(end 106.47299 -144.776444)
		(width 0.127)
		(layer "B.Cu")
		(net "P2E_CPU_PCIE_SW_NODE1_RX_DP")
	)
	(segment
		(start 43.37812 -70.52691)
		(end 43.32732 -70.47611)
		(width 0.1016)
		(layer "B.Cu")
		(net "P2E_CPU_PCIE_SW_NODE1_RX_DP")
	)
	(segment
		(start 43.30192 -70.47611)
		(end 42.9006 -70.47611)
		(width 0.127)
		(layer "B.Cu")
		(net "P2E_CPU_PCIE_SW_NODE1_RX_DP")
	)
	(segment
		(start 48.755554 -103.316786)
		(end 48.927004 -103.316786)
		(width 0.127)
		(layer "B.Cu")
		(net "P2E_CPU_PCIE_SW_NODE1_RX_DP")
	)
	(segment
		(start 43.87596 -69.96049)
		(end 43.87596 -70.409816)
		(width 0.1016)
		(layer "B.Cu")
		(net "P2E_CPU_PCIE_SW_NODE1_RX_DP")
	)
	(segment
		(start 37.691568 -72.73798)
		(end 36.335208 -75.022456)
		(width 0.127)
		(layer "B.Cu")
		(net "P2E_CPU_PCIE_SW_NODE1_RX_DP")
	)
	(segment
		(start 45.170852 -102.106222)
		(end 48.755554 -103.316786)
		(width 0.127)
		(layer "B.Cu")
		(net "P2E_CPU_PCIE_SW_NODE1_RX_DP")
	)
	(segment
		(start 92.32011 -121.504202)
		(end 92.289884 -121.691908)
		(width 0.127)
		(layer "B.Cu")
		(net "P2E_CPU_PCIE_SW_NODE1_RX_DP")
	)
	(segment
		(start 71.427086 -104.08412)
		(end 71.731886 -104.08412)
		(width 0.127)
		(layer "B.Cu")
		(net "P2E_CPU_PCIE_SW_NODE1_RX_DP")
	)
	(segment
		(start 35.66668 -77.526642)
		(end 35.56254 -84.586064)
		(width 0.127)
		(layer "B.Cu")
		(net "P2E_CPU_PCIE_SW_NODE1_RX_DP")
	)
	(segment
		(start 91.89974 -132.624068)
		(end 91.845384 -140.564108)
		(width 0.127)
		(layer "B.Cu")
		(net "P2E_CPU_PCIE_SW_NODE1_RX_DP")
	)
	(segment
		(start 115.892834 -144.34439)
		(end 118.25224 -144.599152)
		(width 0.127)
		(layer "B.Cu")
		(net "P2E_CPU_PCIE_SW_NODE1_RX_DP")
	)
	(segment
		(start 121.000012 -144.956276)
		(end 120.642888 -144.599152)
		(width 0.127)
		(layer "B.Cu")
		(net "P2E_CPU_PCIE_SW_NODE1_RX_DP")
	)
	(segment
		(start 43.704002 -69.35978)
		(end 43.704002 -69.788532)
		(width 0.1016)
		(layer "B.Cu")
		(net "P2E_CPU_PCIE_SW_NODE1_RX_DP")
	)
	(segment
		(start 64.317372 -102.548436)
		(end 64.839088 -102.827328)
		(width 0.127)
		(layer "B.Cu")
		(net "P2E_CPU_PCIE_SW_NODE1_RX_DP")
	)
	(segment
		(start 121.00179 -144.956276)
		(end 121.000012 -144.956276)
		(width 0.127)
		(layer "B.Cu")
		(net "P2E_CPU_PCIE_SW_NODE1_RX_DP")
	)
	(segment
		(start 63.2714 -102.564692)
		(end 64.317372 -102.548436)
		(width 0.127)
		(layer "B.Cu")
		(net "P2E_CPU_PCIE_SW_NODE1_RX_DP")
	)
	(segment
		(start 40.66159 -70.94982)
		(end 40.136064 -71.06412)
		(width 0.127)
		(layer "B.Cu")
		(net "P2E_CPU_PCIE_SW_NODE1_RX_DP")
	)
	(segment
		(start 79.67726 -105.714038)
		(end 81.700116 -106.98099)
		(width 0.127)
		(layer "B.Cu")
		(net "P2E_CPU_PCIE_SW_NODE1_RX_DP")
	)
	(segment
		(start 106.47299 -144.776444)
		(end 115.892834 -144.34439)
		(width 0.127)
		(layer "B.Cu")
		(net "P2E_CPU_PCIE_SW_NODE1_RX_DP")
	)
	(segment
		(start 35.5981 -97.318068)
		(end 37.938456 -99.712272)
		(width 0.127)
		(layer "B.Cu")
		(net "P2E_CPU_PCIE_SW_NODE1_RX_DP")
	)
	(segment
		(start 59.746134 -102.564692)
		(end 63.2714 -102.564692)
		(width 0.127)
		(layer "B.Cu")
		(net "P2E_CPU_PCIE_SW_NODE1_RX_DP")
	)
	(segment
		(start 56.485536 -103.567738)
		(end 59.746134 -102.564692)
		(width 0.127)
		(layer "B.Cu")
		(net "P2E_CPU_PCIE_SW_NODE1_RX_DP")
	)
	(segment
		(start 118.25224 -144.599152)
		(end 118.84152 -144.599152)
		(width 0.127)
		(layer "B.Cu")
		(net "P2E_CPU_PCIE_SW_NODE1_RX_DP")
	)
	(segment
		(start 43.703494 -69.25818)
		(end 43.704002 -69.35978)
		(width 0.1016)
		(layer "B.Cu")
		(net "P2E_CPU_PCIE_SW_NODE1_RX_DP")
	)
	(segment
		(start 68.74383 -104.062022)
		(end 71.427086 -104.08412)
		(width 0.127)
		(layer "B.Cu")
		(net "P2E_CPU_PCIE_SW_NODE1_RX_DP")
	)
	(segment
		(start 43.758866 -70.52691)
		(end 43.37812 -70.52691)
		(width 0.1016)
		(layer "B.Cu")
		(net "P2E_CPU_PCIE_SW_NODE1_RX_DP")
	)
	(segment
		(start 71.731886 -104.08412)
		(end 77.54366 -103.969312)
		(width 0.127)
		(layer "B.Cu")
		(net "P2E_CPU_PCIE_SW_NODE1_RX_DP")
	)
	(segment
		(start 38.553644 -71.866506)
		(end 37.691568 -72.73798)
		(width 0.127)
		(layer "B.Cu")
		(net "P2E_CPU_PCIE_SW_NODE1_RX_DP")
	)
	(segment
		(start 43.390566 -68.948808)
		(end 43.703494 -69.25818)
		(width 0.1016)
		(layer "B.Cu")
		(net "P2E_CPU_PCIE_SW_NODE1_RX_DP")
	)
	(segment
		(start 81.700116 -106.98099)
		(end 82.841846 -108.603542)
		(width 0.127)
		(layer "B.Cu")
		(net "P2E_CPU_PCIE_SW_NODE1_RX_DP")
	)
	(segment
		(start 91.353894 -118.911624)
		(end 92.32011 -121.504202)
		(width 0.127)
		(layer "B.Cu")
		(net "P2E_CPU_PCIE_SW_NODE1_RX_DP")
	)
	(segment
		(start 35.56254 -84.586064)
		(end 34.722816 -94.526608)
		(width 0.127)
		(layer "B.Cu")
		(net "P2E_CPU_PCIE_SW_NODE1_RX_DP")
	)
	(segment
		(start 73.806304 -72.159622)
		(end 73.953878 -72.307196)
		(width 0.1016)
		(layer "F.Cu")
		(net "M1_DQ_NODE1_DQ58")
	)
	(segment
		(start 99.74834 -20.951698)
		(end 99.74834 -23.478998)
		(width 0.1651)
		(layer "F.Cu")
		(net "M1_DQ_NODE1_DQ58")
	)
	(segment
		(start 73.953878 -72.307196)
		(end 75.219306 -72.307196)
		(width 0.1016)
		(layer "F.Cu")
		(net "M1_DQ_NODE1_DQ58")
	)
	(segment
		(start 75.219306 -72.307196)
		(end 75.776328 -72.864218)
		(width 0.1016)
		(layer "F.Cu")
		(net "M1_DQ_NODE1_DQ58")
	)
	(segment
		(start 99.74834 -23.478998)
		(end 99.695 -23.532338)
		(width 0.1651)
		(layer "F.Cu")
		(net "M1_DQ_NODE1_DQ58")
	)
	(segment
		(start 99.750118 -20.94992)
		(end 99.74834 -20.951698)
		(width 0.1651)
		(layer "F.Cu")
		(net "M1_DQ_NODE1_DQ58")
	)
	(segment
		(start 99.695 -23.532338)
		(end 99.693222 -23.532338)
		(width 0.1651)
		(layer "F.Cu")
		(net "M1_DQ_NODE1_DQ58")
	)
	(via
		(at 99.693222 -23.532338)
		(size 0.508)
		(drill 0.254)
		(layers "F.Cu" "B.Cu")
		(net "M1_DQ_NODE1_DQ58")
	)
	(via
		(at 75.776328 -72.864218)
		(size 0.508)
		(drill 0.254)
		(layers "F.Cu" "B.Cu")
		(net "M1_DQ_NODE1_DQ58")
	)
	(segment
		(start 102.12578 -43.925236)
		(end 102.28072 -43.925236)
		(width 0.2032)
		(layer "In7.Cu")
		(net "M1_DQ_NODE1_DQ58")
	)
	(segment
		(start 102.12578 -41.080436)
		(end 102.28072 -41.080436)
		(width 0.2032)
		(layer "In7.Cu")
		(net "M1_DQ_NODE1_DQ58")
	)
	(segment
		(start 103.596694 -31.419038)
		(end 103.844598 -31.171134)
		(width 0.2032)
		(layer "In7.Cu")
		(net "M1_DQ_NODE1_DQ58")
	)
	(segment
		(start 78.54315 -72.750172)
		(end 77.759306 -73.534016)
		(width 0.1016)
		(layer "In7.Cu")
		(net "M1_DQ_NODE1_DQ58")
	)
	(segment
		(start 102.489 -46.978316)
		(end 102.489 -47.272956)
		(width 0.2032)
		(layer "In7.Cu")
		(net "M1_DQ_NODE1_DQ58")
	)
	(segment
		(start 101.9175 -43.716956)
		(end 102.12578 -43.925236)
		(width 0.2032)
		(layer "In7.Cu")
		(net "M1_DQ_NODE1_DQ58")
	)
	(segment
		(start 102.28072 -43.214036)
		(end 102.12578 -43.214036)
		(width 0.2032)
		(layer "In7.Cu")
		(net "M1_DQ_NODE1_DQ58")
	)
	(segment
		(start 101.671882 -28.703778)
		(end 103.341678 -30.373574)
		(width 0.2032)
		(layer "In7.Cu")
		(net "M1_DQ_NODE1_DQ58")
	)
	(segment
		(start 102.28072 -49.614836)
		(end 102.489 -49.823116)
		(width 0.2032)
		(layer "In7.Cu")
		(net "M1_DQ_NODE1_DQ58")
	)
	(segment
		(start 102.28072 -47.481236)
		(end 102.12578 -47.481236)
		(width 0.2032)
		(layer "In7.Cu")
		(net "M1_DQ_NODE1_DQ58")
	)
	(segment
		(start 101.9175 -46.267116)
		(end 101.9175 -46.561756)
		(width 0.2032)
		(layer "In7.Cu")
		(net "M1_DQ_NODE1_DQ58")
	)
	(segment
		(start 89.779094 -69.315076)
		(end 86.638638 -69.315076)
		(width 0.2032)
		(layer "In7.Cu")
		(net "M1_DQ_NODE1_DQ58")
	)
	(segment
		(start 78.82255 -72.750172)
		(end 78.54315 -72.750172)
		(width 0.1016)
		(layer "In7.Cu")
		(net "M1_DQ_NODE1_DQ58")
	)
	(segment
		(start 102.489 -45.555916)
		(end 102.489 -45.850556)
		(width 0.2032)
		(layer "In7.Cu")
		(net "M1_DQ_NODE1_DQ58")
	)
	(segment
		(start 102.489 -48.695356)
		(end 102.28072 -48.903636)
		(width 0.2032)
		(layer "In7.Cu")
		(net "M1_DQ_NODE1_DQ58")
	)
	(segment
		(start 101.262942 -28.703778)
		(end 101.671882 -28.703778)
		(width 0.2032)
		(layer "In7.Cu")
		(net "M1_DQ_NODE1_DQ58")
	)
	(segment
		(start 102.489 -49.823116)
		(end 102.489 -50.117756)
		(width 0.2032)
		(layer "In7.Cu")
		(net "M1_DQ_NODE1_DQ58")
	)
	(segment
		(start 102.12578 -46.058836)
		(end 101.9175 -46.267116)
		(width 0.2032)
		(layer "In7.Cu")
		(net "M1_DQ_NODE1_DQ58")
	)
	(segment
		(start 95.95612 -63.13805)
		(end 89.779094 -69.315076)
		(width 0.2032)
		(layer "In7.Cu")
		(net "M1_DQ_NODE1_DQ58")
	)
	(segment
		(start 103.093774 -31.210758)
		(end 103.302054 -31.419038)
		(width 0.2032)
		(layer "In7.Cu")
		(net "M1_DQ_NODE1_DQ58")
	)
	(segment
		(start 102.489 -41.583356)
		(end 102.28072 -41.791636)
		(width 0.2032)
		(layer "In7.Cu")
		(net "M1_DQ_NODE1_DQ58")
	)
	(segment
		(start 102.28072 -46.058836)
		(end 102.12578 -46.058836)
		(width 0.2032)
		(layer "In7.Cu")
		(net "M1_DQ_NODE1_DQ58")
	)
	(segment
		(start 102.12578 -47.481236)
		(end 101.9175 -47.689516)
		(width 0.2032)
		(layer "In7.Cu")
		(net "M1_DQ_NODE1_DQ58")
	)
	(segment
		(start 101.9175 -50.936906)
		(end 95.95612 -56.898286)
		(width 0.2032)
		(layer "In7.Cu")
		(net "M1_DQ_NODE1_DQ58")
	)
	(segment
		(start 102.489 -47.272956)
		(end 102.28072 -47.481236)
		(width 0.2032)
		(layer "In7.Cu")
		(net "M1_DQ_NODE1_DQ58")
	)
	(segment
		(start 102.28072 -43.925236)
		(end 102.489 -44.133516)
		(width 0.2032)
		(layer "In7.Cu")
		(net "M1_DQ_NODE1_DQ58")
	)
	(segment
		(start 102.28072 -45.347636)
		(end 102.489 -45.555916)
		(width 0.2032)
		(layer "In7.Cu")
		(net "M1_DQ_NODE1_DQ58")
	)
	(segment
		(start 102.489 -44.428156)
		(end 102.28072 -44.636436)
		(width 0.2032)
		(layer "In7.Cu")
		(net "M1_DQ_NODE1_DQ58")
	)
	(segment
		(start 101.9175 -44.844716)
		(end 101.9175 -45.139356)
		(width 0.2032)
		(layer "In7.Cu")
		(net "M1_DQ_NODE1_DQ58")
	)
	(segment
		(start 104.65816 -31.690056)
		(end 104.65816 -37.835586)
		(width 0.2032)
		(layer "In7.Cu")
		(net "M1_DQ_NODE1_DQ58")
	)
	(segment
		(start 101.9175 -50.534316)
		(end 101.9175 -50.936906)
		(width 0.2032)
		(layer "In7.Cu")
		(net "M1_DQ_NODE1_DQ58")
	)
	(segment
		(start 102.12578 -49.614836)
		(end 102.28072 -49.614836)
		(width 0.2032)
		(layer "In7.Cu")
		(net "M1_DQ_NODE1_DQ58")
	)
	(segment
		(start 103.844598 -31.171134)
		(end 104.139238 -31.171134)
		(width 0.2032)
		(layer "In7.Cu")
		(net "M1_DQ_NODE1_DQ58")
	)
	(segment
		(start 103.341678 -30.373574)
		(end 103.341678 -30.668214)
		(width 0.2032)
		(layer "In7.Cu")
		(net "M1_DQ_NODE1_DQ58")
	)
	(segment
		(start 102.12578 -43.214036)
		(end 101.9175 -43.422316)
		(width 0.2032)
		(layer "In7.Cu")
		(net "M1_DQ_NODE1_DQ58")
	)
	(segment
		(start 101.9175 -49.111916)
		(end 101.9175 -49.406556)
		(width 0.2032)
		(layer "In7.Cu")
		(net "M1_DQ_NODE1_DQ58")
	)
	(segment
		(start 101.9175 -41.999916)
		(end 101.9175 -42.294556)
		(width 0.2032)
		(layer "In7.Cu")
		(net "M1_DQ_NODE1_DQ58")
	)
	(segment
		(start 101.9175 -47.984156)
		(end 102.12578 -48.192436)
		(width 0.2032)
		(layer "In7.Cu")
		(net "M1_DQ_NODE1_DQ58")
	)
	(segment
		(start 102.28072 -46.770036)
		(end 102.489 -46.978316)
		(width 0.2032)
		(layer "In7.Cu")
		(net "M1_DQ_NODE1_DQ58")
	)
	(segment
		(start 102.28072 -41.791636)
		(end 102.12578 -41.791636)
		(width 0.2032)
		(layer "In7.Cu")
		(net "M1_DQ_NODE1_DQ58")
	)
	(segment
		(start 86.638638 -69.315076)
		(end 83.203542 -72.750172)
		(width 0.2032)
		(layer "In7.Cu")
		(net "M1_DQ_NODE1_DQ58")
	)
	(segment
		(start 102.12578 -48.903636)
		(end 101.9175 -49.111916)
		(width 0.2032)
		(layer "In7.Cu")
		(net "M1_DQ_NODE1_DQ58")
	)
	(segment
		(start 100.691442 -28.132278)
		(end 101.262942 -28.703778)
		(width 0.2032)
		(layer "In7.Cu")
		(net "M1_DQ_NODE1_DQ58")
	)
	(segment
		(start 76.355956 -73.534016)
		(end 75.98537 -73.16343)
		(width 0.1016)
		(layer "In7.Cu")
		(net "M1_DQ_NODE1_DQ58")
	)
	(segment
		(start 101.9175 -42.294556)
		(end 102.12578 -42.502836)
		(width 0.2032)
		(layer "In7.Cu")
		(net "M1_DQ_NODE1_DQ58")
	)
	(segment
		(start 103.302054 -31.419038)
		(end 103.596694 -31.419038)
		(width 0.2032)
		(layer "In7.Cu")
		(net "M1_DQ_NODE1_DQ58")
	)
	(segment
		(start 102.12578 -44.636436)
		(end 101.9175 -44.844716)
		(width 0.2032)
		(layer "In7.Cu")
		(net "M1_DQ_NODE1_DQ58")
	)
	(segment
		(start 102.12578 -45.347636)
		(end 102.28072 -45.347636)
		(width 0.2032)
		(layer "In7.Cu")
		(net "M1_DQ_NODE1_DQ58")
	)
	(segment
		(start 102.12578 -48.192436)
		(end 102.28072 -48.192436)
		(width 0.2032)
		(layer "In7.Cu")
		(net "M1_DQ_NODE1_DQ58")
	)
	(segment
		(start 103.093774 -30.916118)
		(end 103.093774 -31.210758)
		(width 0.2032)
		(layer "In7.Cu")
		(net "M1_DQ_NODE1_DQ58")
	)
	(segment
		(start 102.489 -41.288716)
		(end 102.489 -41.583356)
		(width 0.2032)
		(layer "In7.Cu")
		(net "M1_DQ_NODE1_DQ58")
	)
	(segment
		(start 102.489 -45.850556)
		(end 102.28072 -46.058836)
		(width 0.2032)
		(layer "In7.Cu")
		(net "M1_DQ_NODE1_DQ58")
	)
	(segment
		(start 102.12578 -42.502836)
		(end 102.28072 -42.502836)
		(width 0.2032)
		(layer "In7.Cu")
		(net "M1_DQ_NODE1_DQ58")
	)
	(segment
		(start 101.9175 -40.576246)
		(end 101.9175 -40.872156)
		(width 0.2032)
		(layer "In7.Cu")
		(net "M1_DQ_NODE1_DQ58")
	)
	(segment
		(start 102.489 -43.005756)
		(end 102.28072 -43.214036)
		(width 0.2032)
		(layer "In7.Cu")
		(net "M1_DQ_NODE1_DQ58")
	)
	(segment
		(start 75.98537 -73.07326)
		(end 75.776328 -72.864218)
		(width 0.1016)
		(layer "In7.Cu")
		(net "M1_DQ_NODE1_DQ58")
	)
	(segment
		(start 104.65816 -37.835586)
		(end 101.9175 -40.576246)
		(width 0.2032)
		(layer "In7.Cu")
		(net "M1_DQ_NODE1_DQ58")
	)
	(segment
		(start 101.9175 -43.422316)
		(end 101.9175 -43.716956)
		(width 0.2032)
		(layer "In7.Cu")
		(net "M1_DQ_NODE1_DQ58")
	)
	(segment
		(start 102.28072 -48.192436)
		(end 102.489 -48.400716)
		(width 0.2032)
		(layer "In7.Cu")
		(net "M1_DQ_NODE1_DQ58")
	)
	(segment
		(start 75.98537 -73.16343)
		(end 75.98537 -73.07326)
		(width 0.1016)
		(layer "In7.Cu")
		(net "M1_DQ_NODE1_DQ58")
	)
	(segment
		(start 102.489 -44.133516)
		(end 102.489 -44.428156)
		(width 0.2032)
		(layer "In7.Cu")
		(net "M1_DQ_NODE1_DQ58")
	)
	(segment
		(start 102.12578 -46.770036)
		(end 102.28072 -46.770036)
		(width 0.2032)
		(layer "In7.Cu")
		(net "M1_DQ_NODE1_DQ58")
	)
	(segment
		(start 101.9175 -47.689516)
		(end 101.9175 -47.984156)
		(width 0.2032)
		(layer "In7.Cu")
		(net "M1_DQ_NODE1_DQ58")
	)
	(segment
		(start 102.28072 -50.326036)
		(end 102.12578 -50.326036)
		(width 0.2032)
		(layer "In7.Cu")
		(net "M1_DQ_NODE1_DQ58")
	)
	(segment
		(start 102.28072 -41.080436)
		(end 102.489 -41.288716)
		(width 0.2032)
		(layer "In7.Cu")
		(net "M1_DQ_NODE1_DQ58")
	)
	(segment
		(start 77.759306 -73.534016)
		(end 76.355956 -73.534016)
		(width 0.1016)
		(layer "In7.Cu")
		(net "M1_DQ_NODE1_DQ58")
	)
	(segment
		(start 102.489 -42.711116)
		(end 102.489 -43.005756)
		(width 0.2032)
		(layer "In7.Cu")
		(net "M1_DQ_NODE1_DQ58")
	)
	(segment
		(start 101.9175 -40.872156)
		(end 102.12578 -41.080436)
		(width 0.2032)
		(layer "In7.Cu")
		(net "M1_DQ_NODE1_DQ58")
	)
	(segment
		(start 102.28072 -44.636436)
		(end 102.12578 -44.636436)
		(width 0.2032)
		(layer "In7.Cu")
		(net "M1_DQ_NODE1_DQ58")
	)
	(segment
		(start 95.95612 -56.898286)
		(end 95.95612 -63.13805)
		(width 0.2032)
		(layer "In7.Cu")
		(net "M1_DQ_NODE1_DQ58")
	)
	(segment
		(start 101.9175 -45.139356)
		(end 102.12578 -45.347636)
		(width 0.2032)
		(layer "In7.Cu")
		(net "M1_DQ_NODE1_DQ58")
	)
	(segment
		(start 101.9175 -49.406556)
		(end 102.12578 -49.614836)
		(width 0.2032)
		(layer "In7.Cu")
		(net "M1_DQ_NODE1_DQ58")
	)
	(segment
		(start 103.341678 -30.668214)
		(end 103.093774 -30.916118)
		(width 0.2032)
		(layer "In7.Cu")
		(net "M1_DQ_NODE1_DQ58")
	)
	(segment
		(start 104.139238 -31.171134)
		(end 104.65816 -31.690056)
		(width 0.2032)
		(layer "In7.Cu")
		(net "M1_DQ_NODE1_DQ58")
	)
	(segment
		(start 102.489 -50.117756)
		(end 102.28072 -50.326036)
		(width 0.2032)
		(layer "In7.Cu")
		(net "M1_DQ_NODE1_DQ58")
	)
	(segment
		(start 101.9175 -46.561756)
		(end 102.12578 -46.770036)
		(width 0.2032)
		(layer "In7.Cu")
		(net "M1_DQ_NODE1_DQ58")
	)
	(segment
		(start 100.691442 -24.530558)
		(end 100.691442 -28.132278)
		(width 0.2032)
		(layer "In7.Cu")
		(net "M1_DQ_NODE1_DQ58")
	)
	(segment
		(start 99.693222 -23.532338)
		(end 100.691442 -24.530558)
		(width 0.2032)
		(layer "In7.Cu")
		(net "M1_DQ_NODE1_DQ58")
	)
	(segment
		(start 102.12578 -41.791636)
		(end 101.9175 -41.999916)
		(width 0.2032)
		(layer "In7.Cu")
		(net "M1_DQ_NODE1_DQ58")
	)
	(segment
		(start 102.28072 -42.502836)
		(end 102.489 -42.711116)
		(width 0.2032)
		(layer "In7.Cu")
		(net "M1_DQ_NODE1_DQ58")
	)
	(segment
		(start 102.12578 -50.326036)
		(end 101.9175 -50.534316)
		(width 0.2032)
		(layer "In7.Cu")
		(net "M1_DQ_NODE1_DQ58")
	)
	(segment
		(start 102.28072 -48.903636)
		(end 102.12578 -48.903636)
		(width 0.2032)
		(layer "In7.Cu")
		(net "M1_DQ_NODE1_DQ58")
	)
	(segment
		(start 102.489 -48.400716)
		(end 102.489 -48.695356)
		(width 0.2032)
		(layer "In7.Cu")
		(net "M1_DQ_NODE1_DQ58")
	)
	(segment
		(start 83.203542 -72.750172)
		(end 78.82255 -72.750172)
		(width 0.2032)
		(layer "In7.Cu")
		(net "M1_DQ_NODE1_DQ58")
	)
	(segment
		(start 61.841634 -116.911882)
		(end 61.841634 -116.914168)
		(width 0.1016)
		(layer "F.Cu")
		(net "BMC_ROMA6")
	)
	(segment
		(start 61.470286 -118.201948)
		(end 61.841634 -117.8306)
		(width 0.1016)
		(layer "F.Cu")
		(net "BMC_ROMA6")
	)
	(segment
		(start 63.349886 -126.175262)
		(end 62.460886 -125.286262)
		(width 0.1016)
		(layer "F.Cu")
		(net "BMC_ROMA6")
	)
	(segment
		(start 61.343286 -122.289062)
		(end 60.962286 -121.908062)
		(width 0.1016)
		(layer "F.Cu")
		(net "BMC_ROMA6")
	)
	(segment
		(start 61.510672 -116.911882)
		(end 61.841634 -116.911882)
		(width 0.1016)
		(layer "F.Cu")
		(net "BMC_ROMA6")
	)
	(segment
		(start 63.741808 -127.259588)
		(end 63.349886 -126.867666)
		(width 0.1016)
		(layer "F.Cu")
		(net "BMC_ROMA6")
	)
	(segment
		(start 63.349886 -126.867666)
		(end 63.349886 -126.175262)
		(width 0.1016)
		(layer "F.Cu")
		(net "BMC_ROMA6")
	)
	(segment
		(start 61.343286 -123.10491)
		(end 61.343286 -122.289062)
		(width 0.1016)
		(layer "F.Cu")
		(net "BMC_ROMA6")
	)
	(segment
		(start 60.962286 -117.460268)
		(end 61.510672 -116.911882)
		(width 0.1016)
		(layer "F.Cu")
		(net "BMC_ROMA6")
	)
	(segment
		(start 61.470286 -118.510812)
		(end 61.470286 -118.201948)
		(width 0.1016)
		(layer "F.Cu")
		(net "BMC_ROMA6")
	)
	(segment
		(start 62.460886 -124.22251)
		(end 61.343286 -123.10491)
		(width 0.1016)
		(layer "F.Cu")
		(net "BMC_ROMA6")
	)
	(segment
		(start 60.962286 -121.908062)
		(end 60.962286 -117.460268)
		(width 0.1016)
		(layer "F.Cu")
		(net "BMC_ROMA6")
	)
	(segment
		(start 62.460886 -125.286262)
		(end 62.460886 -124.22251)
		(width 0.1016)
		(layer "F.Cu")
		(net "BMC_ROMA6")
	)
	(segment
		(start 61.841634 -117.8306)
		(end 61.841634 -116.914168)
		(width 0.1016)
		(layer "F.Cu")
		(net "BMC_ROMA6")
	)
	(via
		(at 61.841634 -116.914168)
		(size 0.508)
		(drill 0.254)
		(layers "F.Cu" "B.Cu")
		(net "BMC_ROMA6")
	)
	(segment
		(start 95.338646 -137.015982)
		(end 95.338646 -136.238488)
		(width 0.254)
		(layer "F.Cu")
		(net "P1V05_SUS_NODE1")
	)
	(segment
		(start 64.801496 -81.661)
		(end 65.094104 -81.953608)
		(width 0.3048)
		(layer "F.Cu")
		(net "P1V05_SUS_NODE1")
	)
	(segment
		(start 65.475866 -82.333846)
		(end 65.474342 -82.333846)
		(width 0.3048)
		(layer "F.Cu")
		(net "P1V05_SUS_NODE1")
	)
	(segment
		(start 65.094104 -81.953608)
		(end 65.475866 -81.571846)
		(width 0.3048)
		(layer "F.Cu")
		(net "P1V05_SUS_NODE1")
	)
	(segment
		(start 65.474342 -82.333846)
		(end 65.094104 -81.953608)
		(width 0.3048)
		(layer "F.Cu")
		(net "P1V05_SUS_NODE1")
	)
	(segment
		(start 95.338646 -137.015982)
		(end 95.62846 -137.305796)
		(width 0.254)
		(layer "F.Cu")
		(net "P1V05_SUS_NODE1")
	)
	(segment
		(start 64.801496 -81.300066)
		(end 64.801496 -81.661)
		(width 0.3048)
		(layer "F.Cu")
		(net "P1V05_SUS_NODE1")
	)
	(via
		(at 94.09684 -77.700632)
		(size 0.508)
		(drill 0.254)
		(layers "F.Cu" "B.Cu")
		(net "P1V05_SUS_NODE1")
	)
	(via
		(at 65.094104 -81.953608)
		(size 0.508)
		(drill 0.254)
		(layers "F.Cu" "B.Cu")
		(net "P1V05_SUS_NODE1")
	)
	(via
		(at 94.56928 -111.636556)
		(size 0.508)
		(drill 0.254)
		(layers "F.Cu" "B.Cu")
		(net "P1V05_SUS_NODE1")
	)
	(via
		(at 94.25432 -113.862104)
		(size 0.508)
		(drill 0.254)
		(layers "F.Cu" "B.Cu")
		(net "P1V05_SUS_NODE1")
	)
	(via
		(at 97.112582 -137.265156)
		(size 0.508)
		(drill 0.254)
		(layers "F.Cu" "B.Cu")
		(net "P1V05_SUS_NODE1")
	)
	(via
		(at 94.66834 -113.20907)
		(size 0.508)
		(drill 0.254)
		(layers "F.Cu" "B.Cu")
		(net "P1V05_SUS_NODE1")
	)
	(via
		(at 93.79712 -76.432664)
		(size 0.508)
		(drill 0.254)
		(layers "F.Cu" "B.Cu")
		(net "P1V05_SUS_NODE1")
	)
	(via
		(at 93.853 -113.251742)
		(size 0.508)
		(drill 0.254)
		(layers "F.Cu" "B.Cu")
		(net "P1V05_SUS_NODE1")
	)
	(via
		(at 86.2584 -84.347304)
		(size 0.508)
		(drill 0.254)
		(layers "F.Cu" "B.Cu")
		(net "P1V05_SUS_NODE1")
	)
	(via
		(at 86.19998 -83.610704)
		(size 0.508)
		(drill 0.254)
		(layers "F.Cu" "B.Cu")
		(net "P1V05_SUS_NODE1")
	)
	(via
		(at 93.63964 -114.167412)
		(size 0.508)
		(drill 0.254)
		(layers "F.Cu" "B.Cu")
		(net "P1V05_SUS_NODE1")
	)
	(via
		(at 95.62846 -137.305796)
		(size 0.508)
		(drill 0.254)
		(layers "F.Cu" "B.Cu")
		(net "P1V05_SUS_NODE1")
	)
	(via
		(at 95.7961 -137.960354)
		(size 0.508)
		(drill 0.254)
		(layers "F.Cu" "B.Cu")
		(net "P1V05_SUS_NODE1")
	)
	(via
		(at 97.179384 -136.494266)
		(size 0.508)
		(drill 0.254)
		(layers "F.Cu" "B.Cu")
		(net "P1V05_SUS_NODE1")
	)
	(via
		(at 94.25686 -77.085698)
		(size 0.508)
		(drill 0.254)
		(layers "F.Cu" "B.Cu")
		(net "P1V05_SUS_NODE1")
	)
	(via
		(at 94.4753 -109.353858)
		(size 0.508)
		(drill 0.254)
		(layers "F.Cu" "B.Cu")
		(net "P1V05_SUS_NODE1")
	)
	(via
		(at 89.875614 -77.773276)
		(size 0.508)
		(drill 0.254)
		(layers "F.Cu" "B.Cu")
		(net "P1V05_SUS_NODE1")
	)
	(segment
		(start 44.215812 -68.94449)
		(end 43.858688 -69.301614)
		(width 0.127)
		(layer "F.Cu")
		(net "P2E_CPU_PCIE_SW_NODE1_RX_DN")
	)
	(segment
		(start 43.858688 -69.301614)
		(end 43.796204 -69.301614)
		(width 0.127)
		(layer "F.Cu")
		(net "P2E_CPU_PCIE_SW_NODE1_RX_DN")
	)
	(via
		(at 67.29222 -103.757222)
		(size 0.4064)
		(drill 0.2032)
		(layers "F.Cu" "B.Cu")
		(net "P2E_CPU_PCIE_SW_NODE1_RX_DN")
	)
	(via
		(at 44.215812 -68.94449)
		(size 0.508)
		(drill 0.254)
		(layers "F.Cu" "B.Cu")
		(net "P2E_CPU_PCIE_SW_NODE1_RX_DN")
	)
	(segment
		(start 36.470336 -76.236576)
		(end 36.301172 -76.334112)
		(width 0.127)
		(layer "B.Cu")
		(net "P2E_CPU_PCIE_SW_NODE1_RX_DN")
	)
	(segment
		(start 121.000774 -143.940276)
		(end 121.00179 -143.940276)
		(width 0.127)
		(layer "B.Cu")
		(net "P2E_CPU_PCIE_SW_NODE1_RX_DN")
	)
	(segment
		(start 106.44886 -144.472406)
		(end 115.902232 -144.038828)
		(width 0.127)
		(layer "B.Cu")
		(net "P2E_CPU_PCIE_SW_NODE1_RX_DN")
	)
	(segment
		(start 40.16756 -71.36892)
		(end 38.737032 -72.114918)
		(width 0.127)
		(layer "B.Cu")
		(net "P2E_CPU_PCIE_SW_NODE1_RX_DN")
	)
	(segment
		(start 120.648222 -144.294352)
		(end 120.668542 -144.274032)
		(width 0.127)
		(layer "B.Cu")
		(net "P2E_CPU_PCIE_SW_NODE1_RX_DN")
	)
	(segment
		(start 120.668542 -144.274032)
		(end 120.668542 -144.272508)
		(width 0.127)
		(layer "B.Cu")
		(net "P2E_CPU_PCIE_SW_NODE1_RX_DN")
	)
	(segment
		(start 84.393024 -109.541818)
		(end 86.64702 -109.516418)
		(width 0.127)
		(layer "B.Cu")
		(net "P2E_CPU_PCIE_SW_NODE1_RX_DN")
	)
	(segment
		(start 94.09811 -143.096234)
		(end 94.759526 -143.99006)
		(width 0.127)
		(layer "B.Cu")
		(net "P2E_CPU_PCIE_SW_NODE1_RX_DN")
	)
	(segment
		(start 36.618926 -75.141836)
		(end 36.47059 -75.699112)
		(width 0.127)
		(layer "B.Cu")
		(net "P2E_CPU_PCIE_SW_NODE1_RX_DN")
	)
	(segment
		(start 66.37782 -103.757222)
		(end 67.29222 -103.757222)
		(width 0.127)
		(layer "B.Cu")
		(net "P2E_CPU_PCIE_SW_NODE1_RX_DN")
	)
	(segment
		(start 59.70016 -102.259892)
		(end 63.26886 -102.259892)
		(width 0.127)
		(layer "B.Cu")
		(net "P2E_CPU_PCIE_SW_NODE1_RX_DN")
	)
	(segment
		(start 94.759526 -143.99006)
		(end 99.010978 -145.31086)
		(width 0.127)
		(layer "B.Cu")
		(net "P2E_CPU_PCIE_SW_NODE1_RX_DN")
	)
	(segment
		(start 35.86734 -84.60105)
		(end 35.03168 -94.492572)
		(width 0.127)
		(layer "B.Cu")
		(net "P2E_CPU_PCIE_SW_NODE1_RX_DN")
	)
	(segment
		(start 36.032948 -77.337412)
		(end 35.970972 -77.568806)
		(width 0.127)
		(layer "B.Cu")
		(net "P2E_CPU_PCIE_SW_NODE1_RX_DN")
	)
	(segment
		(start 37.671248 -73.36917)
		(end 37.718238 -73.551796)
		(width 0.127)
		(layer "B.Cu")
		(net "P2E_CPU_PCIE_SW_NODE1_RX_DN")
	)
	(segment
		(start 42.9641 -70.78091)
		(end 41.875202 -71.25462)
		(width 0.127)
		(layer "B.Cu")
		(net "P2E_CPU_PCIE_SW_NODE1_RX_DN")
	)
	(segment
		(start 43.906694 -69.257418)
		(end 43.907202 -69.359272)
		(width 0.1016)
		(layer "B.Cu")
		(net "P2E_CPU_PCIE_SW_NODE1_RX_DN")
	)
	(segment
		(start 43.37812 -70.73011)
		(end 43.32732 -70.78091)
		(width 0.1016)
		(layer "B.Cu")
		(net "P2E_CPU_PCIE_SW_NODE1_RX_DN")
	)
	(segment
		(start 67.29222 -103.757222)
		(end 68.7451 -103.757222)
		(width 0.127)
		(layer "B.Cu")
		(net "P2E_CPU_PCIE_SW_NODE1_RX_DN")
	)
	(segment
		(start 71.728838 -103.77932)
		(end 77.649832 -103.662226)
		(width 0.127)
		(layer "B.Cu")
		(net "P2E_CPU_PCIE_SW_NODE1_RX_DN")
	)
	(segment
		(start 36.300664 -76.871322)
		(end 36.202112 -77.239876)
		(width 0.127)
		(layer "B.Cu")
		(net "P2E_CPU_PCIE_SW_NODE1_RX_DN")
	)
	(segment
		(start 37.718238 -73.551796)
		(end 37.523166 -73.879964)
		(width 0.127)
		(layer "B.Cu")
		(net "P2E_CPU_PCIE_SW_NODE1_RX_DN")
	)
	(segment
		(start 44.215812 -68.94449)
		(end 43.906694 -69.257418)
		(width 0.1016)
		(layer "B.Cu")
		(net "P2E_CPU_PCIE_SW_NODE1_RX_DN")
	)
	(segment
		(start 35.86734 -97.157032)
		(end 38.14826 -99.490784)
		(width 0.127)
		(layer "B.Cu")
		(net "P2E_CPU_PCIE_SW_NODE1_RX_DN")
	)
	(segment
		(start 92.594938 -121.70283)
		(end 92.20454 -132.630672)
		(width 0.127)
		(layer "B.Cu")
		(net "P2E_CPU_PCIE_SW_NODE1_RX_DN")
	)
	(segment
		(start 43.907202 -69.359272)
		(end 43.907202 -69.704204)
		(width 0.1016)
		(layer "B.Cu")
		(net "P2E_CPU_PCIE_SW_NODE1_RX_DN")
	)
	(segment
		(start 36.47059 -75.699112)
		(end 36.568888 -75.868022)
		(width 0.127)
		(layer "B.Cu")
		(net "P2E_CPU_PCIE_SW_NODE1_RX_DN")
	)
	(segment
		(start 91.65844 -118.855236)
		(end 92.60586 -121.397776)
		(width 0.127)
		(layer "B.Cu")
		(net "P2E_CPU_PCIE_SW_NODE1_RX_DN")
	)
	(segment
		(start 120.668542 -144.272508)
		(end 121.000774 -143.940276)
		(width 0.127)
		(layer "B.Cu")
		(net "P2E_CPU_PCIE_SW_NODE1_RX_DN")
	)
	(segment
		(start 35.03168 -94.492572)
		(end 35.86734 -97.157032)
		(width 0.127)
		(layer "B.Cu")
		(net "P2E_CPU_PCIE_SW_NODE1_RX_DN")
	)
	(segment
		(start 81.913984 -106.755184)
		(end 83.101434 -108.442506)
		(width 0.127)
		(layer "B.Cu")
		(net "P2E_CPU_PCIE_SW_NODE1_RX_DN")
	)
	(segment
		(start 43.843194 -70.73011)
		(end 43.37812 -70.73011)
		(width 0.1016)
		(layer "B.Cu")
		(net "P2E_CPU_PCIE_SW_NODE1_RX_DN")
	)
	(segment
		(start 92.20454 -132.630672)
		(end 92.150946 -140.46454)
		(width 0.127)
		(layer "B.Cu")
		(net "P2E_CPU_PCIE_SW_NODE1_RX_DN")
	)
	(segment
		(start 48.805846 -103.011986)
		(end 48.949864 -103.011986)
		(width 0.127)
		(layer "B.Cu")
		(net "P2E_CPU_PCIE_SW_NODE1_RX_DN")
	)
	(segment
		(start 38.14826 -99.490784)
		(end 40.13454 -101.232208)
		(width 0.127)
		(layer "B.Cu")
		(net "P2E_CPU_PCIE_SW_NODE1_RX_DN")
	)
	(segment
		(start 99.010978 -145.31086)
		(end 106.44886 -144.472406)
		(width 0.127)
		(layer "B.Cu")
		(net "P2E_CPU_PCIE_SW_NODE1_RX_DN")
	)
	(segment
		(start 40.16883 -71.36892)
		(end 40.16756 -71.36892)
		(width 0.127)
		(layer "B.Cu")
		(net "P2E_CPU_PCIE_SW_NODE1_RX_DN")
	)
	(segment
		(start 37.34054 -73.926446)
		(end 37.145468 -74.254868)
		(width 0.127)
		(layer "B.Cu")
		(net "P2E_CPU_PCIE_SW_NODE1_RX_DN")
	)
	(segment
		(start 36.301172 -76.334112)
		(end 36.20262 -76.702666)
		(width 0.127)
		(layer "B.Cu")
		(net "P2E_CPU_PCIE_SW_NODE1_RX_DN")
	)
	(segment
		(start 43.907202 -69.704204)
		(end 44.07916 -69.876162)
		(width 0.1016)
		(layer "B.Cu")
		(net "P2E_CPU_PCIE_SW_NODE1_RX_DN")
	)
	(segment
		(start 43.30192 -70.78091)
		(end 42.9641 -70.78091)
		(width 0.127)
		(layer "B.Cu")
		(net "P2E_CPU_PCIE_SW_NODE1_RX_DN")
	)
	(segment
		(start 43.32732 -70.78091)
		(end 43.30192 -70.78091)
		(width 0.1016)
		(layer "B.Cu")
		(net "P2E_CPU_PCIE_SW_NODE1_RX_DN")
	)
	(segment
		(start 64.39154 -102.242366)
		(end 65.013078 -102.574344)
		(width 0.127)
		(layer "B.Cu")
		(net "P2E_CPU_PCIE_SW_NODE1_RX_DN")
	)
	(segment
		(start 36.202112 -77.239876)
		(end 36.032948 -77.337412)
		(width 0.127)
		(layer "B.Cu")
		(net "P2E_CPU_PCIE_SW_NODE1_RX_DN")
	)
	(segment
		(start 77.649832 -103.662226)
		(end 79.855314 -105.46588)
		(width 0.127)
		(layer "B.Cu")
		(net "P2E_CPU_PCIE_SW_NODE1_RX_DN")
	)
	(segment
		(start 115.902232 -144.038828)
		(end 118.26875 -144.294352)
		(width 0.127)
		(layer "B.Cu")
		(net "P2E_CPU_PCIE_SW_NODE1_RX_DN")
	)
	(segment
		(start 93.907864 -142.545562)
		(end 94.13494 -142.85214)
		(width 0.127)
		(layer "B.Cu")
		(net "P2E_CPU_PCIE_SW_NODE1_RX_DN")
	)
	(segment
		(start 68.7451 -103.757222)
		(end 71.429372 -103.779066)
		(width 0.127)
		(layer "B.Cu")
		(net "P2E_CPU_PCIE_SW_NODE1_RX_DN")
	)
	(segment
		(start 40.13454 -101.232208)
		(end 45.2374 -101.806756)
		(width 0.127)
		(layer "B.Cu")
		(net "P2E_CPU_PCIE_SW_NODE1_RX_DN")
	)
	(segment
		(start 35.970972 -77.568806)
		(end 35.86734 -84.60105)
		(width 0.127)
		(layer "B.Cu")
		(net "P2E_CPU_PCIE_SW_NODE1_RX_DN")
	)
	(segment
		(start 83.101434 -108.442506)
		(end 83.590384 -109.343444)
		(width 0.127)
		(layer "B.Cu")
		(net "P2E_CPU_PCIE_SW_NODE1_RX_DN")
	)
	(segment
		(start 38.737032 -72.114918)
		(end 37.934646 -72.925686)
		(width 0.127)
		(layer "B.Cu")
		(net "P2E_CPU_PCIE_SW_NODE1_RX_DN")
	)
	(segment
		(start 91.61526 -114.014504)
		(end 91.65844 -118.855236)
		(width 0.127)
		(layer "B.Cu")
		(net "P2E_CPU_PCIE_SW_NODE1_RX_DN")
	)
	(segment
		(start 92.60586 -121.397776)
		(end 92.594938 -121.70283)
		(width 0.127)
		(layer "B.Cu")
		(net "P2E_CPU_PCIE_SW_NODE1_RX_DN")
	)
	(segment
		(start 37.934646 -72.925686)
		(end 37.671248 -73.36917)
		(width 0.127)
		(layer "B.Cu")
		(net "P2E_CPU_PCIE_SW_NODE1_RX_DN")
	)
	(segment
		(start 36.997386 -74.765408)
		(end 36.81476 -74.81189)
		(width 0.127)
		(layer "B.Cu")
		(net "P2E_CPU_PCIE_SW_NODE1_RX_DN")
	)
	(segment
		(start 71.726044 -103.77932)
		(end 71.728838 -103.77932)
		(width 0.127)
		(layer "B.Cu")
		(net "P2E_CPU_PCIE_SW_NODE1_RX_DN")
	)
	(segment
		(start 36.81476 -74.81189)
		(end 36.618926 -75.141836)
		(width 0.127)
		(layer "B.Cu")
		(net "P2E_CPU_PCIE_SW_NODE1_RX_DN")
	)
	(segment
		(start 48.949864 -103.011986)
		(end 50.618898 -103.262938)
		(width 0.127)
		(layer "B.Cu")
		(net "P2E_CPU_PCIE_SW_NODE1_RX_DN")
	)
	(segment
		(start 50.618898 -103.262938)
		(end 56.439562 -103.262938)
		(width 0.127)
		(layer "B.Cu")
		(net "P2E_CPU_PCIE_SW_NODE1_RX_DN")
	)
	(segment
		(start 36.20262 -76.702666)
		(end 36.300664 -76.871322)
		(width 0.127)
		(layer "B.Cu")
		(net "P2E_CPU_PCIE_SW_NODE1_RX_DN")
	)
	(segment
		(start 118.26875 -144.294352)
		(end 120.648222 -144.294352)
		(width 0.127)
		(layer "B.Cu")
		(net "P2E_CPU_PCIE_SW_NODE1_RX_DN")
	)
	(segment
		(start 83.590384 -109.343444)
		(end 84.393024 -109.541818)
		(width 0.127)
		(layer "B.Cu")
		(net "P2E_CPU_PCIE_SW_NODE1_RX_DN")
	)
	(segment
		(start 63.26886 -102.259892)
		(end 64.39154 -102.242366)
		(width 0.127)
		(layer "B.Cu")
		(net "P2E_CPU_PCIE_SW_NODE1_RX_DN")
	)
	(segment
		(start 37.145468 -74.254868)
		(end 37.192458 -74.43724)
		(width 0.127)
		(layer "B.Cu")
		(net "P2E_CPU_PCIE_SW_NODE1_RX_DN")
	)
	(segment
		(start 44.07916 -69.876162)
		(end 44.07916 -70.494144)
		(width 0.1016)
		(layer "B.Cu")
		(net "P2E_CPU_PCIE_SW_NODE1_RX_DN")
	)
	(segment
		(start 92.150946 -140.46454)
		(end 93.66377 -142.50924)
		(width 0.127)
		(layer "B.Cu")
		(net "P2E_CPU_PCIE_SW_NODE1_RX_DN")
	)
	(segment
		(start 86.64702 -109.516418)
		(end 89.57056 -109.934248)
		(width 0.127)
		(layer "B.Cu")
		(net "P2E_CPU_PCIE_SW_NODE1_RX_DN")
	)
	(segment
		(start 93.66377 -142.50924)
		(end 93.907864 -142.545562)
		(width 0.127)
		(layer "B.Cu")
		(net "P2E_CPU_PCIE_SW_NODE1_RX_DN")
	)
	(segment
		(start 44.07916 -70.494144)
		(end 43.843194 -70.73011)
		(width 0.1016)
		(layer "B.Cu")
		(net "P2E_CPU_PCIE_SW_NODE1_RX_DN")
	)
	(segment
		(start 79.855314 -105.46588)
		(end 81.913984 -106.755184)
		(width 0.127)
		(layer "B.Cu")
		(net "P2E_CPU_PCIE_SW_NODE1_RX_DN")
	)
	(segment
		(start 56.439562 -103.262938)
		(end 59.70016 -102.259892)
		(width 0.127)
		(layer "B.Cu")
		(net "P2E_CPU_PCIE_SW_NODE1_RX_DN")
	)
	(segment
		(start 65.013078 -102.574344)
		(end 66.37782 -103.757222)
		(width 0.127)
		(layer "B.Cu")
		(net "P2E_CPU_PCIE_SW_NODE1_RX_DN")
	)
	(segment
		(start 41.875202 -71.25462)
		(end 40.694356 -71.25462)
		(width 0.127)
		(layer "B.Cu")
		(net "P2E_CPU_PCIE_SW_NODE1_RX_DN")
	)
	(segment
		(start 36.568888 -75.868022)
		(end 36.470336 -76.236576)
		(width 0.127)
		(layer "B.Cu")
		(net "P2E_CPU_PCIE_SW_NODE1_RX_DN")
	)
	(segment
		(start 89.57056 -109.934248)
		(end 91.056714 -111.03483)
		(width 0.127)
		(layer "B.Cu")
		(net "P2E_CPU_PCIE_SW_NODE1_RX_DN")
	)
	(segment
		(start 71.429372 -103.779066)
		(end 71.726044 -103.77932)
		(width 0.127)
		(layer "B.Cu")
		(net "P2E_CPU_PCIE_SW_NODE1_RX_DN")
	)
	(segment
		(start 37.523166 -73.879964)
		(end 37.34054 -73.926446)
		(width 0.127)
		(layer "B.Cu")
		(net "P2E_CPU_PCIE_SW_NODE1_RX_DN")
	)
	(segment
		(start 37.192458 -74.43724)
		(end 36.997386 -74.765408)
		(width 0.127)
		(layer "B.Cu")
		(net "P2E_CPU_PCIE_SW_NODE1_RX_DN")
	)
	(segment
		(start 94.13494 -142.85214)
		(end 94.09811 -143.096234)
		(width 0.127)
		(layer "B.Cu")
		(net "P2E_CPU_PCIE_SW_NODE1_RX_DN")
	)
	(segment
		(start 40.694356 -71.25462)
		(end 40.16883 -71.36892)
		(width 0.127)
		(layer "B.Cu")
		(net "P2E_CPU_PCIE_SW_NODE1_RX_DN")
	)
	(segment
		(start 45.2374 -101.806756)
		(end 48.805846 -103.011986)
		(width 0.127)
		(layer "B.Cu")
		(net "P2E_CPU_PCIE_SW_NODE1_RX_DN")
	)
	(segment
		(start 91.056714 -111.03483)
		(end 91.61526 -114.014504)
		(width 0.127)
		(layer "B.Cu")
		(net "P2E_CPU_PCIE_SW_NODE1_RX_DN")
	)
	(segment
		(start 49.825402 -66.217038)
		(end 49.519078 -66.523362)
		(width 0.09906)
		(layer "F.Cu")
		(net "M_DDR3_NODE1_DQS0P")
	)
	(segment
		(start 43.49623 -30.504892)
		(end 43.650154 -30.350968)
		(width 0.1651)
		(layer "F.Cu")
		(net "M_DDR3_NODE1_DQS0P")
	)
	(segment
		(start 49.519078 -66.530982)
		(end 49.452022 -66.598038)
		(width 0.09906)
		(layer "F.Cu")
		(net "M_DDR3_NODE1_DQS0P")
	)
	(segment
		(start 43.49623 -30.846268)
		(end 43.49623 -30.504892)
		(width 0.1651)
		(layer "F.Cu")
		(net "M_DDR3_NODE1_DQS0P")
	)
	(segment
		(start 43.650154 -30.350968)
		(end 43.650154 -29.149802)
		(width 0.1651)
		(layer "F.Cu")
		(net "M_DDR3_NODE1_DQS0P")
	)
	(segment
		(start 43.98518 -31.335218)
		(end 43.49623 -30.846268)
		(width 0.1651)
		(layer "F.Cu")
		(net "M_DDR3_NODE1_DQS0P")
	)
	(segment
		(start 49.519078 -66.523362)
		(end 49.519078 -66.530982)
		(width 0.09906)
		(layer "F.Cu")
		(net "M_DDR3_NODE1_DQS0P")
	)
	(via
		(at 49.452022 -66.598038)
		(size 0.508)
		(drill 0.254)
		(layers "F.Cu" "B.Cu")
		(net "M_DDR3_NODE1_DQS0P")
	)
	(via
		(at 43.98518 -31.335218)
		(size 0.508)
		(drill 0.254)
		(layers "F.Cu" "B.Cu")
		(net "M_DDR3_NODE1_DQS0P")
	)
	(segment
		(start 41.191942 -55.458614)
		(end 41.191942 -55.94985)
		(width 0.2032)
		(layer "In7.Cu")
		(net "M_DDR3_NODE1_DQS0P")
	)
	(segment
		(start 34.97072 -52.671726)
		(end 35.895534 -53.59654)
		(width 0.2032)
		(layer "In7.Cu")
		(net "M_DDR3_NODE1_DQS0P")
	)
	(segment
		(start 36.701984 -38.13175)
		(end 36.701984 -38.436042)
		(width 0.2032)
		(layer "In7.Cu")
		(net "M_DDR3_NODE1_DQS0P")
	)
	(segment
		(start 37.882068 -38.573202)
		(end 37.882068 -37.99459)
		(width 0.2032)
		(layer "In7.Cu")
		(net "M_DDR3_NODE1_DQS0P")
	)
	(segment
		(start 36.580318 -40.840152)
		(end 34.97072 -42.44975)
		(width 0.2032)
		(layer "In7.Cu")
		(net "M_DDR3_NODE1_DQS0P")
	)
	(segment
		(start 44.468034 -58.697114)
		(end 44.486322 -58.715402)
		(width 0.09906)
		(layer "In7.Cu")
		(net "M_DDR3_NODE1_DQS0P")
	)
	(segment
		(start 43.98518 -31.335218)
		(end 43.51528 -31.805118)
		(width 0.2032)
		(layer "In7.Cu")
		(net "M_DDR3_NODE1_DQS0P")
	)
	(segment
		(start 44.24934 -58.47842)
		(end 44.468034 -58.697114)
		(width 0.2032)
		(layer "In7.Cu")
		(net "M_DDR3_NODE1_DQS0P")
	)
	(segment
		(start 37.882068 -37.99459)
		(end 41.39311 -34.483548)
		(width 0.2032)
		(layer "In7.Cu")
		(net "M_DDR3_NODE1_DQS0P")
	)
	(segment
		(start 38.457124 -56.15813)
		(end 39.612062 -56.15813)
		(width 0.2032)
		(layer "In7.Cu")
		(net "M_DDR3_NODE1_DQS0P")
	)
	(segment
		(start 45.974508 -60.293504)
		(end 47.015908 -60.293504)
		(width 0.09906)
		(layer "In7.Cu")
		(net "M_DDR3_NODE1_DQS0P")
	)
	(segment
		(start 37.012626 -40.840152)
		(end 36.580318 -40.840152)
		(width 0.2032)
		(layer "In7.Cu")
		(net "M_DDR3_NODE1_DQS0P")
	)
	(segment
		(start 36.189666 -53.59654)
		(end 36.547044 -53.239162)
		(width 0.2032)
		(layer "In7.Cu")
		(net "M_DDR3_NODE1_DQS0P")
	)
	(segment
		(start 39.820342 -55.458614)
		(end 40.166036 -55.11292)
		(width 0.2032)
		(layer "In7.Cu")
		(net "M_DDR3_NODE1_DQS0P")
	)
	(segment
		(start 48.512984 -63.167514)
		(end 50.118264 -64.772794)
		(width 0.09906)
		(layer "In7.Cu")
		(net "M_DDR3_NODE1_DQS0P")
	)
	(segment
		(start 41.400222 -56.15813)
		(end 42.415206 -56.15813)
		(width 0.2032)
		(layer "In7.Cu")
		(net "M_DDR3_NODE1_DQS0P")
	)
	(segment
		(start 40.166036 -55.11292)
		(end 40.846248 -55.11292)
		(width 0.2032)
		(layer "In7.Cu")
		(net "M_DDR3_NODE1_DQS0P")
	)
	(segment
		(start 50.118264 -64.772794)
		(end 50.118264 -66.15557)
		(width 0.09906)
		(layer "In7.Cu")
		(net "M_DDR3_NODE1_DQS0P")
	)
	(segment
		(start 41.39311 -34.179256)
		(end 41.17594 -33.962086)
		(width 0.2032)
		(layer "In7.Cu")
		(net "M_DDR3_NODE1_DQS0P")
	)
	(segment
		(start 34.97072 -42.44975)
		(end 34.97072 -52.671726)
		(width 0.2032)
		(layer "In7.Cu")
		(net "M_DDR3_NODE1_DQS0P")
	)
	(segment
		(start 43.51528 -31.805118)
		(end 43.51528 -32.089852)
		(width 0.2032)
		(layer "In7.Cu")
		(net "M_DDR3_NODE1_DQS0P")
	)
	(segment
		(start 40.871648 -33.962086)
		(end 36.701984 -38.13175)
		(width 0.2032)
		(layer "In7.Cu")
		(net "M_DDR3_NODE1_DQS0P")
	)
	(segment
		(start 38.870128 -38.98265)
		(end 38.291516 -38.98265)
		(width 0.2032)
		(layer "In7.Cu")
		(net "M_DDR3_NODE1_DQS0P")
	)
	(segment
		(start 47.015908 -60.293504)
		(end 47.46498 -60.742576)
		(width 0.09906)
		(layer "In7.Cu")
		(net "M_DDR3_NODE1_DQS0P")
	)
	(segment
		(start 44.486322 -58.805318)
		(end 45.974508 -60.293504)
		(width 0.09906)
		(layer "In7.Cu")
		(net "M_DDR3_NODE1_DQS0P")
	)
	(segment
		(start 48.512984 -62.985904)
		(end 48.512984 -63.167514)
		(width 0.09906)
		(layer "In7.Cu")
		(net "M_DDR3_NODE1_DQS0P")
	)
	(segment
		(start 37.770054 -39.504112)
		(end 37.770054 -40.082724)
		(width 0.2032)
		(layer "In7.Cu")
		(net "M_DDR3_NODE1_DQS0P")
	)
	(segment
		(start 44.16044 -33.692338)
		(end 38.870128 -38.98265)
		(width 0.2032)
		(layer "In7.Cu")
		(net "M_DDR3_NODE1_DQS0P")
	)
	(segment
		(start 49.94148 -66.332354)
		(end 49.717706 -66.332354)
		(width 0.09906)
		(layer "In7.Cu")
		(net "M_DDR3_NODE1_DQS0P")
	)
	(segment
		(start 42.415206 -56.15813)
		(end 44.24934 -57.992264)
		(width 0.2032)
		(layer "In7.Cu")
		(net "M_DDR3_NODE1_DQS0P")
	)
	(segment
		(start 47.46498 -60.742576)
		(end 47.46498 -61.9379)
		(width 0.09906)
		(layer "In7.Cu")
		(net "M_DDR3_NODE1_DQS0P")
	)
	(segment
		(start 38.291516 -38.98265)
		(end 37.882068 -38.573202)
		(width 0.2032)
		(layer "In7.Cu")
		(net "M_DDR3_NODE1_DQS0P")
	)
	(segment
		(start 43.51528 -32.089852)
		(end 44.16044 -32.735012)
		(width 0.2032)
		(layer "In7.Cu")
		(net "M_DDR3_NODE1_DQS0P")
	)
	(segment
		(start 35.895534 -53.59654)
		(end 36.189666 -53.59654)
		(width 0.2032)
		(layer "In7.Cu")
		(net "M_DDR3_NODE1_DQS0P")
	)
	(segment
		(start 41.17594 -33.962086)
		(end 40.871648 -33.962086)
		(width 0.2032)
		(layer "In7.Cu")
		(net "M_DDR3_NODE1_DQS0P")
	)
	(segment
		(start 37.51707 -53.640736)
		(end 37.51707 -54.209188)
		(width 0.2032)
		(layer "In7.Cu")
		(net "M_DDR3_NODE1_DQS0P")
	)
	(segment
		(start 47.46498 -61.9379)
		(end 48.512984 -62.985904)
		(width 0.09906)
		(layer "In7.Cu")
		(net "M_DDR3_NODE1_DQS0P")
	)
	(segment
		(start 41.39311 -34.483548)
		(end 41.39311 -34.179256)
		(width 0.2032)
		(layer "In7.Cu")
		(net "M_DDR3_NODE1_DQS0P")
	)
	(segment
		(start 37.51707 -54.209188)
		(end 37.159692 -54.566566)
		(width 0.2032)
		(layer "In7.Cu")
		(net "M_DDR3_NODE1_DQS0P")
	)
	(segment
		(start 37.159692 -54.860698)
		(end 38.457124 -56.15813)
		(width 0.2032)
		(layer "In7.Cu")
		(net "M_DDR3_NODE1_DQS0P")
	)
	(segment
		(start 44.486322 -58.715402)
		(end 44.486322 -58.805318)
		(width 0.09906)
		(layer "In7.Cu")
		(net "M_DDR3_NODE1_DQS0P")
	)
	(segment
		(start 36.701984 -38.436042)
		(end 37.770054 -39.504112)
		(width 0.2032)
		(layer "In7.Cu")
		(net "M_DDR3_NODE1_DQS0P")
	)
	(segment
		(start 50.118264 -66.15557)
		(end 49.94148 -66.332354)
		(width 0.09906)
		(layer "In7.Cu")
		(net "M_DDR3_NODE1_DQS0P")
	)
	(segment
		(start 39.612062 -56.15813)
		(end 39.820342 -55.94985)
		(width 0.2032)
		(layer "In7.Cu")
		(net "M_DDR3_NODE1_DQS0P")
	)
	(segment
		(start 36.547044 -53.239162)
		(end 37.115496 -53.239162)
		(width 0.2032)
		(layer "In7.Cu")
		(net "M_DDR3_NODE1_DQS0P")
	)
	(segment
		(start 44.24934 -57.992264)
		(end 44.24934 -58.47842)
		(width 0.2032)
		(layer "In7.Cu")
		(net "M_DDR3_NODE1_DQS0P")
	)
	(segment
		(start 37.770054 -40.082724)
		(end 37.012626 -40.840152)
		(width 0.2032)
		(layer "In7.Cu")
		(net "M_DDR3_NODE1_DQS0P")
	)
	(segment
		(start 49.717706 -66.332354)
		(end 49.452022 -66.598038)
		(width 0.09906)
		(layer "In7.Cu")
		(net "M_DDR3_NODE1_DQS0P")
	)
	(segment
		(start 37.159692 -54.566566)
		(end 37.159692 -54.860698)
		(width 0.2032)
		(layer "In7.Cu")
		(net "M_DDR3_NODE1_DQS0P")
	)
	(segment
		(start 37.115496 -53.239162)
		(end 37.51707 -53.640736)
		(width 0.2032)
		(layer "In7.Cu")
		(net "M_DDR3_NODE1_DQS0P")
	)
	(segment
		(start 40.846248 -55.11292)
		(end 41.191942 -55.458614)
		(width 0.2032)
		(layer "In7.Cu")
		(net "M_DDR3_NODE1_DQS0P")
	)
	(segment
		(start 39.820342 -55.94985)
		(end 39.820342 -55.458614)
		(width 0.2032)
		(layer "In7.Cu")
		(net "M_DDR3_NODE1_DQS0P")
	)
	(segment
		(start 41.191942 -55.94985)
		(end 41.400222 -56.15813)
		(width 0.2032)
		(layer "In7.Cu")
		(net "M_DDR3_NODE1_DQS0P")
	)
	(segment
		(start 44.16044 -32.735012)
		(end 44.16044 -33.692338)
		(width 0.2032)
		(layer "In7.Cu")
		(net "M_DDR3_NODE1_DQS0P")
	)
	(segment
		(start 94.83852 -136.238488)
		(end 94.83852 -137.122916)
		(width 0.2032)
		(layer "F.Cu")
		(net "P1V05_SUS_NODE1_ADJ")
	)
	(segment
		(start 94.83852 -137.122916)
		(end 94.720918 -137.240518)
		(width 0.2032)
		(layer "F.Cu")
		(net "P1V05_SUS_NODE1_ADJ")
	)
	(via
		(at 94.058486 -139.781788)
		(size 0.508)
		(drill 0.254)
		(layers "F.Cu" "B.Cu")
		(net "P1V05_SUS_NODE1_ADJ")
	)
	(segment
		(start 63.832486 -121.837958)
		(end 64.78397 -122.789442)
		(width 0.1016)
		(layer "F.Cu")
		(net "BMC_ROMA11")
	)
	(segment
		(start 65.341754 -126.16053)
		(end 64.78397 -125.602746)
		(width 0.1016)
		(layer "F.Cu")
		(net "BMC_ROMA11")
	)
	(segment
		(start 63.832486 -121.444512)
		(end 63.832486 -121.837958)
		(width 0.1016)
		(layer "F.Cu")
		(net "BMC_ROMA11")
	)
	(segment
		(start 64.78397 -125.602746)
		(end 64.78397 -122.84329)
		(width 0.1016)
		(layer "F.Cu")
		(net "BMC_ROMA11")
	)
	(segment
		(start 64.78397 -122.789442)
		(end 64.78397 -122.84329)
		(width 0.1016)
		(layer "F.Cu")
		(net "BMC_ROMA11")
	)
	(segment
		(start 65.341754 -126.459488)
		(end 65.341754 -126.16053)
		(width 0.1016)
		(layer "F.Cu")
		(net "BMC_ROMA11")
	)
	(via
		(at 64.78397 -122.84329)
		(size 0.762)
		(drill 0.381)
		(layers "F.Cu" "B.Cu")
		(net "BMC_ROMA11")
	)
	(segment
		(start 69.70395 -93.345254)
		(end 71.010526 -94.65183)
		(width 0.1016)
		(layer "F.Cu")
		(net "H_CPU_NODE1_ERR0_R")
	)
	(segment
		(start 65.994788 -86.50605)
		(end 65.994788 -87.054182)
		(width 0.1016)
		(layer "F.Cu")
		(net "H_CPU_NODE1_ERR0_R")
	)
	(segment
		(start 65.845436 -85.968078)
		(end 65.845436 -86.356698)
		(width 0.1016)
		(layer "F.Cu")
		(net "H_CPU_NODE1_ERR0_R")
	)
	(segment
		(start 65.475866 -85.598508)
		(end 65.845436 -85.968078)
		(width 0.1016)
		(layer "F.Cu")
		(net "H_CPU_NODE1_ERR0_R")
	)
	(segment
		(start 71.359776 -94.65183)
		(end 71.4883 -94.780354)
		(width 0.1016)
		(layer "F.Cu")
		(net "H_CPU_NODE1_ERR0_R")
	)
	(segment
		(start 71.713344 -95.575882)
		(end 71.713344 -95.005398)
		(width 0.1016)
		(layer "F.Cu")
		(net "H_CPU_NODE1_ERR0_R")
	)
	(segment
		(start 72.321166 -96.309942)
		(end 72.321166 -96.183704)
		(width 0.1016)
		(layer "F.Cu")
		(net "H_CPU_NODE1_ERR0_R")
	)
	(segment
		(start 67.785996 -92.550742)
		(end 68.580508 -93.345254)
		(width 0.1016)
		(layer "F.Cu")
		(net "H_CPU_NODE1_ERR0_R")
	)
	(segment
		(start 66.420492 -90.775536)
		(end 67.785996 -92.14104)
		(width 0.1016)
		(layer "F.Cu")
		(net "H_CPU_NODE1_ERR0_R")
	)
	(segment
		(start 66.448432 -88.4428)
		(end 66.448432 -88.767412)
		(width 0.1016)
		(layer "F.Cu")
		(net "H_CPU_NODE1_ERR0_R")
	)
	(segment
		(start 65.918588 -87.727028)
		(end 66.104516 -87.912956)
		(width 0.1016)
		(layer "F.Cu")
		(net "H_CPU_NODE1_ERR0_R")
	)
	(segment
		(start 72.321166 -96.183704)
		(end 71.713344 -95.575882)
		(width 0.1016)
		(layer "F.Cu")
		(net "H_CPU_NODE1_ERR0_R")
	)
	(segment
		(start 66.448432 -88.767412)
		(end 66.420492 -88.795352)
		(width 0.1016)
		(layer "F.Cu")
		(net "H_CPU_NODE1_ERR0_R")
	)
	(segment
		(start 66.104516 -88.098884)
		(end 66.448432 -88.4428)
		(width 0.1016)
		(layer "F.Cu")
		(net "H_CPU_NODE1_ERR0_R")
	)
	(segment
		(start 65.845436 -86.356698)
		(end 65.994788 -86.50605)
		(width 0.1016)
		(layer "F.Cu")
		(net "H_CPU_NODE1_ERR0_R")
	)
	(segment
		(start 65.475866 -85.381846)
		(end 65.475866 -85.598508)
		(width 0.1016)
		(layer "F.Cu")
		(net "H_CPU_NODE1_ERR0_R")
	)
	(segment
		(start 66.420492 -88.795352)
		(end 66.420492 -90.775536)
		(width 0.1016)
		(layer "F.Cu")
		(net "H_CPU_NODE1_ERR0_R")
	)
	(segment
		(start 65.918588 -87.130382)
		(end 65.918588 -87.727028)
		(width 0.1016)
		(layer "F.Cu")
		(net "H_CPU_NODE1_ERR0_R")
	)
	(segment
		(start 66.104516 -87.912956)
		(end 66.104516 -88.098884)
		(width 0.1016)
		(layer "F.Cu")
		(net "H_CPU_NODE1_ERR0_R")
	)
	(segment
		(start 71.713344 -95.005398)
		(end 71.4883 -94.780354)
		(width 0.1016)
		(layer "F.Cu")
		(net "H_CPU_NODE1_ERR0_R")
	)
	(segment
		(start 67.785996 -92.14104)
		(end 67.785996 -92.550742)
		(width 0.1016)
		(layer "F.Cu")
		(net "H_CPU_NODE1_ERR0_R")
	)
	(segment
		(start 68.580508 -93.345254)
		(end 69.70395 -93.345254)
		(width 0.1016)
		(layer "F.Cu")
		(net "H_CPU_NODE1_ERR0_R")
	)
	(segment
		(start 71.010526 -94.65183)
		(end 71.359776 -94.65183)
		(width 0.1016)
		(layer "F.Cu")
		(net "H_CPU_NODE1_ERR0_R")
	)
	(segment
		(start 65.994788 -87.054182)
		(end 65.918588 -87.130382)
		(width 0.1016)
		(layer "F.Cu")
		(net "H_CPU_NODE1_ERR0_R")
	)
	(via
		(at 71.4883 -94.780354)
		(size 0.508)
		(drill 0.254)
		(layers "F.Cu" "B.Cu")
		(net "H_CPU_NODE1_ERR0_R")
	)
	(segment
		(start 72.008492 -93.320108)
		(end 71.4883 -93.8403)
		(width 0.1016)
		(layer "B.Cu")
		(net "H_CPU_NODE1_ERR0_R")
	)
	(segment
		(start 71.4883 -93.8403)
		(end 71.4883 -94.780354)
		(width 0.1016)
		(layer "B.Cu")
		(net "H_CPU_NODE1_ERR0_R")
	)
	(segment
		(start 65.405508 -47.804324)
		(end 65.100708 -47.804324)
		(width 0.2286)
		(layer "F.Cu")
		(net "M_DDR3_NODE1_MA7")
	)
	(segment
		(start 59.8932 -54.8259)
		(end 59.8932 -59.096656)
		(width 0.2286)
		(layer "F.Cu")
		(net "M_DDR3_NODE1_MA7")
	)
	(segment
		(start 67.929506 -44.238418)
		(end 68.173346 -44.238418)
		(width 0.2286)
		(layer "F.Cu")
		(net "M_DDR3_NODE1_MA7")
	)
	(segment
		(start 71.2978 -38.332664)
		(end 71.082154 -38.117018)
		(width 0.2286)
		(layer "F.Cu")
		(net "M_DDR3_NODE1_MA7")
	)
	(segment
		(start 71.0184 -34.142426)
		(end 71.666862 -33.493964)
		(width 0.2286)
		(layer "F.Cu")
		(net "M_DDR3_NODE1_MA7")
	)
	(segment
		(start 71.2978 -40.111172)
		(end 71.2978 -39.805864)
		(width 0.2286)
		(layer "F.Cu")
		(net "M_DDR3_NODE1_MA7")
	)
	(segment
		(start 68.323968 -45.622464)
		(end 68.108322 -45.406818)
		(width 0.2286)
		(layer "F.Cu")
		(net "M_DDR3_NODE1_MA7")
	)
	(segment
		(start 67.104006 -48.494442)
		(end 67.32016 -48.710596)
		(width 0.2286)
		(layer "F.Cu")
		(net "M_DDR3_NODE1_MA7")
	)
	(segment
		(start 58.78322 -63.580264)
		(end 58.78322 -64.04737)
		(width 0.1016)
		(layer "F.Cu")
		(net "M_DDR3_NODE1_MA7")
	)
	(segment
		(start 69.461888 -45.83176)
		(end 67.104006 -48.189642)
		(width 0.2286)
		(layer "F.Cu")
		(net "M_DDR3_NODE1_MA7")
	)
	(segment
		(start 70.635622 -40.542464)
		(end 70.851268 -40.326818)
		(width 0.2286)
		(layer "F.Cu")
		(net "M_DDR3_NODE1_MA7")
	)
	(segment
		(start 70.635622 -39.374572)
		(end 70.635622 -39.069264)
		(width 0.2286)
		(layer "F.Cu")
		(net "M_DDR3_NODE1_MA7")
	)
	(segment
		(start 71.2978 -39.805864)
		(end 71.082154 -39.590218)
		(width 0.2286)
		(layer "F.Cu")
		(net "M_DDR3_NODE1_MA7")
	)
	(segment
		(start 67.62496 -48.710596)
		(end 70.503796 -45.83176)
		(width 0.2286)
		(layer "F.Cu")
		(net "M_DDR3_NODE1_MA7")
	)
	(segment
		(start 71.85025 -30.80639)
		(end 71.85025 -29.149802)
		(width 0.2286)
		(layer "F.Cu")
		(net "M_DDR3_NODE1_MA7")
	)
	(segment
		(start 64.884554 -47.28337)
		(end 67.929506 -44.238418)
		(width 0.2286)
		(layer "F.Cu")
		(net "M_DDR3_NODE1_MA7")
	)
	(segment
		(start 70.635622 -37.901372)
		(end 70.635622 -37.42309)
		(width 0.2286)
		(layer "F.Cu")
		(net "M_DDR3_NODE1_MA7")
	)
	(segment
		(start 65.167002 -48.729138)
		(end 65.522602 -48.729138)
		(width 0.2286)
		(layer "F.Cu")
		(net "M_DDR3_NODE1_MA7")
	)
	(segment
		(start 68.108322 -45.406818)
		(end 67.803014 -45.406818)
		(width 0.2286)
		(layer "F.Cu")
		(net "M_DDR3_NODE1_MA7")
	)
	(segment
		(start 64.933322 -48.962818)
		(end 65.167002 -48.729138)
		(width 0.2286)
		(layer "F.Cu")
		(net "M_DDR3_NODE1_MA7")
	)
	(segment
		(start 70.851268 -39.590218)
		(end 70.635622 -39.374572)
		(width 0.2286)
		(layer "F.Cu")
		(net "M_DDR3_NODE1_MA7")
	)
	(segment
		(start 59.48172 -61.270642)
		(end 59.48172 -62.135004)
		(width 0.1016)
		(layer "F.Cu")
		(net "M_DDR3_NODE1_MA7")
	)
	(segment
		(start 67.803014 -45.406818)
		(end 65.405508 -47.804324)
		(width 0.2286)
		(layer "F.Cu")
		(net "M_DDR3_NODE1_MA7")
	)
	(segment
		(start 59.237626 -63.125858)
		(end 58.78322 -63.580264)
		(width 0.1016)
		(layer "F.Cu")
		(net "M_DDR3_NODE1_MA7")
	)
	(segment
		(start 70.851268 -38.117018)
		(end 70.635622 -37.901372)
		(width 0.2286)
		(layer "F.Cu")
		(net "M_DDR3_NODE1_MA7")
	)
	(segment
		(start 63.6016 -50.270156)
		(end 63.6016 -51.1175)
		(width 0.2286)
		(layer "F.Cu")
		(net "M_DDR3_NODE1_MA7")
	)
	(segment
		(start 69.766688 -44.789852)
		(end 69.766688 -44.485052)
		(width 0.2286)
		(layer "F.Cu")
		(net "M_DDR3_NODE1_MA7")
	)
	(segment
		(start 70.635622 -37.42309)
		(end 71.0184 -37.040312)
		(width 0.2286)
		(layer "F.Cu")
		(net "M_DDR3_NODE1_MA7")
	)
	(segment
		(start 59.8932 -60.859162)
		(end 59.48172 -61.270642)
		(width 0.1016)
		(layer "F.Cu")
		(net "M_DDR3_NODE1_MA7")
	)
	(segment
		(start 71.082154 -38.853618)
		(end 71.2978 -38.637972)
		(width 0.2286)
		(layer "F.Cu")
		(net "M_DDR3_NODE1_MA7")
	)
	(segment
		(start 69.461888 -45.52696)
		(end 69.461888 -45.83176)
		(width 0.2286)
		(layer "F.Cu")
		(net "M_DDR3_NODE1_MA7")
	)
	(segment
		(start 71.082154 -38.117018)
		(end 70.851268 -38.117018)
		(width 0.2286)
		(layer "F.Cu")
		(net "M_DDR3_NODE1_MA7")
	)
	(segment
		(start 71.082154 -40.326818)
		(end 71.2978 -40.111172)
		(width 0.2286)
		(layer "F.Cu")
		(net "M_DDR3_NODE1_MA7")
	)
	(segment
		(start 70.635622 -39.069264)
		(end 70.851268 -38.853618)
		(width 0.2286)
		(layer "F.Cu")
		(net "M_DDR3_NODE1_MA7")
	)
	(segment
		(start 70.851268 -40.326818)
		(end 71.082154 -40.326818)
		(width 0.2286)
		(layer "F.Cu")
		(net "M_DDR3_NODE1_MA7")
	)
	(segment
		(start 70.851268 -38.853618)
		(end 71.082154 -38.853618)
		(width 0.2286)
		(layer "F.Cu")
		(net "M_DDR3_NODE1_MA7")
	)
	(segment
		(start 71.2978 -38.637972)
		(end 71.2978 -38.332664)
		(width 0.2286)
		(layer "F.Cu")
		(net "M_DDR3_NODE1_MA7")
	)
	(segment
		(start 71.0184 -37.040312)
		(end 71.0184 -34.142426)
		(width 0.2286)
		(layer "F.Cu")
		(net "M_DDR3_NODE1_MA7")
	)
	(segment
		(start 67.104006 -48.189642)
		(end 67.104006 -48.494442)
		(width 0.2286)
		(layer "F.Cu")
		(net "M_DDR3_NODE1_MA7")
	)
	(segment
		(start 70.635622 -43.616118)
		(end 70.635622 -40.542464)
		(width 0.2286)
		(layer "F.Cu")
		(net "M_DDR3_NODE1_MA7")
	)
	(segment
		(start 64.908938 -48.962818)
		(end 63.6016 -50.270156)
		(width 0.2286)
		(layer "F.Cu")
		(net "M_DDR3_NODE1_MA7")
	)
	(segment
		(start 69.766688 -44.485052)
		(end 70.635622 -43.616118)
		(width 0.2286)
		(layer "F.Cu")
		(net "M_DDR3_NODE1_MA7")
	)
	(segment
		(start 71.666862 -33.493964)
		(end 71.666862 -30.989778)
		(width 0.2286)
		(layer "F.Cu")
		(net "M_DDR3_NODE1_MA7")
	)
	(segment
		(start 71.082154 -39.590218)
		(end 70.851268 -39.590218)
		(width 0.2286)
		(layer "F.Cu")
		(net "M_DDR3_NODE1_MA7")
	)
	(segment
		(start 65.522602 -48.729138)
		(end 68.323968 -45.927772)
		(width 0.2286)
		(layer "F.Cu")
		(net "M_DDR3_NODE1_MA7")
	)
	(segment
		(start 64.933322 -48.962818)
		(end 64.908938 -48.962818)
		(width 0.2286)
		(layer "F.Cu")
		(net "M_DDR3_NODE1_MA7")
	)
	(segment
		(start 64.884554 -47.58817)
		(end 64.884554 -47.28337)
		(width 0.2286)
		(layer "F.Cu")
		(net "M_DDR3_NODE1_MA7")
	)
	(segment
		(start 59.237626 -62.379098)
		(end 59.237626 -63.125858)
		(width 0.1016)
		(layer "F.Cu")
		(net "M_DDR3_NODE1_MA7")
	)
	(segment
		(start 59.48172 -62.135004)
		(end 59.237626 -62.379098)
		(width 0.1016)
		(layer "F.Cu")
		(net "M_DDR3_NODE1_MA7")
	)
	(segment
		(start 68.173346 -44.238418)
		(end 69.461888 -45.52696)
		(width 0.2286)
		(layer "F.Cu")
		(net "M_DDR3_NODE1_MA7")
	)
	(segment
		(start 65.100708 -47.804324)
		(end 64.884554 -47.58817)
		(width 0.2286)
		(layer "F.Cu")
		(net "M_DDR3_NODE1_MA7")
	)
	(segment
		(start 63.6016 -51.1175)
		(end 59.8932 -54.8259)
		(width 0.2286)
		(layer "F.Cu")
		(net "M_DDR3_NODE1_MA7")
	)
	(segment
		(start 68.323968 -45.927772)
		(end 68.323968 -45.622464)
		(width 0.2286)
		(layer "F.Cu")
		(net "M_DDR3_NODE1_MA7")
	)
	(segment
		(start 59.8932 -59.096656)
		(end 59.8932 -60.859162)
		(width 0.1016)
		(layer "F.Cu")
		(net "M_DDR3_NODE1_MA7")
	)
	(segment
		(start 71.666862 -30.989778)
		(end 71.85025 -30.80639)
		(width 0.2286)
		(layer "F.Cu")
		(net "M_DDR3_NODE1_MA7")
	)
	(segment
		(start 58.78322 -64.04737)
		(end 58.783728 -64.047878)
		(width 0.1016)
		(layer "F.Cu")
		(net "M_DDR3_NODE1_MA7")
	)
	(segment
		(start 67.32016 -48.710596)
		(end 67.62496 -48.710596)
		(width 0.2286)
		(layer "F.Cu")
		(net "M_DDR3_NODE1_MA7")
	)
	(segment
		(start 70.503796 -45.52696)
		(end 69.766688 -44.789852)
		(width 0.2286)
		(layer "F.Cu")
		(net "M_DDR3_NODE1_MA7")
	)
	(segment
		(start 70.503796 -45.83176)
		(end 70.503796 -45.52696)
		(width 0.2286)
		(layer "F.Cu")
		(net "M_DDR3_NODE1_MA7")
	)
	(via
		(at 64.933322 -48.962818)
		(size 0.762)
		(drill 0.381)
		(layers "F.Cu" "B.Cu")
		(net "M_DDR3_NODE1_MA7")
	)
	(via
		(at 96.452182 -139.545568)
		(size 0.508)
		(drill 0.254)
		(layers "F.Cu" "B.Cu")
		(net "P1V05_SUS_NODE1_ADJ_S")
	)
	(segment
		(start 61.436504 -125.93828)
		(end 61.764164 -126.26594)
		(width 0.1016)
		(layer "F.Cu")
		(net "BMC_ROMD1")
	)
	(segment
		(start 61.013086 -125.261624)
		(end 61.436504 -125.685042)
		(width 0.1016)
		(layer "F.Cu")
		(net "BMC_ROMD1")
	)
	(segment
		(start 61.436504 -125.685042)
		(end 61.436504 -125.93828)
		(width 0.1016)
		(layer "F.Cu")
		(net "BMC_ROMD1")
	)
	(segment
		(start 61.013086 -124.524262)
		(end 61.013086 -125.261624)
		(width 0.1016)
		(layer "F.Cu")
		(net "BMC_ROMD1")
	)
	(segment
		(start 59.260486 -118.510812)
		(end 59.260486 -117.967506)
		(width 0.1016)
		(layer "F.Cu")
		(net "BMC_ROMD1")
	)
	(segment
		(start 58.791094 -117.498114)
		(end 58.574686 -117.714522)
		(width 0.1016)
		(layer "F.Cu")
		(net "BMC_ROMD1")
	)
	(segment
		(start 59.260486 -117.967506)
		(end 58.791094 -117.498114)
		(width 0.1016)
		(layer "F.Cu")
		(net "BMC_ROMD1")
	)
	(segment
		(start 61.764164 -126.26594)
		(end 61.764164 -126.88189)
		(width 0.1016)
		(layer "F.Cu")
		(net "BMC_ROMD1")
	)
	(segment
		(start 61.764164 -126.88189)
		(end 62.141862 -127.259588)
		(width 0.1016)
		(layer "F.Cu")
		(net "BMC_ROMD1")
	)
	(segment
		(start 58.574686 -117.714522)
		(end 58.574686 -122.085862)
		(width 0.1016)
		(layer "F.Cu")
		(net "BMC_ROMD1")
	)
	(segment
		(start 58.574686 -122.085862)
		(end 61.013086 -124.524262)
		(width 0.1016)
		(layer "F.Cu")
		(net "BMC_ROMD1")
	)
	(via
		(at 58.791094 -117.498114)
		(size 0.508)
		(drill 0.254)
		(layers "F.Cu" "B.Cu")
		(net "BMC_ROMD1")
	)
	(segment
		(start 64.950086 -20.94992)
		(end 64.950086 -22.151086)
		(width 0.1651)
		(layer "F.Cu")
		(net "M_DDR3_NODE1_DQSECCN")
	)
	(segment
		(start 65.715642 -66.209418)
		(end 65.342262 -65.836038)
		(width 0.09906)
		(layer "F.Cu")
		(net "M_DDR3_NODE1_DQSECCN")
	)
	(segment
		(start 64.741044 -22.920198)
		(end 64.024764 -22.920198)
		(width 0.1651)
		(layer "F.Cu")
		(net "M_DDR3_NODE1_DQSECCN")
	)
	(segment
		(start 65.10401 -22.557232)
		(end 64.741044 -22.920198)
		(width 0.1651)
		(layer "F.Cu")
		(net "M_DDR3_NODE1_DQSECCN")
	)
	(segment
		(start 65.715642 -66.217038)
		(end 65.715642 -66.209418)
		(width 0.09906)
		(layer "F.Cu")
		(net "M_DDR3_NODE1_DQSECCN")
	)
	(segment
		(start 64.024764 -22.920198)
		(end 63.625222 -23.31974)
		(width 0.1651)
		(layer "F.Cu")
		(net "M_DDR3_NODE1_DQSECCN")
	)
	(segment
		(start 63.625222 -23.648162)
		(end 63.133732 -24.139652)
		(width 0.1651)
		(layer "F.Cu")
		(net "M_DDR3_NODE1_DQSECCN")
	)
	(segment
		(start 64.950086 -22.151086)
		(end 65.10401 -22.30501)
		(width 0.1651)
		(layer "F.Cu")
		(net "M_DDR3_NODE1_DQSECCN")
	)
	(segment
		(start 65.10401 -22.30501)
		(end 65.10401 -22.557232)
		(width 0.1651)
		(layer "F.Cu")
		(net "M_DDR3_NODE1_DQSECCN")
	)
	(segment
		(start 63.625222 -23.31974)
		(end 63.625222 -23.648162)
		(width 0.1651)
		(layer "F.Cu")
		(net "M_DDR3_NODE1_DQSECCN")
	)
	(via
		(at 65.342262 -65.836038)
		(size 0.508)
		(drill 0.254)
		(layers "F.Cu" "B.Cu")
		(net "M_DDR3_NODE1_DQSECCN")
	)
	(via
		(at 63.133732 -24.139652)
		(size 0.508)
		(drill 0.254)
		(layers "F.Cu" "B.Cu")
		(net "M_DDR3_NODE1_DQSECCN")
	)
	(segment
		(start 61.69152 -58.682128)
		(end 61.62802 -58.618628)
		(width 0.09906)
		(layer "In7.Cu")
		(net "M_DDR3_NODE1_DQSECCN")
	)
	(segment
		(start 60.55868 -50.720498)
		(end 60.43676 -50.598578)
		(width 0.2032)
		(layer "In7.Cu")
		(net "M_DDR3_NODE1_DQSECCN")
	)
	(segment
		(start 65.468246 -66.190368)
		(end 65.600834 -66.190368)
		(width 0.09906)
		(layer "In7.Cu")
		(net "M_DDR3_NODE1_DQSECCN")
	)
	(segment
		(start 62.64148 -44.504102)
		(end 62.64148 -40.913812)
		(width 0.2032)
		(layer "In7.Cu")
		(net "M_DDR3_NODE1_DQSECCN")
	)
	(segment
		(start 64.077342 -35.960304)
		(end 64.077342 -31.061152)
		(width 0.2032)
		(layer "In7.Cu")
		(net "M_DDR3_NODE1_DQSECCN")
	)
	(segment
		(start 62.871604 -37.166042)
		(end 64.077342 -35.960304)
		(width 0.2032)
		(layer "In7.Cu")
		(net "M_DDR3_NODE1_DQSECCN")
	)
	(segment
		(start 65.342262 -66.064384)
		(end 65.468246 -66.190368)
		(width 0.09906)
		(layer "In7.Cu")
		(net "M_DDR3_NODE1_DQSECCN")
	)
	(segment
		(start 60.55868 -45.113956)
		(end 60.960254 -44.712382)
		(width 0.2032)
		(layer "In7.Cu")
		(net "M_DDR3_NODE1_DQSECCN")
	)
	(segment
		(start 60.43676 -47.164498)
		(end 60.43676 -46.554898)
		(width 0.2032)
		(layer "In7.Cu")
		(net "M_DDR3_NODE1_DQSECCN")
	)
	(segment
		(start 65.177162 -26.831798)
		(end 63.603632 -25.258268)
		(width 0.2032)
		(layer "In7.Cu")
		(net "M_DDR3_NODE1_DQSECCN")
	)
	(segment
		(start 60.55868 -39.140892)
		(end 62.53353 -37.166042)
		(width 0.2032)
		(layer "In7.Cu")
		(net "M_DDR3_NODE1_DQSECCN")
	)
	(segment
		(start 62.64148 -40.913812)
		(end 62.432946 -40.705278)
		(width 0.2032)
		(layer "In7.Cu")
		(net "M_DDR3_NODE1_DQSECCN")
	)
	(segment
		(start 60.55868 -48.150018)
		(end 60.55868 -47.286418)
		(width 0.2032)
		(layer "In7.Cu")
		(net "M_DDR3_NODE1_DQSECCN")
	)
	(segment
		(start 65.600834 -66.190368)
		(end 65.787016 -66.004186)
		(width 0.09906)
		(layer "In7.Cu")
		(net "M_DDR3_NODE1_DQSECCN")
	)
	(segment
		(start 62.53353 -37.166042)
		(end 62.871604 -37.166042)
		(width 0.2032)
		(layer "In7.Cu")
		(net "M_DDR3_NODE1_DQSECCN")
	)
	(segment
		(start 64.077342 -31.061152)
		(end 65.177162 -29.961332)
		(width 0.2032)
		(layer "In7.Cu")
		(net "M_DDR3_NODE1_DQSECCN")
	)
	(segment
		(start 65.787016 -66.004186)
		(end 65.787016 -65.279778)
		(width 0.09906)
		(layer "In7.Cu")
		(net "M_DDR3_NODE1_DQSECCN")
	)
	(segment
		(start 62.138814 -40.705278)
		(end 61.93028 -40.913812)
		(width 0.2032)
		(layer "In7.Cu")
		(net "M_DDR3_NODE1_DQSECCN")
	)
	(segment
		(start 61.69152 -59.381644)
		(end 61.69152 -58.682128)
		(width 0.09906)
		(layer "In7.Cu")
		(net "M_DDR3_NODE1_DQSECCN")
	)
	(segment
		(start 60.43676 -51.706018)
		(end 60.55868 -51.584098)
		(width 0.2032)
		(layer "In7.Cu")
		(net "M_DDR3_NODE1_DQSECCN")
	)
	(segment
		(start 61.62802 -58.618628)
		(end 61.62802 -58.59272)
		(width 0.09906)
		(layer "In7.Cu")
		(net "M_DDR3_NODE1_DQSECCN")
	)
	(segment
		(start 60.55868 -51.584098)
		(end 60.55868 -50.720498)
		(width 0.2032)
		(layer "In7.Cu")
		(net "M_DDR3_NODE1_DQSECCN")
	)
	(segment
		(start 62.432946 -40.705278)
		(end 62.138814 -40.705278)
		(width 0.2032)
		(layer "In7.Cu")
		(net "M_DDR3_NODE1_DQSECCN")
	)
	(segment
		(start 64.67094 -63.989712)
		(end 62.5729 -61.891672)
		(width 0.09906)
		(layer "In7.Cu")
		(net "M_DDR3_NODE1_DQSECCN")
	)
	(segment
		(start 60.43676 -50.598578)
		(end 60.43676 -49.988978)
		(width 0.2032)
		(layer "In7.Cu")
		(net "M_DDR3_NODE1_DQSECCN")
	)
	(segment
		(start 62.4332 -44.712382)
		(end 62.64148 -44.504102)
		(width 0.2032)
		(layer "In7.Cu")
		(net "M_DDR3_NODE1_DQSECCN")
	)
	(segment
		(start 60.55868 -43.599608)
		(end 60.55868 -39.140892)
		(width 0.2032)
		(layer "In7.Cu")
		(net "M_DDR3_NODE1_DQSECCN")
	)
	(segment
		(start 62.5729 -60.263024)
		(end 61.69152 -59.381644)
		(width 0.09906)
		(layer "In7.Cu")
		(net "M_DDR3_NODE1_DQSECCN")
	)
	(segment
		(start 61.62802 -58.59272)
		(end 61.62802 -58.326528)
		(width 0.2032)
		(layer "In7.Cu")
		(net "M_DDR3_NODE1_DQSECCN")
	)
	(segment
		(start 61.93028 -40.913812)
		(end 61.93028 -43.599608)
		(width 0.2032)
		(layer "In7.Cu")
		(net "M_DDR3_NODE1_DQSECCN")
	)
	(segment
		(start 63.603632 -25.258268)
		(end 63.603632 -24.609552)
		(width 0.2032)
		(layer "In7.Cu")
		(net "M_DDR3_NODE1_DQSECCN")
	)
	(segment
		(start 65.787016 -65.279778)
		(end 64.67094 -64.163702)
		(width 0.09906)
		(layer "In7.Cu")
		(net "M_DDR3_NODE1_DQSECCN")
	)
	(segment
		(start 60.43676 -46.554898)
		(end 60.55868 -46.432978)
		(width 0.2032)
		(layer "In7.Cu")
		(net "M_DDR3_NODE1_DQSECCN")
	)
	(segment
		(start 60.55868 -52.437538)
		(end 60.43676 -52.315618)
		(width 0.2032)
		(layer "In7.Cu")
		(net "M_DDR3_NODE1_DQSECCN")
	)
	(segment
		(start 60.55868 -47.286418)
		(end 60.43676 -47.164498)
		(width 0.2032)
		(layer "In7.Cu")
		(net "M_DDR3_NODE1_DQSECCN")
	)
	(segment
		(start 65.177162 -29.961332)
		(end 65.177162 -26.831798)
		(width 0.2032)
		(layer "In7.Cu")
		(net "M_DDR3_NODE1_DQSECCN")
	)
	(segment
		(start 61.62802 -58.326528)
		(end 60.55868 -57.257188)
		(width 0.2032)
		(layer "In7.Cu")
		(net "M_DDR3_NODE1_DQSECCN")
	)
	(segment
		(start 61.528706 -44.001182)
		(end 60.960254 -44.001182)
		(width 0.2032)
		(layer "In7.Cu")
		(net "M_DDR3_NODE1_DQSECCN")
	)
	(segment
		(start 60.55868 -49.003458)
		(end 60.43676 -48.881538)
		(width 0.2032)
		(layer "In7.Cu")
		(net "M_DDR3_NODE1_DQSECCN")
	)
	(segment
		(start 60.43676 -49.988978)
		(end 60.55868 -49.867058)
		(width 0.2032)
		(layer "In7.Cu")
		(net "M_DDR3_NODE1_DQSECCN")
	)
	(segment
		(start 60.55868 -49.867058)
		(end 60.55868 -49.003458)
		(width 0.2032)
		(layer "In7.Cu")
		(net "M_DDR3_NODE1_DQSECCN")
	)
	(segment
		(start 60.960254 -44.001182)
		(end 60.55868 -43.599608)
		(width 0.2032)
		(layer "In7.Cu")
		(net "M_DDR3_NODE1_DQSECCN")
	)
	(segment
		(start 60.43676 -48.881538)
		(end 60.43676 -48.271938)
		(width 0.2032)
		(layer "In7.Cu")
		(net "M_DDR3_NODE1_DQSECCN")
	)
	(segment
		(start 60.55868 -46.432978)
		(end 60.55868 -45.113956)
		(width 0.2032)
		(layer "In7.Cu")
		(net "M_DDR3_NODE1_DQSECCN")
	)
	(segment
		(start 65.342262 -65.836038)
		(end 65.342262 -66.064384)
		(width 0.09906)
		(layer "In7.Cu")
		(net "M_DDR3_NODE1_DQSECCN")
	)
	(segment
		(start 60.43676 -52.315618)
		(end 60.43676 -51.706018)
		(width 0.2032)
		(layer "In7.Cu")
		(net "M_DDR3_NODE1_DQSECCN")
	)
	(segment
		(start 63.603632 -24.609552)
		(end 63.133732 -24.139652)
		(width 0.2032)
		(layer "In7.Cu")
		(net "M_DDR3_NODE1_DQSECCN")
	)
	(segment
		(start 60.43676 -48.271938)
		(end 60.55868 -48.150018)
		(width 0.2032)
		(layer "In7.Cu")
		(net "M_DDR3_NODE1_DQSECCN")
	)
	(segment
		(start 60.55868 -57.257188)
		(end 60.55868 -52.437538)
		(width 0.2032)
		(layer "In7.Cu")
		(net "M_DDR3_NODE1_DQSECCN")
	)
	(segment
		(start 60.960254 -44.712382)
		(end 62.4332 -44.712382)
		(width 0.2032)
		(layer "In7.Cu")
		(net "M_DDR3_NODE1_DQSECCN")
	)
	(segment
		(start 64.67094 -64.163702)
		(end 64.67094 -63.989712)
		(width 0.09906)
		(layer "In7.Cu")
		(net "M_DDR3_NODE1_DQSECCN")
	)
	(segment
		(start 62.5729 -61.891672)
		(end 62.5729 -60.263024)
		(width 0.09906)
		(layer "In7.Cu")
		(net "M_DDR3_NODE1_DQSECCN")
	)
	(segment
		(start 61.93028 -43.599608)
		(end 61.528706 -44.001182)
		(width 0.2032)
		(layer "In7.Cu")
		(net "M_DDR3_NODE1_DQSECCN")
	)
	(segment
		(start 98.457766 -127.393954)
		(end 98.801428 -127.050292)
		(width 0.1016)
		(layer "F.Cu")
		(net "FM_CPLD_NODE1_P1V05_SUS_EN")
	)
	(segment
		(start 94.074234 -131.529582)
		(end 93.704664 -131.160012)
		(width 0.1016)
		(layer "F.Cu")
		(net "FM_CPLD_NODE1_P1V05_SUS_EN")
	)
	(segment
		(start 93.711522 -130.168142)
		(end 92.976954 -129.433574)
		(width 0.1016)
		(layer "F.Cu")
		(net "FM_CPLD_NODE1_P1V05_SUS_EN")
	)
	(segment
		(start 169.350182 -115.484402)
		(end 167.30472 -113.43894)
		(width 0.1016)
		(layer "F.Cu")
		(net "FM_CPLD_NODE1_P1V05_SUS_EN")
	)
	(segment
		(start 94.074234 -132.420106)
		(end 94.074234 -131.529582)
		(width 0.1016)
		(layer "F.Cu")
		(net "FM_CPLD_NODE1_P1V05_SUS_EN")
	)
	(segment
		(start 93.532452 -130.823462)
		(end 93.711522 -130.644392)
		(width 0.1016)
		(layer "F.Cu")
		(net "FM_CPLD_NODE1_P1V05_SUS_EN")
	)
	(segment
		(start 98.801428 -127.050292)
		(end 98.801428 -126.222506)
		(width 0.1016)
		(layer "F.Cu")
		(net "FM_CPLD_NODE1_P1V05_SUS_EN")
	)
	(segment
		(start 93.532452 -131.160012)
		(end 93.532452 -130.823462)
		(width 0.1016)
		(layer "F.Cu")
		(net "FM_CPLD_NODE1_P1V05_SUS_EN")
	)
	(segment
		(start 173.010322 -116.365528)
		(end 172.129196 -115.484402)
		(width 0.1016)
		(layer "F.Cu")
		(net "FM_CPLD_NODE1_P1V05_SUS_EN")
	)
	(segment
		(start 92.976954 -128.61798)
		(end 94.20098 -127.393954)
		(width 0.1016)
		(layer "F.Cu")
		(net "FM_CPLD_NODE1_P1V05_SUS_EN")
	)
	(segment
		(start 93.711522 -130.644392)
		(end 93.711522 -130.168142)
		(width 0.1016)
		(layer "F.Cu")
		(net "FM_CPLD_NODE1_P1V05_SUS_EN")
	)
	(segment
		(start 172.129196 -115.484402)
		(end 169.350182 -115.484402)
		(width 0.1016)
		(layer "F.Cu")
		(net "FM_CPLD_NODE1_P1V05_SUS_EN")
	)
	(segment
		(start 94.338648 -133.138164)
		(end 94.338648 -132.68452)
		(width 0.1016)
		(layer "F.Cu")
		(net "FM_CPLD_NODE1_P1V05_SUS_EN")
	)
	(segment
		(start 94.20098 -127.393954)
		(end 98.457766 -127.393954)
		(width 0.1016)
		(layer "F.Cu")
		(net "FM_CPLD_NODE1_P1V05_SUS_EN")
	)
	(segment
		(start 92.976954 -129.433574)
		(end 92.976954 -128.61798)
		(width 0.1016)
		(layer "F.Cu")
		(net "FM_CPLD_NODE1_P1V05_SUS_EN")
	)
	(segment
		(start 93.704664 -131.160012)
		(end 93.532452 -131.160012)
		(width 0.1016)
		(layer "F.Cu")
		(net "FM_CPLD_NODE1_P1V05_SUS_EN")
	)
	(segment
		(start 94.338648 -132.68452)
		(end 94.074234 -132.420106)
		(width 0.1016)
		(layer "F.Cu")
		(net "FM_CPLD_NODE1_P1V05_SUS_EN")
	)
	(via
		(at 98.801428 -126.222506)
		(size 0.508)
		(drill 0.254)
		(layers "F.Cu" "B.Cu")
		(net "FM_CPLD_NODE1_P1V05_SUS_EN")
	)
	(via
		(at 167.30472 -113.43894)
		(size 0.508)
		(drill 0.254)
		(layers "F.Cu" "B.Cu")
		(net "FM_CPLD_NODE1_P1V05_SUS_EN")
	)
	(via
		(at 119.40286 -84.537296)
		(size 0.508)
		(drill 0.254)
		(layers "F.Cu" "B.Cu")
		(net "FM_CPLD_NODE1_P1V05_SUS_EN")
	)
	(segment
		(start 101.142038 -101.825806)
		(end 97.97288 -104.994964)
		(width 0.1143)
		(layer "In2.Cu")
		(net "FM_CPLD_NODE1_P1V05_SUS_EN")
	)
	(segment
		(start 97.307146 -111.933482)
		(end 97.307146 -124.728224)
		(width 0.1143)
		(layer "In2.Cu")
		(net "FM_CPLD_NODE1_P1V05_SUS_EN")
	)
	(segment
		(start 97.97288 -104.994964)
		(end 97.97288 -111.267748)
		(width 0.1143)
		(layer "In2.Cu")
		(net "FM_CPLD_NODE1_P1V05_SUS_EN")
	)
	(segment
		(start 119.40286 -86.357714)
		(end 112.20704 -93.553534)
		(width 0.1143)
		(layer "In2.Cu")
		(net "FM_CPLD_NODE1_P1V05_SUS_EN")
	)
	(segment
		(start 112.20704 -93.553534)
		(end 112.20704 -96.378522)
		(width 0.1143)
		(layer "In2.Cu")
		(net "FM_CPLD_NODE1_P1V05_SUS_EN")
	)
	(segment
		(start 112.20704 -96.378522)
		(end 106.759756 -101.825806)
		(width 0.1143)
		(layer "In2.Cu")
		(net "FM_CPLD_NODE1_P1V05_SUS_EN")
	)
	(segment
		(start 106.759756 -101.825806)
		(end 101.142038 -101.825806)
		(width 0.1143)
		(layer "In2.Cu")
		(net "FM_CPLD_NODE1_P1V05_SUS_EN")
	)
	(segment
		(start 119.40286 -84.537296)
		(end 119.40286 -86.357714)
		(width 0.1143)
		(layer "In2.Cu")
		(net "FM_CPLD_NODE1_P1V05_SUS_EN")
	)
	(segment
		(start 97.97288 -111.267748)
		(end 97.307146 -111.933482)
		(width 0.1143)
		(layer "In2.Cu")
		(net "FM_CPLD_NODE1_P1V05_SUS_EN")
	)
	(segment
		(start 97.307146 -124.728224)
		(end 98.801428 -126.222506)
		(width 0.1143)
		(layer "In2.Cu")
		(net "FM_CPLD_NODE1_P1V05_SUS_EN")
	)
	(segment
		(start 119.746014 -84.537296)
		(end 130.251708 -95.04299)
		(width 0.1143)
		(layer "In7.Cu")
		(net "FM_CPLD_NODE1_P1V05_SUS_EN")
	)
	(segment
		(start 130.251708 -95.04299)
		(end 141.81709 -95.04299)
		(width 0.1143)
		(layer "In7.Cu")
		(net "FM_CPLD_NODE1_P1V05_SUS_EN")
	)
	(segment
		(start 141.81709 -95.04299)
		(end 157.565852 -110.791752)
		(width 0.1143)
		(layer "In7.Cu")
		(net "FM_CPLD_NODE1_P1V05_SUS_EN")
	)
	(segment
		(start 164.657532 -110.791752)
		(end 167.30472 -113.43894)
		(width 0.1143)
		(layer "In7.Cu")
		(net "FM_CPLD_NODE1_P1V05_SUS_EN")
	)
	(segment
		(start 119.40286 -84.537296)
		(end 119.746014 -84.537296)
		(width 0.1143)
		(layer "In7.Cu")
		(net "FM_CPLD_NODE1_P1V05_SUS_EN")
	)
	(segment
		(start 157.565852 -110.791752)
		(end 164.657532 -110.791752)
		(width 0.1143)
		(layer "In7.Cu")
		(net "FM_CPLD_NODE1_P1V05_SUS_EN")
	)
	(segment
		(start 59.260486 -121.444512)
		(end 59.260486 -121.933462)
		(width 0.1016)
		(layer "F.Cu")
		(net "BMC_ROMD0")
	)
	(segment
		(start 59.260486 -121.933462)
		(end 59.489086 -122.162062)
		(width 0.1016)
		(layer "F.Cu")
		(net "BMC_ROMD0")
	)
	(segment
		(start 61.690504 -125.78588)
		(end 61.690504 -125.579632)
		(width 0.1016)
		(layer "F.Cu")
		(net "BMC_ROMD0")
	)
	(segment
		(start 61.690504 -125.579632)
		(end 61.292486 -125.181614)
		(width 0.1016)
		(layer "F.Cu")
		(net "BMC_ROMD0")
	)
	(segment
		(start 61.292486 -125.181614)
		(end 61.292486 -124.371862)
		(width 0.1016)
		(layer "F.Cu")
		(net "BMC_ROMD0")
	)
	(segment
		(start 59.489086 -122.568462)
		(end 59.489086 -122.162062)
		(width 0.1016)
		(layer "F.Cu")
		(net "BMC_ROMD0")
	)
	(segment
		(start 62.141862 -126.237238)
		(end 61.690504 -125.78588)
		(width 0.1016)
		(layer "F.Cu")
		(net "BMC_ROMD0")
	)
	(segment
		(start 62.141862 -126.459488)
		(end 62.141862 -126.237238)
		(width 0.1016)
		(layer "F.Cu")
		(net "BMC_ROMD0")
	)
	(segment
		(start 61.292486 -124.371862)
		(end 59.489086 -122.568462)
		(width 0.1016)
		(layer "F.Cu")
		(net "BMC_ROMD0")
	)
	(via
		(at 59.489086 -122.162062)
		(size 0.508)
		(drill 0.254)
		(layers "F.Cu" "B.Cu")
		(net "BMC_ROMD0")
	)
	(segment
		(start 39.73576 -19.015202)
		(end 38.748462 -19.015202)
		(width 0.1016)
		(layer "F.Cu")
		(net "PD_NODE1_DM0")
	)
	(segment
		(start 43.35018 -19.89836)
		(end 42.467022 -19.015202)
		(width 0.1016)
		(layer "F.Cu")
		(net "PD_NODE1_DM0")
	)
	(segment
		(start 43.35018 -20.94992)
		(end 43.35018 -19.89836)
		(width 0.1016)
		(layer "F.Cu")
		(net "PD_NODE1_DM0")
	)
	(segment
		(start 42.467022 -19.015202)
		(end 39.73576 -19.015202)
		(width 0.1016)
		(layer "F.Cu")
		(net "PD_NODE1_DM0")
	)
	(via
		(at 39.73576 -19.015202)
		(size 0.508)
		(drill 0.254)
		(layers "F.Cu" "B.Cu")
		(net "PD_NODE1_DM0")
	)
	(segment
		(start 181.693312 -122.204988)
		(end 181.171342 -122.204988)
		(width 0.1016)
		(layer "F.Cu")
		(net "PWRGD_NODE1_P1V05_SUS_PG")
	)
	(segment
		(start 181.171342 -122.204988)
		(end 181.01056 -122.36577)
		(width 0.1016)
		(layer "F.Cu")
		(net "PWRGD_NODE1_P1V05_SUS_PG")
	)
	(via
		(at 181.693312 -122.204988)
		(size 0.508)
		(drill 0.254)
		(layers "F.Cu" "B.Cu")
		(net "PWRGD_NODE1_P1V05_SUS_PG")
	)
	(via
		(at 93.68155 -137.103104)
		(size 0.508)
		(drill 0.254)
		(layers "F.Cu" "B.Cu")
		(net "PWRGD_NODE1_P1V05_SUS_PG")
	)
	(segment
		(start 173.36008 -128.221994)
		(end 173.36008 -127.967994)
		(width 0.1143)
		(layer "In6.Cu")
		(net "PWRGD_NODE1_P1V05_SUS_PG")
	)
	(segment
		(start 177.11674 -130.969258)
		(end 176.702974 -130.969258)
		(width 0.1143)
		(layer "In6.Cu")
		(net "PWRGD_NODE1_P1V05_SUS_PG")
	)
	(segment
		(start 115.565682 -141.679676)
		(end 114.77244 -141.679676)
		(width 0.1143)
		(layer "In6.Cu")
		(net "PWRGD_NODE1_P1V05_SUS_PG")
	)
	(segment
		(start 169.258234 -127.434848)
		(end 167.19296 -129.500122)
		(width 0.1143)
		(layer "In6.Cu")
		(net "PWRGD_NODE1_P1V05_SUS_PG")
	)
	(segment
		(start 177.274982 -130.811016)
		(end 177.11674 -130.969258)
		(width 0.1143)
		(layer "In6.Cu")
		(net "PWRGD_NODE1_P1V05_SUS_PG")
	)
	(segment
		(start 176.544732 -130.811016)
		(end 175.949102 -130.811016)
		(width 0.1143)
		(layer "In6.Cu")
		(net "PWRGD_NODE1_P1V05_SUS_PG")
	)
	(segment
		(start 149.0345 -131.836922)
		(end 148.753068 -132.118354)
		(width 0.1143)
		(layer "In6.Cu")
		(net "PWRGD_NODE1_P1V05_SUS_PG")
	)
	(segment
		(start 175.949102 -130.811016)
		(end 173.36008 -128.221994)
		(width 0.1143)
		(layer "In6.Cu")
		(net "PWRGD_NODE1_P1V05_SUS_PG")
	)
	(segment
		(start 173.36008 -127.967994)
		(end 172.826934 -127.434848)
		(width 0.1143)
		(layer "In6.Cu")
		(net "PWRGD_NODE1_P1V05_SUS_PG")
	)
	(segment
		(start 112.81664 -143.635476)
		(end 98.910394 -143.635476)
		(width 0.1143)
		(layer "In6.Cu")
		(net "PWRGD_NODE1_P1V05_SUS_PG")
	)
	(segment
		(start 98.62058 -144.047464)
		(end 98.180906 -144.487138)
		(width 0.1143)
		(layer "In6.Cu")
		(net "PWRGD_NODE1_P1V05_SUS_PG")
	)
	(segment
		(start 98.62058 -143.92529)
		(end 98.62058 -144.047464)
		(width 0.1143)
		(layer "In6.Cu")
		(net "PWRGD_NODE1_P1V05_SUS_PG")
	)
	(segment
		(start 124.654056 -132.118354)
		(end 115.971066 -140.801344)
		(width 0.1143)
		(layer "In6.Cu")
		(net "PWRGD_NODE1_P1V05_SUS_PG")
	)
	(segment
		(start 181.788562 -126.327662)
		(end 181.788562 -128.171702)
		(width 0.1143)
		(layer "In6.Cu")
		(net "PWRGD_NODE1_P1V05_SUS_PG")
	)
	(segment
		(start 97.73412 -144.487138)
		(end 92.355416 -139.108434)
		(width 0.1143)
		(layer "In6.Cu")
		(net "PWRGD_NODE1_P1V05_SUS_PG")
	)
	(segment
		(start 160.489138 -131.836922)
		(end 149.0345 -131.836922)
		(width 0.1143)
		(layer "In6.Cu")
		(net "PWRGD_NODE1_P1V05_SUS_PG")
	)
	(segment
		(start 92.355416 -139.108434)
		(end 92.355416 -138.429238)
		(width 0.1143)
		(layer "In6.Cu")
		(net "PWRGD_NODE1_P1V05_SUS_PG")
	)
	(segment
		(start 172.826934 -127.434848)
		(end 169.258234 -127.434848)
		(width 0.1143)
		(layer "In6.Cu")
		(net "PWRGD_NODE1_P1V05_SUS_PG")
	)
	(segment
		(start 181.788562 -128.171702)
		(end 179.149248 -130.811016)
		(width 0.1143)
		(layer "In6.Cu")
		(net "PWRGD_NODE1_P1V05_SUS_PG")
	)
	(segment
		(start 92.355416 -138.429238)
		(end 93.68155 -137.103104)
		(width 0.1143)
		(layer "In6.Cu")
		(net "PWRGD_NODE1_P1V05_SUS_PG")
	)
	(segment
		(start 176.702974 -130.969258)
		(end 176.544732 -130.811016)
		(width 0.1143)
		(layer "In6.Cu")
		(net "PWRGD_NODE1_P1V05_SUS_PG")
	)
	(segment
		(start 181.693312 -126.232412)
		(end 181.788562 -126.327662)
		(width 0.1143)
		(layer "In6.Cu")
		(net "PWRGD_NODE1_P1V05_SUS_PG")
	)
	(segment
		(start 181.693312 -122.204988)
		(end 181.693312 -126.232412)
		(width 0.1143)
		(layer "In6.Cu")
		(net "PWRGD_NODE1_P1V05_SUS_PG")
	)
	(segment
		(start 167.19296 -129.500122)
		(end 162.825938 -129.500122)
		(width 0.1143)
		(layer "In6.Cu")
		(net "PWRGD_NODE1_P1V05_SUS_PG")
	)
	(segment
		(start 114.77244 -141.679676)
		(end 112.81664 -143.635476)
		(width 0.1143)
		(layer "In6.Cu")
		(net "PWRGD_NODE1_P1V05_SUS_PG")
	)
	(segment
		(start 179.149248 -130.811016)
		(end 177.274982 -130.811016)
		(width 0.1143)
		(layer "In6.Cu")
		(net "PWRGD_NODE1_P1V05_SUS_PG")
	)
	(segment
		(start 115.971066 -141.274292)
		(end 115.565682 -141.679676)
		(width 0.1143)
		(layer "In6.Cu")
		(net "PWRGD_NODE1_P1V05_SUS_PG")
	)
	(segment
		(start 148.753068 -132.118354)
		(end 124.654056 -132.118354)
		(width 0.1143)
		(layer "In6.Cu")
		(net "PWRGD_NODE1_P1V05_SUS_PG")
	)
	(segment
		(start 98.180906 -144.487138)
		(end 97.73412 -144.487138)
		(width 0.1143)
		(layer "In6.Cu")
		(net "PWRGD_NODE1_P1V05_SUS_PG")
	)
	(segment
		(start 98.910394 -143.635476)
		(end 98.62058 -143.92529)
		(width 0.1143)
		(layer "In6.Cu")
		(net "PWRGD_NODE1_P1V05_SUS_PG")
	)
	(segment
		(start 162.825938 -129.500122)
		(end 160.489138 -131.836922)
		(width 0.1143)
		(layer "In6.Cu")
		(net "PWRGD_NODE1_P1V05_SUS_PG")
	)
	(segment
		(start 115.971066 -140.801344)
		(end 115.971066 -141.274292)
		(width 0.1143)
		(layer "In6.Cu")
		(net "PWRGD_NODE1_P1V05_SUS_PG")
	)
	(segment
		(start 66.141854 -129.657348)
		(end 66.540888 -129.258314)
		(width 0.1016)
		(layer "F.Cu")
		(net "BMC_ROMA12")
	)
	(segment
		(start 66.141854 -129.659634)
		(end 66.141854 -129.657348)
		(width 0.1016)
		(layer "F.Cu")
		(net "BMC_ROMA12")
	)
	(via
		(at 66.540888 -129.258314)
		(size 0.49022)
		(drill 0.254)
		(layers "F.Cu" "B.Cu")
		(net "BMC_ROMA12")
	)
	(via
		(at 67.312286 -130.95097)
		(size 0.6604)
		(drill 0.3302)
		(layers "F.Cu" "B.Cu")
		(net "BMC_ROMA12")
	)
	(segment
		(start 66.407792 -129.39141)
		(end 66.540888 -129.258314)
		(width 0.1016)
		(layer "B.Cu")
		(net "BMC_ROMA12")
	)
	(segment
		(start 66.540888 -129.495804)
		(end 66.938398 -129.893314)
		(width 0.1016)
		(layer "B.Cu")
		(net "BMC_ROMA12")
	)
	(segment
		(start 66.540888 -129.258314)
		(end 66.540888 -129.495804)
		(width 0.1016)
		(layer "B.Cu")
		(net "BMC_ROMA12")
	)
	(segment
		(start 65.721992 -129.39141)
		(end 66.407792 -129.39141)
		(width 0.1016)
		(layer "B.Cu")
		(net "BMC_ROMA12")
	)
	(segment
		(start 66.938398 -129.893314)
		(end 66.938398 -130.577082)
		(width 0.1016)
		(layer "B.Cu")
		(net "BMC_ROMA12")
	)
	(segment
		(start 66.938398 -130.577082)
		(end 67.312286 -130.95097)
		(width 0.1016)
		(layer "B.Cu")
		(net "BMC_ROMA12")
	)
	(segment
		(start 43.20413 -30.504892)
		(end 43.050206 -30.350968)
		(width 0.1651)
		(layer "F.Cu")
		(net "M_DDR3_NODE1_DQS0N")
	)
	(segment
		(start 49.543716 -65.744344)
		(end 49.452022 -65.836038)
		(width 0.09906)
		(layer "F.Cu")
		(net "M_DDR3_NODE1_DQS0N")
	)
	(segment
		(start 43.20413 -30.846268)
		(end 43.20413 -30.504892)
		(width 0.1651)
		(layer "F.Cu")
		(net "M_DDR3_NODE1_DQS0N")
	)
	(segment
		(start 43.050206 -30.350968)
		(end 43.050206 -29.149802)
		(width 0.1651)
		(layer "F.Cu")
		(net "M_DDR3_NODE1_DQS0N")
	)
	(segment
		(start 49.825402 -65.455038)
		(end 49.543716 -65.736724)
		(width 0.09906)
		(layer "F.Cu")
		(net "M_DDR3_NODE1_DQS0N")
	)
	(segment
		(start 49.543716 -65.736724)
		(end 49.543716 -65.744344)
		(width 0.09906)
		(layer "F.Cu")
		(net "M_DDR3_NODE1_DQS0N")
	)
	(segment
		(start 42.71518 -31.335218)
		(end 43.20413 -30.846268)
		(width 0.1651)
		(layer "F.Cu")
		(net "M_DDR3_NODE1_DQS0N")
	)
	(via
		(at 49.452022 -65.836038)
		(size 0.508)
		(drill 0.254)
		(layers "F.Cu" "B.Cu")
		(net "M_DDR3_NODE1_DQS0N")
	)
	(via
		(at 42.71518 -31.335218)
		(size 0.508)
		(drill 0.254)
		(layers "F.Cu" "B.Cu")
		(net "M_DDR3_NODE1_DQS0N")
	)
	(segment
		(start 49.915064 -64.857122)
		(end 49.915064 -66.071242)
		(width 0.09906)
		(layer "In7.Cu")
		(net "M_DDR3_NODE1_DQS0N")
	)
	(segment
		(start 34.64052 -48.07585)
		(end 34.5313 -48.18507)
		(width 0.2032)
		(layer "In7.Cu")
		(net "M_DDR3_NODE1_DQS0N")
	)
	(segment
		(start 43.91914 -58.12917)
		(end 43.91914 -58.61558)
		(width 0.2032)
		(layer "In7.Cu")
		(net "M_DDR3_NODE1_DQS0N")
	)
	(segment
		(start 37.18687 -53.777642)
		(end 37.18687 -54.072282)
		(width 0.2032)
		(layer "In7.Cu")
		(net "M_DDR3_NODE1_DQS0N")
	)
	(segment
		(start 44.234354 -58.930794)
		(end 44.252642 -58.949082)
		(width 0.09906)
		(layer "In7.Cu")
		(net "M_DDR3_NODE1_DQS0N")
	)
	(segment
		(start 49.745138 -66.129154)
		(end 49.452022 -65.836038)
		(width 0.09906)
		(layer "In7.Cu")
		(net "M_DDR3_NODE1_DQS0N")
	)
	(segment
		(start 36.829492 -54.42966)
		(end 36.829492 -54.997604)
		(width 0.2032)
		(layer "In7.Cu")
		(net "M_DDR3_NODE1_DQS0N")
	)
	(segment
		(start 34.64052 -42.31259)
		(end 34.64052 -46.28769)
		(width 0.2032)
		(layer "In7.Cu")
		(net "M_DDR3_NODE1_DQS0N")
	)
	(segment
		(start 41.72331 -34.04235)
		(end 41.312846 -33.631886)
		(width 0.2032)
		(layer "In7.Cu")
		(net "M_DDR3_NODE1_DQS0N")
	)
	(segment
		(start 34.5313 -48.18507)
		(end 34.5313 -48.79467)
		(width 0.2032)
		(layer "In7.Cu")
		(net "M_DDR3_NODE1_DQS0N")
	)
	(segment
		(start 36.371784 -38.572948)
		(end 37.439854 -39.641018)
		(width 0.2032)
		(layer "In7.Cu")
		(net "M_DDR3_NODE1_DQS0N")
	)
	(segment
		(start 34.64052 -47.11573)
		(end 34.64052 -48.07585)
		(width 0.2032)
		(layer "In7.Cu")
		(net "M_DDR3_NODE1_DQS0N")
	)
	(segment
		(start 45.89018 -60.496704)
		(end 46.93158 -60.496704)
		(width 0.09906)
		(layer "In7.Cu")
		(net "M_DDR3_NODE1_DQS0N")
	)
	(segment
		(start 38.212268 -38.131496)
		(end 41.72331 -34.620454)
		(width 0.2032)
		(layer "In7.Cu")
		(net "M_DDR3_NODE1_DQS0N")
	)
	(segment
		(start 34.5313 -50.58283)
		(end 34.64052 -50.69205)
		(width 0.2032)
		(layer "In7.Cu")
		(net "M_DDR3_NODE1_DQS0N")
	)
	(segment
		(start 39.748968 -56.48833)
		(end 40.150542 -56.086756)
		(width 0.2032)
		(layer "In7.Cu")
		(net "M_DDR3_NODE1_DQS0N")
	)
	(segment
		(start 37.18687 -54.072282)
		(end 36.829492 -54.42966)
		(width 0.2032)
		(layer "In7.Cu")
		(net "M_DDR3_NODE1_DQS0N")
	)
	(segment
		(start 40.861742 -55.59552)
		(end 40.861742 -56.086756)
		(width 0.2032)
		(layer "In7.Cu")
		(net "M_DDR3_NODE1_DQS0N")
	)
	(segment
		(start 47.26178 -60.826904)
		(end 47.26178 -62.022228)
		(width 0.09906)
		(layer "In7.Cu")
		(net "M_DDR3_NODE1_DQS0N")
	)
	(segment
		(start 34.64052 -52.808632)
		(end 35.758628 -53.92674)
		(width 0.2032)
		(layer "In7.Cu")
		(net "M_DDR3_NODE1_DQS0N")
	)
	(segment
		(start 34.5313 -49.97323)
		(end 34.5313 -50.58283)
		(width 0.2032)
		(layer "In7.Cu")
		(net "M_DDR3_NODE1_DQS0N")
	)
	(segment
		(start 40.734742 -33.631886)
		(end 36.371784 -37.994844)
		(width 0.2032)
		(layer "In7.Cu")
		(net "M_DDR3_NODE1_DQS0N")
	)
	(segment
		(start 44.252642 -58.949082)
		(end 44.342558 -58.949082)
		(width 0.09906)
		(layer "In7.Cu")
		(net "M_DDR3_NODE1_DQS0N")
	)
	(segment
		(start 49.857152 -66.129154)
		(end 49.745138 -66.129154)
		(width 0.09906)
		(layer "In7.Cu")
		(net "M_DDR3_NODE1_DQS0N")
	)
	(segment
		(start 38.212268 -38.436296)
		(end 38.212268 -38.131496)
		(width 0.2032)
		(layer "In7.Cu")
		(net "M_DDR3_NODE1_DQS0N")
	)
	(segment
		(start 36.326572 -53.92674)
		(end 36.68395 -53.569362)
		(width 0.2032)
		(layer "In7.Cu")
		(net "M_DDR3_NODE1_DQS0N")
	)
	(segment
		(start 40.861742 -56.086756)
		(end 41.263316 -56.48833)
		(width 0.2032)
		(layer "In7.Cu")
		(net "M_DDR3_NODE1_DQS0N")
	)
	(segment
		(start 37.439854 -39.945818)
		(end 36.87572 -40.509952)
		(width 0.2032)
		(layer "In7.Cu")
		(net "M_DDR3_NODE1_DQS0N")
	)
	(segment
		(start 43.91914 -58.61558)
		(end 44.234354 -58.930794)
		(width 0.2032)
		(layer "In7.Cu")
		(net "M_DDR3_NODE1_DQS0N")
	)
	(segment
		(start 38.428422 -38.65245)
		(end 38.212268 -38.436296)
		(width 0.2032)
		(layer "In7.Cu")
		(net "M_DDR3_NODE1_DQS0N")
	)
	(segment
		(start 34.5313 -46.39691)
		(end 34.5313 -47.00651)
		(width 0.2032)
		(layer "In7.Cu")
		(net "M_DDR3_NODE1_DQS0N")
	)
	(segment
		(start 37.439854 -39.641018)
		(end 37.439854 -39.945818)
		(width 0.2032)
		(layer "In7.Cu")
		(net "M_DDR3_NODE1_DQS0N")
	)
	(segment
		(start 44.342558 -58.949082)
		(end 45.89018 -60.496704)
		(width 0.09906)
		(layer "In7.Cu")
		(net "M_DDR3_NODE1_DQS0N")
	)
	(segment
		(start 48.309784 -63.251842)
		(end 49.915064 -64.857122)
		(width 0.09906)
		(layer "In7.Cu")
		(net "M_DDR3_NODE1_DQS0N")
	)
	(segment
		(start 48.309784 -63.070232)
		(end 48.309784 -63.251842)
		(width 0.09906)
		(layer "In7.Cu")
		(net "M_DDR3_NODE1_DQS0N")
	)
	(segment
		(start 40.302942 -55.44312)
		(end 40.709342 -55.44312)
		(width 0.2032)
		(layer "In7.Cu")
		(net "M_DDR3_NODE1_DQS0N")
	)
	(segment
		(start 42.71518 -31.335218)
		(end 43.18508 -31.805118)
		(width 0.2032)
		(layer "In7.Cu")
		(net "M_DDR3_NODE1_DQS0N")
	)
	(segment
		(start 47.26178 -62.022228)
		(end 48.309784 -63.070232)
		(width 0.09906)
		(layer "In7.Cu")
		(net "M_DDR3_NODE1_DQS0N")
	)
	(segment
		(start 34.64052 -49.86401)
		(end 34.5313 -49.97323)
		(width 0.2032)
		(layer "In7.Cu")
		(net "M_DDR3_NODE1_DQS0N")
	)
	(segment
		(start 34.5313 -48.79467)
		(end 34.64052 -48.90389)
		(width 0.2032)
		(layer "In7.Cu")
		(net "M_DDR3_NODE1_DQS0N")
	)
	(segment
		(start 41.312846 -33.631886)
		(end 40.734742 -33.631886)
		(width 0.2032)
		(layer "In7.Cu")
		(net "M_DDR3_NODE1_DQS0N")
	)
	(segment
		(start 38.733222 -38.65245)
		(end 38.428422 -38.65245)
		(width 0.2032)
		(layer "In7.Cu")
		(net "M_DDR3_NODE1_DQS0N")
	)
	(segment
		(start 36.829492 -54.997604)
		(end 38.320218 -56.48833)
		(width 0.2032)
		(layer "In7.Cu")
		(net "M_DDR3_NODE1_DQS0N")
	)
	(segment
		(start 34.64052 -50.69205)
		(end 34.64052 -52.808632)
		(width 0.2032)
		(layer "In7.Cu")
		(net "M_DDR3_NODE1_DQS0N")
	)
	(segment
		(start 43.18508 -32.226758)
		(end 43.83024 -32.871918)
		(width 0.2032)
		(layer "In7.Cu")
		(net "M_DDR3_NODE1_DQS0N")
	)
	(segment
		(start 34.5313 -47.00651)
		(end 34.64052 -47.11573)
		(width 0.2032)
		(layer "In7.Cu")
		(net "M_DDR3_NODE1_DQS0N")
	)
	(segment
		(start 41.72331 -34.620454)
		(end 41.72331 -34.04235)
		(width 0.2032)
		(layer "In7.Cu")
		(net "M_DDR3_NODE1_DQS0N")
	)
	(segment
		(start 49.915064 -66.071242)
		(end 49.857152 -66.129154)
		(width 0.09906)
		(layer "In7.Cu")
		(net "M_DDR3_NODE1_DQS0N")
	)
	(segment
		(start 43.83024 -32.871918)
		(end 43.83024 -33.555432)
		(width 0.2032)
		(layer "In7.Cu")
		(net "M_DDR3_NODE1_DQS0N")
	)
	(segment
		(start 36.87572 -40.509952)
		(end 36.443158 -40.509952)
		(width 0.2032)
		(layer "In7.Cu")
		(net "M_DDR3_NODE1_DQS0N")
	)
	(segment
		(start 36.97859 -53.569362)
		(end 37.18687 -53.777642)
		(width 0.2032)
		(layer "In7.Cu")
		(net "M_DDR3_NODE1_DQS0N")
	)
	(segment
		(start 36.68395 -53.569362)
		(end 36.97859 -53.569362)
		(width 0.2032)
		(layer "In7.Cu")
		(net "M_DDR3_NODE1_DQS0N")
	)
	(segment
		(start 46.93158 -60.496704)
		(end 47.26178 -60.826904)
		(width 0.09906)
		(layer "In7.Cu")
		(net "M_DDR3_NODE1_DQS0N")
	)
	(segment
		(start 42.2783 -56.48833)
		(end 43.91914 -58.12917)
		(width 0.2032)
		(layer "In7.Cu")
		(net "M_DDR3_NODE1_DQS0N")
	)
	(segment
		(start 36.371784 -37.994844)
		(end 36.371784 -38.572948)
		(width 0.2032)
		(layer "In7.Cu")
		(net "M_DDR3_NODE1_DQS0N")
	)
	(segment
		(start 40.150542 -56.086756)
		(end 40.150542 -55.59552)
		(width 0.2032)
		(layer "In7.Cu")
		(net "M_DDR3_NODE1_DQS0N")
	)
	(segment
		(start 40.150542 -55.59552)
		(end 40.302942 -55.44312)
		(width 0.2032)
		(layer "In7.Cu")
		(net "M_DDR3_NODE1_DQS0N")
	)
	(segment
		(start 34.64052 -46.28769)
		(end 34.5313 -46.39691)
		(width 0.2032)
		(layer "In7.Cu")
		(net "M_DDR3_NODE1_DQS0N")
	)
	(segment
		(start 43.18508 -31.805118)
		(end 43.18508 -32.226758)
		(width 0.2032)
		(layer "In7.Cu")
		(net "M_DDR3_NODE1_DQS0N")
	)
	(segment
		(start 40.709342 -55.44312)
		(end 40.861742 -55.59552)
		(width 0.2032)
		(layer "In7.Cu")
		(net "M_DDR3_NODE1_DQS0N")
	)
	(segment
		(start 43.83024 -33.555432)
		(end 38.733222 -38.65245)
		(width 0.2032)
		(layer "In7.Cu")
		(net "M_DDR3_NODE1_DQS0N")
	)
	(segment
		(start 34.64052 -48.90389)
		(end 34.64052 -49.86401)
		(width 0.2032)
		(layer "In7.Cu")
		(net "M_DDR3_NODE1_DQS0N")
	)
	(segment
		(start 35.758628 -53.92674)
		(end 36.326572 -53.92674)
		(width 0.2032)
		(layer "In7.Cu")
		(net "M_DDR3_NODE1_DQS0N")
	)
	(segment
		(start 41.263316 -56.48833)
		(end 42.2783 -56.48833)
		(width 0.2032)
		(layer "In7.Cu")
		(net "M_DDR3_NODE1_DQS0N")
	)
	(segment
		(start 38.320218 -56.48833)
		(end 39.748968 -56.48833)
		(width 0.2032)
		(layer "In7.Cu")
		(net "M_DDR3_NODE1_DQS0N")
	)
	(segment
		(start 36.443158 -40.509952)
		(end 34.64052 -42.31259)
		(width 0.2032)
		(layer "In7.Cu")
		(net "M_DDR3_NODE1_DQS0N")
	)
	(segment
		(start 150.770844 -65.73139)
		(end 153.89606 -65.73139)
		(width 0.10414)
		(layer "F.Cu")
		(net "SATA_A_NODE1_TX_N0")
	)
	(segment
		(start 150.597362 -65.557908)
		(end 150.770844 -65.73139)
		(width 0.10414)
		(layer "F.Cu")
		(net "SATA_A_NODE1_TX_N0")
	)
	(segment
		(start 154.956764 -65.482216)
		(end 154.70759 -65.73139)
		(width 0.10414)
		(layer "F.Cu")
		(net "SATA_A_NODE1_TX_N0")
	)
	(segment
		(start 154.70759 -65.73139)
		(end 153.89606 -65.73139)
		(width 0.10414)
		(layer "F.Cu")
		(net "SATA_A_NODE1_TX_N0")
	)
	(segment
		(start 149.57171 -65.557908)
		(end 150.597362 -65.557908)
		(width 0.10414)
		(layer "F.Cu")
		(net "SATA_A_NODE1_TX_N0")
	)
	(via
		(at 153.89606 -65.73139)
		(size 0.4064)
		(drill 0.2032)
		(layers "F.Cu" "B.Cu")
		(net "SATA_A_NODE1_TX_N0")
	)
	(segment
		(start 66.9417 -129.657348)
		(end 67.340734 -129.258314)
		(width 0.1016)
		(layer "F.Cu")
		(net "BMC_ROMA23")
	)
	(segment
		(start 66.9417 -129.659634)
		(end 66.9417 -129.657348)
		(width 0.1016)
		(layer "F.Cu")
		(net "BMC_ROMA23")
	)
	(via
		(at 67.340734 -129.258314)
		(size 0.49022)
		(drill 0.254)
		(layers "F.Cu" "B.Cu")
		(net "BMC_ROMA23")
	)
	(via
		(at 67.286886 -126.530862)
		(size 0.6604)
		(drill 0.3302)
		(layers "F.Cu" "B.Cu")
		(net "BMC_ROMA23")
	)
	(segment
		(start 67.080384 -128.99771)
		(end 66.943478 -128.860804)
		(width 0.1016)
		(layer "B.Cu")
		(net "BMC_ROMA23")
	)
	(segment
		(start 68.912486 -118.917212)
		(end 68.912486 -122.25401)
		(width 0.1016)
		(layer "B.Cu")
		(net "BMC_ROMA23")
	)
	(segment
		(start 69.471286 -118.358412)
		(end 68.912486 -118.917212)
		(width 0.1016)
		(layer "B.Cu")
		(net "BMC_ROMA23")
	)
	(segment
		(start 67.286886 -126.988062)
		(end 67.286886 -126.530862)
		(width 0.1016)
		(layer "B.Cu")
		(net "BMC_ROMA23")
	)
	(segment
		(start 66.943478 -128.860804)
		(end 66.943478 -127.33147)
		(width 0.1016)
		(layer "B.Cu")
		(net "BMC_ROMA23")
	)
	(segment
		(start 67.080384 -128.997964)
		(end 67.080384 -128.99771)
		(width 0.1016)
		(layer "B.Cu")
		(net "BMC_ROMA23")
	)
	(segment
		(start 68.912486 -122.25401)
		(end 66.507868 -124.658628)
		(width 0.1016)
		(layer "B.Cu")
		(net "BMC_ROMA23")
	)
	(segment
		(start 66.943478 -127.33147)
		(end 67.286886 -126.988062)
		(width 0.1016)
		(layer "B.Cu")
		(net "BMC_ROMA23")
	)
	(segment
		(start 66.507868 -124.658628)
		(end 66.507868 -125.751844)
		(width 0.1016)
		(layer "B.Cu")
		(net "BMC_ROMA23")
	)
	(segment
		(start 67.340734 -129.258314)
		(end 67.080384 -128.997964)
		(width 0.1016)
		(layer "B.Cu")
		(net "BMC_ROMA23")
	)
	(segment
		(start 66.507868 -125.751844)
		(end 67.286886 -126.530862)
		(width 0.1016)
		(layer "B.Cu")
		(net "BMC_ROMA23")
	)
	(segment
		(start 11.867642 -136.13511)
		(end 10.83818 -136.13511)
		(width 0.508)
		(layer "F.Cu")
		(net "P3V3_SUS_NODE1")
	)
	(segment
		(start 15.29334 -145.784316)
		(end 15.29334 -145.258028)
		(width 0.508)
		(layer "F.Cu")
		(net "P3V3_SUS_NODE1")
	)
	(segment
		(start 34.65068 -152.235408)
		(end 34.19094 -152.695148)
		(width 0.508)
		(layer "F.Cu")
		(net "P3V3_SUS_NODE1")
	)
	(segment
		(start 83.860132 -88.702134)
		(end 84.69376 -88.702134)
		(width 0.508)
		(layer "F.Cu")
		(net "P3V3_SUS_NODE1")
	)
	(segment
		(start 9.923018 -135.219948)
		(end 5.831332 -135.219948)
		(width 0.508)
		(layer "F.Cu")
		(net "P3V3_SUS_NODE1")
	)
	(segment
		(start 62.295532 -83.950048)
		(end 62.74435 -83.950048)
		(width 0.3048)
		(layer "F.Cu")
		(net "P3V3_SUS_NODE1")
	)
	(segment
		(start 62.20333 -83.857846)
		(end 62.295532 -83.950048)
		(width 0.3048)
		(layer "F.Cu")
		(net "P3V3_SUS_NODE1")
	)
	(segment
		(start 34.990786 -173.01845)
		(end 35.33394 -173.01845)
		(width 0.508)
		(layer "F.Cu")
		(net "P3V3_SUS_NODE1")
	)
	(segment
		(start 17.229074 -36.038028)
		(end 16.334486 -36.038028)
		(width 0.508)
		(layer "F.Cu")
		(net "P3V3_SUS_NODE1")
	)
	(segment
		(start 80.363568 -86.974172)
		(end 81.56702 -86.974172)
		(width 0.508)
		(layer "F.Cu")
		(net "P3V3_SUS_NODE1")
	)
	(segment
		(start 76.21016 -116.772182)
		(end 76.21016 -116.583206)
		(width 0.508)
		(layer "F.Cu")
		(net "P3V3_SUS_NODE1")
	)
	(segment
		(start 28.1686 -152.235408)
		(end 23.33244 -152.235408)
		(width 0.508)
		(layer "F.Cu")
		(net "P3V3_SUS_NODE1")
	)
	(segment
		(start 10.83818 -136.13511)
		(end 9.923018 -135.219948)
		(width 0.508)
		(layer "F.Cu")
		(net "P3V3_SUS_NODE1")
	)
	(segment
		(start 15.23238 -149.394164)
		(end 15.23238 -145.845276)
		(width 0.508)
		(layer "F.Cu")
		(net "P3V3_SUS_NODE1")
	)
	(segment
		(start 62.20333 -82.333846)
		(end 62.20333 -83.095846)
		(width 0.3048)
		(layer "F.Cu")
		(net "P3V3_SUS_NODE1")
	)
	(segment
		(start 5.471922 -135.579358)
		(end 1.11506 -135.579358)
		(width 0.508)
		(layer "F.Cu")
		(net "P3V3_SUS_NODE1")
	)
	(segment
		(start 35.33394 -173.01845)
		(end 35.58794 -172.76445)
		(width 0.508)
		(layer "F.Cu")
		(net "P3V3_SUS_NODE1")
	)
	(segment
		(start 22.246336 -151.149304)
		(end 16.98752 -151.149304)
		(width 0.508)
		(layer "F.Cu")
		(net "P3V3_SUS_NODE1")
	)
	(segment
		(start 34.19094 -152.695148)
		(end 28.62834 -152.695148)
		(width 0.508)
		(layer "F.Cu")
		(net "P3V3_SUS_NODE1")
	)
	(segment
		(start 15.23238 -139.499848)
		(end 11.867642 -136.13511)
		(width 0.508)
		(layer "F.Cu")
		(net "P3V3_SUS_NODE1")
	)
	(segment
		(start 35.58794 -172.76445)
		(end 35.58794 -171.680378)
		(width 0.508)
		(layer "F.Cu")
		(net "P3V3_SUS_NODE1")
	)
	(segment
		(start 76.70546 -116.087906)
		(end 76.70546 -109.481874)
		(width 0.508)
		(layer "F.Cu")
		(net "P3V3_SUS_NODE1")
	)
	(segment
		(start 15.23238 -145.845276)
		(end 15.29334 -145.784316)
		(width 0.508)
		(layer "F.Cu")
		(net "P3V3_SUS_NODE1")
	)
	(segment
		(start 62.20333 -81.571846)
		(end 62.20333 -82.333846)
		(width 0.3048)
		(layer "F.Cu")
		(net "P3V3_SUS_NODE1")
	)
	(segment
		(start 77.880718 -108.306616)
		(end 78.59776 -108.306616)
		(width 0.508)
		(layer "F.Cu")
		(net "P3V3_SUS_NODE1")
	)
	(segment
		(start 5.831332 -135.219948)
		(end 5.471922 -135.579358)
		(width 0.508)
		(layer "F.Cu")
		(net "P3V3_SUS_NODE1")
	)
	(segment
		(start 16.98752 -151.149304)
		(end 15.23238 -149.394164)
		(width 0.508)
		(layer "F.Cu")
		(net "P3V3_SUS_NODE1")
	)
	(segment
		(start 28.62834 -152.695148)
		(end 28.1686 -152.235408)
		(width 0.508)
		(layer "F.Cu")
		(net "P3V3_SUS_NODE1")
	)
	(segment
		(start 83.872832 -89.865454)
		(end 84.766404 -89.865454)
		(width 0.508)
		(layer "F.Cu")
		(net "P3V3_SUS_NODE1")
	)
	(segment
		(start 76.21016 -116.583206)
		(end 76.70546 -116.087906)
		(width 0.508)
		(layer "F.Cu")
		(net "P3V3_SUS_NODE1")
	)
	(segment
		(start 15.29334 -145.258028)
		(end 15.23238 -145.197068)
		(width 0.508)
		(layer "F.Cu")
		(net "P3V3_SUS_NODE1")
	)
	(segment
		(start 23.33244 -152.235408)
		(end 22.246336 -151.149304)
		(width 0.508)
		(layer "F.Cu")
		(net "P3V3_SUS_NODE1")
	)
	(segment
		(start 62.20333 -83.095846)
		(end 62.20333 -83.857846)
		(width 0.3048)
		(layer "F.Cu")
		(net "P3V3_SUS_NODE1")
	)
	(segment
		(start 15.23238 -145.197068)
		(end 15.23238 -139.499848)
		(width 0.508)
		(layer "F.Cu")
		(net "P3V3_SUS_NODE1")
	)
	(segment
		(start 76.70546 -109.481874)
		(end 77.880718 -108.306616)
		(width 0.508)
		(layer "F.Cu")
		(net "P3V3_SUS_NODE1")
	)
	(via
		(at 78.59776 -108.306616)
		(size 0.508)
		(drill 0.254)
		(layers "F.Cu" "B.Cu")
		(net "P3V3_SUS_NODE1")
	)
	(via
		(at 81.56702 -86.974172)
		(size 0.508)
		(drill 0.254)
		(layers "F.Cu" "B.Cu")
		(net "P3V3_SUS_NODE1")
	)
	(via
		(at 84.766404 -89.865454)
		(size 0.508)
		(drill 0.254)
		(layers "F.Cu" "B.Cu")
		(net "P3V3_SUS_NODE1")
	)
	(via
		(at 76.33462 -85.61705)
		(size 0.6604)
		(drill 0.3302)
		(layers "F.Cu" "B.Cu")
		(net "P3V3_SUS_NODE1")
	)
	(via
		(at 1.11506 -135.579358)
		(size 0.508)
		(drill 0.254)
		(layers "F.Cu" "B.Cu")
		(net "P3V3_SUS_NODE1")
	)
	(via
		(at 84.69376 -88.702134)
		(size 0.508)
		(drill 0.254)
		(layers "F.Cu" "B.Cu")
		(net "P3V3_SUS_NODE1")
	)
	(via
		(at 76.21016 -116.772182)
		(size 0.508)
		(drill 0.254)
		(layers "F.Cu" "B.Cu")
		(net "P3V3_SUS_NODE1")
	)
	(via
		(at 62.74435 -83.950048)
		(size 0.508)
		(drill 0.254)
		(layers "F.Cu" "B.Cu")
		(net "P3V3_SUS_NODE1")
	)
	(via
		(at 81.85277 -94.47149)
		(size 0.508)
		(drill 0.254)
		(layers "F.Cu" "B.Cu")
		(net "P3V3_SUS_NODE1")
	)
	(via
		(at 35.58794 -171.680378)
		(size 0.508)
		(drill 0.254)
		(layers "F.Cu" "B.Cu")
		(net "P3V3_SUS_NODE1")
	)
	(via
		(at 81.118202 -94.525846)
		(size 0.508)
		(drill 0.254)
		(layers "F.Cu" "B.Cu")
		(net "P3V3_SUS_NODE1")
	)
	(via
		(at 81.609438 -93.405706)
		(size 0.508)
		(drill 0.254)
		(layers "F.Cu" "B.Cu")
		(net "P3V3_SUS_NODE1")
	)
	(via
		(at 66.908426 -99.9363)
		(size 0.508)
		(drill 0.254)
		(layers "F.Cu" "B.Cu")
		(net "P3V3_SUS_NODE1")
	)
	(via
		(at 16.334486 -36.038028)
		(size 0.508)
		(drill 0.254)
		(layers "F.Cu" "B.Cu")
		(net "P3V3_SUS_NODE1")
	)
	(via
		(at 34.65068 -152.235408)
		(size 0.508)
		(drill 0.254)
		(layers "F.Cu" "B.Cu")
		(net "P3V3_SUS_NODE1")
	)
	(via
		(at 73.614788 -84.605368)
		(size 0.6604)
		(drill 0.3302)
		(layers "F.Cu" "B.Cu")
		(net "P3V3_SUS_NODE1")
	)
	(segment
		(start 76.29525 -87.463884)
		(end 76.29525 -88.808814)
		(width 0.508)
		(layer "B.Cu")
		(net "P3V3_SUS_NODE1")
	)
	(segment
		(start 78.59014 -91.103704)
		(end 79.600806 -91.103704)
		(width 0.508)
		(layer "B.Cu")
		(net "P3V3_SUS_NODE1")
	)
	(segment
		(start 72.045576 -83.960208)
		(end 72.045576 -83.96859)
		(width 0.508)
		(layer "B.Cu")
		(net "P3V3_SUS_NODE1")
	)
	(segment
		(start 76.29525 -88.808814)
		(end 78.59014 -91.103704)
		(width 0.508)
		(layer "B.Cu")
		(net "P3V3_SUS_NODE1")
	)
	(segment
		(start 76.29525 -87.005414)
		(end 76.53782 -86.762844)
		(width 0.508)
		(layer "B.Cu")
		(net "P3V3_SUS_NODE1")
	)
	(segment
		(start 72.682354 -84.605368)
		(end 73.614788 -84.605368)
		(width 0.508)
		(layer "B.Cu")
		(net "P3V3_SUS_NODE1")
	)
	(segment
		(start 76.29525 -87.463884)
		(end 76.29525 -87.005414)
		(width 0.508)
		(layer "B.Cu")
		(net "P3V3_SUS_NODE1")
	)
	(segment
		(start 72.045576 -83.96859)
		(end 72.682354 -84.605368)
		(width 0.508)
		(layer "B.Cu")
		(net "P3V3_SUS_NODE1")
	)
	(segment
		(start 81.609438 -93.112336)
		(end 81.609438 -93.405706)
		(width 0.508)
		(layer "B.Cu")
		(net "P3V3_SUS_NODE1")
	)
	(segment
		(start 74.752962 -84.459064)
		(end 75.176634 -84.459064)
		(width 0.508)
		(layer "B.Cu")
		(net "P3V3_SUS_NODE1")
	)
	(segment
		(start 79.600806 -91.103704)
		(end 81.609438 -93.112336)
		(width 0.508)
		(layer "B.Cu")
		(net "P3V3_SUS_NODE1")
	)
	(segment
		(start 74.606658 -84.605368)
		(end 74.752962 -84.459064)
		(width 0.508)
		(layer "B.Cu")
		(net "P3V3_SUS_NODE1")
	)
	(segment
		(start 75.176634 -84.459064)
		(end 76.33462 -85.61705)
		(width 0.508)
		(layer "B.Cu")
		(net "P3V3_SUS_NODE1")
	)
	(segment
		(start 66.553334 -99.581208)
		(end 65.706498 -99.581208)
		(width 0.508)
		(layer "B.Cu")
		(net "P3V3_SUS_NODE1")
	)
	(segment
		(start 76.53782 -85.82025)
		(end 76.33462 -85.61705)
		(width 0.508)
		(layer "B.Cu")
		(net "P3V3_SUS_NODE1")
	)
	(segment
		(start 66.908426 -99.9363)
		(end 66.553334 -99.581208)
		(width 0.508)
		(layer "B.Cu")
		(net "P3V3_SUS_NODE1")
	)
	(segment
		(start 76.53782 -86.762844)
		(end 76.53782 -85.82025)
		(width 0.508)
		(layer "B.Cu")
		(net "P3V3_SUS_NODE1")
	)
	(segment
		(start 73.614788 -84.605368)
		(end 74.606658 -84.605368)
		(width 0.508)
		(layer "B.Cu")
		(net "P3V3_SUS_NODE1")
	)
	(segment
		(start 79.11084 -101.295708)
		(end 79.11084 -107.793536)
		(width 0.508)
		(layer "In2.Cu")
		(net "P3V3_SUS_NODE1")
	)
	(segment
		(start 51.311048 -116.139214)
		(end 75.577192 -116.139214)
		(width 0.508)
		(layer "In2.Cu")
		(net "P3V3_SUS_NODE1")
	)
	(segment
		(start 81.41208 -98.994468)
		(end 79.11084 -101.295708)
		(width 0.508)
		(layer "In2.Cu")
		(net "P3V3_SUS_NODE1")
	)
	(segment
		(start 38.421564 -127.91948)
		(end 39.97198 -126.369064)
		(width 0.508)
		(layer "In2.Cu")
		(net "P3V3_SUS_NODE1")
	)
	(segment
		(start 38.602158 -135.051038)
		(end 38.421564 -134.870444)
		(width 0.508)
		(layer "In2.Cu")
		(net "P3V3_SUS_NODE1")
	)
	(segment
		(start 35.07486 -171.167298)
		(end 35.07486 -152.659588)
		(width 0.508)
		(layer "In2.Cu")
		(net "P3V3_SUS_NODE1")
	)
	(segment
		(start 35.07486 -152.659588)
		(end 34.65068 -152.235408)
		(width 0.508)
		(layer "In2.Cu")
		(net "P3V3_SUS_NODE1")
	)
	(segment
		(start 75.577192 -116.139214)
		(end 76.21016 -116.772182)
		(width 0.508)
		(layer "In2.Cu")
		(net "P3V3_SUS_NODE1")
	)
	(segment
		(start 47.6504 -119.799862)
		(end 51.311048 -116.139214)
		(width 0.508)
		(layer "In2.Cu")
		(net "P3V3_SUS_NODE1")
	)
	(segment
		(start 39.97198 -126.369064)
		(end 41.571418 -126.369064)
		(width 0.508)
		(layer "In2.Cu")
		(net "P3V3_SUS_NODE1")
	)
	(segment
		(start 35.87496 -138.305286)
		(end 38.602158 -135.578088)
		(width 0.508)
		(layer "In2.Cu")
		(net "P3V3_SUS_NODE1")
	)
	(segment
		(start 41.571418 -126.369064)
		(end 47.6504 -120.290082)
		(width 0.508)
		(layer "In2.Cu")
		(net "P3V3_SUS_NODE1")
	)
	(segment
		(start 35.07486 -151.811228)
		(end 35.07486 -143.920718)
		(width 0.508)
		(layer "In2.Cu")
		(net "P3V3_SUS_NODE1")
	)
	(segment
		(start 38.421564 -134.870444)
		(end 38.421564 -127.91948)
		(width 0.508)
		(layer "In2.Cu")
		(net "P3V3_SUS_NODE1")
	)
	(segment
		(start 35.87496 -143.120618)
		(end 35.87496 -138.305286)
		(width 0.508)
		(layer "In2.Cu")
		(net "P3V3_SUS_NODE1")
	)
	(segment
		(start 35.07486 -143.920718)
		(end 35.87496 -143.120618)
		(width 0.508)
		(layer "In2.Cu")
		(net "P3V3_SUS_NODE1")
	)
	(segment
		(start 79.11084 -107.793536)
		(end 78.59776 -108.306616)
		(width 0.508)
		(layer "In2.Cu")
		(net "P3V3_SUS_NODE1")
	)
	(segment
		(start 34.65068 -152.235408)
		(end 35.07486 -151.811228)
		(width 0.508)
		(layer "In2.Cu")
		(net "P3V3_SUS_NODE1")
	)
	(segment
		(start 35.58794 -171.680378)
		(end 35.07486 -171.167298)
		(width 0.508)
		(layer "In2.Cu")
		(net "P3V3_SUS_NODE1")
	)
	(segment
		(start 47.6504 -120.290082)
		(end 47.6504 -119.799862)
		(width 0.508)
		(layer "In2.Cu")
		(net "P3V3_SUS_NODE1")
	)
	(segment
		(start 81.41208 -95.413068)
		(end 81.41208 -98.994468)
		(width 0.508)
		(layer "In2.Cu")
		(net "P3V3_SUS_NODE1")
	)
	(segment
		(start 38.602158 -135.578088)
		(end 38.602158 -135.051038)
		(width 0.508)
		(layer "In2.Cu")
		(net "P3V3_SUS_NODE1")
	)
	(segment
		(start 14.65326 -37.363908)
		(end 15.97914 -36.038028)
		(width 0.508)
		(layer "In6.Cu")
		(net "P3V3_SUS_NODE1")
	)
	(segment
		(start 1.593088 -72.687688)
		(end 12.73556 -72.687688)
		(width 0.508)
		(layer "In6.Cu")
		(net "P3V3_SUS_NODE1")
	)
	(segment
		(start 13.29182 -72.131428)
		(end 13.29182 -69.431916)
		(width 0.508)
		(layer "In6.Cu")
		(net "P3V3_SUS_NODE1")
	)
	(segment
		(start 13.29182 -69.431916)
		(end 14.81836 -67.905376)
		(width 0.508)
		(layer "In6.Cu")
		(net "P3V3_SUS_NODE1")
	)
	(segment
		(start 1.11506 -73.165716)
		(end 1.593088 -72.687688)
		(width 0.508)
		(layer "In6.Cu")
		(net "P3V3_SUS_NODE1")
	)
	(segment
		(start 13.27404 -63.051182)
		(end 13.27404 -40.856408)
		(width 0.508)
		(layer "In6.Cu")
		(net "P3V3_SUS_NODE1")
	)
	(segment
		(start 14.81836 -64.595502)
		(end 13.27404 -63.051182)
		(width 0.508)
		(layer "In6.Cu")
		(net "P3V3_SUS_NODE1")
	)
	(segment
		(start 15.97914 -36.038028)
		(end 16.334486 -36.038028)
		(width 0.508)
		(layer "In6.Cu")
		(net "P3V3_SUS_NODE1")
	)
	(segment
		(start 1.11506 -135.579358)
		(end 1.11506 -73.165716)
		(width 0.508)
		(layer "In6.Cu")
		(net "P3V3_SUS_NODE1")
	)
	(segment
		(start 12.73556 -72.687688)
		(end 13.29182 -72.131428)
		(width 0.508)
		(layer "In6.Cu")
		(net "P3V3_SUS_NODE1")
	)
	(segment
		(start 13.27404 -40.856408)
		(end 14.65326 -39.477188)
		(width 0.508)
		(layer "In6.Cu")
		(net "P3V3_SUS_NODE1")
	)
	(segment
		(start 14.65326 -39.477188)
		(end 14.65326 -37.363908)
		(width 0.508)
		(layer "In6.Cu")
		(net "P3V3_SUS_NODE1")
	)
	(segment
		(start 14.81836 -67.905376)
		(end 14.81836 -64.595502)
		(width 0.508)
		(layer "In6.Cu")
		(net "P3V3_SUS_NODE1")
	)
	(segment
		(start 82.350102 -22.534372)
		(end 82.350102 -20.94992)
		(width 0.1651)
		(layer "F.Cu")
		(net "M1_DQ_NODE1_DQ32")
	)
	(segment
		(start 67.39636 -62.954916)
		(end 67.39636 -62.117986)
		(width 0.1016)
		(layer "F.Cu")
		(net "M1_DQ_NODE1_DQ32")
	)
	(segment
		(start 67.059048 -63.49492)
		(end 67.06108 -63.49492)
		(width 0.1016)
		(layer "F.Cu")
		(net "M1_DQ_NODE1_DQ32")
	)
	(segment
		(start 67.14744 -63.40856)
		(end 67.14744 -63.203836)
		(width 0.1016)
		(layer "F.Cu")
		(net "M1_DQ_NODE1_DQ32")
	)
	(segment
		(start 67.39636 -62.117986)
		(end 68.48602 -61.028326)
		(width 0.1016)
		(layer "F.Cu")
		(net "M1_DQ_NODE1_DQ32")
	)
	(segment
		(start 68.48602 -60.367418)
		(end 68.64604 -60.207398)
		(width 0.1016)
		(layer "F.Cu")
		(net "M1_DQ_NODE1_DQ32")
	)
	(segment
		(start 82.31378 -22.570694)
		(end 82.350102 -22.534372)
		(width 0.1651)
		(layer "F.Cu")
		(net "M1_DQ_NODE1_DQ32")
	)
	(segment
		(start 68.48602 -61.028326)
		(end 68.48602 -60.367418)
		(width 0.1016)
		(layer "F.Cu")
		(net "M1_DQ_NODE1_DQ32")
	)
	(segment
		(start 67.14744 -63.203836)
		(end 67.39636 -62.954916)
		(width 0.1016)
		(layer "F.Cu")
		(net "M1_DQ_NODE1_DQ32")
	)
	(segment
		(start 67.06108 -63.49492)
		(end 67.14744 -63.40856)
		(width 0.1016)
		(layer "F.Cu")
		(net "M1_DQ_NODE1_DQ32")
	)
	(via
		(at 68.64604 -60.207398)
		(size 0.508)
		(drill 0.254)
		(layers "F.Cu" "B.Cu")
		(net "M1_DQ_NODE1_DQ32")
	)
	(via
		(at 82.31378 -22.570694)
		(size 0.508)
		(drill 0.254)
		(layers "F.Cu" "B.Cu")
		(net "M1_DQ_NODE1_DQ32")
	)
	(segment
		(start 77.22616 -32.012636)
		(end 76.57338 -32.665416)
		(width 0.2032)
		(layer "In7.Cu")
		(net "M1_DQ_NODE1_DQ32")
	)
	(segment
		(start 74.092562 -34.144458)
		(end 73.797922 -34.144458)
		(width 0.2032)
		(layer "In7.Cu")
		(net "M1_DQ_NODE1_DQ32")
	)
	(segment
		(start 77.22616 -29.958284)
		(end 77.226414 -29.958284)
		(width 0.2032)
		(layer "In7.Cu")
		(net "M1_DQ_NODE1_DQ32")
	)
	(segment
		(start 77.22616 -31.78175)
		(end 77.22616 -32.012636)
		(width 0.2032)
		(layer "In7.Cu")
		(net "M1_DQ_NODE1_DQ32")
	)
	(segment
		(start 74.300842 -34.352738)
		(end 74.092562 -34.144458)
		(width 0.2032)
		(layer "In7.Cu")
		(net "M1_DQ_NODE1_DQ32")
	)
	(segment
		(start 80.836262 -22.854158)
		(end 80.836262 -22.356318)
		(width 0.2032)
		(layer "In7.Cu")
		(net "M1_DQ_NODE1_DQ32")
	)
	(segment
		(start 72.890888 -36.34486)
		(end 72.890888 -36.057332)
		(width 0.2032)
		(layer "In7.Cu")
		(net "M1_DQ_NODE1_DQ32")
	)
	(segment
		(start 67.40906 -58.733182)
		(end 68.64604 -59.970162)
		(width 0.2032)
		(layer "In7.Cu")
		(net "M1_DQ_NODE1_DQ32")
	)
	(segment
		(start 73.797922 -34.144458)
		(end 69.9643 -37.97808)
		(width 0.2032)
		(layer "In7.Cu")
		(net "M1_DQ_NODE1_DQ32")
	)
	(segment
		(start 68.64604 -59.970162)
		(end 68.64604 -60.207398)
		(width 0.2032)
		(layer "In7.Cu")
		(net "M1_DQ_NODE1_DQ32")
	)
	(segment
		(start 69.9643 -37.97808)
		(end 69.9643 -40.388286)
		(width 0.2032)
		(layer "In7.Cu")
		(net "M1_DQ_NODE1_DQ32")
	)
	(segment
		(start 75.76566 -33.24225)
		(end 75.76566 -34.1884)
		(width 0.2032)
		(layer "In7.Cu")
		(net "M1_DQ_NODE1_DQ32")
	)
	(segment
		(start 72.890888 -36.057332)
		(end 74.300842 -34.647378)
		(width 0.2032)
		(layer "In7.Cu")
		(net "M1_DQ_NODE1_DQ32")
	)
	(segment
		(start 82.31378 -22.570694)
		(end 81.781396 -23.103078)
		(width 0.2032)
		(layer "In7.Cu")
		(net "M1_DQ_NODE1_DQ32")
	)
	(segment
		(start 75.76566 -34.1884)
		(end 73.393808 -36.560252)
		(width 0.2032)
		(layer "In7.Cu")
		(net "M1_DQ_NODE1_DQ32")
	)
	(segment
		(start 77.22616 -27.949906)
		(end 77.22616 -29.958284)
		(width 0.2032)
		(layer "In7.Cu")
		(net "M1_DQ_NODE1_DQ32")
	)
	(segment
		(start 77.867002 -23.006558)
		(end 77.867002 -27.309064)
		(width 0.2032)
		(layer "In7.Cu")
		(net "M1_DQ_NODE1_DQ32")
	)
	(segment
		(start 67.40906 -42.943526)
		(end 67.40906 -58.733182)
		(width 0.2032)
		(layer "In7.Cu")
		(net "M1_DQ_NODE1_DQ32")
	)
	(segment
		(start 73.393808 -36.560252)
		(end 73.10628 -36.560252)
		(width 0.2032)
		(layer "In7.Cu")
		(net "M1_DQ_NODE1_DQ32")
	)
	(segment
		(start 76.57338 -32.666432)
		(end 76.341478 -32.666432)
		(width 0.2032)
		(layer "In7.Cu")
		(net "M1_DQ_NODE1_DQ32")
	)
	(segment
		(start 81.085182 -23.103078)
		(end 80.836262 -22.854158)
		(width 0.2032)
		(layer "In7.Cu")
		(net "M1_DQ_NODE1_DQ32")
	)
	(segment
		(start 69.9643 -40.388286)
		(end 67.40906 -42.943526)
		(width 0.2032)
		(layer "In7.Cu")
		(net "M1_DQ_NODE1_DQ32")
	)
	(segment
		(start 81.781396 -23.103078)
		(end 81.085182 -23.103078)
		(width 0.2032)
		(layer "In7.Cu")
		(net "M1_DQ_NODE1_DQ32")
	)
	(segment
		(start 80.836262 -22.356318)
		(end 80.297782 -21.817838)
		(width 0.2032)
		(layer "In7.Cu")
		(net "M1_DQ_NODE1_DQ32")
	)
	(segment
		(start 77.226414 -31.781496)
		(end 77.22616 -31.78175)
		(width 0.2032)
		(layer "In7.Cu")
		(net "M1_DQ_NODE1_DQ32")
	)
	(segment
		(start 74.300842 -34.647378)
		(end 74.300842 -34.352738)
		(width 0.2032)
		(layer "In7.Cu")
		(net "M1_DQ_NODE1_DQ32")
	)
	(segment
		(start 79.055722 -21.817838)
		(end 77.867002 -23.006558)
		(width 0.2032)
		(layer "In7.Cu")
		(net "M1_DQ_NODE1_DQ32")
	)
	(segment
		(start 80.297782 -21.817838)
		(end 79.055722 -21.817838)
		(width 0.2032)
		(layer "In7.Cu")
		(net "M1_DQ_NODE1_DQ32")
	)
	(segment
		(start 76.341478 -32.666432)
		(end 75.76566 -33.24225)
		(width 0.2032)
		(layer "In7.Cu")
		(net "M1_DQ_NODE1_DQ32")
	)
	(segment
		(start 77.226414 -29.958284)
		(end 77.226414 -31.781496)
		(width 0.2032)
		(layer "In7.Cu")
		(net "M1_DQ_NODE1_DQ32")
	)
	(segment
		(start 73.10628 -36.560252)
		(end 72.890888 -36.34486)
		(width 0.2032)
		(layer "In7.Cu")
		(net "M1_DQ_NODE1_DQ32")
	)
	(segment
		(start 76.57338 -32.665416)
		(end 76.57338 -32.666432)
		(width 0.2032)
		(layer "In7.Cu")
		(net "M1_DQ_NODE1_DQ32")
	)
	(segment
		(start 77.867002 -27.309064)
		(end 77.22616 -27.949906)
		(width 0.2032)
		(layer "In7.Cu")
		(net "M1_DQ_NODE1_DQ32")
	)
	(segment
		(start 84.150708 -107.827064)
		(end 84.09686 -107.773216)
		(width 0.1016)
		(layer "F.Cu")
		(net "FM_CPLD_NODE1_P3V3_SUS_EN_G")
	)
	(segment
		(start 84.150708 -108.39958)
		(end 84.150708 -107.827064)
		(width 0.1016)
		(layer "F.Cu")
		(net "FM_CPLD_NODE1_P3V3_SUS_EN_G")
	)
	(segment
		(start 83.564476 -106.487468)
		(end 83.564476 -105.569766)
		(width 0.1016)
		(layer "F.Cu")
		(net "FM_CPLD_NODE1_P3V3_SUS_EN_G")
	)
	(segment
		(start 84.09686 -107.773216)
		(end 84.09686 -107.019852)
		(width 0.1016)
		(layer "F.Cu")
		(net "FM_CPLD_NODE1_P3V3_SUS_EN_G")
	)
	(segment
		(start 84.09686 -107.019852)
		(end 83.564476 -106.487468)
		(width 0.1016)
		(layer "F.Cu")
		(net "FM_CPLD_NODE1_P3V3_SUS_EN_G")
	)
	(via
		(at 84.09686 -107.773216)
		(size 0.508)
		(drill 0.254)
		(layers "F.Cu" "B.Cu")
		(net "FM_CPLD_NODE1_P3V3_SUS_EN_G")
	)
	(via
		(at 112.50168 -172.23613)
		(size 0.6604)
		(drill 0.3302)
		(layers "F.Cu" "B.Cu")
		(net "N21699571")
	)
	(segment
		(start 113.52276 -173.629574)
		(end 113.52276 -172.564298)
		(width 0.1016)
		(layer "B.Cu")
		(net "N21699571")
	)
	(segment
		(start 112.50168 -172.23613)
		(end 111.99368 -172.23613)
		(width 0.1016)
		(layer "B.Cu")
		(net "N21699571")
	)
	(segment
		(start 111.99368 -172.23613)
		(end 111.724186 -172.505624)
		(width 0.1016)
		(layer "B.Cu")
		(net "N21699571")
	)
	(segment
		(start 111.724186 -172.505624)
		(end 110.84941 -172.505624)
		(width 0.1016)
		(layer "B.Cu")
		(net "N21699571")
	)
	(segment
		(start 113.194592 -172.23613)
		(end 112.50168 -172.23613)
		(width 0.1016)
		(layer "B.Cu")
		(net "N21699571")
	)
	(segment
		(start 113.52276 -172.564298)
		(end 113.194592 -172.23613)
		(width 0.1016)
		(layer "B.Cu")
		(net "N21699571")
	)
	(segment
		(start 154.624278 -66.16573)
		(end 151.204676 -66.16573)
		(width 0.10414)
		(layer "F.Cu")
		(net "SATA_A_NODE1_TX_P0")
	)
	(segment
		(start 150.382986 -65.957958)
		(end 150.590758 -66.16573)
		(width 0.10414)
		(layer "F.Cu")
		(net "SATA_A_NODE1_TX_P0")
	)
	(segment
		(start 154.956764 -66.498216)
		(end 154.624278 -66.16573)
		(width 0.10414)
		(layer "F.Cu")
		(net "SATA_A_NODE1_TX_P0")
	)
	(segment
		(start 149.57171 -65.957958)
		(end 150.382986 -65.957958)
		(width 0.10414)
		(layer "F.Cu")
		(net "SATA_A_NODE1_TX_P0")
	)
	(segment
		(start 150.590758 -66.16573)
		(end 151.204676 -66.16573)
		(width 0.10414)
		(layer "F.Cu")
		(net "SATA_A_NODE1_TX_P0")
	)
	(via
		(at 151.204676 -66.16573)
		(size 0.4064)
		(drill 0.2032)
		(layers "F.Cu" "B.Cu")
		(net "SATA_A_NODE1_TX_P0")
	)
	(segment
		(start 65.341754 -128.859534)
		(end 65.341754 -128.859026)
		(width 0.1016)
		(layer "F.Cu")
		(net "BMC_ROMA8")
	)
	(segment
		(start 65.341754 -128.859026)
		(end 64.940942 -128.458214)
		(width 0.1016)
		(layer "F.Cu")
		(net "BMC_ROMA8")
	)
	(via
		(at 64.940942 -128.458214)
		(size 0.49022)
		(drill 0.254)
		(layers "F.Cu" "B.Cu")
		(net "BMC_ROMA8")
	)
	(via
		(at 65.229486 -126.022862)
		(size 0.6604)
		(drill 0.3302)
		(layers "F.Cu" "B.Cu")
		(net "BMC_ROMA8")
	)
	(segment
		(start 65.559686 -123.330462)
		(end 65.559686 -123.787662)
		(width 0.1016)
		(layer "B.Cu")
		(net "BMC_ROMA8")
	)
	(segment
		(start 64.940942 -128.458214)
		(end 64.940942 -128.241806)
		(width 0.1016)
		(layer "B.Cu")
		(net "BMC_ROMA8")
	)
	(segment
		(start 66.702686 -118.942612)
		(end 66.702686 -122.187462)
		(width 0.1016)
		(layer "B.Cu")
		(net "BMC_ROMA8")
	)
	(segment
		(start 65.229486 -127.318262)
		(end 65.229486 -126.022862)
		(width 0.1016)
		(layer "B.Cu")
		(net "BMC_ROMA8")
	)
	(segment
		(start 66.702686 -122.187462)
		(end 65.559686 -123.330462)
		(width 0.1016)
		(layer "B.Cu")
		(net "BMC_ROMA8")
	)
	(segment
		(start 65.356486 -127.445262)
		(end 65.229486 -127.318262)
		(width 0.1016)
		(layer "B.Cu")
		(net "BMC_ROMA8")
	)
	(segment
		(start 65.559686 -123.787662)
		(end 65.229486 -124.117862)
		(width 0.1016)
		(layer "B.Cu")
		(net "BMC_ROMA8")
	)
	(segment
		(start 64.940942 -128.241806)
		(end 65.356486 -127.826262)
		(width 0.1016)
		(layer "B.Cu")
		(net "BMC_ROMA8")
	)
	(segment
		(start 65.356486 -127.826262)
		(end 65.356486 -127.445262)
		(width 0.1016)
		(layer "B.Cu")
		(net "BMC_ROMA8")
	)
	(segment
		(start 65.229486 -124.117862)
		(end 65.229486 -126.022862)
		(width 0.1016)
		(layer "B.Cu")
		(net "BMC_ROMA8")
	)
	(segment
		(start 67.286886 -118.358412)
		(end 66.702686 -118.942612)
		(width 0.1016)
		(layer "B.Cu")
		(net "BMC_ROMA8")
	)
	(segment
		(start 84.450174 -30.20441)
		(end 85.075522 -30.829758)
		(width 0.1016)
		(layer "F.Cu")
		(net "PD_NODE1_DM4")
	)
	(segment
		(start 85.075522 -31.716218)
		(end 84.222082 -32.569658)
		(width 0.1016)
		(layer "F.Cu")
		(net "PD_NODE1_DM4")
	)
	(segment
		(start 84.450174 -29.149802)
		(end 84.450174 -30.20441)
		(width 0.1016)
		(layer "F.Cu")
		(net "PD_NODE1_DM4")
	)
	(segment
		(start 84.222082 -32.569658)
		(end 84.222082 -32.694118)
		(width 0.1016)
		(layer "F.Cu")
		(net "PD_NODE1_DM4")
	)
	(segment
		(start 85.075522 -30.829758)
		(end 85.075522 -31.716218)
		(width 0.1016)
		(layer "F.Cu")
		(net "PD_NODE1_DM4")
	)
	(via
		(at 84.222082 -32.694118)
		(size 0.508)
		(drill 0.254)
		(layers "F.Cu" "B.Cu")
		(net "PD_NODE1_DM4")
	)
	(segment
		(start 85.292692 -29.793438)
		(end 85.292692 -31.623508)
		(width 0.1016)
		(layer "B.Cu")
		(net "PD_NODE1_DM4")
	)
	(segment
		(start 85.292692 -31.623508)
		(end 84.222082 -32.694118)
		(width 0.1016)
		(layer "B.Cu")
		(net "PD_NODE1_DM4")
	)
	(segment
		(start 74.071226 -96.309942)
		(end 73.311766 -95.550482)
		(width 0.1016)
		(layer "F.Cu")
		(net "H_CPU_NODE1_ERR2_R")
	)
	(segment
		(start 66.953892 -88.416638)
		(end 67.424808 -88.887554)
		(width 0.1016)
		(layer "F.Cu")
		(net "H_CPU_NODE1_ERR2_R")
	)
	(segment
		(start 74.353166 -96.309942)
		(end 74.071226 -96.309942)
		(width 0.1016)
		(layer "F.Cu")
		(net "H_CPU_NODE1_ERR2_R")
	)
	(segment
		(start 67.424808 -90.607896)
		(end 69.028564 -92.211652)
		(width 0.1016)
		(layer "F.Cu")
		(net "H_CPU_NODE1_ERR2_R")
	)
	(segment
		(start 73.311766 -95.550482)
		(end 73.236074 -95.550482)
		(width 0.1016)
		(layer "F.Cu")
		(net "H_CPU_NODE1_ERR2_R")
	)
	(segment
		(start 66.953892 -88.103964)
		(end 66.953892 -88.416638)
		(width 0.1016)
		(layer "F.Cu")
		(net "H_CPU_NODE1_ERR2_R")
	)
	(segment
		(start 67.424808 -88.887554)
		(end 67.424808 -90.607896)
		(width 0.1016)
		(layer "F.Cu")
		(net "H_CPU_NODE1_ERR2_R")
	)
	(segment
		(start 73.236074 -95.550482)
		(end 72.7837 -95.098108)
		(width 0.1016)
		(layer "F.Cu")
		(net "H_CPU_NODE1_ERR2_R")
	)
	(segment
		(start 71.059294 -92.211652)
		(end 72.73036 -93.882718)
		(width 0.1016)
		(layer "F.Cu")
		(net "H_CPU_NODE1_ERR2_R")
	)
	(segment
		(start 72.73036 -93.882718)
		(end 72.73036 -95.044768)
		(width 0.1016)
		(layer "F.Cu")
		(net "H_CPU_NODE1_ERR2_R")
	)
	(segment
		(start 72.73036 -95.044768)
		(end 72.7837 -95.098108)
		(width 0.1016)
		(layer "F.Cu")
		(net "H_CPU_NODE1_ERR2_R")
	)
	(segment
		(start 69.028564 -92.211652)
		(end 71.059294 -92.211652)
		(width 0.1016)
		(layer "F.Cu")
		(net "H_CPU_NODE1_ERR2_R")
	)
	(via
		(at 72.7837 -95.098108)
		(size 0.508)
		(drill 0.254)
		(layers "F.Cu" "B.Cu")
		(net "H_CPU_NODE1_ERR2_R")
	)
	(segment
		(start 70.31355 -93.222318)
		(end 70.31355 -94.38005)
		(width 0.1016)
		(layer "B.Cu")
		(net "H_CPU_NODE1_ERR2_R")
	)
	(segment
		(start 70.31355 -94.38005)
		(end 71.221854 -95.288354)
		(width 0.1016)
		(layer "B.Cu")
		(net "H_CPU_NODE1_ERR2_R")
	)
	(segment
		(start 71.221854 -95.288354)
		(end 72.593454 -95.288354)
		(width 0.1016)
		(layer "B.Cu")
		(net "H_CPU_NODE1_ERR2_R")
	)
	(segment
		(start 72.593454 -95.288354)
		(end 72.7837 -95.098108)
		(width 0.1016)
		(layer "B.Cu")
		(net "H_CPU_NODE1_ERR2_R")
	)
	(segment
		(start 85.5599 -96.604328)
		(end 85.5599 -98.02876)
		(width 0.1016)
		(layer "F.Cu")
		(net "FM_CPLD_NODE1_P3V3_SUS_EN_LV")
	)
	(segment
		(start 82.440272 -103.395526)
		(end 82.614516 -103.56977)
		(width 0.1016)
		(layer "F.Cu")
		(net "FM_CPLD_NODE1_P3V3_SUS_EN_LV")
	)
	(segment
		(start 84.253324 -96.604836)
		(end 84.439506 -96.604836)
		(width 0.1016)
		(layer "F.Cu")
		(net "FM_CPLD_NODE1_P3V3_SUS_EN_LV")
	)
	(segment
		(start 80.502252 -103.395526)
		(end 82.440272 -103.395526)
		(width 0.1016)
		(layer "F.Cu")
		(net "FM_CPLD_NODE1_P3V3_SUS_EN_LV")
	)
	(segment
		(start 82.936588 -97.921572)
		(end 84.253324 -96.604836)
		(width 0.1016)
		(layer "F.Cu")
		(net "FM_CPLD_NODE1_P3V3_SUS_EN_LV")
	)
	(segment
		(start 82.936588 -98.076766)
		(end 82.936588 -97.921572)
		(width 0.1016)
		(layer "F.Cu")
		(net "FM_CPLD_NODE1_P3V3_SUS_EN_LV")
	)
	(segment
		(start 85.5599 -98.02876)
		(end 84.73948 -98.84918)
		(width 0.1016)
		(layer "F.Cu")
		(net "FM_CPLD_NODE1_P3V3_SUS_EN_LV")
	)
	(segment
		(start 85.5599 -96.604328)
		(end 84.439506 -96.604328)
		(width 0.1016)
		(layer "F.Cu")
		(net "FM_CPLD_NODE1_P3V3_SUS_EN_LV")
	)
	(segment
		(start 83.657948 -103.56977)
		(end 82.614516 -103.56977)
		(width 0.1016)
		(layer "F.Cu")
		(net "FM_CPLD_NODE1_P3V3_SUS_EN_LV")
	)
	(segment
		(start 84.73948 -102.488238)
		(end 83.657948 -103.56977)
		(width 0.1016)
		(layer "F.Cu")
		(net "FM_CPLD_NODE1_P3V3_SUS_EN_LV")
	)
	(segment
		(start 84.439506 -96.604328)
		(end 84.439506 -96.604836)
		(width 0.1016)
		(layer "F.Cu")
		(net "FM_CPLD_NODE1_P3V3_SUS_EN_LV")
	)
	(segment
		(start 84.73948 -98.84918)
		(end 84.73948 -102.488238)
		(width 0.1016)
		(layer "F.Cu")
		(net "FM_CPLD_NODE1_P3V3_SUS_EN_LV")
	)
	(via
		(at 85.5599 -96.604328)
		(size 0.508)
		(drill 0.254)
		(layers "F.Cu" "B.Cu")
		(net "FM_CPLD_NODE1_P3V3_SUS_EN_LV")
	)
	(segment
		(start 64.899032 -117.442742)
		(end 64.520572 -117.064282)
		(width 0.1016)
		(layer "F.Cu")
		(net "BMC_ROMA22")
	)
	(segment
		(start 66.141854 -126.459488)
		(end 65.386458 -125.704092)
		(width 0.1016)
		(layer "F.Cu")
		(net "BMC_ROMA22")
	)
	(segment
		(start 64.391286 -117.991636)
		(end 63.982092 -117.582442)
		(width 0.1016)
		(layer "F.Cu")
		(net "BMC_ROMA22")
	)
	(segment
		(start 65.107566 -122.131074)
		(end 64.847216 -122.131074)
		(width 0.1016)
		(layer "F.Cu")
		(net "BMC_ROMA22")
	)
	(segment
		(start 64.391286 -121.675144)
		(end 64.391286 -117.991636)
		(width 0.1016)
		(layer "F.Cu")
		(net "BMC_ROMA22")
	)
	(segment
		(start 64.520572 -117.064282)
		(end 63.95212 -117.064282)
		(width 0.1016)
		(layer "F.Cu")
		(net "BMC_ROMA22")
	)
	(segment
		(start 63.982092 -117.582442)
		(end 63.982092 -117.094254)
		(width 0.1016)
		(layer "F.Cu")
		(net "BMC_ROMA22")
	)
	(segment
		(start 64.899286 -117.966998)
		(end 64.899032 -117.966744)
		(width 0.1016)
		(layer "F.Cu")
		(net "BMC_ROMA22")
	)
	(segment
		(start 64.899286 -118.358412)
		(end 64.899286 -117.966998)
		(width 0.1016)
		(layer "F.Cu")
		(net "BMC_ROMA22")
	)
	(segment
		(start 64.899032 -117.966744)
		(end 64.899032 -117.442742)
		(width 0.1016)
		(layer "F.Cu")
		(net "BMC_ROMA22")
	)
	(segment
		(start 65.386458 -122.409966)
		(end 65.107566 -122.131074)
		(width 0.1016)
		(layer "F.Cu")
		(net "BMC_ROMA22")
	)
	(segment
		(start 64.847216 -122.131074)
		(end 64.391286 -121.675144)
		(width 0.1016)
		(layer "F.Cu")
		(net "BMC_ROMA22")
	)
	(segment
		(start 65.386458 -125.704092)
		(end 65.386458 -122.409966)
		(width 0.1016)
		(layer "F.Cu")
		(net "BMC_ROMA22")
	)
	(segment
		(start 63.982092 -117.094254)
		(end 63.95212 -117.064282)
		(width 0.1016)
		(layer "F.Cu")
		(net "BMC_ROMA22")
	)
	(via
		(at 63.95212 -117.064282)
		(size 0.508)
		(drill 0.254)
		(layers "F.Cu" "B.Cu")
		(net "BMC_ROMA22")
	)
	(segment
		(start 78.75016 -23.071836)
		(end 79.134462 -23.456138)
		(width 0.2286)
		(layer "F.Cu")
		(net "M_DDR3_NODE1_WE_L")
	)
	(segment
		(start 64.561974 -60.449206)
		(end 64.561974 -59.568334)
		(width 0.1016)
		(layer "F.Cu")
		(net "M_DDR3_NODE1_WE_L")
	)
	(segment
		(start 63.233554 -62.675516)
		(end 63.233554 -61.777626)
		(width 0.1016)
		(layer "F.Cu")
		(net "M_DDR3_NODE1_WE_L")
	)
	(segment
		(start 63.233554 -61.777626)
		(end 64.561974 -60.449206)
		(width 0.1016)
		(layer "F.Cu")
		(net "M_DDR3_NODE1_WE_L")
	)
	(segment
		(start 78.75016 -20.94992)
		(end 78.75016 -23.071836)
		(width 0.2286)
		(layer "F.Cu")
		(net "M_DDR3_NODE1_WE_L")
	)
	(segment
		(start 63.28664 -64.047878)
		(end 63.28664 -63.89243)
		(width 0.1016)
		(layer "F.Cu")
		(net "M_DDR3_NODE1_WE_L")
	)
	(segment
		(start 63.002668 -62.906402)
		(end 63.233554 -62.675516)
		(width 0.1016)
		(layer "F.Cu")
		(net "M_DDR3_NODE1_WE_L")
	)
	(segment
		(start 63.166498 -63.307722)
		(end 63.002668 -63.143892)
		(width 0.1016)
		(layer "F.Cu")
		(net "M_DDR3_NODE1_WE_L")
	)
	(segment
		(start 63.28664 -63.89243)
		(end 63.166498 -63.772288)
		(width 0.1016)
		(layer "F.Cu")
		(net "M_DDR3_NODE1_WE_L")
	)
	(segment
		(start 63.002668 -63.143892)
		(end 63.002668 -62.906402)
		(width 0.1016)
		(layer "F.Cu")
		(net "M_DDR3_NODE1_WE_L")
	)
	(segment
		(start 63.166498 -63.772288)
		(end 63.166498 -63.307722)
		(width 0.1016)
		(layer "F.Cu")
		(net "M_DDR3_NODE1_WE_L")
	)
	(via
		(at 79.134462 -23.456138)
		(size 0.508)
		(drill 0.254)
		(layers "F.Cu" "B.Cu")
		(net "M_DDR3_NODE1_WE_L")
	)
	(via
		(at 64.561974 -59.568334)
		(size 0.508)
		(drill 0.254)
		(layers "F.Cu" "B.Cu")
		(net "M_DDR3_NODE1_WE_L")
	)
	(segment
		(start 73.776332 -51.62931)
		(end 73.776332 -51.93411)
		(width 0.2286)
		(layer "In2.Cu")
		(net "M_DDR3_NODE1_WE_L")
	)
	(segment
		(start 80.815942 -34.761678)
		(end 80.815942 -36.533836)
		(width 0.2286)
		(layer "In2.Cu")
		(net "M_DDR3_NODE1_WE_L")
	)
	(segment
		(start 80.21574 -38.743636)
		(end 80.431386 -38.959282)
		(width 0.2286)
		(layer "In2.Cu")
		(net "M_DDR3_NODE1_WE_L")
	)
	(segment
		(start 78.415134 -48.711104)
		(end 78.19898 -48.927258)
		(width 0.2286)
		(layer "In2.Cu")
		(net "M_DDR3_NODE1_WE_L")
	)
	(segment
		(start 73.973182 -52.435506)
		(end 73.757028 -52.65166)
		(width 0.2286)
		(layer "In2.Cu")
		(net "M_DDR3_NODE1_WE_L")
	)
	(segment
		(start 79.240888 -47.88535)
		(end 78.936088 -47.88535)
		(width 0.2286)
		(layer "In2.Cu")
		(net "M_DDR3_NODE1_WE_L")
	)
	(segment
		(start 79.228696 -47.13605)
		(end 79.457042 -47.364396)
		(width 0.2286)
		(layer "In2.Cu")
		(net "M_DDR3_NODE1_WE_L")
	)
	(segment
		(start 80.155542 -30.588966)
		(end 80.41132 -30.844744)
		(width 0.2286)
		(layer "In2.Cu")
		(net "M_DDR3_NODE1_WE_L")
	)
	(segment
		(start 80.600296 -36.749482)
		(end 80.431386 -36.749482)
		(width 0.2286)
		(layer "In2.Cu")
		(net "M_DDR3_NODE1_WE_L")
	)
	(segment
		(start 76.319126 -49.74082)
		(end 76.102972 -49.956974)
		(width 0.2286)
		(layer "In2.Cu")
		(net "M_DDR3_NODE1_WE_L")
	)
	(segment
		(start 78.19898 -48.927258)
		(end 77.89418 -48.927258)
		(width 0.2286)
		(layer "In2.Cu")
		(net "M_DDR3_NODE1_WE_L")
	)
	(segment
		(start 65.551558 -59.118754)
		(end 64.967866 -59.118754)
		(width 0.1016)
		(layer "In2.Cu")
		(net "M_DDR3_NODE1_WE_L")
	)
	(segment
		(start 80.431386 -37.486082)
		(end 80.600296 -37.486082)
		(width 0.2286)
		(layer "In2.Cu")
		(net "M_DDR3_NODE1_WE_L")
	)
	(segment
		(start 80.815942 -38.007036)
		(end 80.600296 -38.222682)
		(width 0.2286)
		(layer "In2.Cu")
		(net "M_DDR3_NODE1_WE_L")
	)
	(segment
		(start 76.029058 -51.09718)
		(end 75.54087 -51.09718)
		(width 0.2286)
		(layer "In2.Cu")
		(net "M_DDR3_NODE1_WE_L")
	)
	(segment
		(start 78.415134 -48.406304)
		(end 78.415134 -48.711104)
		(width 0.2286)
		(layer "In2.Cu")
		(net "M_DDR3_NODE1_WE_L")
	)
	(segment
		(start 80.431386 -40.432482)
		(end 80.600296 -40.432482)
		(width 0.2286)
		(layer "In2.Cu")
		(net "M_DDR3_NODE1_WE_L")
	)
	(segment
		(start 79.457042 -47.669196)
		(end 79.240888 -47.88535)
		(width 0.2286)
		(layer "In2.Cu")
		(net "M_DDR3_NODE1_WE_L")
	)
	(segment
		(start 76.331318 -50.79492)
		(end 76.029058 -51.09718)
		(width 0.2286)
		(layer "In2.Cu")
		(net "M_DDR3_NODE1_WE_L")
	)
	(segment
		(start 80.0862 -24.457152)
		(end 80.0862 -25.864566)
		(width 0.2286)
		(layer "In2.Cu")
		(net "M_DDR3_NODE1_WE_L")
	)
	(segment
		(start 74.736706 -50.668936)
		(end 73.776332 -51.62931)
		(width 0.2286)
		(layer "In2.Cu")
		(net "M_DDR3_NODE1_WE_L")
	)
	(segment
		(start 79.228696 -46.83125)
		(end 79.228696 -47.13605)
		(width 0.2286)
		(layer "In2.Cu")
		(net "M_DDR3_NODE1_WE_L")
	)
	(segment
		(start 80.21574 -37.270436)
		(end 80.431386 -37.486082)
		(width 0.2286)
		(layer "In2.Cu")
		(net "M_DDR3_NODE1_WE_L")
	)
	(segment
		(start 70.387464 -53.493162)
		(end 67.42938 -56.451246)
		(width 0.2286)
		(layer "In2.Cu")
		(net "M_DDR3_NODE1_WE_L")
	)
	(segment
		(start 80.600296 -38.959282)
		(end 80.815942 -39.174928)
		(width 0.2286)
		(layer "In2.Cu")
		(net "M_DDR3_NODE1_WE_L")
	)
	(segment
		(start 79.977996 -46.843442)
		(end 79.74965 -46.615096)
		(width 0.2286)
		(layer "In2.Cu")
		(net "M_DDR3_NODE1_WE_L")
	)
	(segment
		(start 64.561974 -59.524646)
		(end 64.561974 -59.568334)
		(width 0.1016)
		(layer "In2.Cu")
		(net "M_DDR3_NODE1_WE_L")
	)
	(segment
		(start 79.72552 -30.158944)
		(end 80.15478 -30.588204)
		(width 0.2286)
		(layer "In2.Cu")
		(net "M_DDR3_NODE1_WE_L")
	)
	(segment
		(start 77.157072 -49.969166)
		(end 76.852272 -49.969166)
		(width 0.2286)
		(layer "In2.Cu")
		(net "M_DDR3_NODE1_WE_L")
	)
	(segment
		(start 79.134462 -23.456138)
		(end 79.365602 -23.687278)
		(width 0.2286)
		(layer "In2.Cu")
		(net "M_DDR3_NODE1_WE_L")
	)
	(segment
		(start 77.373226 -49.448212)
		(end 77.373226 -49.753012)
		(width 0.2286)
		(layer "In2.Cu")
		(net "M_DDR3_NODE1_WE_L")
	)
	(segment
		(start 67.42938 -56.451246)
		(end 67.42938 -56.954166)
		(width 0.2286)
		(layer "In2.Cu")
		(net "M_DDR3_NODE1_WE_L")
	)
	(segment
		(start 77.361034 -48.698912)
		(end 77.14488 -48.915066)
		(width 0.2286)
		(layer "In2.Cu")
		(net "M_DDR3_NODE1_WE_L")
	)
	(segment
		(start 67.42938 -57.240932)
		(end 65.551558 -59.118754)
		(width 0.1016)
		(layer "In2.Cu")
		(net "M_DDR3_NODE1_WE_L")
	)
	(segment
		(start 79.365602 -23.687278)
		(end 79.365602 -23.736554)
		(width 0.2286)
		(layer "In2.Cu")
		(net "M_DDR3_NODE1_WE_L")
	)
	(segment
		(start 73.757028 -52.65166)
		(end 73.452228 -52.65166)
		(width 0.2286)
		(layer "In2.Cu")
		(net "M_DDR3_NODE1_WE_L")
	)
	(segment
		(start 80.203802 -34.149538)
		(end 80.815942 -34.761678)
		(width 0.2286)
		(layer "In2.Cu")
		(net "M_DDR3_NODE1_WE_L")
	)
	(segment
		(start 80.600296 -37.486082)
		(end 80.815942 -37.701728)
		(width 0.2286)
		(layer "In2.Cu")
		(net "M_DDR3_NODE1_WE_L")
	)
	(segment
		(start 67.42938 -56.954166)
		(end 67.42938 -57.240932)
		(width 0.1016)
		(layer "In2.Cu")
		(net "M_DDR3_NODE1_WE_L")
	)
	(segment
		(start 73.973182 -52.130706)
		(end 73.973182 -52.435506)
		(width 0.2286)
		(layer "In2.Cu")
		(net "M_DDR3_NODE1_WE_L")
	)
	(segment
		(start 73.776332 -51.93411)
		(end 73.973182 -52.130706)
		(width 0.2286)
		(layer "In2.Cu")
		(net "M_DDR3_NODE1_WE_L")
	)
	(segment
		(start 80.431386 -38.222682)
		(end 80.21574 -38.438328)
		(width 0.2286)
		(layer "In2.Cu")
		(net "M_DDR3_NODE1_WE_L")
	)
	(segment
		(start 80.815942 -39.174928)
		(end 80.815942 -39.480236)
		(width 0.2286)
		(layer "In2.Cu")
		(net "M_DDR3_NODE1_WE_L")
	)
	(segment
		(start 78.402942 -47.657004)
		(end 78.186788 -47.873158)
		(width 0.2286)
		(layer "In2.Cu")
		(net "M_DDR3_NODE1_WE_L")
	)
	(segment
		(start 77.373226 -49.753012)
		(end 77.157072 -49.969166)
		(width 0.2286)
		(layer "In2.Cu")
		(net "M_DDR3_NODE1_WE_L")
	)
	(segment
		(start 77.665834 -48.698912)
		(end 77.361034 -48.698912)
		(width 0.2286)
		(layer "In2.Cu")
		(net "M_DDR3_NODE1_WE_L")
	)
	(segment
		(start 76.852272 -49.969166)
		(end 76.623926 -49.74082)
		(width 0.2286)
		(layer "In2.Cu")
		(net "M_DDR3_NODE1_WE_L")
	)
	(segment
		(start 79.365602 -23.736554)
		(end 80.0862 -24.457152)
		(width 0.2286)
		(layer "In2.Cu")
		(net "M_DDR3_NODE1_WE_L")
	)
	(segment
		(start 80.815942 -37.701728)
		(end 80.815942 -38.007036)
		(width 0.2286)
		(layer "In2.Cu")
		(net "M_DDR3_NODE1_WE_L")
	)
	(segment
		(start 80.600296 -38.222682)
		(end 80.431386 -38.222682)
		(width 0.2286)
		(layer "In2.Cu")
		(net "M_DDR3_NODE1_WE_L")
	)
	(segment
		(start 80.815942 -36.533836)
		(end 80.600296 -36.749482)
		(width 0.2286)
		(layer "In2.Cu")
		(net "M_DDR3_NODE1_WE_L")
	)
	(segment
		(start 80.815942 -39.480236)
		(end 80.600296 -39.695882)
		(width 0.2286)
		(layer "In2.Cu")
		(net "M_DDR3_NODE1_WE_L")
	)
	(segment
		(start 75.112626 -50.668936)
		(end 74.736706 -50.668936)
		(width 0.2286)
		(layer "In2.Cu")
		(net "M_DDR3_NODE1_WE_L")
	)
	(segment
		(start 77.14488 -48.915066)
		(end 77.14488 -49.219866)
		(width 0.2286)
		(layer "In2.Cu")
		(net "M_DDR3_NODE1_WE_L")
	)
	(segment
		(start 76.102972 -50.261774)
		(end 76.331318 -50.49012)
		(width 0.2286)
		(layer "In2.Cu")
		(net "M_DDR3_NODE1_WE_L")
	)
	(segment
		(start 80.600296 -40.432482)
		(end 80.815942 -40.648128)
		(width 0.2286)
		(layer "In2.Cu")
		(net "M_DDR3_NODE1_WE_L")
	)
	(segment
		(start 80.815942 -40.648128)
		(end 80.815942 -46.310296)
		(width 0.2286)
		(layer "In2.Cu")
		(net "M_DDR3_NODE1_WE_L")
	)
	(segment
		(start 72.950578 -52.455064)
		(end 71.91248 -53.493162)
		(width 0.2286)
		(layer "In2.Cu")
		(net "M_DDR3_NODE1_WE_L")
	)
	(segment
		(start 80.15478 -30.588966)
		(end 80.155542 -30.588966)
		(width 0.2286)
		(layer "In2.Cu")
		(net "M_DDR3_NODE1_WE_L")
	)
	(segment
		(start 78.186788 -47.873158)
		(end 78.186788 -48.177958)
		(width 0.2286)
		(layer "In2.Cu")
		(net "M_DDR3_NODE1_WE_L")
	)
	(segment
		(start 77.14488 -49.219866)
		(end 77.373226 -49.448212)
		(width 0.2286)
		(layer "In2.Cu")
		(net "M_DDR3_NODE1_WE_L")
	)
	(segment
		(start 73.255378 -52.455064)
		(end 72.950578 -52.455064)
		(width 0.2286)
		(layer "In2.Cu")
		(net "M_DDR3_NODE1_WE_L")
	)
	(segment
		(start 80.21574 -38.438328)
		(end 80.21574 -38.743636)
		(width 0.2286)
		(layer "In2.Cu")
		(net "M_DDR3_NODE1_WE_L")
	)
	(segment
		(start 80.0862 -25.864566)
		(end 79.72552 -26.225246)
		(width 0.2286)
		(layer "In2.Cu")
		(net "M_DDR3_NODE1_WE_L")
	)
	(segment
		(start 78.707742 -47.657004)
		(end 78.402942 -47.657004)
		(width 0.2286)
		(layer "In2.Cu")
		(net "M_DDR3_NODE1_WE_L")
	)
	(segment
		(start 80.431386 -36.749482)
		(end 80.21574 -36.965128)
		(width 0.2286)
		(layer "In2.Cu")
		(net "M_DDR3_NODE1_WE_L")
	)
	(segment
		(start 79.74965 -46.615096)
		(end 79.44485 -46.615096)
		(width 0.2286)
		(layer "In2.Cu")
		(net "M_DDR3_NODE1_WE_L")
	)
	(segment
		(start 80.41132 -30.844744)
		(end 80.41132 -31.72714)
		(width 0.2286)
		(layer "In2.Cu")
		(net "M_DDR3_NODE1_WE_L")
	)
	(segment
		(start 80.431386 -38.959282)
		(end 80.600296 -38.959282)
		(width 0.2286)
		(layer "In2.Cu")
		(net "M_DDR3_NODE1_WE_L")
	)
	(segment
		(start 75.54087 -51.09718)
		(end 75.112626 -50.668936)
		(width 0.2286)
		(layer "In2.Cu")
		(net "M_DDR3_NODE1_WE_L")
	)
	(segment
		(start 80.420718 -31.736538)
		(end 80.203802 -31.953454)
		(width 0.2286)
		(layer "In2.Cu")
		(net "M_DDR3_NODE1_WE_L")
	)
	(segment
		(start 77.89418 -48.927258)
		(end 77.665834 -48.698912)
		(width 0.2286)
		(layer "In2.Cu")
		(net "M_DDR3_NODE1_WE_L")
	)
	(segment
		(start 78.936088 -47.88535)
		(end 78.707742 -47.657004)
		(width 0.2286)
		(layer "In2.Cu")
		(net "M_DDR3_NODE1_WE_L")
	)
	(segment
		(start 79.72552 -26.225246)
		(end 79.72552 -30.158944)
		(width 0.2286)
		(layer "In2.Cu")
		(net "M_DDR3_NODE1_WE_L")
	)
	(segment
		(start 71.91248 -53.493162)
		(end 70.387464 -53.493162)
		(width 0.2286)
		(layer "In2.Cu")
		(net "M_DDR3_NODE1_WE_L")
	)
	(segment
		(start 80.15478 -30.588204)
		(end 80.15478 -30.588966)
		(width 0.2286)
		(layer "In2.Cu")
		(net "M_DDR3_NODE1_WE_L")
	)
	(segment
		(start 76.623926 -49.74082)
		(end 76.319126 -49.74082)
		(width 0.2286)
		(layer "In2.Cu")
		(net "M_DDR3_NODE1_WE_L")
	)
	(segment
		(start 64.967866 -59.118754)
		(end 64.561974 -59.524646)
		(width 0.1016)
		(layer "In2.Cu")
		(net "M_DDR3_NODE1_WE_L")
	)
	(segment
		(start 80.41132 -31.72714)
		(end 80.420718 -31.736538)
		(width 0.2286)
		(layer "In2.Cu")
		(net "M_DDR3_NODE1_WE_L")
	)
	(segment
		(start 80.282796 -46.843442)
		(end 79.977996 -46.843442)
		(width 0.2286)
		(layer "In2.Cu")
		(net "M_DDR3_NODE1_WE_L")
	)
	(segment
		(start 80.203802 -31.953454)
		(end 80.203802 -34.149538)
		(width 0.2286)
		(layer "In2.Cu")
		(net "M_DDR3_NODE1_WE_L")
	)
	(segment
		(start 80.21574 -39.911528)
		(end 80.21574 -40.216836)
		(width 0.2286)
		(layer "In2.Cu")
		(net "M_DDR3_NODE1_WE_L")
	)
	(segment
		(start 80.21574 -40.216836)
		(end 80.431386 -40.432482)
		(width 0.2286)
		(layer "In2.Cu")
		(net "M_DDR3_NODE1_WE_L")
	)
	(segment
		(start 80.431386 -39.695882)
		(end 80.21574 -39.911528)
		(width 0.2286)
		(layer "In2.Cu")
		(net "M_DDR3_NODE1_WE_L")
	)
	(segment
		(start 73.452228 -52.65166)
		(end 73.255378 -52.455064)
		(width 0.2286)
		(layer "In2.Cu")
		(net "M_DDR3_NODE1_WE_L")
	)
	(segment
		(start 76.331318 -50.49012)
		(end 76.331318 -50.79492)
		(width 0.2286)
		(layer "In2.Cu")
		(net "M_DDR3_NODE1_WE_L")
	)
	(segment
		(start 80.600296 -39.695882)
		(end 80.431386 -39.695882)
		(width 0.2286)
		(layer "In2.Cu")
		(net "M_DDR3_NODE1_WE_L")
	)
	(segment
		(start 79.457042 -47.364396)
		(end 79.457042 -47.669196)
		(width 0.2286)
		(layer "In2.Cu")
		(net "M_DDR3_NODE1_WE_L")
	)
	(segment
		(start 79.44485 -46.615096)
		(end 79.228696 -46.83125)
		(width 0.2286)
		(layer "In2.Cu")
		(net "M_DDR3_NODE1_WE_L")
	)
	(segment
		(start 80.815942 -46.310296)
		(end 80.282796 -46.843442)
		(width 0.2286)
		(layer "In2.Cu")
		(net "M_DDR3_NODE1_WE_L")
	)
	(segment
		(start 78.186788 -48.177958)
		(end 78.415134 -48.406304)
		(width 0.2286)
		(layer "In2.Cu")
		(net "M_DDR3_NODE1_WE_L")
	)
	(segment
		(start 80.21574 -36.965128)
		(end 80.21574 -37.270436)
		(width 0.2286)
		(layer "In2.Cu")
		(net "M_DDR3_NODE1_WE_L")
	)
	(segment
		(start 76.102972 -49.956974)
		(end 76.102972 -50.261774)
		(width 0.2286)
		(layer "In2.Cu")
		(net "M_DDR3_NODE1_WE_L")
	)
	(segment
		(start 81.940146 -107.097322)
		(end 81.940146 -106.552492)
		(width 0.1016)
		(layer "F.Cu")
		(net "FM_CPLD_NODE1_P3V3_SUS_EN")
	)
	(segment
		(start 81.940146 -107.097322)
		(end 81.940146 -108.09859)
		(width 0.1016)
		(layer "F.Cu")
		(net "FM_CPLD_NODE1_P3V3_SUS_EN")
	)
	(segment
		(start 171.857162 -117.212364)
		(end 168.12133 -117.212364)
		(width 0.1016)
		(layer "F.Cu")
		(net "FM_CPLD_NODE1_P3V3_SUS_EN")
	)
	(segment
		(start 81.664556 -106.276902)
		(end 81.664556 -105.569766)
		(width 0.1016)
		(layer "F.Cu")
		(net "FM_CPLD_NODE1_P3V3_SUS_EN")
	)
	(segment
		(start 172.010324 -117.365526)
		(end 171.857162 -117.212364)
		(width 0.1016)
		(layer "F.Cu")
		(net "FM_CPLD_NODE1_P3V3_SUS_EN")
	)
	(segment
		(start 81.940146 -106.552492)
		(end 81.664556 -106.276902)
		(width 0.1016)
		(layer "F.Cu")
		(net "FM_CPLD_NODE1_P3V3_SUS_EN")
	)
	(segment
		(start 81.940146 -108.09859)
		(end 81.940146 -109.114082)
		(width 0.1016)
		(layer "F.Cu")
		(net "FM_CPLD_NODE1_P3V3_SUS_EN")
	)
	(segment
		(start 168.12133 -117.212364)
		(end 164.40912 -113.500154)
		(width 0.1016)
		(layer "F.Cu")
		(net "FM_CPLD_NODE1_P3V3_SUS_EN")
	)
	(segment
		(start 81.940146 -109.114082)
		(end 81.940146 -109.85627)
		(width 0.1016)
		(layer "F.Cu")
		(net "FM_CPLD_NODE1_P3V3_SUS_EN")
	)
	(via
		(at 81.940146 -109.85627)
		(size 0.508)
		(drill 0.254)
		(layers "F.Cu" "B.Cu")
		(net "FM_CPLD_NODE1_P3V3_SUS_EN")
	)
	(via
		(at 139.31138 -96.044258)
		(size 0.508)
		(drill 0.254)
		(layers "F.Cu" "B.Cu")
		(net "FM_CPLD_NODE1_P3V3_SUS_EN")
	)
	(via
		(at 164.40912 -113.500154)
		(size 0.508)
		(drill 0.254)
		(layers "F.Cu" "B.Cu")
		(net "FM_CPLD_NODE1_P3V3_SUS_EN")
	)
	(via
		(at 88.67394 -95.444818)
		(size 0.508)
		(drill 0.254)
		(layers "F.Cu" "B.Cu")
		(net "FM_CPLD_NODE1_P3V3_SUS_EN")
	)
	(segment
		(start 84.93252 -107.557316)
		(end 84.93252 -97.955608)
		(width 0.1143)
		(layer "In2.Cu")
		(net "FM_CPLD_NODE1_P3V3_SUS_EN")
	)
	(segment
		(start 87.353902 -95.534226)
		(end 88.584532 -95.534226)
		(width 0.1143)
		(layer "In2.Cu")
		(net "FM_CPLD_NODE1_P3V3_SUS_EN")
	)
	(segment
		(start 81.940146 -109.791246)
		(end 83.370928 -108.360464)
		(width 0.1143)
		(layer "In2.Cu")
		(net "FM_CPLD_NODE1_P3V3_SUS_EN")
	)
	(segment
		(start 88.584532 -95.534226)
		(end 88.67394 -95.444818)
		(width 0.1143)
		(layer "In2.Cu")
		(net "FM_CPLD_NODE1_P3V3_SUS_EN")
	)
	(segment
		(start 84.93252 -97.955608)
		(end 87.353902 -95.534226)
		(width 0.1143)
		(layer "In2.Cu")
		(net "FM_CPLD_NODE1_P3V3_SUS_EN")
	)
	(segment
		(start 83.370928 -108.360464)
		(end 84.129372 -108.360464)
		(width 0.1143)
		(layer "In2.Cu")
		(net "FM_CPLD_NODE1_P3V3_SUS_EN")
	)
	(segment
		(start 84.129372 -108.360464)
		(end 84.93252 -107.557316)
		(width 0.1143)
		(layer "In2.Cu")
		(net "FM_CPLD_NODE1_P3V3_SUS_EN")
	)
	(segment
		(start 81.940146 -109.85627)
		(end 81.940146 -109.791246)
		(width 0.1143)
		(layer "In2.Cu")
		(net "FM_CPLD_NODE1_P3V3_SUS_EN")
	)
	(segment
		(start 125.801374 -90.919046)
		(end 98.095054 -90.919046)
		(width 0.1143)
		(layer "In6.Cu")
		(net "FM_CPLD_NODE1_P3V3_SUS_EN")
	)
	(segment
		(start 135.784082 -92.51696)
		(end 127.399288 -92.51696)
		(width 0.1143)
		(layer "In6.Cu")
		(net "FM_CPLD_NODE1_P3V3_SUS_EN")
	)
	(segment
		(start 139.31138 -96.044258)
		(end 135.784082 -92.51696)
		(width 0.1143)
		(layer "In6.Cu")
		(net "FM_CPLD_NODE1_P3V3_SUS_EN")
	)
	(segment
		(start 98.095054 -90.919046)
		(end 92.80144 -96.21266)
		(width 0.1143)
		(layer "In6.Cu")
		(net "FM_CPLD_NODE1_P3V3_SUS_EN")
	)
	(segment
		(start 88.91905 -95.444818)
		(end 88.67394 -95.444818)
		(width 0.1143)
		(layer "In6.Cu")
		(net "FM_CPLD_NODE1_P3V3_SUS_EN")
	)
	(segment
		(start 127.399288 -92.51696)
		(end 125.801374 -90.919046)
		(width 0.1143)
		(layer "In6.Cu")
		(net "FM_CPLD_NODE1_P3V3_SUS_EN")
	)
	(segment
		(start 92.80144 -96.21266)
		(end 89.686892 -96.21266)
		(width 0.1143)
		(layer "In6.Cu")
		(net "FM_CPLD_NODE1_P3V3_SUS_EN")
	)
	(segment
		(start 89.686892 -96.21266)
		(end 88.91905 -95.444818)
		(width 0.1143)
		(layer "In6.Cu")
		(net "FM_CPLD_NODE1_P3V3_SUS_EN")
	)
	(segment
		(start 162.328352 -111.407956)
		(end 164.40912 -113.488724)
		(width 0.1143)
		(layer "In7.Cu")
		(net "FM_CPLD_NODE1_P3V3_SUS_EN")
	)
	(segment
		(start 164.40912 -113.488724)
		(end 164.40912 -113.500154)
		(width 0.1143)
		(layer "In7.Cu")
		(net "FM_CPLD_NODE1_P3V3_SUS_EN")
	)
	(segment
		(start 141.905228 -96.044258)
		(end 157.268926 -111.407956)
		(width 0.1143)
		(layer "In7.Cu")
		(net "FM_CPLD_NODE1_P3V3_SUS_EN")
	)
	(segment
		(start 139.31138 -96.044258)
		(end 141.905228 -96.044258)
		(width 0.1143)
		(layer "In7.Cu")
		(net "FM_CPLD_NODE1_P3V3_SUS_EN")
	)
	(segment
		(start 157.268926 -111.407956)
		(end 162.328352 -111.407956)
		(width 0.1143)
		(layer "In7.Cu")
		(net "FM_CPLD_NODE1_P3V3_SUS_EN")
	)
	(segment
		(start 90.150188 -22.237192)
		(end 89.843102 -22.544278)
		(width 0.1651)
		(layer "F.Cu")
		(net "M1_DQ_NODE1_DQ42")
	)
	(segment
		(start 70.388226 -66.217038)
		(end 70.951344 -66.780156)
		(width 0.1016)
		(layer "F.Cu")
		(net "M1_DQ_NODE1_DQ42")
	)
	(segment
		(start 89.843102 -22.544278)
		(end 89.843102 -23.636478)
		(width 0.1651)
		(layer "F.Cu")
		(net "M1_DQ_NODE1_DQ42")
	)
	(segment
		(start 70.951344 -66.780156)
		(end 70.951344 -67.25793)
		(width 0.1016)
		(layer "F.Cu")
		(net "M1_DQ_NODE1_DQ42")
	)
	(segment
		(start 90.150188 -20.94992)
		(end 90.150188 -22.237192)
		(width 0.1651)
		(layer "F.Cu")
		(net "M1_DQ_NODE1_DQ42")
	)
	(via
		(at 70.951344 -67.25793)
		(size 0.508)
		(drill 0.254)
		(layers "F.Cu" "B.Cu")
		(net "M1_DQ_NODE1_DQ42")
	)
	(via
		(at 89.843102 -23.636478)
		(size 0.508)
		(drill 0.254)
		(layers "F.Cu" "B.Cu")
		(net "M1_DQ_NODE1_DQ42")
	)
	(segment
		(start 93.08338 -42.332656)
		(end 93.08338 -41.916096)
		(width 0.2032)
		(layer "In2.Cu")
		(net "M1_DQ_NODE1_DQ42")
	)
	(segment
		(start 93.37802 -49.604676)
		(end 93.37802 -44.049696)
		(width 0.2032)
		(layer "In2.Cu")
		(net "M1_DQ_NODE1_DQ42")
	)
	(segment
		(start 93.37802 -41.204896)
		(end 93.08338 -40.910256)
		(width 0.2032)
		(layer "In2.Cu")
		(net "M1_DQ_NODE1_DQ42")
	)
	(segment
		(start 93.08338 -39.071296)
		(end 93.37802 -38.776656)
		(width 0.2032)
		(layer "In2.Cu")
		(net "M1_DQ_NODE1_DQ42")
	)
	(segment
		(start 75.395074 -64.915034)
		(end 76.539598 -64.915034)
		(width 0.1016)
		(layer "In2.Cu")
		(net "M1_DQ_NODE1_DQ42")
	)
	(segment
		(start 90.9447 -25.763474)
		(end 89.843102 -24.661876)
		(width 0.2032)
		(layer "In2.Cu")
		(net "M1_DQ_NODE1_DQ42")
	)
	(segment
		(start 92.07627 -26.776426)
		(end 91.294204 -26.776426)
		(width 0.2032)
		(layer "In2.Cu")
		(net "M1_DQ_NODE1_DQ42")
	)
	(segment
		(start 92.44076 -27.140916)
		(end 92.07627 -26.776426)
		(width 0.2032)
		(layer "In2.Cu")
		(net "M1_DQ_NODE1_DQ42")
	)
	(segment
		(start 93.37802 -38.776656)
		(end 93.37802 -38.360096)
		(width 0.2032)
		(layer "In2.Cu")
		(net "M1_DQ_NODE1_DQ42")
	)
	(segment
		(start 93.08338 -43.338496)
		(end 93.37802 -43.043856)
		(width 0.2032)
		(layer "In2.Cu")
		(net "M1_DQ_NODE1_DQ42")
	)
	(segment
		(start 93.37802 -44.049696)
		(end 93.08338 -43.755056)
		(width 0.2032)
		(layer "In2.Cu")
		(net "M1_DQ_NODE1_DQ42")
	)
	(segment
		(start 93.37802 -41.621456)
		(end 93.37802 -41.204896)
		(width 0.2032)
		(layer "In2.Cu")
		(net "M1_DQ_NODE1_DQ42")
	)
	(segment
		(start 93.37802 -42.627296)
		(end 93.08338 -42.332656)
		(width 0.2032)
		(layer "In2.Cu")
		(net "M1_DQ_NODE1_DQ42")
	)
	(segment
		(start 93.37802 -37.354256)
		(end 93.37802 -36.937696)
		(width 0.2032)
		(layer "In2.Cu")
		(net "M1_DQ_NODE1_DQ42")
	)
	(segment
		(start 78.387194 -60.996068)
		(end 81.986628 -60.996068)
		(width 0.2032)
		(layer "In2.Cu")
		(net "M1_DQ_NODE1_DQ42")
	)
	(segment
		(start 71.946262 -67.512438)
		(end 72.251316 -67.207384)
		(width 0.1016)
		(layer "In2.Cu")
		(net "M1_DQ_NODE1_DQ42")
	)
	(segment
		(start 71.205344 -67.512438)
		(end 71.946262 -67.512438)
		(width 0.1016)
		(layer "In2.Cu")
		(net "M1_DQ_NODE1_DQ42")
	)
	(segment
		(start 91.4019 -30.159706)
		(end 92.44076 -29.120846)
		(width 0.2032)
		(layer "In2.Cu")
		(net "M1_DQ_NODE1_DQ42")
	)
	(segment
		(start 93.08338 -36.226496)
		(end 93.37802 -35.931856)
		(width 0.2032)
		(layer "In2.Cu")
		(net "M1_DQ_NODE1_DQ42")
	)
	(segment
		(start 92.44076 -29.120846)
		(end 92.44076 -27.140916)
		(width 0.2032)
		(layer "In2.Cu")
		(net "M1_DQ_NODE1_DQ42")
	)
	(segment
		(start 93.37802 -36.937696)
		(end 93.08338 -36.643056)
		(width 0.2032)
		(layer "In2.Cu")
		(net "M1_DQ_NODE1_DQ42")
	)
	(segment
		(start 93.08338 -43.755056)
		(end 93.08338 -43.338496)
		(width 0.2032)
		(layer "In2.Cu")
		(net "M1_DQ_NODE1_DQ42")
	)
	(segment
		(start 93.37802 -35.931856)
		(end 93.37802 -34.489136)
		(width 0.2032)
		(layer "In2.Cu")
		(net "M1_DQ_NODE1_DQ42")
	)
	(segment
		(start 93.37802 -40.199056)
		(end 93.37802 -39.782496)
		(width 0.2032)
		(layer "In2.Cu")
		(net "M1_DQ_NODE1_DQ42")
	)
	(segment
		(start 73.102724 -67.207384)
		(end 75.395074 -64.915034)
		(width 0.1016)
		(layer "In2.Cu")
		(net "M1_DQ_NODE1_DQ42")
	)
	(segment
		(start 76.722224 -64.732408)
		(end 76.93152 -64.523112)
		(width 0.2032)
		(layer "In2.Cu")
		(net "M1_DQ_NODE1_DQ42")
	)
	(segment
		(start 93.08338 -41.916096)
		(end 93.37802 -41.621456)
		(width 0.2032)
		(layer "In2.Cu")
		(net "M1_DQ_NODE1_DQ42")
	)
	(segment
		(start 93.08338 -38.065456)
		(end 93.08338 -37.648896)
		(width 0.2032)
		(layer "In2.Cu")
		(net "M1_DQ_NODE1_DQ42")
	)
	(segment
		(start 90.9447 -26.426922)
		(end 90.9447 -25.763474)
		(width 0.2032)
		(layer "In2.Cu")
		(net "M1_DQ_NODE1_DQ42")
	)
	(segment
		(start 91.4019 -32.513016)
		(end 91.4019 -30.159706)
		(width 0.2032)
		(layer "In2.Cu")
		(net "M1_DQ_NODE1_DQ42")
	)
	(segment
		(start 70.951344 -67.25793)
		(end 71.205344 -67.51193)
		(width 0.1016)
		(layer "In2.Cu")
		(net "M1_DQ_NODE1_DQ42")
	)
	(segment
		(start 93.08338 -36.643056)
		(end 93.08338 -36.226496)
		(width 0.2032)
		(layer "In2.Cu")
		(net "M1_DQ_NODE1_DQ42")
	)
	(segment
		(start 93.08338 -40.493696)
		(end 93.37802 -40.199056)
		(width 0.2032)
		(layer "In2.Cu")
		(net "M1_DQ_NODE1_DQ42")
	)
	(segment
		(start 93.37802 -43.043856)
		(end 93.37802 -42.627296)
		(width 0.2032)
		(layer "In2.Cu")
		(net "M1_DQ_NODE1_DQ42")
	)
	(segment
		(start 93.37802 -39.782496)
		(end 93.08338 -39.487856)
		(width 0.2032)
		(layer "In2.Cu")
		(net "M1_DQ_NODE1_DQ42")
	)
	(segment
		(start 76.93152 -62.451742)
		(end 78.387194 -60.996068)
		(width 0.2032)
		(layer "In2.Cu")
		(net "M1_DQ_NODE1_DQ42")
	)
	(segment
		(start 72.251316 -67.207384)
		(end 73.102724 -67.207384)
		(width 0.1016)
		(layer "In2.Cu")
		(net "M1_DQ_NODE1_DQ42")
	)
	(segment
		(start 93.08338 -39.487856)
		(end 93.08338 -39.071296)
		(width 0.2032)
		(layer "In2.Cu")
		(net "M1_DQ_NODE1_DQ42")
	)
	(segment
		(start 81.986628 -60.996068)
		(end 93.37802 -49.604676)
		(width 0.2032)
		(layer "In2.Cu")
		(net "M1_DQ_NODE1_DQ42")
	)
	(segment
		(start 89.843102 -24.661876)
		(end 89.843102 -23.636478)
		(width 0.2032)
		(layer "In2.Cu")
		(net "M1_DQ_NODE1_DQ42")
	)
	(segment
		(start 91.294204 -26.776426)
		(end 90.9447 -26.426922)
		(width 0.2032)
		(layer "In2.Cu")
		(net "M1_DQ_NODE1_DQ42")
	)
	(segment
		(start 93.08338 -37.648896)
		(end 93.37802 -37.354256)
		(width 0.2032)
		(layer "In2.Cu")
		(net "M1_DQ_NODE1_DQ42")
	)
	(segment
		(start 76.539598 -64.915034)
		(end 76.722224 -64.732408)
		(width 0.1016)
		(layer "In2.Cu")
		(net "M1_DQ_NODE1_DQ42")
	)
	(segment
		(start 93.37802 -34.489136)
		(end 91.4019 -32.513016)
		(width 0.2032)
		(layer "In2.Cu")
		(net "M1_DQ_NODE1_DQ42")
	)
	(segment
		(start 93.37802 -38.360096)
		(end 93.08338 -38.065456)
		(width 0.2032)
		(layer "In2.Cu")
		(net "M1_DQ_NODE1_DQ42")
	)
	(segment
		(start 71.205344 -67.51193)
		(end 71.205344 -67.512438)
		(width 0.1016)
		(layer "In2.Cu")
		(net "M1_DQ_NODE1_DQ42")
	)
	(segment
		(start 93.08338 -40.910256)
		(end 93.08338 -40.493696)
		(width 0.2032)
		(layer "In2.Cu")
		(net "M1_DQ_NODE1_DQ42")
	)
	(segment
		(start 76.93152 -64.523112)
		(end 76.93152 -62.451742)
		(width 0.2032)
		(layer "In2.Cu")
		(net "M1_DQ_NODE1_DQ42")
	)
	(via
		(at 48.025558 -111.323374)
		(size 0.508)
		(drill 0.254)
		(layers "F.Cu" "B.Cu")
		(net "SW_P3V3_STB_NODE1_BT")
	)
	(segment
		(start 62.141862 -129.659634)
		(end 62.141862 -129.659126)
		(width 0.1016)
		(layer "F.Cu")
		(net "BMC_ROMA16")
	)
	(segment
		(start 62.141862 -129.659126)
		(end 61.74105 -129.258314)
		(width 0.1016)
		(layer "F.Cu")
		(net "BMC_ROMA16")
	)
	(via
		(at 61.74105 -129.258314)
		(size 0.49022)
		(drill 0.254)
		(layers "F.Cu" "B.Cu")
		(net "BMC_ROMA16")
	)
	(via
		(at 59.666886 -124.371862)
		(size 0.6604)
		(drill 0.3302)
		(layers "F.Cu" "B.Cu")
		(net "BMC_ROMA16")
	)
	(segment
		(start 61.74105 -129.258314)
		(end 61.503306 -129.258314)
		(width 0.1016)
		(layer "B.Cu")
		(net "BMC_ROMA16")
	)
	(segment
		(start 59.997086 -121.160032)
		(end 59.997086 -122.620532)
		(width 0.1016)
		(layer "B.Cu")
		(net "BMC_ROMA16")
	)
	(segment
		(start 60.54344 -126.925324)
		(end 59.666886 -126.04877)
		(width 0.1016)
		(layer "B.Cu")
		(net "BMC_ROMA16")
	)
	(segment
		(start 59.771026 -119.448072)
		(end 59.771026 -120.933972)
		(width 0.1016)
		(layer "B.Cu")
		(net "BMC_ROMA16")
	)
	(segment
		(start 59.997086 -122.620532)
		(end 59.666886 -122.950732)
		(width 0.1016)
		(layer "B.Cu")
		(net "BMC_ROMA16")
	)
	(segment
		(start 61.503306 -129.258314)
		(end 61.105796 -128.860804)
		(width 0.1016)
		(layer "B.Cu")
		(net "BMC_ROMA16")
	)
	(segment
		(start 59.666886 -122.950732)
		(end 59.666886 -124.371862)
		(width 0.1016)
		(layer "B.Cu")
		(net "BMC_ROMA16")
	)
	(segment
		(start 61.105796 -128.860804)
		(end 60.781184 -128.860804)
		(width 0.1016)
		(layer "B.Cu")
		(net "BMC_ROMA16")
	)
	(segment
		(start 60.54344 -128.62306)
		(end 60.54344 -126.925324)
		(width 0.1016)
		(layer "B.Cu")
		(net "BMC_ROMA16")
	)
	(segment
		(start 60.781184 -128.860804)
		(end 60.54344 -128.62306)
		(width 0.1016)
		(layer "B.Cu")
		(net "BMC_ROMA16")
	)
	(segment
		(start 59.771026 -120.933972)
		(end 59.997086 -121.160032)
		(width 0.1016)
		(layer "B.Cu")
		(net "BMC_ROMA16")
	)
	(segment
		(start 59.666886 -126.04877)
		(end 59.666886 -124.371862)
		(width 0.1016)
		(layer "B.Cu")
		(net "BMC_ROMA16")
	)
	(segment
		(start 48.29937 -85.000846)
		(end 48.300132 -85.000084)
		(width 0.1143)
		(layer "F.Cu")
		(net "PD_NODE1_NTB_CLKINP")
	)
	(segment
		(start 48.300132 -85.000084)
		(end 48.514 -85.000084)
		(width 0.1143)
		(layer "F.Cu")
		(net "PD_NODE1_NTB_CLKINP")
	)
	(segment
		(start 48.514 -85.000084)
		(end 48.77816 -84.735924)
		(width 0.1143)
		(layer "F.Cu")
		(net "PD_NODE1_NTB_CLKINP")
	)
	(via
		(at 48.77816 -84.735924)
		(size 0.508)
		(drill 0.254)
		(layers "F.Cu" "B.Cu")
		(net "PD_NODE1_NTB_CLKINP")
	)
	(segment
		(start 48.0695 -87.154004)
		(end 48.0695 -85.74532)
		(width 0.1016)
		(layer "B.Cu")
		(net "PD_NODE1_NTB_CLKINP")
	)
	(segment
		(start 48.0695 -85.74532)
		(end 48.77816 -85.03666)
		(width 0.1016)
		(layer "B.Cu")
		(net "PD_NODE1_NTB_CLKINP")
	)
	(segment
		(start 48.274732 -88.072976)
		(end 48.274732 -87.359236)
		(width 0.1016)
		(layer "B.Cu")
		(net "PD_NODE1_NTB_CLKINP")
	)
	(segment
		(start 48.77816 -85.03666)
		(end 48.77816 -84.735924)
		(width 0.1016)
		(layer "B.Cu")
		(net "PD_NODE1_NTB_CLKINP")
	)
	(segment
		(start 48.274732 -87.359236)
		(end 48.0695 -87.154004)
		(width 0.1016)
		(layer "B.Cu")
		(net "PD_NODE1_NTB_CLKINP")
	)
	(segment
		(start 63.511176 -62.848998)
		(end 63.511176 -61.862208)
		(width 0.1016)
		(layer "F.Cu")
		(net "M_DDR3_NODE1_CS0_L")
	)
	(segment
		(start 80.549242 -24.158956)
		(end 80.549242 -22.923754)
		(width 0.1651)
		(layer "F.Cu")
		(net "M_DDR3_NODE1_CS0_L")
	)
	(segment
		(start 63.511176 -61.862208)
		(end 63.976504 -61.39688)
		(width 0.1016)
		(layer "F.Cu")
		(net "M_DDR3_NODE1_CS0_L")
	)
	(segment
		(start 63.366396 -62.993778)
		(end 63.511176 -62.848998)
		(width 0.1016)
		(layer "F.Cu")
		(net "M_DDR3_NODE1_CS0_L")
	)
	(segment
		(start 80.549242 -22.923754)
		(end 80.550258 -22.923754)
		(width 0.1651)
		(layer "F.Cu")
		(net "M_DDR3_NODE1_CS0_L")
	)
	(segment
		(start 64.28867 -61.39688)
		(end 64.622172 -61.063378)
		(width 0.1016)
		(layer "F.Cu")
		(net "M_DDR3_NODE1_CS0_L")
	)
	(segment
		(start 80.550258 -22.923754)
		(end 80.550258 -20.94992)
		(width 0.1651)
		(layer "F.Cu")
		(net "M_DDR3_NODE1_CS0_L")
	)
	(segment
		(start 63.976504 -61.39688)
		(end 64.28867 -61.39688)
		(width 0.1016)
		(layer "F.Cu")
		(net "M_DDR3_NODE1_CS0_L")
	)
	(segment
		(start 80.76438 -24.374094)
		(end 80.549242 -24.158956)
		(width 0.1651)
		(layer "F.Cu")
		(net "M_DDR3_NODE1_CS0_L")
	)
	(via
		(at 80.76438 -24.374094)
		(size 0.508)
		(drill 0.254)
		(layers "F.Cu" "B.Cu")
		(net "M_DDR3_NODE1_CS0_L")
	)
	(via
		(at 64.622172 -61.063378)
		(size 0.508)
		(drill 0.254)
		(layers "F.Cu" "B.Cu")
		(net "M_DDR3_NODE1_CS0_L")
	)
	(segment
		(start 71.461376 -55.363618)
		(end 71.461376 -55.069486)
		(width 0.2032)
		(layer "In2.Cu")
		(net "M_DDR3_NODE1_CS0_L")
	)
	(segment
		(start 81.93024 -39.082726)
		(end 81.699862 -39.082726)
		(width 0.2032)
		(layer "In2.Cu")
		(net "M_DDR3_NODE1_CS0_L")
	)
	(segment
		(start 70.67042 -54.142386)
		(end 72.391778 -54.142386)
		(width 0.2032)
		(layer "In2.Cu")
		(net "M_DDR3_NODE1_CS0_L")
	)
	(segment
		(start 81.699862 -46.287182)
		(end 81.95056 -46.287182)
		(width 0.2032)
		(layer "In2.Cu")
		(net "M_DDR3_NODE1_CS0_L")
	)
	(segment
		(start 80.42402 -26.442924)
		(end 80.7339 -26.133044)
		(width 0.2032)
		(layer "In2.Cu")
		(net "M_DDR3_NODE1_CS0_L")
	)
	(segment
		(start 82.13852 -39.585646)
		(end 82.13852 -39.291006)
		(width 0.2032)
		(layer "In2.Cu")
		(net "M_DDR3_NODE1_CS0_L")
	)
	(segment
		(start 65.948052 -59.534044)
		(end 68.11264 -57.369456)
		(width 0.1016)
		(layer "In2.Cu")
		(net "M_DDR3_NODE1_CS0_L")
	)
	(segment
		(start 70.958202 -54.860698)
		(end 69.836792 -55.981854)
		(width 0.2032)
		(layer "In2.Cu")
		(net "M_DDR3_NODE1_CS0_L")
	)
	(segment
		(start 81.20634 -32.240728)
		(end 81.20634 -30.723586)
		(width 0.2032)
		(layer "In2.Cu")
		(net "M_DDR3_NODE1_CS0_L")
	)
	(segment
		(start 82.15884 -46.078902)
		(end 82.15884 -45.784262)
		(width 0.2032)
		(layer "In2.Cu")
		(net "M_DDR3_NODE1_CS0_L")
	)
	(segment
		(start 73.11136 -53.422804)
		(end 73.952862 -53.422804)
		(width 0.2032)
		(layer "In2.Cu")
		(net "M_DDR3_NODE1_CS0_L")
	)
	(segment
		(start 72.391778 -54.142386)
		(end 73.11136 -53.422804)
		(width 0.2032)
		(layer "In2.Cu")
		(net "M_DDR3_NODE1_CS0_L")
	)
	(segment
		(start 75.296268 -52.079398)
		(end 76.140818 -52.079398)
		(width 0.2032)
		(layer "In2.Cu")
		(net "M_DDR3_NODE1_CS0_L")
	)
	(segment
		(start 81.699862 -45.575982)
		(end 81.491582 -45.367702)
		(width 0.2032)
		(layer "In2.Cu")
		(net "M_DDR3_NODE1_CS0_L")
	)
	(segment
		(start 73.952862 -53.422804)
		(end 75.296268 -52.079398)
		(width 0.2032)
		(layer "In2.Cu")
		(net "M_DDR3_NODE1_CS0_L")
	)
	(segment
		(start 69.542152 -55.981854)
		(end 69.333872 -55.773574)
		(width 0.2032)
		(layer "In2.Cu")
		(net "M_DDR3_NODE1_CS0_L")
	)
	(segment
		(start 68.536312 -56.276494)
		(end 68.830952 -56.276494)
		(width 0.2032)
		(layer "In2.Cu")
		(net "M_DDR3_NODE1_CS0_L")
	)
	(segment
		(start 81.491582 -40.002206)
		(end 81.699862 -39.793926)
		(width 0.2032)
		(layer "In2.Cu")
		(net "M_DDR3_NODE1_CS0_L")
	)
	(segment
		(start 80.42402 -29.941266)
		(end 80.42402 -26.442924)
		(width 0.2032)
		(layer "In2.Cu")
		(net "M_DDR3_NODE1_CS0_L")
	)
	(segment
		(start 82.15884 -45.784262)
		(end 81.95056 -45.575982)
		(width 0.2032)
		(layer "In2.Cu")
		(net "M_DDR3_NODE1_CS0_L")
	)
	(segment
		(start 68.830952 -56.276494)
		(end 69.542152 -56.987694)
		(width 0.2032)
		(layer "In2.Cu")
		(net "M_DDR3_NODE1_CS0_L")
	)
	(segment
		(start 68.11264 -56.700166)
		(end 68.536312 -56.276494)
		(width 0.2032)
		(layer "In2.Cu")
		(net "M_DDR3_NODE1_CS0_L")
	)
	(segment
		(start 81.699862 -39.082726)
		(end 81.491582 -38.874446)
		(width 0.2032)
		(layer "In2.Cu")
		(net "M_DDR3_NODE1_CS0_L")
	)
	(segment
		(start 80.894682 -33.534858)
		(end 80.894682 -32.552386)
		(width 0.2032)
		(layer "In2.Cu")
		(net "M_DDR3_NODE1_CS0_L")
	)
	(segment
		(start 81.491582 -34.131758)
		(end 80.894682 -33.534858)
		(width 0.2032)
		(layer "In2.Cu")
		(net "M_DDR3_NODE1_CS0_L")
	)
	(segment
		(start 65.173098 -59.534044)
		(end 65.948052 -59.534044)
		(width 0.1016)
		(layer "In2.Cu")
		(net "M_DDR3_NODE1_CS0_L")
	)
	(segment
		(start 68.11264 -57.369456)
		(end 68.11264 -57.185052)
		(width 0.1016)
		(layer "In2.Cu")
		(net "M_DDR3_NODE1_CS0_L")
	)
	(segment
		(start 80.7339 -26.133044)
		(end 80.7339 -24.404574)
		(width 0.2032)
		(layer "In2.Cu")
		(net "M_DDR3_NODE1_CS0_L")
	)
	(segment
		(start 81.699862 -39.793926)
		(end 81.93024 -39.793926)
		(width 0.2032)
		(layer "In2.Cu")
		(net "M_DDR3_NODE1_CS0_L")
	)
	(segment
		(start 81.491582 -46.728634)
		(end 81.491582 -46.495462)
		(width 0.2032)
		(layer "In2.Cu")
		(net "M_DDR3_NODE1_CS0_L")
	)
	(segment
		(start 71.461376 -55.069486)
		(end 71.252588 -54.860698)
		(width 0.2032)
		(layer "In2.Cu")
		(net "M_DDR3_NODE1_CS0_L")
	)
	(segment
		(start 82.13852 -39.291006)
		(end 81.93024 -39.082726)
		(width 0.2032)
		(layer "In2.Cu")
		(net "M_DDR3_NODE1_CS0_L")
	)
	(segment
		(start 69.836792 -56.987694)
		(end 71.461376 -55.363618)
		(width 0.2032)
		(layer "In2.Cu")
		(net "M_DDR3_NODE1_CS0_L")
	)
	(segment
		(start 69.333872 -55.773574)
		(end 69.333872 -55.478934)
		(width 0.2032)
		(layer "In2.Cu")
		(net "M_DDR3_NODE1_CS0_L")
	)
	(segment
		(start 80.894682 -32.552386)
		(end 81.20634 -32.240728)
		(width 0.2032)
		(layer "In2.Cu")
		(net "M_DDR3_NODE1_CS0_L")
	)
	(segment
		(start 81.93024 -39.793926)
		(end 82.13852 -39.585646)
		(width 0.2032)
		(layer "In2.Cu")
		(net "M_DDR3_NODE1_CS0_L")
	)
	(segment
		(start 81.491582 -46.495462)
		(end 81.699862 -46.287182)
		(width 0.2032)
		(layer "In2.Cu")
		(net "M_DDR3_NODE1_CS0_L")
	)
	(segment
		(start 81.95056 -46.287182)
		(end 82.15884 -46.078902)
		(width 0.2032)
		(layer "In2.Cu")
		(net "M_DDR3_NODE1_CS0_L")
	)
	(segment
		(start 68.11264 -57.185052)
		(end 68.11264 -56.700166)
		(width 0.2032)
		(layer "In2.Cu")
		(net "M_DDR3_NODE1_CS0_L")
	)
	(segment
		(start 64.622172 -61.063378)
		(end 64.830198 -60.855352)
		(width 0.1016)
		(layer "In2.Cu")
		(net "M_DDR3_NODE1_CS0_L")
	)
	(segment
		(start 69.836792 -55.981854)
		(end 69.542152 -55.981854)
		(width 0.2032)
		(layer "In2.Cu")
		(net "M_DDR3_NODE1_CS0_L")
	)
	(segment
		(start 69.542152 -56.987694)
		(end 69.836792 -56.987694)
		(width 0.2032)
		(layer "In2.Cu")
		(net "M_DDR3_NODE1_CS0_L")
	)
	(segment
		(start 64.830198 -59.876944)
		(end 65.173098 -59.534044)
		(width 0.1016)
		(layer "In2.Cu")
		(net "M_DDR3_NODE1_CS0_L")
	)
	(segment
		(start 71.252588 -54.860698)
		(end 70.958202 -54.860698)
		(width 0.2032)
		(layer "In2.Cu")
		(net "M_DDR3_NODE1_CS0_L")
	)
	(segment
		(start 81.20634 -30.723586)
		(end 80.42402 -29.941266)
		(width 0.2032)
		(layer "In2.Cu")
		(net "M_DDR3_NODE1_CS0_L")
	)
	(segment
		(start 81.95056 -45.575982)
		(end 81.699862 -45.575982)
		(width 0.2032)
		(layer "In2.Cu")
		(net "M_DDR3_NODE1_CS0_L")
	)
	(segment
		(start 64.830198 -60.855352)
		(end 64.830198 -59.876944)
		(width 0.1016)
		(layer "In2.Cu")
		(net "M_DDR3_NODE1_CS0_L")
	)
	(segment
		(start 80.7339 -24.404574)
		(end 80.76438 -24.374094)
		(width 0.2032)
		(layer "In2.Cu")
		(net "M_DDR3_NODE1_CS0_L")
	)
	(segment
		(start 81.491582 -45.367702)
		(end 81.491582 -40.002206)
		(width 0.2032)
		(layer "In2.Cu")
		(net "M_DDR3_NODE1_CS0_L")
	)
	(segment
		(start 69.333872 -55.478934)
		(end 70.67042 -54.142386)
		(width 0.2032)
		(layer "In2.Cu")
		(net "M_DDR3_NODE1_CS0_L")
	)
	(segment
		(start 81.491582 -38.874446)
		(end 81.491582 -34.131758)
		(width 0.2032)
		(layer "In2.Cu")
		(net "M_DDR3_NODE1_CS0_L")
	)
	(segment
		(start 76.140818 -52.079398)
		(end 81.491582 -46.728634)
		(width 0.2032)
		(layer "In2.Cu")
		(net "M_DDR3_NODE1_CS0_L")
	)
	(segment
		(start 42.941748 -108.533184)
		(end 43.271694 -108.86313)
		(width 0.254)
		(layer "F.Cu")
		(net "P3V3_STB_NODE1_SS")
	)
	(segment
		(start 42.636694 -108.533184)
		(end 42.941748 -108.533184)
		(width 0.254)
		(layer "F.Cu")
		(net "P3V3_STB_NODE1_SS")
	)
	(segment
		(start 43.877992 -109.728)
		(end 43.271694 -109.121702)
		(width 0.254)
		(layer "F.Cu")
		(net "P3V3_STB_NODE1_SS")
	)
	(segment
		(start 44.383706 -109.728)
		(end 43.877992 -109.728)
		(width 0.254)
		(layer "F.Cu")
		(net "P3V3_STB_NODE1_SS")
	)
	(segment
		(start 43.271694 -109.121702)
		(end 43.271694 -108.86313)
		(width 0.254)
		(layer "F.Cu")
		(net "P3V3_STB_NODE1_SS")
	)
	(via
		(at 43.271694 -108.86313)
		(size 0.508)
		(drill 0.254)
		(layers "F.Cu" "B.Cu")
		(net "P3V3_STB_NODE1_SS")
	)
	(via
		(at 80.31226 -169.891202)
		(size 0.6604)
		(drill 0.3302)
		(layers "F.Cu" "B.Cu")
		(net "N21699285")
	)
	(segment
		(start 81.89976 -169.819574)
		(end 80.9371 -169.819574)
		(width 0.1016)
		(layer "B.Cu")
		(net "N21699285")
	)
	(segment
		(start 79.878682 -169.457624)
		(end 80.31226 -169.891202)
		(width 0.1016)
		(layer "B.Cu")
		(net "N21699285")
	)
	(segment
		(start 80.31226 -169.892472)
		(end 80.31226 -169.891202)
		(width 0.1016)
		(layer "B.Cu")
		(net "N21699285")
	)
	(segment
		(start 80.9371 -169.819574)
		(end 80.848962 -169.907712)
		(width 0.1016)
		(layer "B.Cu")
		(net "N21699285")
	)
	(segment
		(start 79.23149 -169.457624)
		(end 79.878682 -169.457624)
		(width 0.1016)
		(layer "B.Cu")
		(net "N21699285")
	)
	(segment
		(start 80.848962 -169.907712)
		(end 80.3275 -169.907712)
		(width 0.1016)
		(layer "B.Cu")
		(net "N21699285")
	)
	(segment
		(start 80.3275 -169.907712)
		(end 80.31226 -169.892472)
		(width 0.1016)
		(layer "B.Cu")
		(net "N21699285")
	)
	(segment
		(start 63.741808 -126.459488)
		(end 63.741808 -126.186184)
		(width 0.1016)
		(layer "F.Cu")
		(net "BMC_ROMA7")
	)
	(segment
		(start 61.605668 -122.120152)
		(end 61.605668 -122.405648)
		(width 0.1016)
		(layer "F.Cu")
		(net "BMC_ROMA7")
	)
	(segment
		(start 62.791086 -123.686062)
		(end 62.206124 -123.1011)
		(width 0.1016)
		(layer "F.Cu")
		(net "BMC_ROMA7")
	)
	(segment
		(start 62.206124 -123.006104)
		(end 62.07506 -122.87504)
		(width 0.1016)
		(layer "F.Cu")
		(net "BMC_ROMA7")
	)
	(segment
		(start 61.444886 -121.95937)
		(end 61.605668 -122.120152)
		(width 0.1016)
		(layer "F.Cu")
		(net "BMC_ROMA7")
	)
	(segment
		(start 62.206124 -123.1011)
		(end 62.206124 -123.006104)
		(width 0.1016)
		(layer "F.Cu")
		(net "BMC_ROMA7")
	)
	(segment
		(start 63.741808 -126.186184)
		(end 62.791086 -125.235462)
		(width 0.1016)
		(layer "F.Cu")
		(net "BMC_ROMA7")
	)
	(segment
		(start 61.605668 -122.405648)
		(end 62.07506 -122.87504)
		(width 0.1016)
		(layer "F.Cu")
		(net "BMC_ROMA7")
	)
	(segment
		(start 62.791086 -125.235462)
		(end 62.791086 -123.686062)
		(width 0.1016)
		(layer "F.Cu")
		(net "BMC_ROMA7")
	)
	(segment
		(start 61.444886 -121.444512)
		(end 61.444886 -121.95937)
		(width 0.1016)
		(layer "F.Cu")
		(net "BMC_ROMA7")
	)
	(via
		(at 62.07506 -122.87504)
		(size 0.762)
		(drill 0.381)
		(layers "F.Cu" "B.Cu")
		(net "BMC_ROMA7")
	)
	(segment
		(start 48.450246 -27.277822)
		(end 47.803562 -26.631138)
		(width 0.1016)
		(layer "F.Cu")
		(net "PD_NODE1_DM1")
	)
	(segment
		(start 48.450246 -29.149802)
		(end 48.450246 -27.277822)
		(width 0.1016)
		(layer "F.Cu")
		(net "PD_NODE1_DM1")
	)
	(segment
		(start 47.803562 -26.631138)
		(end 47.803562 -26.560018)
		(width 0.1016)
		(layer "F.Cu")
		(net "PD_NODE1_DM1")
	)
	(via
		(at 47.803562 -26.560018)
		(size 0.508)
		(drill 0.254)
		(layers "F.Cu" "B.Cu")
		(net "PD_NODE1_DM1")
	)
	(segment
		(start 48.259492 -28.696158)
		(end 48.259492 -27.015948)
		(width 0.1016)
		(layer "B.Cu")
		(net "PD_NODE1_DM1")
	)
	(segment
		(start 48.259492 -27.015948)
		(end 47.803562 -26.560018)
		(width 0.1016)
		(layer "B.Cu")
		(net "PD_NODE1_DM1")
	)
	(segment
		(start 78.613 -119.83085)
		(end 78.613 -116.58346)
		(width 0.1016)
		(layer "F.Cu")
		(net "PWRGD_NODE1_P5V_STB_PG")
	)
	(segment
		(start 78.14818 -120.29567)
		(end 78.613 -119.83085)
		(width 0.1016)
		(layer "F.Cu")
		(net "PWRGD_NODE1_P5V_STB_PG")
	)
	(segment
		(start 84.06384 -150.966678)
		(end 84.06384 -157.902656)
		(width 0.1016)
		(layer "F.Cu")
		(net "PWRGD_NODE1_P5V_STB_PG")
	)
	(segment
		(start 187.1218 -116.961666)
		(end 187.2869 -116.796566)
		(width 0.1016)
		(layer "F.Cu")
		(net "PWRGD_NODE1_P5V_STB_PG")
	)
	(segment
		(start 81.519268 -148.422106)
		(end 84.06384 -150.966678)
		(width 0.1016)
		(layer "F.Cu")
		(net "PWRGD_NODE1_P5V_STB_PG")
	)
	(segment
		(start 78.613 -116.58346)
		(end 78.28788 -116.25834)
		(width 0.1016)
		(layer "F.Cu")
		(net "PWRGD_NODE1_P5V_STB_PG")
	)
	(segment
		(start 79.98714 -157.842458)
		(end 79.97952 -157.842458)
		(width 0.254)
		(layer "F.Cu")
		(net "PWRGD_NODE1_P5V_STB_PG")
	)
	(segment
		(start 186.602878 -116.961666)
		(end 187.1218 -116.961666)
		(width 0.1016)
		(layer "F.Cu")
		(net "PWRGD_NODE1_P5V_STB_PG")
	)
	(segment
		(start 187.2869 -116.796566)
		(end 187.2869 -116.795042)
		(width 0.1016)
		(layer "F.Cu")
		(net "PWRGD_NODE1_P5V_STB_PG")
	)
	(segment
		(start 79.97952 -157.027626)
		(end 79.57312 -156.621226)
		(width 0.254)
		(layer "F.Cu")
		(net "PWRGD_NODE1_P5V_STB_PG")
	)
	(segment
		(start 47.019718 -105.38079)
		(end 47.018194 -105.382314)
		(width 0.254)
		(layer "F.Cu")
		(net "PWRGD_NODE1_P5V_STB_PG")
	)
	(segment
		(start 80.99552 -157.842458)
		(end 79.98714 -157.842458)
		(width 0.254)
		(layer "F.Cu")
		(net "PWRGD_NODE1_P5V_STB_PG")
	)
	(segment
		(start 77.32776 -145.79219)
		(end 79.957676 -148.422106)
		(width 0.1016)
		(layer "F.Cu")
		(net "PWRGD_NODE1_P5V_STB_PG")
	)
	(segment
		(start 77.32014 -145.486628)
		(end 77.32776 -145.494248)
		(width 0.1016)
		(layer "F.Cu")
		(net "PWRGD_NODE1_P5V_STB_PG")
	)
	(segment
		(start 46.261528 -106.255058)
		(end 46.41342 -106.40695)
		(width 0.254)
		(layer "F.Cu")
		(net "PWRGD_NODE1_P5V_STB_PG")
	)
	(segment
		(start 47.018194 -105.382314)
		(end 47.018194 -106.40695)
		(width 0.254)
		(layer "F.Cu")
		(net "PWRGD_NODE1_P5V_STB_PG")
	)
	(segment
		(start 46.41342 -106.40695)
		(end 47.018194 -106.40695)
		(width 0.254)
		(layer "F.Cu")
		(net "PWRGD_NODE1_P5V_STB_PG")
	)
	(segment
		(start 84.06384 -157.902656)
		(end 83.59394 -158.372556)
		(width 0.1016)
		(layer "F.Cu")
		(net "PWRGD_NODE1_P5V_STB_PG")
	)
	(segment
		(start 45.604176 -106.255058)
		(end 46.261528 -106.255058)
		(width 0.254)
		(layer "F.Cu")
		(net "PWRGD_NODE1_P5V_STB_PG")
	)
	(segment
		(start 80.99552 -157.373574)
		(end 80.642968 -157.021022)
		(width 0.254)
		(layer "F.Cu")
		(net "PWRGD_NODE1_P5V_STB_PG")
	)
	(segment
		(start 79.57312 -156.621226)
		(end 79.57312 -156.215334)
		(width 0.254)
		(layer "F.Cu")
		(net "PWRGD_NODE1_P5V_STB_PG")
	)
	(segment
		(start 77.32776 -145.494248)
		(end 77.32776 -145.79219)
		(width 0.1016)
		(layer "F.Cu")
		(net "PWRGD_NODE1_P5V_STB_PG")
	)
	(segment
		(start 78.28788 -116.25834)
		(end 78.28788 -109.868208)
		(width 0.1016)
		(layer "F.Cu")
		(net "PWRGD_NODE1_P5V_STB_PG")
	)
	(segment
		(start 79.957676 -148.422106)
		(end 81.519268 -148.422106)
		(width 0.1016)
		(layer "F.Cu")
		(net "PWRGD_NODE1_P5V_STB_PG")
	)
	(segment
		(start 79.97952 -157.842458)
		(end 79.97952 -157.027626)
		(width 0.254)
		(layer "F.Cu")
		(net "PWRGD_NODE1_P5V_STB_PG")
	)
	(segment
		(start 80.99552 -157.842458)
		(end 80.99552 -157.373574)
		(width 0.254)
		(layer "F.Cu")
		(net "PWRGD_NODE1_P5V_STB_PG")
	)
	(via
		(at 46.261528 -106.255058)
		(size 0.508)
		(drill 0.254)
		(layers "F.Cu" "B.Cu")
		(net "PWRGD_NODE1_P5V_STB_PG")
	)
	(via
		(at 83.59394 -158.372556)
		(size 0.508)
		(drill 0.254)
		(layers "F.Cu" "B.Cu")
		(net "PWRGD_NODE1_P5V_STB_PG")
	)
	(via
		(at 80.642968 -157.021022)
		(size 0.508)
		(drill 0.254)
		(layers "F.Cu" "B.Cu")
		(net "PWRGD_NODE1_P5V_STB_PG")
	)
	(via
		(at 78.28788 -109.868208)
		(size 0.508)
		(drill 0.254)
		(layers "F.Cu" "B.Cu")
		(net "PWRGD_NODE1_P5V_STB_PG")
	)
	(via
		(at 128.26492 -156.57195)
		(size 0.508)
		(drill 0.254)
		(layers "F.Cu" "B.Cu")
		(net "PWRGD_NODE1_P5V_STB_PG")
	)
	(via
		(at 158.0134 -118.318788)
		(size 0.508)
		(drill 0.254)
		(layers "F.Cu" "B.Cu")
		(net "PWRGD_NODE1_P5V_STB_PG")
	)
	(via
		(at 187.2869 -116.795042)
		(size 0.508)
		(drill 0.254)
		(layers "F.Cu" "B.Cu")
		(net "PWRGD_NODE1_P5V_STB_PG")
	)
	(via
		(at 77.32014 -145.486628)
		(size 0.508)
		(drill 0.254)
		(layers "F.Cu" "B.Cu")
		(net "PWRGD_NODE1_P5V_STB_PG")
	)
	(via
		(at 78.14818 -120.29567)
		(size 0.508)
		(drill 0.254)
		(layers "F.Cu" "B.Cu")
		(net "PWRGD_NODE1_P5V_STB_PG")
	)
	(segment
		(start 145.4404 -145.344642)
		(end 145.4404 -150.651972)
		(width 0.1143)
		(layer "In2.Cu")
		(net "PWRGD_NODE1_P5V_STB_PG")
	)
	(segment
		(start 78.448662 -120.596152)
		(end 78.14818 -120.29567)
		(width 0.1143)
		(layer "In2.Cu")
		(net "PWRGD_NODE1_P5V_STB_PG")
	)
	(segment
		(start 77.76972 -145.037048)
		(end 77.76972 -128.272794)
		(width 0.1143)
		(layer "In2.Cu")
		(net "PWRGD_NODE1_P5V_STB_PG")
	)
	(segment
		(start 147.193762 -141.497558)
		(end 147.128992 -141.562328)
		(width 0.1143)
		(layer "In2.Cu")
		(net "PWRGD_NODE1_P5V_STB_PG")
	)
	(segment
		(start 157.06598 -128.289812)
		(end 147.193762 -138.16203)
		(width 0.1143)
		(layer "In2.Cu")
		(net "PWRGD_NODE1_P5V_STB_PG")
	)
	(segment
		(start 132.320284 -154.79268)
		(end 130.78206 -156.330904)
		(width 0.1143)
		(layer "In2.Cu")
		(net "PWRGD_NODE1_P5V_STB_PG")
	)
	(segment
		(start 141.299692 -154.79268)
		(end 132.320284 -154.79268)
		(width 0.1143)
		(layer "In2.Cu")
		(net "PWRGD_NODE1_P5V_STB_PG")
	)
	(segment
		(start 77.32014 -145.486628)
		(end 77.76972 -145.037048)
		(width 0.1143)
		(layer "In2.Cu")
		(net "PWRGD_NODE1_P5V_STB_PG")
	)
	(segment
		(start 129.010664 -156.330904)
		(end 128.769618 -156.57195)
		(width 0.1143)
		(layer "In2.Cu")
		(net "PWRGD_NODE1_P5V_STB_PG")
	)
	(segment
		(start 158.0134 -123.273312)
		(end 157.06598 -124.220732)
		(width 0.1143)
		(layer "In2.Cu")
		(net "PWRGD_NODE1_P5V_STB_PG")
	)
	(segment
		(start 146.144742 -144.6403)
		(end 145.4404 -145.344642)
		(width 0.1143)
		(layer "In2.Cu")
		(net "PWRGD_NODE1_P5V_STB_PG")
	)
	(segment
		(start 146.241262 -144.6403)
		(end 146.144742 -144.6403)
		(width 0.1143)
		(layer "In2.Cu")
		(net "PWRGD_NODE1_P5V_STB_PG")
	)
	(segment
		(start 157.06598 -124.220732)
		(end 157.06598 -128.289812)
		(width 0.1143)
		(layer "In2.Cu")
		(net "PWRGD_NODE1_P5V_STB_PG")
	)
	(segment
		(start 130.78206 -156.330904)
		(end 129.010664 -156.330904)
		(width 0.1143)
		(layer "In2.Cu")
		(net "PWRGD_NODE1_P5V_STB_PG")
	)
	(segment
		(start 145.4404 -150.651972)
		(end 141.299692 -154.79268)
		(width 0.1143)
		(layer "In2.Cu")
		(net "PWRGD_NODE1_P5V_STB_PG")
	)
	(segment
		(start 147.128992 -143.752824)
		(end 146.497802 -144.38376)
		(width 0.1143)
		(layer "In2.Cu")
		(net "PWRGD_NODE1_P5V_STB_PG")
	)
	(segment
		(start 147.193762 -138.16203)
		(end 147.193762 -141.497558)
		(width 0.1143)
		(layer "In2.Cu")
		(net "PWRGD_NODE1_P5V_STB_PG")
	)
	(segment
		(start 78.448662 -127.593852)
		(end 78.448662 -120.596152)
		(width 0.1143)
		(layer "In2.Cu")
		(net "PWRGD_NODE1_P5V_STB_PG")
	)
	(segment
		(start 128.769618 -156.57195)
		(end 128.26492 -156.57195)
		(width 0.1143)
		(layer "In2.Cu")
		(net "PWRGD_NODE1_P5V_STB_PG")
	)
	(segment
		(start 146.497802 -144.38376)
		(end 146.241262 -144.6403)
		(width 0.1143)
		(layer "In2.Cu")
		(net "PWRGD_NODE1_P5V_STB_PG")
	)
	(segment
		(start 158.0134 -118.318788)
		(end 158.0134 -123.273312)
		(width 0.1143)
		(layer "In2.Cu")
		(net "PWRGD_NODE1_P5V_STB_PG")
	)
	(segment
		(start 147.128992 -141.562328)
		(end 147.128992 -143.752824)
		(width 0.1143)
		(layer "In2.Cu")
		(net "PWRGD_NODE1_P5V_STB_PG")
	)
	(segment
		(start 77.76972 -128.272794)
		(end 78.448662 -127.593852)
		(width 0.1143)
		(layer "In2.Cu")
		(net "PWRGD_NODE1_P5V_STB_PG")
	)
	(segment
		(start 186.661806 -116.169948)
		(end 187.2869 -116.795042)
		(width 0.1143)
		(layer "In7.Cu")
		(net "PWRGD_NODE1_P5V_STB_PG")
	)
	(segment
		(start 121.663714 -159.13227)
		(end 120.44934 -159.13227)
		(width 0.1143)
		(layer "In7.Cu")
		(net "PWRGD_NODE1_P5V_STB_PG")
	)
	(segment
		(start 169.567098 -113.566448)
		(end 178.599084 -113.566448)
		(width 0.1143)
		(layer "In7.Cu")
		(net "PWRGD_NODE1_P5V_STB_PG")
	)
	(segment
		(start 47.157386 -105.3592)
		(end 64.59474 -105.3592)
		(width 0.1143)
		(layer "In7.Cu")
		(net "PWRGD_NODE1_P5V_STB_PG")
	)
	(segment
		(start 178.599084 -113.566448)
		(end 181.202584 -116.169948)
		(width 0.1143)
		(layer "In7.Cu")
		(net "PWRGD_NODE1_P5V_STB_PG")
	)
	(segment
		(start 102.85476 -159.785304)
		(end 102.72268 -159.917384)
		(width 0.1143)
		(layer "In7.Cu")
		(net "PWRGD_NODE1_P5V_STB_PG")
	)
	(segment
		(start 84.32038 -159.098996)
		(end 83.59394 -158.372556)
		(width 0.1143)
		(layer "In7.Cu")
		(net "PWRGD_NODE1_P5V_STB_PG")
	)
	(segment
		(start 162.003994 -116.461794)
		(end 164.073586 -114.392202)
		(width 0.1143)
		(layer "In7.Cu")
		(net "PWRGD_NODE1_P5V_STB_PG")
	)
	(segment
		(start 80.642968 -157.021022)
		(end 80.642968 -158.031688)
		(width 0.1143)
		(layer "In7.Cu")
		(net "PWRGD_NODE1_P5V_STB_PG")
	)
	(segment
		(start 128.26492 -156.57195)
		(end 124.224034 -156.57195)
		(width 0.1143)
		(layer "In7.Cu")
		(net "PWRGD_NODE1_P5V_STB_PG")
	)
	(segment
		(start 71.26478 -105.60685)
		(end 74.989436 -109.331506)
		(width 0.1143)
		(layer "In7.Cu")
		(net "PWRGD_NODE1_P5V_STB_PG")
	)
	(segment
		(start 102.72268 -159.918654)
		(end 98.949764 -159.918654)
		(width 0.1143)
		(layer "In7.Cu")
		(net "PWRGD_NODE1_P5V_STB_PG")
	)
	(segment
		(start 98.251518 -159.220408)
		(end 91.26093 -159.220408)
		(width 0.1143)
		(layer "In7.Cu")
		(net "PWRGD_NODE1_P5V_STB_PG")
	)
	(segment
		(start 117.42166 -159.442658)
		(end 117.286532 -159.577786)
		(width 0.1143)
		(layer "In7.Cu")
		(net "PWRGD_NODE1_P5V_STB_PG")
	)
	(segment
		(start 103.165148 -159.644588)
		(end 103.024432 -159.785304)
		(width 0.1143)
		(layer "In7.Cu")
		(net "PWRGD_NODE1_P5V_STB_PG")
	)
	(segment
		(start 120.44934 -159.13227)
		(end 120.13946 -159.44215)
		(width 0.1143)
		(layer "In7.Cu")
		(net "PWRGD_NODE1_P5V_STB_PG")
	)
	(segment
		(start 83.395058 -158.571438)
		(end 83.59394 -158.372556)
		(width 0.1143)
		(layer "In7.Cu")
		(net "PWRGD_NODE1_P5V_STB_PG")
	)
	(segment
		(start 98.949764 -159.918654)
		(end 98.251518 -159.220408)
		(width 0.1143)
		(layer "In7.Cu")
		(net "PWRGD_NODE1_P5V_STB_PG")
	)
	(segment
		(start 64.59474 -105.3592)
		(end 64.84239 -105.60685)
		(width 0.1143)
		(layer "In7.Cu")
		(net "PWRGD_NODE1_P5V_STB_PG")
	)
	(segment
		(start 158.0134 -117.634766)
		(end 159.186372 -116.461794)
		(width 0.1143)
		(layer "In7.Cu")
		(net "PWRGD_NODE1_P5V_STB_PG")
	)
	(segment
		(start 91.26093 -159.220408)
		(end 91.14028 -159.099758)
		(width 0.1143)
		(layer "In7.Cu")
		(net "PWRGD_NODE1_P5V_STB_PG")
	)
	(segment
		(start 102.72268 -159.917384)
		(end 102.72268 -159.918654)
		(width 0.1143)
		(layer "In7.Cu")
		(net "PWRGD_NODE1_P5V_STB_PG")
	)
	(segment
		(start 46.261528 -106.255058)
		(end 47.157386 -105.3592)
		(width 0.1143)
		(layer "In7.Cu")
		(net "PWRGD_NODE1_P5V_STB_PG")
	)
	(segment
		(start 158.0134 -118.318788)
		(end 158.0134 -117.634766)
		(width 0.1143)
		(layer "In7.Cu")
		(net "PWRGD_NODE1_P5V_STB_PG")
	)
	(segment
		(start 64.84239 -105.60685)
		(end 71.26478 -105.60685)
		(width 0.1143)
		(layer "In7.Cu")
		(net "PWRGD_NODE1_P5V_STB_PG")
	)
	(segment
		(start 81.182718 -158.571438)
		(end 83.395058 -158.571438)
		(width 0.1143)
		(layer "In7.Cu")
		(net "PWRGD_NODE1_P5V_STB_PG")
	)
	(segment
		(start 112.798098 -160.33877)
		(end 111.99622 -159.536892)
		(width 0.1143)
		(layer "In7.Cu")
		(net "PWRGD_NODE1_P5V_STB_PG")
	)
	(segment
		(start 103.024432 -159.785304)
		(end 102.85476 -159.785304)
		(width 0.1143)
		(layer "In7.Cu")
		(net "PWRGD_NODE1_P5V_STB_PG")
	)
	(segment
		(start 159.186372 -116.461794)
		(end 162.003994 -116.461794)
		(width 0.1143)
		(layer "In7.Cu")
		(net "PWRGD_NODE1_P5V_STB_PG")
	)
	(segment
		(start 103.27386 -159.536892)
		(end 103.166164 -159.644588)
		(width 0.1143)
		(layer "In7.Cu")
		(net "PWRGD_NODE1_P5V_STB_PG")
	)
	(segment
		(start 91.14028 -159.099758)
		(end 91.14028 -159.098996)
		(width 0.1143)
		(layer "In7.Cu")
		(net "PWRGD_NODE1_P5V_STB_PG")
	)
	(segment
		(start 164.073586 -114.392202)
		(end 168.741344 -114.392202)
		(width 0.1143)
		(layer "In7.Cu")
		(net "PWRGD_NODE1_P5V_STB_PG")
	)
	(segment
		(start 77.751178 -109.331506)
		(end 78.28788 -109.868208)
		(width 0.1143)
		(layer "In7.Cu")
		(net "PWRGD_NODE1_P5V_STB_PG")
	)
	(segment
		(start 168.741344 -114.392202)
		(end 169.567098 -113.566448)
		(width 0.1143)
		(layer "In7.Cu")
		(net "PWRGD_NODE1_P5V_STB_PG")
	)
	(segment
		(start 124.224034 -156.57195)
		(end 121.663714 -159.13227)
		(width 0.1143)
		(layer "In7.Cu")
		(net "PWRGD_NODE1_P5V_STB_PG")
	)
	(segment
		(start 117.286532 -159.577786)
		(end 117.286024 -159.577786)
		(width 0.1143)
		(layer "In7.Cu")
		(net "PWRGD_NODE1_P5V_STB_PG")
	)
	(segment
		(start 181.202584 -116.169948)
		(end 186.661806 -116.169948)
		(width 0.1143)
		(layer "In7.Cu")
		(net "PWRGD_NODE1_P5V_STB_PG")
	)
	(segment
		(start 120.13946 -159.442658)
		(end 117.42166 -159.442658)
		(width 0.1143)
		(layer "In7.Cu")
		(net "PWRGD_NODE1_P5V_STB_PG")
	)
	(segment
		(start 116.52504 -160.33877)
		(end 112.798098 -160.33877)
		(width 0.1143)
		(layer "In7.Cu")
		(net "PWRGD_NODE1_P5V_STB_PG")
	)
	(segment
		(start 103.166164 -159.644588)
		(end 103.165148 -159.644588)
		(width 0.1143)
		(layer "In7.Cu")
		(net "PWRGD_NODE1_P5V_STB_PG")
	)
	(segment
		(start 80.642968 -158.031688)
		(end 81.182718 -158.571438)
		(width 0.1143)
		(layer "In7.Cu")
		(net "PWRGD_NODE1_P5V_STB_PG")
	)
	(segment
		(start 117.286024 -159.577786)
		(end 116.52504 -160.33877)
		(width 0.1143)
		(layer "In7.Cu")
		(net "PWRGD_NODE1_P5V_STB_PG")
	)
	(segment
		(start 120.13946 -159.44215)
		(end 120.13946 -159.442658)
		(width 0.1143)
		(layer "In7.Cu")
		(net "PWRGD_NODE1_P5V_STB_PG")
	)
	(segment
		(start 111.99622 -159.536892)
		(end 103.27386 -159.536892)
		(width 0.1143)
		(layer "In7.Cu")
		(net "PWRGD_NODE1_P5V_STB_PG")
	)
	(segment
		(start 74.989436 -109.331506)
		(end 77.751178 -109.331506)
		(width 0.1143)
		(layer "In7.Cu")
		(net "PWRGD_NODE1_P5V_STB_PG")
	)
	(segment
		(start 91.14028 -159.098996)
		(end 84.32038 -159.098996)
		(width 0.1143)
		(layer "In7.Cu")
		(net "PWRGD_NODE1_P5V_STB_PG")
	)
	(via
		(at 50.029364 -177.97907)
		(size 0.6604)
		(drill 0.3302)
		(layers "F.Cu" "B.Cu")
		(net "N21699710")
	)
	(segment
		(start 54.95036 -177.940716)
		(end 52.30876 -177.940716)
		(width 0.1016)
		(layer "B.Cu")
		(net "N21699710")
	)
	(segment
		(start 49.71669 -178.291744)
		(end 50.029364 -177.97907)
		(width 0.1016)
		(layer "B.Cu")
		(net "N21699710")
	)
	(segment
		(start 48.75403 -178.291744)
		(end 49.71669 -178.291744)
		(width 0.1016)
		(layer "B.Cu")
		(net "N21699710")
	)
	(segment
		(start 58.15076 -179.240688)
		(end 56.250332 -179.240688)
		(width 0.1016)
		(layer "B.Cu")
		(net "N21699710")
	)
	(segment
		(start 56.250332 -179.240688)
		(end 54.95036 -177.940716)
		(width 0.1016)
		(layer "B.Cu")
		(net "N21699710")
	)
	(segment
		(start 52.30876 -177.940716)
		(end 50.067718 -177.940716)
		(width 0.1016)
		(layer "B.Cu")
		(net "N21699710")
	)
	(segment
		(start 50.067718 -177.940716)
		(end 50.029364 -177.97907)
		(width 0.1016)
		(layer "B.Cu")
		(net "N21699710")
	)
	(segment
		(start 163.7538 -56.22036)
		(end 155.45943 -64.51473)
		(width 0.10414)
		(layer "F.Cu")
		(net "SATA_A_NODE1_RX_N0")
	)
	(segment
		(start 162.260534 -49.978564)
		(end 163.7538 -51.47183)
		(width 0.10414)
		(layer "F.Cu")
		(net "SATA_A_NODE1_RX_N0")
	)
	(segment
		(start 161.280348 -49.560734)
		(end 161.698178 -49.978564)
		(width 0.10414)
		(layer "F.Cu")
		(net "SATA_A_NODE1_RX_N0")
	)
	(segment
		(start 155.45943 -64.51473)
		(end 151.356822 -64.51473)
		(width 0.10414)
		(layer "F.Cu")
		(net "SATA_A_NODE1_RX_N0")
	)
	(segment
		(start 163.7538 -51.47183)
		(end 163.7538 -56.22036)
		(width 0.10414)
		(layer "F.Cu")
		(net "SATA_A_NODE1_RX_N0")
	)
	(segment
		(start 151.356822 -64.51473)
		(end 151.11349 -64.758062)
		(width 0.10414)
		(layer "F.Cu")
		(net "SATA_A_NODE1_RX_N0")
	)
	(segment
		(start 161.698178 -49.978564)
		(end 162.260534 -49.978564)
		(width 0.10414)
		(layer "F.Cu")
		(net "SATA_A_NODE1_RX_N0")
	)
	(segment
		(start 151.11349 -64.758062)
		(end 149.57171 -64.758062)
		(width 0.10414)
		(layer "F.Cu")
		(net "SATA_A_NODE1_RX_N0")
	)
	(via
		(at 161.280348 -49.560734)
		(size 0.508)
		(drill 0.254)
		(layers "F.Cu" "B.Cu")
		(net "SATA_A_NODE1_RX_N0")
	)
	(segment
		(start 160.57245 -49.978564)
		(end 160.201864 -49.607978)
		(width 0.10414)
		(layer "B.Cu")
		(net "SATA_A_NODE1_RX_N0")
	)
	(segment
		(start 161.280348 -49.560734)
		(end 160.862518 -49.978564)
		(width 0.10414)
		(layer "B.Cu")
		(net "SATA_A_NODE1_RX_N0")
	)
	(segment
		(start 160.862518 -49.978564)
		(end 160.57245 -49.978564)
		(width 0.10414)
		(layer "B.Cu")
		(net "SATA_A_NODE1_RX_N0")
	)
	(segment
		(start 64.541908 -126.459488)
		(end 64.541908 -126.198884)
		(width 0.1016)
		(layer "F.Cu")
		(net "BMC_ROMA20")
	)
	(segment
		(start 63.645034 -122.950478)
		(end 63.429388 -122.734832)
		(width 0.1016)
		(layer "F.Cu")
		(net "BMC_ROMA20")
	)
	(segment
		(start 62.511686 -121.444512)
		(end 62.511686 -121.81713)
		(width 0.1016)
		(layer "F.Cu")
		(net "BMC_ROMA20")
	)
	(segment
		(start 64.541908 -126.198884)
		(end 63.645034 -125.30201)
		(width 0.1016)
		(layer "F.Cu")
		(net "BMC_ROMA20")
	)
	(segment
		(start 62.511686 -121.81713)
		(end 63.429388 -122.734832)
		(width 0.1016)
		(layer "F.Cu")
		(net "BMC_ROMA20")
	)
	(segment
		(start 63.645034 -125.30201)
		(end 63.645034 -122.950478)
		(width 0.1016)
		(layer "F.Cu")
		(net "BMC_ROMA20")
	)
	(via
		(at 63.429388 -122.734832)
		(size 0.762)
		(drill 0.381)
		(layers "F.Cu" "B.Cu")
		(net "BMC_ROMA20")
	)
	(segment
		(start 78.90256 -34.187638)
		(end 78.69936 -33.984438)
		(width 0.2286)
		(layer "F.Cu")
		(net "M_DDR3_NODE1_RAS_L")
	)
	(segment
		(start 79.982822 -35.787838)
		(end 80.478122 -35.292538)
		(width 0.2286)
		(layer "F.Cu")
		(net "M_DDR3_NODE1_RAS_L")
	)
	(segment
		(start 79.050134 -30.730952)
		(end 79.050134 -29.149802)
		(width 0.2286)
		(layer "F.Cu")
		(net "M_DDR3_NODE1_RAS_L")
	)
	(segment
		(start 79.540862 -39.806118)
		(end 79.210662 -39.806118)
		(width 0.2286)
		(layer "F.Cu")
		(net "M_DDR3_NODE1_RAS_L")
	)
	(segment
		(start 80.478122 -34.995104)
		(end 79.670656 -34.187638)
		(width 0.2286)
		(layer "F.Cu")
		(net "M_DDR3_NODE1_RAS_L")
	)
	(segment
		(start 79.744062 -36.55187)
		(end 79.744062 -36.026598)
		(width 0.2286)
		(layer "F.Cu")
		(net "M_DDR3_NODE1_RAS_L")
	)
	(segment
		(start 77.67574 -31.818072)
		(end 77.67574 -31.494984)
		(width 0.2286)
		(layer "F.Cu")
		(net "M_DDR3_NODE1_RAS_L")
	)
	(segment
		(start 78.270862 -39.138098)
		(end 78.492858 -38.916102)
		(width 0.2286)
		(layer "F.Cu")
		(net "M_DDR3_NODE1_RAS_L")
	)
	(segment
		(start 79.744062 -37.719762)
		(end 79.959708 -37.504116)
		(width 0.2286)
		(layer "F.Cu")
		(net "M_DDR3_NODE1_RAS_L")
	)
	(segment
		(start 79.744062 -40.009318)
		(end 79.540862 -39.806118)
		(width 0.2286)
		(layer "F.Cu")
		(net "M_DDR3_NODE1_RAS_L")
	)
	(segment
		(start 78.474062 -43.110658)
		(end 78.270862 -42.907458)
		(width 0.2286)
		(layer "F.Cu")
		(net "M_DDR3_NODE1_RAS_L")
	)
	(segment
		(start 78.514448 -31.266638)
		(end 79.050134 -30.730952)
		(width 0.2286)
		(layer "F.Cu")
		(net "M_DDR3_NODE1_RAS_L")
	)
	(segment
		(start 64.1604 -56.601614)
		(end 65.149476 -55.612538)
		(width 0.2286)
		(layer "F.Cu")
		(net "M_DDR3_NODE1_RAS_L")
	)
	(segment
		(start 79.66456 -33.053782)
		(end 79.66456 -32.723582)
		(width 0.2286)
		(layer "F.Cu")
		(net "M_DDR3_NODE1_RAS_L")
	)
	(segment
		(start 79.744062 -47.121318)
		(end 79.744062 -40.009318)
		(width 0.2286)
		(layer "F.Cu")
		(net "M_DDR3_NODE1_RAS_L")
	)
	(segment
		(start 78.69936 -33.460182)
		(end 78.90256 -33.256982)
		(width 0.2286)
		(layer "F.Cu")
		(net "M_DDR3_NODE1_RAS_L")
	)
	(segment
		(start 79.007462 -42.907458)
		(end 78.804262 -43.110658)
		(width 0.2286)
		(layer "F.Cu")
		(net "M_DDR3_NODE1_RAS_L")
	)
	(segment
		(start 63.581534 -60.55614)
		(end 63.581534 -59.033918)
		(width 0.1016)
		(layer "F.Cu")
		(net "M_DDR3_NODE1_RAS_L")
	)
	(segment
		(start 78.706726 -32.520382)
		(end 78.232762 -32.046418)
		(width 0.2286)
		(layer "F.Cu")
		(net "M_DDR3_NODE1_RAS_L")
	)
	(segment
		(start 79.959708 -37.504116)
		(end 80.407256 -37.504116)
		(width 0.2286)
		(layer "F.Cu")
		(net "M_DDR3_NODE1_RAS_L")
	)
	(segment
		(start 78.270862 -42.907458)
		(end 78.270862 -39.138098)
		(width 0.2286)
		(layer "F.Cu")
		(net "M_DDR3_NODE1_RAS_L")
	)
	(segment
		(start 78.90256 -33.256982)
		(end 79.46136 -33.256982)
		(width 0.2286)
		(layer "F.Cu")
		(net "M_DDR3_NODE1_RAS_L")
	)
	(segment
		(start 79.46136 -32.520382)
		(end 78.706726 -32.520382)
		(width 0.2286)
		(layer "F.Cu")
		(net "M_DDR3_NODE1_RAS_L")
	)
	(segment
		(start 78.232762 -32.046418)
		(end 77.904086 -32.046418)
		(width 0.2286)
		(layer "F.Cu")
		(net "M_DDR3_NODE1_RAS_L")
	)
	(segment
		(start 78.804262 -43.110658)
		(end 78.474062 -43.110658)
		(width 0.2286)
		(layer "F.Cu")
		(net "M_DDR3_NODE1_RAS_L")
	)
	(segment
		(start 80.407256 -37.504116)
		(end 80.622902 -37.28847)
		(width 0.2286)
		(layer "F.Cu")
		(net "M_DDR3_NODE1_RAS_L")
	)
	(segment
		(start 63.581534 -59.033918)
		(end 64.1604 -58.455052)
		(width 0.1016)
		(layer "F.Cu")
		(net "M_DDR3_NODE1_RAS_L")
	)
	(segment
		(start 79.538576 -38.914324)
		(end 79.744062 -38.708838)
		(width 0.2286)
		(layer "F.Cu")
		(net "M_DDR3_NODE1_RAS_L")
	)
	(segment
		(start 79.670656 -34.187638)
		(end 78.90256 -34.187638)
		(width 0.2286)
		(layer "F.Cu")
		(net "M_DDR3_NODE1_RAS_L")
	)
	(segment
		(start 78.69936 -33.984438)
		(end 78.69936 -33.460182)
		(width 0.2286)
		(layer "F.Cu")
		(net "M_DDR3_NODE1_RAS_L")
	)
	(segment
		(start 80.622902 -36.983162)
		(end 80.407256 -36.767516)
		(width 0.2286)
		(layer "F.Cu")
		(net "M_DDR3_NODE1_RAS_L")
	)
	(segment
		(start 64.1604 -58.138568)
		(end 64.1604 -56.601614)
		(width 0.2286)
		(layer "F.Cu")
		(net "M_DDR3_NODE1_RAS_L")
	)
	(segment
		(start 77.904086 -32.046418)
		(end 77.67574 -31.818072)
		(width 0.2286)
		(layer "F.Cu")
		(net "M_DDR3_NODE1_RAS_L")
	)
	(segment
		(start 62.606936 -61.530738)
		(end 63.581534 -60.55614)
		(width 0.1016)
		(layer "F.Cu")
		(net "M_DDR3_NODE1_RAS_L")
	)
	(segment
		(start 80.622902 -37.28847)
		(end 80.622902 -36.983162)
		(width 0.2286)
		(layer "F.Cu")
		(net "M_DDR3_NODE1_RAS_L")
	)
	(segment
		(start 79.538576 -38.916102)
		(end 79.538576 -38.914324)
		(width 0.2286)
		(layer "F.Cu")
		(net "M_DDR3_NODE1_RAS_L")
	)
	(segment
		(start 80.407256 -36.767516)
		(end 79.959708 -36.767516)
		(width 0.2286)
		(layer "F.Cu")
		(net "M_DDR3_NODE1_RAS_L")
	)
	(segment
		(start 79.46136 -33.256982)
		(end 79.66456 -33.053782)
		(width 0.2286)
		(layer "F.Cu")
		(net "M_DDR3_NODE1_RAS_L")
	)
	(segment
		(start 77.67574 -31.494984)
		(end 77.904086 -31.266638)
		(width 0.2286)
		(layer "F.Cu")
		(net "M_DDR3_NODE1_RAS_L")
	)
	(segment
		(start 62.606936 -62.55004)
		(end 62.606936 -61.530738)
		(width 0.1016)
		(layer "F.Cu")
		(net "M_DDR3_NODE1_RAS_L")
	)
	(segment
		(start 79.007462 -40.009318)
		(end 79.007462 -42.907458)
		(width 0.2286)
		(layer "F.Cu")
		(net "M_DDR3_NODE1_RAS_L")
	)
	(segment
		(start 65.149476 -55.612538)
		(end 71.252842 -55.612538)
		(width 0.2286)
		(layer "F.Cu")
		(net "M_DDR3_NODE1_RAS_L")
	)
	(segment
		(start 79.210662 -39.806118)
		(end 79.007462 -40.009318)
		(width 0.2286)
		(layer "F.Cu")
		(net "M_DDR3_NODE1_RAS_L")
	)
	(segment
		(start 77.904086 -31.266638)
		(end 78.514448 -31.266638)
		(width 0.2286)
		(layer "F.Cu")
		(net "M_DDR3_NODE1_RAS_L")
	)
	(segment
		(start 78.492858 -38.916102)
		(end 79.538576 -38.916102)
		(width 0.2286)
		(layer "F.Cu")
		(net "M_DDR3_NODE1_RAS_L")
	)
	(segment
		(start 80.478122 -35.292538)
		(end 80.478122 -34.995104)
		(width 0.2286)
		(layer "F.Cu")
		(net "M_DDR3_NODE1_RAS_L")
	)
	(segment
		(start 64.1604 -58.455052)
		(end 64.1604 -58.138568)
		(width 0.1016)
		(layer "F.Cu")
		(net "M_DDR3_NODE1_RAS_L")
	)
	(segment
		(start 79.744062 -36.026598)
		(end 79.982822 -35.787838)
		(width 0.2286)
		(layer "F.Cu")
		(net "M_DDR3_NODE1_RAS_L")
	)
	(segment
		(start 79.66456 -32.723582)
		(end 79.46136 -32.520382)
		(width 0.2286)
		(layer "F.Cu")
		(net "M_DDR3_NODE1_RAS_L")
	)
	(segment
		(start 79.744062 -38.708838)
		(end 79.744062 -37.719762)
		(width 0.2286)
		(layer "F.Cu")
		(net "M_DDR3_NODE1_RAS_L")
	)
	(segment
		(start 79.959708 -36.767516)
		(end 79.744062 -36.55187)
		(width 0.2286)
		(layer "F.Cu")
		(net "M_DDR3_NODE1_RAS_L")
	)
	(segment
		(start 71.252842 -55.612538)
		(end 79.744062 -47.121318)
		(width 0.2286)
		(layer "F.Cu")
		(net "M_DDR3_NODE1_RAS_L")
	)
	(via
		(at 79.982822 -35.787838)
		(size 0.762)
		(drill 0.381)
		(layers "F.Cu" "B.Cu")
		(net "M_DDR3_NODE1_RAS_L")
	)
	(segment
		(start 134.528052 -123.068334)
		(end 133.994652 -122.534934)
		(width 0.127)
		(layer "F.Cu")
		(net "CLK_100M_NIC2_NODE1_DP")
	)
	(segment
		(start 151.313896 -151.778208)
		(end 154.61234 -151.778208)
		(width 0.127)
		(layer "F.Cu")
		(net "CLK_100M_NIC2_NODE1_DP")
	)
	(segment
		(start 155.669488 -152.444704)
		(end 155.767024 -152.347168)
		(width 0.127)
		(layer "F.Cu")
		(net "CLK_100M_NIC2_NODE1_DP")
	)
	(segment
		(start 150.842218 -151.30653)
		(end 151.313896 -151.778208)
		(width 0.127)
		(layer "F.Cu")
		(net "CLK_100M_NIC2_NODE1_DP")
	)
	(segment
		(start 155.767024 -152.347168)
		(end 156.470096 -152.347168)
		(width 0.127)
		(layer "F.Cu")
		(net "CLK_100M_NIC2_NODE1_DP")
	)
	(segment
		(start 143.220186 -126.344426)
		(end 135.471408 -126.344426)
		(width 0.127)
		(layer "F.Cu")
		(net "CLK_100M_NIC2_NODE1_DP")
	)
	(segment
		(start 155.278836 -152.444704)
		(end 155.669488 -152.444704)
		(width 0.127)
		(layer "F.Cu")
		(net "CLK_100M_NIC2_NODE1_DP")
	)
	(segment
		(start 133.994652 -122.534934)
		(end 133.994652 -121.565416)
		(width 0.127)
		(layer "F.Cu")
		(net "CLK_100M_NIC2_NODE1_DP")
	)
	(segment
		(start 133.953758 -121.524522)
		(end 133.953758 -121.064528)
		(width 0.127)
		(layer "F.Cu")
		(net "CLK_100M_NIC2_NODE1_DP")
	)
	(segment
		(start 134.528052 -125.40107)
		(end 134.528052 -123.068334)
		(width 0.127)
		(layer "F.Cu")
		(net "CLK_100M_NIC2_NODE1_DP")
	)
	(segment
		(start 146.23796 -129.3622)
		(end 143.220186 -126.344426)
		(width 0.127)
		(layer "F.Cu")
		(net "CLK_100M_NIC2_NODE1_DP")
	)
	(segment
		(start 146.23796 -129.592832)
		(end 146.23796 -129.3622)
		(width 0.127)
		(layer "F.Cu")
		(net "CLK_100M_NIC2_NODE1_DP")
	)
	(segment
		(start 154.61234 -151.778208)
		(end 155.278836 -152.444704)
		(width 0.127)
		(layer "F.Cu")
		(net "CLK_100M_NIC2_NODE1_DP")
	)
	(segment
		(start 145.75536 -130.075432)
		(end 146.23796 -129.592832)
		(width 0.127)
		(layer "F.Cu")
		(net "CLK_100M_NIC2_NODE1_DP")
	)
	(segment
		(start 135.471408 -126.344426)
		(end 134.528052 -125.40107)
		(width 0.127)
		(layer "F.Cu")
		(net "CLK_100M_NIC2_NODE1_DP")
	)
	(segment
		(start 133.994652 -121.565416)
		(end 133.953758 -121.524522)
		(width 0.127)
		(layer "F.Cu")
		(net "CLK_100M_NIC2_NODE1_DP")
	)
	(via
		(at 145.75536 -130.075432)
		(size 0.508)
		(drill 0.254)
		(layers "F.Cu" "B.Cu")
		(net "CLK_100M_NIC2_NODE1_DP")
	)
	(via
		(at 150.842218 -151.30653)
		(size 0.508)
		(drill 0.254)
		(layers "F.Cu" "B.Cu")
		(net "CLK_100M_NIC2_NODE1_DP")
	)
	(segment
		(start 149.96541 -145.076672)
		(end 150.34641 -145.076672)
		(width 0.127)
		(layer "B.Cu")
		(net "CLK_100M_NIC2_NODE1_DP")
	)
	(segment
		(start 149.313138 -145.076672)
		(end 149.448774 -145.212308)
		(width 0.127)
		(layer "B.Cu")
		(net "CLK_100M_NIC2_NODE1_DP")
	)
	(segment
		(start 149.829774 -145.212308)
		(end 149.96541 -145.076672)
		(width 0.127)
		(layer "B.Cu")
		(net "CLK_100M_NIC2_NODE1_DP")
	)
	(segment
		(start 146.23796 -130.558032)
		(end 146.23796 -135.819388)
		(width 0.127)
		(layer "B.Cu")
		(net "CLK_100M_NIC2_NODE1_DP")
	)
	(segment
		(start 152.00122 -149.247098)
		(end 152.00122 -149.628098)
		(width 0.127)
		(layer "B.Cu")
		(net "CLK_100M_NIC2_NODE1_DP")
	)
	(segment
		(start 152.146 -149.102318)
		(end 152.00122 -149.247098)
		(width 0.127)
		(layer "B.Cu")
		(net "CLK_100M_NIC2_NODE1_DP")
	)
	(segment
		(start 151.525478 -145.076672)
		(end 152.146 -145.697194)
		(width 0.127)
		(layer "B.Cu")
		(net "CLK_100M_NIC2_NODE1_DP")
	)
	(segment
		(start 151.324818 -151.78913)
		(end 150.842218 -151.30653)
		(width 0.127)
		(layer "B.Cu")
		(net "CLK_100M_NIC2_NODE1_DP")
	)
	(segment
		(start 150.34641 -145.076672)
		(end 150.482046 -145.212308)
		(width 0.127)
		(layer "B.Cu")
		(net "CLK_100M_NIC2_NODE1_DP")
	)
	(segment
		(start 148.944838 -145.076672)
		(end 149.313138 -145.076672)
		(width 0.127)
		(layer "B.Cu")
		(net "CLK_100M_NIC2_NODE1_DP")
	)
	(segment
		(start 147.3073 -136.888728)
		(end 147.3073 -143.439134)
		(width 0.127)
		(layer "B.Cu")
		(net "CLK_100M_NIC2_NODE1_DP")
	)
	(segment
		(start 152.146 -150.153878)
		(end 152.00122 -150.298658)
		(width 0.127)
		(layer "B.Cu")
		(net "CLK_100M_NIC2_NODE1_DP")
	)
	(segment
		(start 152.146 -145.697194)
		(end 152.146 -149.102318)
		(width 0.127)
		(layer "B.Cu")
		(net "CLK_100M_NIC2_NODE1_DP")
	)
	(segment
		(start 152.146 -150.824438)
		(end 152.146 -151.195024)
		(width 0.127)
		(layer "B.Cu")
		(net "CLK_100M_NIC2_NODE1_DP")
	)
	(segment
		(start 150.998682 -145.076672)
		(end 151.525478 -145.076672)
		(width 0.127)
		(layer "B.Cu")
		(net "CLK_100M_NIC2_NODE1_DP")
	)
	(segment
		(start 149.448774 -145.212308)
		(end 149.829774 -145.212308)
		(width 0.127)
		(layer "B.Cu")
		(net "CLK_100M_NIC2_NODE1_DP")
	)
	(segment
		(start 150.863046 -145.212308)
		(end 150.998682 -145.076672)
		(width 0.127)
		(layer "B.Cu")
		(net "CLK_100M_NIC2_NODE1_DP")
	)
	(segment
		(start 145.75536 -130.075432)
		(end 146.23796 -130.558032)
		(width 0.127)
		(layer "B.Cu")
		(net "CLK_100M_NIC2_NODE1_DP")
	)
	(segment
		(start 152.00122 -150.298658)
		(end 152.00122 -150.679658)
		(width 0.127)
		(layer "B.Cu")
		(net "CLK_100M_NIC2_NODE1_DP")
	)
	(segment
		(start 152.00122 -150.679658)
		(end 152.146 -150.824438)
		(width 0.127)
		(layer "B.Cu")
		(net "CLK_100M_NIC2_NODE1_DP")
	)
	(segment
		(start 152.146 -151.195024)
		(end 151.551894 -151.78913)
		(width 0.127)
		(layer "B.Cu")
		(net "CLK_100M_NIC2_NODE1_DP")
	)
	(segment
		(start 150.482046 -145.212308)
		(end 150.863046 -145.212308)
		(width 0.127)
		(layer "B.Cu")
		(net "CLK_100M_NIC2_NODE1_DP")
	)
	(segment
		(start 146.23796 -135.819388)
		(end 147.3073 -136.888728)
		(width 0.127)
		(layer "B.Cu")
		(net "CLK_100M_NIC2_NODE1_DP")
	)
	(segment
		(start 147.3073 -143.439134)
		(end 148.944838 -145.076672)
		(width 0.127)
		(layer "B.Cu")
		(net "CLK_100M_NIC2_NODE1_DP")
	)
	(segment
		(start 152.146 -149.772878)
		(end 152.146 -150.153878)
		(width 0.127)
		(layer "B.Cu")
		(net "CLK_100M_NIC2_NODE1_DP")
	)
	(segment
		(start 151.551894 -151.78913)
		(end 151.324818 -151.78913)
		(width 0.127)
		(layer "B.Cu")
		(net "CLK_100M_NIC2_NODE1_DP")
	)
	(segment
		(start 152.00122 -149.628098)
		(end 152.146 -149.772878)
		(width 0.127)
		(layer "B.Cu")
		(net "CLK_100M_NIC2_NODE1_DP")
	)
	(segment
		(start 187.149232 -118.711472)
		(end 187.2869 -118.573804)
		(width 0.1016)
		(layer "F.Cu")
		(net "PWRGD_NODE1_P3V3_STB_PG")
	)
	(segment
		(start 43.686222 -106.875834)
		(end 44.702222 -106.875834)
		(width 0.254)
		(layer "F.Cu")
		(net "PWRGD_NODE1_P3V3_STB_PG")
	)
	(segment
		(start 44.702222 -106.875834)
		(end 44.702222 -107.690666)
		(width 0.254)
		(layer "F.Cu")
		(net "PWRGD_NODE1_P3V3_STB_PG")
	)
	(segment
		(start 187.2869 -118.573804)
		(end 187.2869 -117.93982)
		(width 0.1016)
		(layer "F.Cu")
		(net "PWRGD_NODE1_P3V3_STB_PG")
	)
	(segment
		(start 186.64428 -118.711472)
		(end 187.149232 -118.711472)
		(width 0.1016)
		(layer "F.Cu")
		(net "PWRGD_NODE1_P3V3_STB_PG")
	)
	(segment
		(start 45.108622 -108.097066)
		(end 45.108622 -108.502958)
		(width 0.254)
		(layer "F.Cu")
		(net "PWRGD_NODE1_P3V3_STB_PG")
	)
	(segment
		(start 43.686222 -106.875834)
		(end 43.686222 -107.344718)
		(width 0.254)
		(layer "F.Cu")
		(net "PWRGD_NODE1_P3V3_STB_PG")
	)
	(segment
		(start 44.702222 -107.690666)
		(end 45.108622 -108.097066)
		(width 0.254)
		(layer "F.Cu")
		(net "PWRGD_NODE1_P3V3_STB_PG")
	)
	(segment
		(start 43.686222 -107.344718)
		(end 44.038774 -107.69727)
		(width 0.254)
		(layer "F.Cu")
		(net "PWRGD_NODE1_P3V3_STB_PG")
	)
	(via
		(at 81.147412 -109.064806)
		(size 0.508)
		(drill 0.254)
		(layers "F.Cu" "B.Cu")
		(net "PWRGD_NODE1_P3V3_STB_PG")
	)
	(via
		(at 44.038774 -107.69727)
		(size 0.508)
		(drill 0.254)
		(layers "F.Cu" "B.Cu")
		(net "PWRGD_NODE1_P3V3_STB_PG")
	)
	(via
		(at 187.2869 -117.93982)
		(size 0.508)
		(drill 0.254)
		(layers "F.Cu" "B.Cu")
		(net "PWRGD_NODE1_P3V3_STB_PG")
	)
	(via
		(at 159.0675 -114.362992)
		(size 0.508)
		(drill 0.254)
		(layers "F.Cu" "B.Cu")
		(net "PWRGD_NODE1_P3V3_STB_PG")
	)
	(segment
		(start 94.139004 -115.134898)
		(end 94.283022 -114.991134)
		(width 0.1143)
		(layer "In6.Cu")
		(net "PWRGD_NODE1_P3V3_STB_PG")
	)
	(segment
		(start 89.62136 -114.878358)
		(end 89.8779 -115.134898)
		(width 0.1143)
		(layer "In6.Cu")
		(net "PWRGD_NODE1_P3V3_STB_PG")
	)
	(segment
		(start 81.46796 -110.084108)
		(end 82.26298 -110.879128)
		(width 0.1143)
		(layer "In6.Cu")
		(net "PWRGD_NODE1_P3V3_STB_PG")
	)
	(segment
		(start 133.31444 -108.652056)
		(end 145.147538 -108.652056)
		(width 0.1143)
		(layer "In6.Cu")
		(net "PWRGD_NODE1_P3V3_STB_PG")
	)
	(segment
		(start 145.147538 -108.652056)
		(end 150.01748 -113.521998)
		(width 0.1143)
		(layer "In6.Cu")
		(net "PWRGD_NODE1_P3V3_STB_PG")
	)
	(segment
		(start 85.626702 -110.879128)
		(end 89.62136 -114.873786)
		(width 0.1143)
		(layer "In6.Cu")
		(net "PWRGD_NODE1_P3V3_STB_PG")
	)
	(segment
		(start 89.62136 -114.873786)
		(end 89.62136 -114.878358)
		(width 0.1143)
		(layer "In6.Cu")
		(net "PWRGD_NODE1_P3V3_STB_PG")
	)
	(segment
		(start 158.226506 -113.521998)
		(end 159.0675 -114.362992)
		(width 0.1143)
		(layer "In6.Cu")
		(net "PWRGD_NODE1_P3V3_STB_PG")
	)
	(segment
		(start 82.26298 -110.879128)
		(end 85.626702 -110.879128)
		(width 0.1143)
		(layer "In6.Cu")
		(net "PWRGD_NODE1_P3V3_STB_PG")
	)
	(segment
		(start 94.283022 -114.991134)
		(end 100.940108 -108.334048)
		(width 0.1143)
		(layer "In6.Cu")
		(net "PWRGD_NODE1_P3V3_STB_PG")
	)
	(segment
		(start 119.23522 -108.334048)
		(end 122.125486 -105.443782)
		(width 0.1143)
		(layer "In6.Cu")
		(net "PWRGD_NODE1_P3V3_STB_PG")
	)
	(segment
		(start 132.33908 -106.483658)
		(end 132.33908 -107.676696)
		(width 0.1143)
		(layer "In6.Cu")
		(net "PWRGD_NODE1_P3V3_STB_PG")
	)
	(segment
		(start 131.299204 -105.443782)
		(end 132.33908 -106.483658)
		(width 0.1143)
		(layer "In6.Cu")
		(net "PWRGD_NODE1_P3V3_STB_PG")
	)
	(segment
		(start 81.147412 -109.064806)
		(end 81.46796 -109.385354)
		(width 0.1143)
		(layer "In6.Cu")
		(net "PWRGD_NODE1_P3V3_STB_PG")
	)
	(segment
		(start 132.33908 -107.676696)
		(end 133.31444 -108.652056)
		(width 0.1143)
		(layer "In6.Cu")
		(net "PWRGD_NODE1_P3V3_STB_PG")
	)
	(segment
		(start 122.125486 -105.443782)
		(end 131.299204 -105.443782)
		(width 0.1143)
		(layer "In6.Cu")
		(net "PWRGD_NODE1_P3V3_STB_PG")
	)
	(segment
		(start 150.01748 -113.521998)
		(end 158.226506 -113.521998)
		(width 0.1143)
		(layer "In6.Cu")
		(net "PWRGD_NODE1_P3V3_STB_PG")
	)
	(segment
		(start 100.940108 -108.334048)
		(end 119.23522 -108.334048)
		(width 0.1143)
		(layer "In6.Cu")
		(net "PWRGD_NODE1_P3V3_STB_PG")
	)
	(segment
		(start 81.46796 -109.385354)
		(end 81.46796 -110.084108)
		(width 0.1143)
		(layer "In6.Cu")
		(net "PWRGD_NODE1_P3V3_STB_PG")
	)
	(segment
		(start 89.8779 -115.134898)
		(end 94.139004 -115.134898)
		(width 0.1143)
		(layer "In6.Cu")
		(net "PWRGD_NODE1_P3V3_STB_PG")
	)
	(segment
		(start 186.829954 -115.718336)
		(end 187.72505 -116.613432)
		(width 0.1143)
		(layer "In7.Cu")
		(net "PWRGD_NODE1_P3V3_STB_PG")
	)
	(segment
		(start 178.001422 -112.54613)
		(end 178.77282 -113.317528)
		(width 0.1143)
		(layer "In7.Cu")
		(net "PWRGD_NODE1_P3V3_STB_PG")
	)
	(segment
		(start 187.2869 -117.862604)
		(end 187.2869 -117.93982)
		(width 0.1143)
		(layer "In7.Cu")
		(net "PWRGD_NODE1_P3V3_STB_PG")
	)
	(segment
		(start 161.921952 -115.10645)
		(end 162.9029 -114.125502)
		(width 0.1143)
		(layer "In7.Cu")
		(net "PWRGD_NODE1_P3V3_STB_PG")
	)
	(segment
		(start 46.643544 -105.0925)
		(end 44.038774 -107.69727)
		(width 0.1143)
		(layer "In7.Cu")
		(net "PWRGD_NODE1_P3V3_STB_PG")
	)
	(segment
		(start 184.9247 -115.146836)
		(end 185.4962 -115.718336)
		(width 0.1143)
		(layer "In7.Cu")
		(net "PWRGD_NODE1_P3V3_STB_PG")
	)
	(segment
		(start 187.72505 -116.613432)
		(end 187.72505 -117.424708)
		(width 0.1143)
		(layer "In7.Cu")
		(net "PWRGD_NODE1_P3V3_STB_PG")
	)
	(segment
		(start 185.4962 -115.718336)
		(end 186.829954 -115.718336)
		(width 0.1143)
		(layer "In7.Cu")
		(net "PWRGD_NODE1_P3V3_STB_PG")
	)
	(segment
		(start 64.805052 -105.167684)
		(end 64.729868 -105.0925)
		(width 0.1143)
		(layer "In7.Cu")
		(net "PWRGD_NODE1_P3V3_STB_PG")
	)
	(segment
		(start 159.0675 -114.362992)
		(end 159.810958 -115.10645)
		(width 0.1143)
		(layer "In7.Cu")
		(net "PWRGD_NODE1_P3V3_STB_PG")
	)
	(segment
		(start 75.496928 -109.064806)
		(end 71.599806 -105.167684)
		(width 0.1143)
		(layer "In7.Cu")
		(net "PWRGD_NODE1_P3V3_STB_PG")
	)
	(segment
		(start 81.147412 -109.064806)
		(end 75.496928 -109.064806)
		(width 0.1143)
		(layer "In7.Cu")
		(net "PWRGD_NODE1_P3V3_STB_PG")
	)
	(segment
		(start 187.72505 -117.424708)
		(end 187.2869 -117.862604)
		(width 0.1143)
		(layer "In7.Cu")
		(net "PWRGD_NODE1_P3V3_STB_PG")
	)
	(segment
		(start 169.165524 -112.777778)
		(end 171.173648 -112.777778)
		(width 0.1143)
		(layer "In7.Cu")
		(net "PWRGD_NODE1_P3V3_STB_PG")
	)
	(segment
		(start 180.48986 -113.317528)
		(end 182.319168 -115.146836)
		(width 0.1143)
		(layer "In7.Cu")
		(net "PWRGD_NODE1_P3V3_STB_PG")
	)
	(segment
		(start 71.599806 -105.167684)
		(end 64.805052 -105.167684)
		(width 0.1143)
		(layer "In7.Cu")
		(net "PWRGD_NODE1_P3V3_STB_PG")
	)
	(segment
		(start 167.8178 -114.125502)
		(end 169.165524 -112.777778)
		(width 0.1143)
		(layer "In7.Cu")
		(net "PWRGD_NODE1_P3V3_STB_PG")
	)
	(segment
		(start 162.9029 -114.125502)
		(end 167.8178 -114.125502)
		(width 0.1143)
		(layer "In7.Cu")
		(net "PWRGD_NODE1_P3V3_STB_PG")
	)
	(segment
		(start 178.77282 -113.317528)
		(end 180.48986 -113.317528)
		(width 0.1143)
		(layer "In7.Cu")
		(net "PWRGD_NODE1_P3V3_STB_PG")
	)
	(segment
		(start 182.319168 -115.146836)
		(end 184.9247 -115.146836)
		(width 0.1143)
		(layer "In7.Cu")
		(net "PWRGD_NODE1_P3V3_STB_PG")
	)
	(segment
		(start 171.405296 -112.54613)
		(end 178.001422 -112.54613)
		(width 0.1143)
		(layer "In7.Cu")
		(net "PWRGD_NODE1_P3V3_STB_PG")
	)
	(segment
		(start 64.729868 -105.0925)
		(end 46.643544 -105.0925)
		(width 0.1143)
		(layer "In7.Cu")
		(net "PWRGD_NODE1_P3V3_STB_PG")
	)
	(segment
		(start 171.173648 -112.777778)
		(end 171.405296 -112.54613)
		(width 0.1143)
		(layer "In7.Cu")
		(net "PWRGD_NODE1_P3V3_STB_PG")
	)
	(segment
		(start 159.810958 -115.10645)
		(end 161.921952 -115.10645)
		(width 0.1143)
		(layer "In7.Cu")
		(net "PWRGD_NODE1_P3V3_STB_PG")
	)
	(via
		(at 95.931228 -173.06417)
		(size 0.6604)
		(drill 0.3302)
		(layers "F.Cu" "B.Cu")
		(net "N21699606")
	)
	(segment
		(start 94.851982 -173.140624)
		(end 95.854774 -173.140624)
		(width 0.1016)
		(layer "B.Cu")
		(net "N21699606")
	)
	(segment
		(start 97.52076 -173.64456)
		(end 96.511618 -173.64456)
		(width 0.1016)
		(layer "B.Cu")
		(net "N21699606")
	)
	(segment
		(start 95.854774 -173.140624)
		(end 95.931228 -173.06417)
		(width 0.1016)
		(layer "B.Cu")
		(net "N21699606")
	)
	(segment
		(start 96.511618 -173.64456)
		(end 95.931228 -173.06417)
		(width 0.1016)
		(layer "B.Cu")
		(net "N21699606")
	)
	(segment
		(start 63.472822 -118.383812)
		(end 63.171832 -118.082822)
		(width 0.1016)
		(layer "F.Cu")
		(net "BMC_ROMA10")
	)
	(segment
		(start 65.341754 -127.259588)
		(end 64.964564 -126.882398)
		(width 0.1016)
		(layer "F.Cu")
		(net "BMC_ROMA10")
	)
	(segment
		(start 63.222886 -121.675652)
		(end 63.222886 -119.850916)
		(width 0.1016)
		(layer "F.Cu")
		(net "BMC_ROMA10")
	)
	(segment
		(start 63.171832 -118.082822)
		(end 62.60211 -118.082822)
		(width 0.1016)
		(layer "F.Cu")
		(net "BMC_ROMA10")
	)
	(segment
		(start 62.600332 -118.082822)
		(end 62.60211 -118.082822)
		(width 0.1016)
		(layer "F.Cu")
		(net "BMC_ROMA10")
	)
	(segment
		(start 64.964564 -126.21514)
		(end 64.162178 -125.412754)
		(width 0.1016)
		(layer "F.Cu")
		(net "BMC_ROMA10")
	)
	(segment
		(start 63.222886 -119.850916)
		(end 62.600332 -119.228362)
		(width 0.1016)
		(layer "F.Cu")
		(net "BMC_ROMA10")
	)
	(segment
		(start 64.162178 -122.614944)
		(end 63.222886 -121.675652)
		(width 0.1016)
		(layer "F.Cu")
		(net "BMC_ROMA10")
	)
	(segment
		(start 64.162178 -125.412754)
		(end 64.162178 -122.614944)
		(width 0.1016)
		(layer "F.Cu")
		(net "BMC_ROMA10")
	)
	(segment
		(start 63.832486 -118.383812)
		(end 63.472822 -118.383812)
		(width 0.1016)
		(layer "F.Cu")
		(net "BMC_ROMA10")
	)
	(segment
		(start 64.964564 -126.882398)
		(end 64.964564 -126.21514)
		(width 0.1016)
		(layer "F.Cu")
		(net "BMC_ROMA10")
	)
	(segment
		(start 62.600332 -119.228362)
		(end 62.600332 -118.082822)
		(width 0.1016)
		(layer "F.Cu")
		(net "BMC_ROMA10")
	)
	(via
		(at 62.60211 -118.082822)
		(size 0.508)
		(drill 0.254)
		(layers "F.Cu" "B.Cu")
		(net "BMC_ROMA10")
	)
	(segment
		(start 70.388226 -65.455038)
		(end 70.452742 -65.455038)
		(width 0.1016)
		(layer "F.Cu")
		(net "M1_DQ_NODE1_DQ40")
	)
	(segment
		(start 70.452742 -65.455038)
		(end 70.817994 -65.82029)
		(width 0.1016)
		(layer "F.Cu")
		(net "M1_DQ_NODE1_DQ40")
	)
	(segment
		(start 87.750142 -23.070058)
		(end 87.747602 -23.072598)
		(width 0.1651)
		(layer "F.Cu")
		(net "M1_DQ_NODE1_DQ40")
	)
	(segment
		(start 87.750142 -20.94992)
		(end 87.750142 -23.070058)
		(width 0.1651)
		(layer "F.Cu")
		(net "M1_DQ_NODE1_DQ40")
	)
	(via
		(at 70.817994 -65.82029)
		(size 0.508)
		(drill 0.254)
		(layers "F.Cu" "B.Cu")
		(net "M1_DQ_NODE1_DQ40")
	)
	(via
		(at 87.747602 -23.072598)
		(size 0.508)
		(drill 0.254)
		(layers "F.Cu" "B.Cu")
		(net "M1_DQ_NODE1_DQ40")
	)
	(segment
		(start 87.30488 -32.599376)
		(end 87.30488 -35.379914)
		(width 0.2032)
		(layer "In2.Cu")
		(net "M1_DQ_NODE1_DQ40")
	)
	(segment
		(start 84.874608 -51.813968)
		(end 83.823048 -51.813968)
		(width 0.2032)
		(layer "In2.Cu")
		(net "M1_DQ_NODE1_DQ40")
	)
	(segment
		(start 73.837546 -61.136276)
		(end 73.15962 -61.814202)
		(width 0.2032)
		(layer "In2.Cu")
		(net "M1_DQ_NODE1_DQ40")
	)
	(segment
		(start 83.823048 -51.813968)
		(end 79.774034 -55.862982)
		(width 0.2032)
		(layer "In2.Cu")
		(net "M1_DQ_NODE1_DQ40")
	)
	(segment
		(start 70.9676 -64.312292)
		(end 70.9676 -65.67297)
		(width 0.1016)
		(layer "In2.Cu")
		(net "M1_DQ_NODE1_DQ40")
	)
	(segment
		(start 88.809322 -24.134318)
		(end 88.809322 -31.094934)
		(width 0.2032)
		(layer "In2.Cu")
		(net "M1_DQ_NODE1_DQ40")
	)
	(segment
		(start 78.87081 -57.977278)
		(end 78.57617 -57.977278)
		(width 0.2032)
		(layer "In2.Cu")
		(net "M1_DQ_NODE1_DQ40")
	)
	(segment
		(start 79.271114 -56.660542)
		(end 78.976474 -56.660542)
		(width 0.2032)
		(layer "In2.Cu")
		(net "M1_DQ_NODE1_DQ40")
	)
	(segment
		(start 79.07909 -57.768998)
		(end 78.87081 -57.977278)
		(width 0.2032)
		(layer "In2.Cu")
		(net "M1_DQ_NODE1_DQ40")
	)
	(segment
		(start 77.158088 -57.977278)
		(end 73.99909 -61.136276)
		(width 0.2032)
		(layer "In2.Cu")
		(net "M1_DQ_NODE1_DQ40")
	)
	(segment
		(start 73.15962 -61.814202)
		(end 73.15962 -62.748668)
		(width 0.2032)
		(layer "In2.Cu")
		(net "M1_DQ_NODE1_DQ40")
	)
	(segment
		(start 78.768194 -57.163462)
		(end 79.07909 -57.474358)
		(width 0.2032)
		(layer "In2.Cu")
		(net "M1_DQ_NODE1_DQ40")
	)
	(segment
		(start 79.750666 -56.845454)
		(end 79.456026 -56.845454)
		(width 0.2032)
		(layer "In2.Cu")
		(net "M1_DQ_NODE1_DQ40")
	)
	(segment
		(start 87.747602 -23.072598)
		(end 88.809322 -24.134318)
		(width 0.2032)
		(layer "In2.Cu")
		(net "M1_DQ_NODE1_DQ40")
	)
	(segment
		(start 85.974174 -52.431442)
		(end 85.765894 -52.223162)
		(width 0.2032)
		(layer "In2.Cu")
		(net "M1_DQ_NODE1_DQ40")
	)
	(segment
		(start 79.456026 -56.845454)
		(end 79.271114 -56.660542)
		(width 0.2032)
		(layer "In2.Cu")
		(net "M1_DQ_NODE1_DQ40")
	)
	(segment
		(start 86.268814 -52.431442)
		(end 85.974174 -52.431442)
		(width 0.2032)
		(layer "In2.Cu")
		(net "M1_DQ_NODE1_DQ40")
	)
	(segment
		(start 85.765894 -52.223162)
		(end 85.765894 -51.928522)
		(width 0.2032)
		(layer "In2.Cu")
		(net "M1_DQ_NODE1_DQ40")
	)
	(segment
		(start 86.924388 -50.475388)
		(end 86.716108 -50.267108)
		(width 0.2032)
		(layer "In2.Cu")
		(net "M1_DQ_NODE1_DQ40")
	)
	(segment
		(start 79.958946 -56.342534)
		(end 79.958946 -56.637174)
		(width 0.2032)
		(layer "In2.Cu")
		(net "M1_DQ_NODE1_DQ40")
	)
	(segment
		(start 78.57617 -57.977278)
		(end 78.265274 -57.666382)
		(width 0.2032)
		(layer "In2.Cu")
		(net "M1_DQ_NODE1_DQ40")
	)
	(segment
		(start 78.265274 -57.666382)
		(end 77.970634 -57.666382)
		(width 0.2032)
		(layer "In2.Cu")
		(net "M1_DQ_NODE1_DQ40")
	)
	(segment
		(start 85.765894 -51.928522)
		(end 86.924388 -50.770028)
		(width 0.2032)
		(layer "In2.Cu")
		(net "M1_DQ_NODE1_DQ40")
	)
	(segment
		(start 79.774034 -55.862982)
		(end 79.774034 -56.157622)
		(width 0.2032)
		(layer "In2.Cu")
		(net "M1_DQ_NODE1_DQ40")
	)
	(segment
		(start 73.15962 -62.748668)
		(end 72.544178 -63.36411)
		(width 0.2032)
		(layer "In2.Cu")
		(net "M1_DQ_NODE1_DQ40")
	)
	(segment
		(start 86.716108 -50.267108)
		(end 86.421468 -50.267108)
		(width 0.2032)
		(layer "In2.Cu")
		(net "M1_DQ_NODE1_DQ40")
	)
	(segment
		(start 71.915782 -63.36411)
		(end 71.253604 -64.026288)
		(width 0.2032)
		(layer "In2.Cu")
		(net "M1_DQ_NODE1_DQ40")
	)
	(segment
		(start 87.30488 -35.379914)
		(end 89.93378 -38.008814)
		(width 0.2032)
		(layer "In2.Cu")
		(net "M1_DQ_NODE1_DQ40")
	)
	(segment
		(start 86.924388 -50.770028)
		(end 86.924388 -50.475388)
		(width 0.2032)
		(layer "In2.Cu")
		(net "M1_DQ_NODE1_DQ40")
	)
	(segment
		(start 78.976474 -56.660542)
		(end 78.768194 -56.868822)
		(width 0.2032)
		(layer "In2.Cu")
		(net "M1_DQ_NODE1_DQ40")
	)
	(segment
		(start 79.774034 -56.157622)
		(end 79.958946 -56.342534)
		(width 0.2032)
		(layer "In2.Cu")
		(net "M1_DQ_NODE1_DQ40")
	)
	(segment
		(start 70.82028 -65.82029)
		(end 70.817994 -65.82029)
		(width 0.1016)
		(layer "In2.Cu")
		(net "M1_DQ_NODE1_DQ40")
	)
	(segment
		(start 71.253604 -64.026288)
		(end 70.9676 -64.312292)
		(width 0.1016)
		(layer "In2.Cu")
		(net "M1_DQ_NODE1_DQ40")
	)
	(segment
		(start 88.809322 -31.094934)
		(end 87.30488 -32.599376)
		(width 0.2032)
		(layer "In2.Cu")
		(net "M1_DQ_NODE1_DQ40")
	)
	(segment
		(start 73.99909 -61.136276)
		(end 73.837546 -61.136276)
		(width 0.2032)
		(layer "In2.Cu")
		(net "M1_DQ_NODE1_DQ40")
	)
	(segment
		(start 79.07909 -57.474358)
		(end 79.07909 -57.768998)
		(width 0.2032)
		(layer "In2.Cu")
		(net "M1_DQ_NODE1_DQ40")
	)
	(segment
		(start 72.544178 -63.36411)
		(end 71.915782 -63.36411)
		(width 0.2032)
		(layer "In2.Cu")
		(net "M1_DQ_NODE1_DQ40")
	)
	(segment
		(start 89.93378 -48.766476)
		(end 86.268814 -52.431442)
		(width 0.2032)
		(layer "In2.Cu")
		(net "M1_DQ_NODE1_DQ40")
	)
	(segment
		(start 70.9676 -65.67297)
		(end 70.82028 -65.82029)
		(width 0.1016)
		(layer "In2.Cu")
		(net "M1_DQ_NODE1_DQ40")
	)
	(segment
		(start 77.659738 -57.977278)
		(end 77.158088 -57.977278)
		(width 0.2032)
		(layer "In2.Cu")
		(net "M1_DQ_NODE1_DQ40")
	)
	(segment
		(start 78.768194 -56.868822)
		(end 78.768194 -57.163462)
		(width 0.2032)
		(layer "In2.Cu")
		(net "M1_DQ_NODE1_DQ40")
	)
	(segment
		(start 79.958946 -56.637174)
		(end 79.750666 -56.845454)
		(width 0.2032)
		(layer "In2.Cu")
		(net "M1_DQ_NODE1_DQ40")
	)
	(segment
		(start 77.970634 -57.666382)
		(end 77.659738 -57.977278)
		(width 0.2032)
		(layer "In2.Cu")
		(net "M1_DQ_NODE1_DQ40")
	)
	(segment
		(start 89.93378 -38.008814)
		(end 89.93378 -48.766476)
		(width 0.2032)
		(layer "In2.Cu")
		(net "M1_DQ_NODE1_DQ40")
	)
	(segment
		(start 86.421468 -50.267108)
		(end 84.874608 -51.813968)
		(width 0.2032)
		(layer "In2.Cu")
		(net "M1_DQ_NODE1_DQ40")
	)
	(segment
		(start 134.832852 -122.941842)
		(end 134.299452 -122.408442)
		(width 0.127)
		(layer "F.Cu")
		(net "CLK_100M_NIC2_NODE1_DN")
	)
	(segment
		(start 146.54276 -129.592832)
		(end 146.54276 -129.235708)
		(width 0.127)
		(layer "F.Cu")
		(net "CLK_100M_NIC2_NODE1_DN")
	)
	(segment
		(start 151.33574 -152.083008)
		(end 154.48534 -152.083008)
		(width 0.127)
		(layer "F.Cu")
		(net "CLK_100M_NIC2_NODE1_DN")
	)
	(segment
		(start 155.151836 -152.749504)
		(end 155.73248 -152.749504)
		(width 0.127)
		(layer "F.Cu")
		(net "CLK_100M_NIC2_NODE1_DN")
	)
	(segment
		(start 143.346678 -126.039626)
		(end 135.5979 -126.039626)
		(width 0.127)
		(layer "F.Cu")
		(net "CLK_100M_NIC2_NODE1_DN")
	)
	(segment
		(start 155.83027 -152.847294)
		(end 156.470096 -152.847294)
		(width 0.127)
		(layer "F.Cu")
		(net "CLK_100M_NIC2_NODE1_DN")
	)
	(segment
		(start 155.73248 -152.749504)
		(end 155.83027 -152.847294)
		(width 0.127)
		(layer "F.Cu")
		(net "CLK_100M_NIC2_NODE1_DN")
	)
	(segment
		(start 154.48534 -152.083008)
		(end 155.151836 -152.749504)
		(width 0.127)
		(layer "F.Cu")
		(net "CLK_100M_NIC2_NODE1_DN")
	)
	(segment
		(start 150.842218 -152.57653)
		(end 151.33574 -152.083008)
		(width 0.127)
		(layer "F.Cu")
		(net "CLK_100M_NIC2_NODE1_DN")
	)
	(segment
		(start 135.5979 -126.039626)
		(end 134.832852 -125.274578)
		(width 0.127)
		(layer "F.Cu")
		(net "CLK_100M_NIC2_NODE1_DN")
	)
	(segment
		(start 134.353808 -121.5009)
		(end 134.353808 -121.064528)
		(width 0.127)
		(layer "F.Cu")
		(net "CLK_100M_NIC2_NODE1_DN")
	)
	(segment
		(start 146.54276 -129.235708)
		(end 143.346678 -126.039626)
		(width 0.127)
		(layer "F.Cu")
		(net "CLK_100M_NIC2_NODE1_DN")
	)
	(segment
		(start 134.299452 -122.408442)
		(end 134.299452 -121.555256)
		(width 0.127)
		(layer "F.Cu")
		(net "CLK_100M_NIC2_NODE1_DN")
	)
	(segment
		(start 134.832852 -125.274578)
		(end 134.832852 -122.941842)
		(width 0.127)
		(layer "F.Cu")
		(net "CLK_100M_NIC2_NODE1_DN")
	)
	(segment
		(start 134.299452 -121.555256)
		(end 134.353808 -121.5009)
		(width 0.127)
		(layer "F.Cu")
		(net "CLK_100M_NIC2_NODE1_DN")
	)
	(segment
		(start 147.02536 -130.075432)
		(end 146.54276 -129.592832)
		(width 0.127)
		(layer "F.Cu")
		(net "CLK_100M_NIC2_NODE1_DN")
	)
	(via
		(at 150.842218 -152.57653)
		(size 0.508)
		(drill 0.254)
		(layers "F.Cu" "B.Cu")
		(net "CLK_100M_NIC2_NODE1_DN")
	)
	(via
		(at 147.02536 -130.075432)
		(size 0.508)
		(drill 0.254)
		(layers "F.Cu" "B.Cu")
		(net "CLK_100M_NIC2_NODE1_DN")
	)
	(segment
		(start 151.65197 -144.771872)
		(end 152.4508 -145.570702)
		(width 0.127)
		(layer "B.Cu")
		(net "CLK_100M_NIC2_NODE1_DN")
	)
	(segment
		(start 146.54276 -130.558032)
		(end 146.54276 -135.692896)
		(width 0.127)
		(layer "B.Cu")
		(net "CLK_100M_NIC2_NODE1_DN")
	)
	(segment
		(start 147.6121 -136.762236)
		(end 147.6121 -143.312642)
		(width 0.127)
		(layer "B.Cu")
		(net "CLK_100M_NIC2_NODE1_DN")
	)
	(segment
		(start 147.02536 -130.075432)
		(end 146.54276 -130.558032)
		(width 0.127)
		(layer "B.Cu")
		(net "CLK_100M_NIC2_NODE1_DN")
	)
	(segment
		(start 147.6121 -143.312642)
		(end 149.07133 -144.771872)
		(width 0.127)
		(layer "B.Cu")
		(net "CLK_100M_NIC2_NODE1_DN")
	)
	(segment
		(start 152.4508 -151.321516)
		(end 151.678386 -152.09393)
		(width 0.127)
		(layer "B.Cu")
		(net "CLK_100M_NIC2_NODE1_DN")
	)
	(segment
		(start 152.4508 -145.570702)
		(end 152.4508 -151.321516)
		(width 0.127)
		(layer "B.Cu")
		(net "CLK_100M_NIC2_NODE1_DN")
	)
	(segment
		(start 151.678386 -152.09393)
		(end 151.324818 -152.09393)
		(width 0.127)
		(layer "B.Cu")
		(net "CLK_100M_NIC2_NODE1_DN")
	)
	(segment
		(start 151.324818 -152.09393)
		(end 150.842218 -152.57653)
		(width 0.127)
		(layer "B.Cu")
		(net "CLK_100M_NIC2_NODE1_DN")
	)
	(segment
		(start 146.54276 -135.692896)
		(end 147.6121 -136.762236)
		(width 0.127)
		(layer "B.Cu")
		(net "CLK_100M_NIC2_NODE1_DN")
	)
	(segment
		(start 149.07133 -144.771872)
		(end 151.65197 -144.771872)
		(width 0.127)
		(layer "B.Cu")
		(net "CLK_100M_NIC2_NODE1_DN")
	)
	(via
		(at 48.901858 -108.978446)
		(size 0.508)
		(drill 0.254)
		(layers "F.Cu" "B.Cu")
		(net "SW_P3V3_STB_NODE1_PH")
	)
	(via
		(at 143.552672 -168.811956)
		(size 0.508)
		(drill 0.254)
		(layers "F.Cu" "B.Cu")
		(net "N21700156")
	)
	(segment
		(start 144.68729 -169.946574)
		(end 143.552672 -168.811956)
		(width 0.1016)
		(layer "B.Cu")
		(net "N21700156")
	)
	(segment
		(start 142.47241 -168.949624)
		(end 143.415004 -168.949624)
		(width 0.1016)
		(layer "B.Cu")
		(net "N21700156")
	)
	(segment
		(start 143.415004 -168.949624)
		(end 143.552672 -168.811956)
		(width 0.1016)
		(layer "B.Cu")
		(net "N21700156")
	)
	(segment
		(start 145.14576 -169.946574)
		(end 144.68729 -169.946574)
		(width 0.1016)
		(layer "B.Cu")
		(net "N21700156")
	)
	(segment
		(start 158.74111 -60.618624)
		(end 158.520384 -60.83935)
		(width 0.10414)
		(layer "F.Cu")
		(net "SATA_A_NODE1_RX_P0")
	)
	(segment
		(start 160.404556 -58.67527)
		(end 160.18383 -58.895996)
		(width 0.10414)
		(layer "F.Cu")
		(net "SATA_A_NODE1_RX_P0")
	)
	(segment
		(start 159.963104 -59.39663)
		(end 159.683196 -59.39663)
		(width 0.10414)
		(layer "F.Cu")
		(net "SATA_A_NODE1_RX_P0")
	)
	(segment
		(start 159.683196 -59.39663)
		(end 159.46247 -59.617356)
		(width 0.10414)
		(layer "F.Cu")
		(net "SATA_A_NODE1_RX_P0")
	)
	(segment
		(start 159.46247 -59.897264)
		(end 159.241744 -60.11799)
		(width 0.10414)
		(layer "F.Cu")
		(net "SATA_A_NODE1_RX_P0")
	)
	(segment
		(start 158.240476 -60.83935)
		(end 158.01975 -61.060076)
		(width 0.10414)
		(layer "F.Cu")
		(net "SATA_A_NODE1_RX_P0")
	)
	(segment
		(start 163.17976 -53.493924)
		(end 163.17976 -53.806344)
		(width 0.10414)
		(layer "F.Cu")
		(net "SATA_A_NODE1_RX_P0")
	)
	(segment
		(start 163.31946 -56.040274)
		(end 162.848544 -56.51119)
		(width 0.10414)
		(layer "F.Cu")
		(net "SATA_A_NODE1_RX_P0")
	)
	(segment
		(start 163.31946 -51.651916)
		(end 163.31946 -53.354224)
		(width 0.10414)
		(layer "F.Cu")
		(net "SATA_A_NODE1_RX_P0")
	)
	(segment
		(start 163.31946 -54.258464)
		(end 163.17976 -54.398164)
		(width 0.10414)
		(layer "F.Cu")
		(net "SATA_A_NODE1_RX_P0")
	)
	(segment
		(start 163.31946 -55.754524)
		(end 163.31946 -56.040274)
		(width 0.10414)
		(layer "F.Cu")
		(net "SATA_A_NODE1_RX_P0")
	)
	(segment
		(start 163.31946 -55.162704)
		(end 163.17976 -55.302404)
		(width 0.10414)
		(layer "F.Cu")
		(net "SATA_A_NODE1_RX_P0")
	)
	(segment
		(start 158.01975 -61.339984)
		(end 155.279344 -64.08039)
		(width 0.10414)
		(layer "F.Cu")
		(net "SATA_A_NODE1_RX_P0")
	)
	(segment
		(start 161.698178 -50.412904)
		(end 162.080448 -50.412904)
		(width 0.10414)
		(layer "F.Cu")
		(net "SATA_A_NODE1_RX_P0")
	)
	(segment
		(start 162.34791 -56.731916)
		(end 162.34791 -57.011824)
		(width 0.10414)
		(layer "F.Cu")
		(net "SATA_A_NODE1_RX_P0")
	)
	(segment
		(start 150.220172 -64.358012)
		(end 149.57171 -64.358012)
		(width 0.10414)
		(layer "F.Cu")
		(net "SATA_A_NODE1_RX_P0")
	)
	(segment
		(start 158.961836 -60.11799)
		(end 158.74111 -60.338716)
		(width 0.10414)
		(layer "F.Cu")
		(net "SATA_A_NODE1_RX_P0")
	)
	(segment
		(start 150.362666 -64.323722)
		(end 150.220172 -64.358012)
		(width 0.10414)
		(layer "F.Cu")
		(net "SATA_A_NODE1_RX_P0")
	)
	(segment
		(start 159.46247 -59.617356)
		(end 159.46247 -59.897264)
		(width 0.10414)
		(layer "F.Cu")
		(net "SATA_A_NODE1_RX_P0")
	)
	(segment
		(start 163.17976 -54.710584)
		(end 163.31946 -54.850284)
		(width 0.10414)
		(layer "F.Cu")
		(net "SATA_A_NODE1_RX_P0")
	)
	(segment
		(start 151.176736 -64.08039)
		(end 150.933404 -64.323722)
		(width 0.10414)
		(layer "F.Cu")
		(net "SATA_A_NODE1_RX_P0")
	)
	(segment
		(start 163.17976 -55.614824)
		(end 163.31946 -55.754524)
		(width 0.10414)
		(layer "F.Cu")
		(net "SATA_A_NODE1_RX_P0")
	)
	(segment
		(start 162.568636 -56.51119)
		(end 162.34791 -56.731916)
		(width 0.10414)
		(layer "F.Cu")
		(net "SATA_A_NODE1_RX_P0")
	)
	(segment
		(start 163.31946 -53.946044)
		(end 163.31946 -54.258464)
		(width 0.10414)
		(layer "F.Cu")
		(net "SATA_A_NODE1_RX_P0")
	)
	(segment
		(start 162.848544 -56.51119)
		(end 162.568636 -56.51119)
		(width 0.10414)
		(layer "F.Cu")
		(net "SATA_A_NODE1_RX_P0")
	)
	(segment
		(start 162.080448 -50.412904)
		(end 163.31946 -51.651916)
		(width 0.10414)
		(layer "F.Cu")
		(net "SATA_A_NODE1_RX_P0")
	)
	(segment
		(start 161.62655 -57.453276)
		(end 161.62655 -57.733184)
		(width 0.10414)
		(layer "F.Cu")
		(net "SATA_A_NODE1_RX_P0")
	)
	(segment
		(start 162.127184 -57.23255)
		(end 161.847276 -57.23255)
		(width 0.10414)
		(layer "F.Cu")
		(net "SATA_A_NODE1_RX_P0")
	)
	(segment
		(start 161.125916 -57.95391)
		(end 160.90519 -58.174636)
		(width 0.10414)
		(layer "F.Cu")
		(net "SATA_A_NODE1_RX_P0")
	)
	(segment
		(start 161.62655 -57.733184)
		(end 161.405824 -57.95391)
		(width 0.10414)
		(layer "F.Cu")
		(net "SATA_A_NODE1_RX_P0")
	)
	(segment
		(start 158.74111 -60.338716)
		(end 158.74111 -60.618624)
		(width 0.10414)
		(layer "F.Cu")
		(net "SATA_A_NODE1_RX_P0")
	)
	(segment
		(start 159.241744 -60.11799)
		(end 158.961836 -60.11799)
		(width 0.10414)
		(layer "F.Cu")
		(net "SATA_A_NODE1_RX_P0")
	)
	(segment
		(start 160.18383 -58.895996)
		(end 160.18383 -59.175904)
		(width 0.10414)
		(layer "F.Cu")
		(net "SATA_A_NODE1_RX_P0")
	)
	(segment
		(start 161.280348 -50.830734)
		(end 161.698178 -50.412904)
		(width 0.10414)
		(layer "F.Cu")
		(net "SATA_A_NODE1_RX_P0")
	)
	(segment
		(start 150.933404 -64.323722)
		(end 150.362666 -64.323722)
		(width 0.10414)
		(layer "F.Cu")
		(net "SATA_A_NODE1_RX_P0")
	)
	(segment
		(start 163.17976 -55.302404)
		(end 163.17976 -55.614824)
		(width 0.10414)
		(layer "F.Cu")
		(net "SATA_A_NODE1_RX_P0")
	)
	(segment
		(start 160.90519 -58.174636)
		(end 160.90519 -58.454544)
		(width 0.10414)
		(layer "F.Cu")
		(net "SATA_A_NODE1_RX_P0")
	)
	(segment
		(start 161.405824 -57.95391)
		(end 161.125916 -57.95391)
		(width 0.10414)
		(layer "F.Cu")
		(net "SATA_A_NODE1_RX_P0")
	)
	(segment
		(start 163.17976 -54.398164)
		(end 163.17976 -54.710584)
		(width 0.10414)
		(layer "F.Cu")
		(net "SATA_A_NODE1_RX_P0")
	)
	(segment
		(start 162.34791 -57.011824)
		(end 162.127184 -57.23255)
		(width 0.10414)
		(layer "F.Cu")
		(net "SATA_A_NODE1_RX_P0")
	)
	(segment
		(start 155.279344 -64.08039)
		(end 151.176736 -64.08039)
		(width 0.10414)
		(layer "F.Cu")
		(net "SATA_A_NODE1_RX_P0")
	)
	(segment
		(start 160.684464 -58.67527)
		(end 160.404556 -58.67527)
		(width 0.10414)
		(layer "F.Cu")
		(net "SATA_A_NODE1_RX_P0")
	)
	(segment
		(start 160.18383 -59.175904)
		(end 159.963104 -59.39663)
		(width 0.10414)
		(layer "F.Cu")
		(net "SATA_A_NODE1_RX_P0")
	)
	(segment
		(start 163.17976 -53.806344)
		(end 163.31946 -53.946044)
		(width 0.10414)
		(layer "F.Cu")
		(net "SATA_A_NODE1_RX_P0")
	)
	(segment
		(start 163.31946 -53.354224)
		(end 163.17976 -53.493924)
		(width 0.10414)
		(layer "F.Cu")
		(net "SATA_A_NODE1_RX_P0")
	)
	(segment
		(start 158.01975 -61.060076)
		(end 158.01975 -61.339984)
		(width 0.10414)
		(layer "F.Cu")
		(net "SATA_A_NODE1_RX_P0")
	)
	(segment
		(start 160.90519 -58.454544)
		(end 160.684464 -58.67527)
		(width 0.10414)
		(layer "F.Cu")
		(net "SATA_A_NODE1_RX_P0")
	)
	(segment
		(start 161.847276 -57.23255)
		(end 161.62655 -57.453276)
		(width 0.10414)
		(layer "F.Cu")
		(net "SATA_A_NODE1_RX_P0")
	)
	(segment
		(start 163.31946 -54.850284)
		(end 163.31946 -55.162704)
		(width 0.10414)
		(layer "F.Cu")
		(net "SATA_A_NODE1_RX_P0")
	)
	(segment
		(start 158.520384 -60.83935)
		(end 158.240476 -60.83935)
		(width 0.10414)
		(layer "F.Cu")
		(net "SATA_A_NODE1_RX_P0")
	)
	(via
		(at 161.280348 -50.830734)
		(size 0.508)
		(drill 0.254)
		(layers "F.Cu" "B.Cu")
		(net "SATA_A_NODE1_RX_P0")
	)
	(segment
		(start 160.862518 -50.412904)
		(end 160.412938 -50.412904)
		(width 0.10414)
		(layer "B.Cu")
		(net "SATA_A_NODE1_RX_P0")
	)
	(segment
		(start 161.280348 -50.830734)
		(end 160.862518 -50.412904)
		(width 0.10414)
		(layer "B.Cu")
		(net "SATA_A_NODE1_RX_P0")
	)
	(segment
		(start 160.412938 -50.412904)
		(end 160.201864 -50.623978)
		(width 0.10414)
		(layer "B.Cu")
		(net "SATA_A_NODE1_RX_P0")
	)
	(segment
		(start 62.141862 -128.058926)
		(end 61.74105 -127.658114)
		(width 0.1016)
		(layer "F.Cu")
		(net "BMC_ROMD2")
	)
	(segment
		(start 62.141862 -128.059434)
		(end 62.141862 -128.058926)
		(width 0.1016)
		(layer "F.Cu")
		(net "BMC_ROMD2")
	)
	(via
		(at 61.74105 -127.658114)
		(size 0.49022)
		(drill 0.254)
		(layers "F.Cu" "B.Cu")
		(net "BMC_ROMD2")
	)
	(via
		(at 60.8838 -123.674378)
		(size 0.6604)
		(drill 0.3302)
		(layers "F.Cu" "B.Cu")
		(net "BMC_ROMD2")
	)
	(segment
		(start 61.444886 -122.782076)
		(end 61.444886 -121.444512)
		(width 0.1016)
		(layer "B.Cu")
		(net "BMC_ROMD2")
	)
	(segment
		(start 60.8838 -123.343162)
		(end 61.444886 -122.782076)
		(width 0.1016)
		(layer "B.Cu")
		(net "BMC_ROMD2")
	)
	(segment
		(start 61.038486 -126.378462)
		(end 61.622686 -126.962662)
		(width 0.1016)
		(layer "B.Cu")
		(net "BMC_ROMD2")
	)
	(segment
		(start 61.622686 -127.53975)
		(end 61.74105 -127.658114)
		(width 0.1016)
		(layer "B.Cu")
		(net "BMC_ROMD2")
	)
	(segment
		(start 61.038486 -123.829064)
		(end 61.038486 -126.378462)
		(width 0.1016)
		(layer "B.Cu")
		(net "BMC_ROMD2")
	)
	(segment
		(start 60.8838 -123.674378)
		(end 60.8838 -123.343162)
		(width 0.1016)
		(layer "B.Cu")
		(net "BMC_ROMD2")
	)
	(segment
		(start 60.8838 -123.674378)
		(end 61.038486 -123.829064)
		(width 0.1016)
		(layer "B.Cu")
		(net "BMC_ROMD2")
	)
	(segment
		(start 61.622686 -126.962662)
		(end 61.622686 -127.53975)
		(width 0.1016)
		(layer "B.Cu")
		(net "BMC_ROMD2")
	)
	(segment
		(start 59.168792 -59.694064)
		(end 59.168792 -59.447938)
		(width 0.1016)
		(layer "F.Cu")
		(net "M_DDR3_NODE1_MA8")
	)
	(segment
		(start 71.550022 -24.103838)
		(end 71.550022 -23.367238)
		(width 0.2286)
		(layer "F.Cu")
		(net "M_DDR3_NODE1_MA8")
	)
	(segment
		(start 70.80504 -25.669494)
		(end 70.80504 -24.84882)
		(width 0.2286)
		(layer "F.Cu")
		(net "M_DDR3_NODE1_MA8")
	)
	(segment
		(start 58.863484 -62.993778)
		(end 58.863484 -62.455298)
		(width 0.1016)
		(layer "F.Cu")
		(net "M_DDR3_NODE1_MA8")
	)
	(segment
		(start 59.273694 -62.045088)
		(end 59.273694 -59.798966)
		(width 0.1016)
		(layer "F.Cu")
		(net "M_DDR3_NODE1_MA8")
	)
	(segment
		(start 58.863484 -62.455298)
		(end 59.273694 -62.045088)
		(width 0.1016)
		(layer "F.Cu")
		(net "M_DDR3_NODE1_MA8")
	)
	(segment
		(start 70.80504 -24.84882)
		(end 71.550022 -24.103838)
		(width 0.2286)
		(layer "F.Cu")
		(net "M_DDR3_NODE1_MA8")
	)
	(segment
		(start 59.273694 -59.798966)
		(end 59.168792 -59.694064)
		(width 0.1016)
		(layer "F.Cu")
		(net "M_DDR3_NODE1_MA8")
	)
	(segment
		(start 71.550022 -23.367238)
		(end 71.550276 -23.366984)
		(width 0.2286)
		(layer "F.Cu")
		(net "M_DDR3_NODE1_MA8")
	)
	(segment
		(start 71.550276 -23.366984)
		(end 71.550276 -20.94992)
		(width 0.2286)
		(layer "F.Cu")
		(net "M_DDR3_NODE1_MA8")
	)
	(via
		(at 59.168792 -59.447938)
		(size 0.508)
		(drill 0.254)
		(layers "F.Cu" "B.Cu")
		(net "M_DDR3_NODE1_MA8")
	)
	(via
		(at 70.80504 -25.669494)
		(size 0.508)
		(drill 0.254)
		(layers "F.Cu" "B.Cu")
		(net "M_DDR3_NODE1_MA8")
	)
	(segment
		(start 69.110606 -39.001954)
		(end 68.89496 -38.786308)
		(width 0.2286)
		(layer "In2.Cu")
		(net "M_DDR3_NODE1_MA8")
	)
	(segment
		(start 70.29704 -26.177494)
		(end 70.29704 -29.889196)
		(width 0.2286)
		(layer "In2.Cu")
		(net "M_DDR3_NODE1_MA8")
	)
	(segment
		(start 67.251326 -39.095934)
		(end 62.53734 -43.80992)
		(width 0.2286)
		(layer "In2.Cu")
		(net "M_DDR3_NODE1_MA8")
	)
	(segment
		(start 70.80504 -25.669494)
		(end 70.29704 -26.177494)
		(width 0.2286)
		(layer "In2.Cu")
		(net "M_DDR3_NODE1_MA8")
	)
	(segment
		(start 68.89496 -33.48863)
		(end 68.74256 -33.33623)
		(width 0.2286)
		(layer "In2.Cu")
		(net "M_DDR3_NODE1_MA8")
	)
	(segment
		(start 68.89496 -38.786308)
		(end 68.89496 -33.48863)
		(width 0.2286)
		(layer "In2.Cu")
		(net "M_DDR3_NODE1_MA8")
	)
	(segment
		(start 59.3471 -59.26963)
		(end 59.168792 -59.447938)
		(width 0.2286)
		(layer "In2.Cu")
		(net "M_DDR3_NODE1_MA8")
	)
	(segment
		(start 62.53734 -50.330608)
		(end 59.3471 -53.520848)
		(width 0.2286)
		(layer "In2.Cu")
		(net "M_DDR3_NODE1_MA8")
	)
	(segment
		(start 59.3471 -53.520848)
		(end 59.3471 -59.26963)
		(width 0.2286)
		(layer "In2.Cu")
		(net "M_DDR3_NODE1_MA8")
	)
	(segment
		(start 70.29704 -29.889196)
		(end 69.63156 -30.554676)
		(width 0.2286)
		(layer "In2.Cu")
		(net "M_DDR3_NODE1_MA8")
	)
	(segment
		(start 69.63156 -38.786308)
		(end 69.415914 -39.001954)
		(width 0.2286)
		(layer "In2.Cu")
		(net "M_DDR3_NODE1_MA8")
	)
	(segment
		(start 62.53734 -43.80992)
		(end 62.53734 -50.330608)
		(width 0.2286)
		(layer "In2.Cu")
		(net "M_DDR3_NODE1_MA8")
	)
	(segment
		(start 68.0212 -39.095934)
		(end 67.251326 -39.095934)
		(width 0.2286)
		(layer "In2.Cu")
		(net "M_DDR3_NODE1_MA8")
	)
	(segment
		(start 68.15836 -33.48863)
		(end 68.15836 -38.958774)
		(width 0.2286)
		(layer "In2.Cu")
		(net "M_DDR3_NODE1_MA8")
	)
	(segment
		(start 68.74256 -33.33623)
		(end 68.31076 -33.33623)
		(width 0.2286)
		(layer "In2.Cu")
		(net "M_DDR3_NODE1_MA8")
	)
	(segment
		(start 68.15836 -38.958774)
		(end 68.0212 -39.095934)
		(width 0.2286)
		(layer "In2.Cu")
		(net "M_DDR3_NODE1_MA8")
	)
	(segment
		(start 69.415914 -39.001954)
		(end 69.110606 -39.001954)
		(width 0.2286)
		(layer "In2.Cu")
		(net "M_DDR3_NODE1_MA8")
	)
	(segment
		(start 69.63156 -30.554676)
		(end 69.63156 -38.786308)
		(width 0.2286)
		(layer "In2.Cu")
		(net "M_DDR3_NODE1_MA8")
	)
	(segment
		(start 68.31076 -33.33623)
		(end 68.15836 -33.48863)
		(width 0.2286)
		(layer "In2.Cu")
		(net "M_DDR3_NODE1_MA8")
	)
	(segment
		(start 45.604176 -107.055158)
		(end 45.604176 -107.691682)
		(width 0.254)
		(layer "F.Cu")
		(net "P3V3_STB_NODE1_EN")
	)
	(segment
		(start 45.604176 -107.691682)
		(end 45.608748 -107.696254)
		(width 0.254)
		(layer "F.Cu")
		(net "P3V3_STB_NODE1_EN")
	)
	(segment
		(start 45.608748 -108.502958)
		(end 45.608748 -107.696254)
		(width 0.254)
		(layer "F.Cu")
		(net "P3V3_STB_NODE1_EN")
	)
	(via
		(at 45.608748 -107.696254)
		(size 0.508)
		(drill 0.254)
		(layers "F.Cu" "B.Cu")
		(net "P3V3_STB_NODE1_EN")
	)
	(via
		(at 122.231658 -174.082964)
		(size 0.508)
		(drill 0.254)
		(layers "F.Cu" "B.Cu")
		(net "N21699372")
	)
	(segment
		(start 121.530618 -175.579532)
		(end 122.231658 -174.878492)
		(width 0.1016)
		(layer "B.Cu")
		(net "N21699372")
	)
	(segment
		(start 123.30811 -173.394624)
		(end 122.919998 -173.394624)
		(width 0.1016)
		(layer "B.Cu")
		(net "N21699372")
	)
	(segment
		(start 122.231658 -174.878492)
		(end 122.231658 -174.082964)
		(width 0.1016)
		(layer "B.Cu")
		(net "N21699372")
	)
	(segment
		(start 122.919998 -173.394624)
		(end 122.231658 -174.082964)
		(width 0.1016)
		(layer "B.Cu")
		(net "N21699372")
	)
	(segment
		(start 119.36476 -175.579532)
		(end 121.530618 -175.579532)
		(width 0.1016)
		(layer "B.Cu")
		(net "N21699372")
	)
	(segment
		(start 73.35012 -20.94992)
		(end 73.35012 -22.35962)
		(width 0.2286)
		(layer "F.Cu")
		(net "M_DDR3_NODE1_MA3")
	)
	(segment
		(start 73.35012 -22.35962)
		(end 73.348342 -22.361398)
		(width 0.2286)
		(layer "F.Cu")
		(net "M_DDR3_NODE1_MA3")
	)
	(segment
		(start 73.348342 -22.361398)
		(end 73.348342 -22.988778)
		(width 0.2286)
		(layer "F.Cu")
		(net "M_DDR3_NODE1_MA3")
	)
	(segment
		(start 60.323476 -64.199516)
		(end 60.348876 -64.199516)
		(width 0.2286)
		(layer "F.Cu")
		(net "M_DDR3_NODE1_MA3")
	)
	(segment
		(start 60.017406 -63.898526)
		(end 60.298076 -64.179196)
		(width 0.2286)
		(layer "F.Cu")
		(net "M_DDR3_NODE1_MA3")
	)
	(segment
		(start 59.89828 -63.898526)
		(end 60.017406 -63.898526)
		(width 0.2286)
		(layer "F.Cu")
		(net "M_DDR3_NODE1_MA3")
	)
	(segment
		(start 73.348342 -22.988778)
		(end 73.005442 -23.331678)
		(width 0.2286)
		(layer "F.Cu")
		(net "M_DDR3_NODE1_MA3")
	)
	(segment
		(start 60.303156 -64.179196)
		(end 60.323476 -64.199516)
		(width 0.2286)
		(layer "F.Cu")
		(net "M_DDR3_NODE1_MA3")
	)
	(segment
		(start 60.298076 -64.179196)
		(end 60.303156 -64.179196)
		(width 0.2286)
		(layer "F.Cu")
		(net "M_DDR3_NODE1_MA3")
	)
	(via
		(at 73.005442 -23.331678)
		(size 0.508)
		(drill 0.254)
		(layers "F.Cu" "B.Cu")
		(net "M_DDR3_NODE1_MA3")
	)
	(via
		(at 60.348876 -64.199516)
		(size 0.508)
		(drill 0.254)
		(layers "F.Cu" "B.Cu")
		(net "M_DDR3_NODE1_MA3")
	)
	(segment
		(start 70.29196 -39.073582)
		(end 70.29196 -30.846776)
		(width 0.2286)
		(layer "In2.Cu")
		(net "M_DDR3_NODE1_MA3")
	)
	(segment
		(start 71.15048 -29.988256)
		(end 71.15048 -28.508706)
		(width 0.2286)
		(layer "In2.Cu")
		(net "M_DDR3_NODE1_MA3")
	)
	(segment
		(start 63.3222 -43.960288)
		(end 63.537846 -43.744642)
		(width 0.2286)
		(layer "In2.Cu")
		(net "M_DDR3_NODE1_MA3")
	)
	(segment
		(start 59.85129 -62.71514)
		(end 60.390278 -62.71514)
		(width 0.2286)
		(layer "In2.Cu")
		(net "M_DDR3_NODE1_MA3")
	)
	(segment
		(start 64.579754 -49.22901)
		(end 64.7954 -49.013364)
		(width 0.2286)
		(layer "In2.Cu")
		(net "M_DDR3_NODE1_MA3")
	)
	(segment
		(start 60.348876 -64.199516)
		(end 59.67984 -63.53048)
		(width 0.2286)
		(layer "In2.Cu")
		(net "M_DDR3_NODE1_MA3")
	)
	(segment
		(start 59.67984 -63.53048)
		(end 59.67984 -62.88659)
		(width 0.2286)
		(layer "In2.Cu")
		(net "M_DDR3_NODE1_MA3")
	)
	(segment
		(start 60.390278 -62.71514)
		(end 60.7441 -62.361318)
		(width 0.2286)
		(layer "In2.Cu")
		(net "M_DDR3_NODE1_MA3")
	)
	(segment
		(start 63.843154 -43.744642)
		(end 64.0588 -43.960288)
		(width 0.2286)
		(layer "In2.Cu")
		(net "M_DDR3_NODE1_MA3")
	)
	(segment
		(start 71.511922 -25.933146)
		(end 72.09282 -25.352248)
		(width 0.2286)
		(layer "In2.Cu")
		(net "M_DDR3_NODE1_MA3")
	)
	(segment
		(start 64.0588 -43.960288)
		(end 64.0588 -49.013364)
		(width 0.2286)
		(layer "In2.Cu")
		(net "M_DDR3_NODE1_MA3")
	)
	(segment
		(start 60.7441 -62.361318)
		(end 60.7441 -61.403738)
		(width 0.2286)
		(layer "In2.Cu")
		(net "M_DDR3_NODE1_MA3")
	)
	(segment
		(start 72.09282 -24.2443)
		(end 73.005442 -23.331678)
		(width 0.2286)
		(layer "In2.Cu")
		(net "M_DDR3_NODE1_MA3")
	)
	(segment
		(start 59.67984 -62.88659)
		(end 59.85129 -62.71514)
		(width 0.2286)
		(layer "In2.Cu")
		(net "M_DDR3_NODE1_MA3")
	)
	(segment
		(start 69.5071 -39.858442)
		(end 70.29196 -39.073582)
		(width 0.2286)
		(layer "In2.Cu")
		(net "M_DDR3_NODE1_MA3")
	)
	(segment
		(start 70.29196 -30.846776)
		(end 71.15048 -29.988256)
		(width 0.2286)
		(layer "In2.Cu")
		(net "M_DDR3_NODE1_MA3")
	)
	(segment
		(start 60.0075 -53.797962)
		(end 63.3222 -50.483262)
		(width 0.2286)
		(layer "In2.Cu")
		(net "M_DDR3_NODE1_MA3")
	)
	(segment
		(start 64.7954 -42.879772)
		(end 67.81673 -39.858442)
		(width 0.2286)
		(layer "In2.Cu")
		(net "M_DDR3_NODE1_MA3")
	)
	(segment
		(start 71.511922 -28.147264)
		(end 71.511922 -25.933146)
		(width 0.2286)
		(layer "In2.Cu")
		(net "M_DDR3_NODE1_MA3")
	)
	(segment
		(start 64.7954 -49.013364)
		(end 64.7954 -42.879772)
		(width 0.2286)
		(layer "In2.Cu")
		(net "M_DDR3_NODE1_MA3")
	)
	(segment
		(start 64.274446 -49.22901)
		(end 64.579754 -49.22901)
		(width 0.2286)
		(layer "In2.Cu")
		(net "M_DDR3_NODE1_MA3")
	)
	(segment
		(start 60.0075 -60.667138)
		(end 60.0075 -53.797962)
		(width 0.2286)
		(layer "In2.Cu")
		(net "M_DDR3_NODE1_MA3")
	)
	(segment
		(start 71.15048 -28.508706)
		(end 71.511922 -28.147264)
		(width 0.2286)
		(layer "In2.Cu")
		(net "M_DDR3_NODE1_MA3")
	)
	(segment
		(start 64.0588 -49.013364)
		(end 64.274446 -49.22901)
		(width 0.2286)
		(layer "In2.Cu")
		(net "M_DDR3_NODE1_MA3")
	)
	(segment
		(start 72.09282 -25.352248)
		(end 72.09282 -24.2443)
		(width 0.2286)
		(layer "In2.Cu")
		(net "M_DDR3_NODE1_MA3")
	)
	(segment
		(start 60.7441 -61.403738)
		(end 60.0075 -60.667138)
		(width 0.2286)
		(layer "In2.Cu")
		(net "M_DDR3_NODE1_MA3")
	)
	(segment
		(start 63.3222 -50.483262)
		(end 63.3222 -43.960288)
		(width 0.2286)
		(layer "In2.Cu")
		(net "M_DDR3_NODE1_MA3")
	)
	(segment
		(start 67.81673 -39.858442)
		(end 69.5071 -39.858442)
		(width 0.2286)
		(layer "In2.Cu")
		(net "M_DDR3_NODE1_MA3")
	)
	(segment
		(start 63.537846 -43.744642)
		(end 63.843154 -43.744642)
		(width 0.2286)
		(layer "In2.Cu")
		(net "M_DDR3_NODE1_MA3")
	)
	(segment
		(start 41.852596 -112.033558)
		(end 41.852596 -113.038636)
		(width 0.254)
		(layer "F.Cu")
		(net "P3V3_STB_NODE1_FB")
	)
	(segment
		(start 41.852596 -111.866172)
		(end 41.852596 -112.033558)
		(width 0.254)
		(layer "F.Cu")
		(net "P3V3_STB_NODE1_FB")
	)
	(segment
		(start 44.383706 -110.727998)
		(end 44.01947 -110.727998)
		(width 0.254)
		(layer "F.Cu")
		(net "P3V3_STB_NODE1_FB")
	)
	(segment
		(start 42.51833 -110.955836)
		(end 42.51833 -111.200438)
		(width 0.254)
		(layer "F.Cu")
		(net "P3V3_STB_NODE1_FB")
	)
	(segment
		(start 43.791632 -110.955836)
		(end 43.353482 -110.955836)
		(width 0.254)
		(layer "F.Cu")
		(net "P3V3_STB_NODE1_FB")
	)
	(segment
		(start 43.353482 -110.955836)
		(end 42.51833 -110.955836)
		(width 0.254)
		(layer "F.Cu")
		(net "P3V3_STB_NODE1_FB")
	)
	(segment
		(start 42.51833 -111.200438)
		(end 41.852596 -111.866172)
		(width 0.254)
		(layer "F.Cu")
		(net "P3V3_STB_NODE1_FB")
	)
	(segment
		(start 44.01947 -110.727998)
		(end 43.791632 -110.955836)
		(width 0.254)
		(layer "F.Cu")
		(net "P3V3_STB_NODE1_FB")
	)
	(via
		(at 43.353482 -110.955836)
		(size 0.508)
		(drill 0.254)
		(layers "F.Cu" "B.Cu")
		(net "P3V3_STB_NODE1_FB")
	)
	(via
		(at 60.11672 -177.969672)
		(size 0.6604)
		(drill 0.3302)
		(layers "F.Cu" "B.Cu")
		(net "N21700864")
	)
	(segment
		(start 59.49569 -178.590702)
		(end 60.11672 -177.969672)
		(width 0.1016)
		(layer "B.Cu")
		(net "N21700864")
	)
	(segment
		(start 60.747148 -178.6001)
		(end 60.11672 -177.969672)
		(width 0.1016)
		(layer "B.Cu")
		(net "N21700864")
	)
	(segment
		(start 61.302392 -178.6001)
		(end 60.747148 -178.6001)
		(width 0.1016)
		(layer "B.Cu")
		(net "N21700864")
	)
	(segment
		(start 58.15076 -178.590702)
		(end 59.49569 -178.590702)
		(width 0.1016)
		(layer "B.Cu")
		(net "N21700864")
	)
	(segment
		(start 66.474086 -127.724662)
		(end 66.540888 -127.658114)
		(width 0.1016)
		(layer "F.Cu")
		(net "BMC_ROMA14")
	)
	(segment
		(start 66.141854 -128.059434)
		(end 66.141854 -128.057148)
		(width 0.1016)
		(layer "F.Cu")
		(net "BMC_ROMA14")
	)
	(segment
		(start 66.141854 -128.057148)
		(end 66.474086 -127.724662)
		(width 0.1016)
		(layer "F.Cu")
		(net "BMC_ROMA14")
	)
	(via
		(at 67.61607 -122.769122)
		(size 0.6604)
		(drill 0.3302)
		(layers "F.Cu" "B.Cu")
		(net "BMC_ROMA14")
	)
	(via
		(at 66.540888 -127.658114)
		(size 0.49022)
		(drill 0.254)
		(layers "F.Cu" "B.Cu")
		(net "BMC_ROMA14")
	)
	(segment
		(start 66.245486 -124.561346)
		(end 67.61607 -123.190762)
		(width 0.1016)
		(layer "B.Cu")
		(net "BMC_ROMA14")
	)
	(segment
		(start 66.651886 -126.886462)
		(end 66.245486 -126.480062)
		(width 0.1016)
		(layer "B.Cu")
		(net "BMC_ROMA14")
	)
	(segment
		(start 68.353686 -121.444512)
		(end 68.353686 -122.031506)
		(width 0.1016)
		(layer "B.Cu")
		(net "BMC_ROMA14")
	)
	(segment
		(start 66.245486 -126.480062)
		(end 66.245486 -124.561346)
		(width 0.1016)
		(layer "B.Cu")
		(net "BMC_ROMA14")
	)
	(segment
		(start 66.540888 -127.658114)
		(end 66.651886 -127.547116)
		(width 0.1016)
		(layer "B.Cu")
		(net "BMC_ROMA14")
	)
	(segment
		(start 66.651886 -127.547116)
		(end 66.651886 -126.886462)
		(width 0.1016)
		(layer "B.Cu")
		(net "BMC_ROMA14")
	)
	(segment
		(start 68.353686 -122.031506)
		(end 67.61607 -122.769122)
		(width 0.1016)
		(layer "B.Cu")
		(net "BMC_ROMA14")
	)
	(segment
		(start 67.61607 -123.190762)
		(end 67.61607 -122.769122)
		(width 0.1016)
		(layer "B.Cu")
		(net "BMC_ROMA14")
	)
	(segment
		(start 67.836542 -38.019482)
		(end 67.495166 -38.360858)
		(width 0.2286)
		(layer "F.Cu")
		(net "M_DDR3_NODE1_MA9")
	)
	(segment
		(start 66.148458 -37.62375)
		(end 63.512446 -40.259762)
		(width 0.2286)
		(layer "F.Cu")
		(net "M_DDR3_NODE1_MA9")
	)
	(segment
		(start 57.91581 -59.483752)
		(end 57.91581 -60.463684)
		(width 0.1016)
		(layer "F.Cu")
		(net "M_DDR3_NODE1_MA9")
	)
	(segment
		(start 58.052716 -63.494412)
		(end 58.053224 -63.49492)
		(width 0.1016)
		(layer "F.Cu")
		(net "M_DDR3_NODE1_MA9")
	)
	(segment
		(start 70.050152 -30.462728)
		(end 70.050152 -29.149802)
		(width 0.2286)
		(layer "F.Cu")
		(net "M_DDR3_NODE1_MA9")
	)
	(segment
		(start 63.21044 -48.645064)
		(end 61.80074 -50.054764)
		(width 0.2286)
		(layer "F.Cu")
		(net "M_DDR3_NODE1_MA9")
	)
	(segment
		(start 57.91581 -60.463684)
		(end 58.241692 -60.789566)
		(width 0.1016)
		(layer "F.Cu")
		(net "M_DDR3_NODE1_MA9")
	)
	(segment
		(start 66.669412 -38.881812)
		(end 66.669412 -39.186612)
		(width 0.2286)
		(layer "F.Cu")
		(net "M_DDR3_NODE1_MA9")
	)
	(segment
		(start 62.939168 -43.222164)
		(end 63.154814 -43.43781)
		(width 0.2286)
		(layer "F.Cu")
		(net "M_DDR3_NODE1_MA9")
	)
	(segment
		(start 58.409078 -62.375796)
		(end 58.409078 -62.720728)
		(width 0.1016)
		(layer "F.Cu")
		(net "M_DDR3_NODE1_MA9")
	)
	(segment
		(start 68.463922 -39.170864)
		(end 68.464176 -39.475664)
		(width 0.2286)
		(layer "F.Cu")
		(net "M_DDR3_NODE1_MA9")
	)
	(segment
		(start 67.942714 -38.955218)
		(end 68.248022 -38.954964)
		(width 0.2286)
		(layer "F.Cu")
		(net "M_DDR3_NODE1_MA9")
	)
	(segment
		(start 58.59526 -54.104794)
		(end 58.59526 -58.570114)
		(width 0.2286)
		(layer "F.Cu")
		(net "M_DDR3_NODE1_MA9")
	)
	(segment
		(start 66.148458 -38.665658)
		(end 66.453258 -38.665658)
		(width 0.2286)
		(layer "F.Cu")
		(net "M_DDR3_NODE1_MA9")
	)
	(segment
		(start 63.460122 -43.43781)
		(end 67.942714 -38.955218)
		(width 0.2286)
		(layer "F.Cu")
		(net "M_DDR3_NODE1_MA9")
	)
	(segment
		(start 67.495166 -38.360858)
		(end 67.190366 -38.360858)
		(width 0.2286)
		(layer "F.Cu")
		(net "M_DDR3_NODE1_MA9")
	)
	(segment
		(start 58.241692 -60.789566)
		(end 58.241692 -62.20841)
		(width 0.1016)
		(layer "F.Cu")
		(net "M_DDR3_NODE1_MA9")
	)
	(segment
		(start 63.21044 -44.7294)
		(end 63.21044 -48.645064)
		(width 0.2286)
		(layer "F.Cu")
		(net "M_DDR3_NODE1_MA9")
	)
	(segment
		(start 58.59526 -58.804302)
		(end 57.91581 -59.483752)
		(width 0.1016)
		(layer "F.Cu")
		(net "M_DDR3_NODE1_MA9")
	)
	(segment
		(start 67.836542 -36.831778)
		(end 67.836542 -34.553906)
		(width 0.2286)
		(layer "F.Cu")
		(net "M_DDR3_NODE1_MA9")
	)
	(segment
		(start 58.409078 -62.720728)
		(end 58.052716 -63.07709)
		(width 0.1016)
		(layer "F.Cu")
		(net "M_DDR3_NODE1_MA9")
	)
	(segment
		(start 70.208902 -32.181546)
		(end 70.208902 -30.621478)
		(width 0.2286)
		(layer "F.Cu")
		(net "M_DDR3_NODE1_MA9")
	)
	(segment
		(start 64.0334 -40.780716)
		(end 66.148458 -38.665658)
		(width 0.2286)
		(layer "F.Cu")
		(net "M_DDR3_NODE1_MA9")
	)
	(segment
		(start 66.453258 -38.665658)
		(end 66.669412 -38.881812)
		(width 0.2286)
		(layer "F.Cu")
		(net "M_DDR3_NODE1_MA9")
	)
	(segment
		(start 61.80074 -50.899314)
		(end 58.59526 -54.104794)
		(width 0.2286)
		(layer "F.Cu")
		(net "M_DDR3_NODE1_MA9")
	)
	(segment
		(start 63.154814 -43.43781)
		(end 63.460122 -43.43781)
		(width 0.2286)
		(layer "F.Cu")
		(net "M_DDR3_NODE1_MA9")
	)
	(segment
		(start 58.052716 -63.07709)
		(end 58.052716 -63.494412)
		(width 0.1016)
		(layer "F.Cu")
		(net "M_DDR3_NODE1_MA9")
	)
	(segment
		(start 58.59526 -58.570114)
		(end 58.59526 -58.804302)
		(width 0.1016)
		(layer "F.Cu")
		(net "M_DDR3_NODE1_MA9")
	)
	(segment
		(start 66.453258 -37.62375)
		(end 66.148458 -37.62375)
		(width 0.2286)
		(layer "F.Cu")
		(net "M_DDR3_NODE1_MA9")
	)
	(segment
		(start 68.464176 -39.475664)
		(end 63.21044 -44.7294)
		(width 0.2286)
		(layer "F.Cu")
		(net "M_DDR3_NODE1_MA9")
	)
	(segment
		(start 70.208902 -30.621478)
		(end 70.050152 -30.462728)
		(width 0.2286)
		(layer "F.Cu")
		(net "M_DDR3_NODE1_MA9")
	)
	(segment
		(start 61.80074 -50.054764)
		(end 61.80074 -50.899314)
		(width 0.2286)
		(layer "F.Cu")
		(net "M_DDR3_NODE1_MA9")
	)
	(segment
		(start 67.190366 -38.360858)
		(end 66.453258 -37.62375)
		(width 0.2286)
		(layer "F.Cu")
		(net "M_DDR3_NODE1_MA9")
	)
	(segment
		(start 67.836542 -36.831778)
		(end 67.836542 -38.019482)
		(width 0.2286)
		(layer "F.Cu")
		(net "M_DDR3_NODE1_MA9")
	)
	(segment
		(start 58.241692 -62.20841)
		(end 58.409078 -62.375796)
		(width 0.1016)
		(layer "F.Cu")
		(net "M_DDR3_NODE1_MA9")
	)
	(segment
		(start 63.7286 -40.780716)
		(end 64.0334 -40.780716)
		(width 0.2286)
		(layer "F.Cu")
		(net "M_DDR3_NODE1_MA9")
	)
	(segment
		(start 66.669412 -39.186612)
		(end 62.939168 -42.916856)
		(width 0.2286)
		(layer "F.Cu")
		(net "M_DDR3_NODE1_MA9")
	)
	(segment
		(start 63.512446 -40.564562)
		(end 63.7286 -40.780716)
		(width 0.2286)
		(layer "F.Cu")
		(net "M_DDR3_NODE1_MA9")
	)
	(segment
		(start 62.939168 -42.916856)
		(end 62.939168 -43.222164)
		(width 0.2286)
		(layer "F.Cu")
		(net "M_DDR3_NODE1_MA9")
	)
	(segment
		(start 68.248022 -38.954964)
		(end 68.463922 -39.170864)
		(width 0.2286)
		(layer "F.Cu")
		(net "M_DDR3_NODE1_MA9")
	)
	(segment
		(start 63.512446 -40.259762)
		(end 63.512446 -40.564562)
		(width 0.2286)
		(layer "F.Cu")
		(net "M_DDR3_NODE1_MA9")
	)
	(segment
		(start 67.836542 -34.553906)
		(end 70.208902 -32.181546)
		(width 0.2286)
		(layer "F.Cu")
		(net "M_DDR3_NODE1_MA9")
	)
	(via
		(at 67.836542 -36.831778)
		(size 0.762)
		(drill 0.381)
		(layers "F.Cu" "B.Cu")
		(net "M_DDR3_NODE1_MA9")
	)
	(segment
		(start 42.732452 -110.023148)
		(end 42.569638 -109.860334)
		(width 0.254)
		(layer "F.Cu")
		(net "P3V3_STB_NODE1_VREG5")
	)
	(segment
		(start 42.78757 -106.51236)
		(end 42.551858 -106.748072)
		(width 0.254)
		(layer "F.Cu")
		(net "P3V3_STB_NODE1_VREG5")
	)
	(segment
		(start 42.569638 -109.860334)
		(end 42.569638 -109.495082)
		(width 0.254)
		(layer "F.Cu")
		(net "P3V3_STB_NODE1_VREG5")
	)
	(segment
		(start 44.383706 -110.227872)
		(end 43.659552 -110.227872)
		(width 0.254)
		(layer "F.Cu")
		(net "P3V3_STB_NODE1_VREG5")
	)
	(segment
		(start 43.686222 -106.075734)
		(end 43.235372 -106.075734)
		(width 0.254)
		(layer "F.Cu")
		(net "P3V3_STB_NODE1_VREG5")
	)
	(segment
		(start 41.94302 -107.35691)
		(end 42.551858 -106.748072)
		(width 0.254)
		(layer "F.Cu")
		(net "P3V3_STB_NODE1_VREG5")
	)
	(segment
		(start 43.235372 -106.075734)
		(end 42.798746 -106.51236)
		(width 0.254)
		(layer "F.Cu")
		(net "P3V3_STB_NODE1_VREG5")
	)
	(segment
		(start 42.798746 -106.51236)
		(end 42.78757 -106.51236)
		(width 0.254)
		(layer "F.Cu")
		(net "P3V3_STB_NODE1_VREG5")
	)
	(segment
		(start 43.659552 -110.227872)
		(end 43.454828 -110.023148)
		(width 0.254)
		(layer "F.Cu")
		(net "P3V3_STB_NODE1_VREG5")
	)
	(segment
		(start 43.454828 -110.023148)
		(end 42.732452 -110.023148)
		(width 0.254)
		(layer "F.Cu")
		(net "P3V3_STB_NODE1_VREG5")
	)
	(segment
		(start 41.94302 -108.868464)
		(end 41.94302 -107.35691)
		(width 0.254)
		(layer "F.Cu")
		(net "P3V3_STB_NODE1_VREG5")
	)
	(segment
		(start 42.569638 -109.495082)
		(end 41.94302 -108.868464)
		(width 0.254)
		(layer "F.Cu")
		(net "P3V3_STB_NODE1_VREG5")
	)
	(via
		(at 42.551858 -106.748072)
		(size 0.508)
		(drill 0.254)
		(layers "F.Cu" "B.Cu")
		(net "P3V3_STB_NODE1_VREG5")
	)
	(segment
		(start 94.851982 -179.386992)
		(end 94.851982 -179.386738)
		(width 0.1016)
		(layer "F.Cu")
		(net "N21700941")
	)
	(segment
		(start 95.927926 -179.384198)
		(end 95.978472 -179.333652)
		(width 0.1016)
		(layer "F.Cu")
		(net "N21700941")
	)
	(segment
		(start 94.851982 -179.386738)
		(end 94.854522 -179.384198)
		(width 0.1016)
		(layer "F.Cu")
		(net "N21700941")
	)
	(segment
		(start 97.792032 -179.333652)
		(end 97.819972 -179.361592)
		(width 0.1016)
		(layer "F.Cu")
		(net "N21700941")
	)
	(segment
		(start 94.854522 -179.384198)
		(end 95.927926 -179.384198)
		(width 0.1016)
		(layer "F.Cu")
		(net "N21700941")
	)
	(segment
		(start 97.819972 -179.361592)
		(end 97.819972 -179.363624)
		(width 0.1016)
		(layer "F.Cu")
		(net "N21700941")
	)
	(segment
		(start 95.978472 -179.333652)
		(end 97.792032 -179.333652)
		(width 0.1016)
		(layer "F.Cu")
		(net "N21700941")
	)
	(segment
		(start 94.851982 -178.370992)
		(end 94.851982 -179.386738)
		(width 0.1016)
		(layer "F.Cu")
		(net "N21700941")
	)
	(via
		(at 95.927926 -179.384198)
		(size 0.508)
		(drill 0.254)
		(layers "F.Cu" "B.Cu")
		(net "N21700941")
	)
	(segment
		(start 64.541908 -128.058926)
		(end 64.141096 -127.658114)
		(width 0.1016)
		(layer "F.Cu")
		(net "BMC_ROMA21")
	)
	(segment
		(start 64.541908 -128.059434)
		(end 64.541908 -128.058926)
		(width 0.1016)
		(layer "F.Cu")
		(net "BMC_ROMA21")
	)
	(via
		(at 64.141096 -127.658114)
		(size 0.49022)
		(drill 0.254)
		(layers "F.Cu" "B.Cu")
		(net "BMC_ROMA21")
	)
	(via
		(at 63.581788 -125.340364)
		(size 0.6604)
		(drill 0.3302)
		(layers "F.Cu" "B.Cu")
		(net "BMC_ROMA21")
	)
	(segment
		(start 63.375286 -123.990862)
		(end 63.375286 -125.133862)
		(width 0.1016)
		(layer "B.Cu")
		(net "BMC_ROMA21")
	)
	(segment
		(start 63.375286 -125.133862)
		(end 63.581788 -125.340364)
		(width 0.1016)
		(layer "B.Cu")
		(net "BMC_ROMA21")
	)
	(segment
		(start 63.705486 -125.464062)
		(end 63.581788 -125.340364)
		(width 0.1016)
		(layer "B.Cu")
		(net "BMC_ROMA21")
	)
	(segment
		(start 64.141096 -127.550672)
		(end 63.705486 -127.115062)
		(width 0.1016)
		(layer "B.Cu")
		(net "BMC_ROMA21")
	)
	(segment
		(start 64.899286 -121.444512)
		(end 64.899286 -122.466862)
		(width 0.1016)
		(layer "B.Cu")
		(net "BMC_ROMA21")
	)
	(segment
		(start 63.705486 -127.115062)
		(end 63.705486 -125.464062)
		(width 0.1016)
		(layer "B.Cu")
		(net "BMC_ROMA21")
	)
	(segment
		(start 64.899286 -122.466862)
		(end 63.375286 -123.990862)
		(width 0.1016)
		(layer "B.Cu")
		(net "BMC_ROMA21")
	)
	(segment
		(start 64.141096 -127.658114)
		(end 64.141096 -127.550672)
		(width 0.1016)
		(layer "B.Cu")
		(net "BMC_ROMA21")
	)
	(segment
		(start 48.29937 -85.762846)
		(end 48.308514 -85.77199)
		(width 0.1143)
		(layer "F.Cu")
		(net "PD_NODE1_NTB_CLKINN")
	)
	(segment
		(start 48.308514 -85.77199)
		(end 48.734218 -85.77199)
		(width 0.1143)
		(layer "F.Cu")
		(net "PD_NODE1_NTB_CLKINN")
	)
	(segment
		(start 48.734218 -85.77199)
		(end 48.82642 -85.679788)
		(width 0.1143)
		(layer "F.Cu")
		(net "PD_NODE1_NTB_CLKINN")
	)
	(via
		(at 48.82642 -85.679788)
		(size 0.508)
		(drill 0.254)
		(layers "F.Cu" "B.Cu")
		(net "PD_NODE1_NTB_CLKINN")
	)
	(via
		(at 49.66462 -86.600284)
		(size 0.6604)
		(drill 0.3302)
		(layers "F.Cu" "B.Cu")
		(net "PD_NODE1_NTB_CLKINN")
	)
	(segment
		(start 49.32299 -86.941914)
		(end 49.66462 -86.600284)
		(width 0.1016)
		(layer "B.Cu")
		(net "PD_NODE1_NTB_CLKINN")
	)
	(segment
		(start 49.22774 -85.678264)
		(end 49.66462 -86.115144)
		(width 0.1016)
		(layer "B.Cu")
		(net "PD_NODE1_NTB_CLKINN")
	)
	(segment
		(start 49.66462 -86.115144)
		(end 49.66462 -86.600284)
		(width 0.1016)
		(layer "B.Cu")
		(net "PD_NODE1_NTB_CLKINN")
	)
	(segment
		(start 48.82642 -85.679788)
		(end 48.82642 -85.678264)
		(width 0.1016)
		(layer "B.Cu")
		(net "PD_NODE1_NTB_CLKINN")
	)
	(segment
		(start 48.82642 -85.678264)
		(end 49.22774 -85.678264)
		(width 0.1016)
		(layer "B.Cu")
		(net "PD_NODE1_NTB_CLKINN")
	)
	(segment
		(start 49.32299 -88.095836)
		(end 49.32299 -86.941914)
		(width 0.1016)
		(layer "B.Cu")
		(net "PD_NODE1_NTB_CLKINN")
	)
	(segment
		(start 71.416672 -51.497992)
		(end 72.15378 -52.2351)
		(width 0.2286)
		(layer "F.Cu")
		(net "M_DDR3_NODE1_MA10")
	)
	(segment
		(start 68.856606 -53.668168)
		(end 69.31025 -53.668168)
		(width 0.2286)
		(layer "F.Cu")
		(net "M_DDR3_NODE1_MA10")
	)
	(segment
		(start 62.738 -56.011572)
		(end 64.652398 -54.097174)
		(width 0.2286)
		(layer "F.Cu")
		(net "M_DDR3_NODE1_MA10")
	)
	(segment
		(start 71.632826 -52.756054)
		(end 71.416672 -52.5399)
		(width 0.2286)
		(layer "F.Cu")
		(net "M_DDR3_NODE1_MA10")
	)
	(segment
		(start 71.111872 -51.497992)
		(end 71.416672 -51.497992)
		(width 0.2286)
		(layer "F.Cu")
		(net "M_DDR3_NODE1_MA10")
	)
	(segment
		(start 77.01788 -24.992838)
		(end 77.550264 -24.460454)
		(width 0.2286)
		(layer "F.Cu")
		(net "M_DDR3_NODE1_MA10")
	)
	(segment
		(start 76.553314 -47.217076)
		(end 75.522328 -47.217076)
		(width 0.2286)
		(layer "F.Cu")
		(net "M_DDR3_NODE1_MA10")
	)
	(segment
		(start 75.766422 -48.927258)
		(end 75.766422 -48.358298)
		(width 0.2286)
		(layer "F.Cu")
		(net "M_DDR3_NODE1_MA10")
	)
	(segment
		(start 75.306682 -47.00143)
		(end 75.306682 -46.696122)
		(width 0.2286)
		(layer "F.Cu")
		(net "M_DDR3_NODE1_MA10")
	)
	(segment
		(start 75.306682 -46.696122)
		(end 75.522328 -46.480476)
		(width 0.2286)
		(layer "F.Cu")
		(net "M_DDR3_NODE1_MA10")
	)
	(segment
		(start 77.550264 -24.460454)
		(end 77.550264 -20.94992)
		(width 0.2286)
		(layer "F.Cu")
		(net "M_DDR3_NODE1_MA10")
	)
	(segment
		(start 76.022962 -48.101758)
		(end 76.591922 -48.101758)
		(width 0.2286)
		(layer "F.Cu")
		(net "M_DDR3_NODE1_MA10")
	)
	(segment
		(start 62.018672 -60.924694)
		(end 62.56782 -60.375546)
		(width 0.1016)
		(layer "F.Cu")
		(net "M_DDR3_NODE1_MA10")
	)
	(segment
		(start 70.596506 -54.097174)
		(end 71.632826 -53.060854)
		(width 0.2286)
		(layer "F.Cu")
		(net "M_DDR3_NODE1_MA10")
	)
	(segment
		(start 62.738 -58.551572)
		(end 62.738 -58.035444)
		(width 0.1016)
		(layer "F.Cu")
		(net "M_DDR3_NODE1_MA10")
	)
	(segment
		(start 71.111872 -52.5399)
		(end 70.533006 -53.118766)
		(width 0.2286)
		(layer "F.Cu")
		(net "M_DDR3_NODE1_MA10")
	)
	(segment
		(start 62.56782 -60.375546)
		(end 62.56782 -58.721752)
		(width 0.1016)
		(layer "F.Cu")
		(net "M_DDR3_NODE1_MA10")
	)
	(segment
		(start 76.591922 -48.101758)
		(end 76.76896 -47.92472)
		(width 0.2286)
		(layer "F.Cu")
		(net "M_DDR3_NODE1_MA10")
	)
	(segment
		(start 75.522328 -46.480476)
		(end 76.553314 -46.480476)
		(width 0.2286)
		(layer "F.Cu")
		(net "M_DDR3_NODE1_MA10")
	)
	(segment
		(start 68.4276 -54.097174)
		(end 68.856606 -53.668168)
		(width 0.2286)
		(layer "F.Cu")
		(net "M_DDR3_NODE1_MA10")
	)
	(segment
		(start 69.31025 -53.668168)
		(end 69.739256 -54.097174)
		(width 0.2286)
		(layer "F.Cu")
		(net "M_DDR3_NODE1_MA10")
	)
	(segment
		(start 62.56782 -58.721752)
		(end 62.738 -58.551572)
		(width 0.1016)
		(layer "F.Cu")
		(net "M_DDR3_NODE1_MA10")
	)
	(segment
		(start 76.553314 -46.480476)
		(end 76.76896 -46.26483)
		(width 0.2286)
		(layer "F.Cu")
		(net "M_DDR3_NODE1_MA10")
	)
	(segment
		(start 75.522328 -47.217076)
		(end 75.306682 -47.00143)
		(width 0.2286)
		(layer "F.Cu")
		(net "M_DDR3_NODE1_MA10")
	)
	(segment
		(start 70.227698 -53.118766)
		(end 70.012052 -52.90312)
		(width 0.2286)
		(layer "F.Cu")
		(net "M_DDR3_NODE1_MA10")
	)
	(segment
		(start 61.885576 -63.047118)
		(end 61.885576 -62.116462)
		(width 0.1016)
		(layer "F.Cu")
		(net "M_DDR3_NODE1_MA10")
	)
	(segment
		(start 76.76896 -47.92472)
		(end 76.76896 -47.432722)
		(width 0.2286)
		(layer "F.Cu")
		(net "M_DDR3_NODE1_MA10")
	)
	(segment
		(start 71.632826 -53.060854)
		(end 71.632826 -52.756054)
		(width 0.2286)
		(layer "F.Cu")
		(net "M_DDR3_NODE1_MA10")
	)
	(segment
		(start 64.652398 -54.097174)
		(end 68.4276 -54.097174)
		(width 0.2286)
		(layer "F.Cu")
		(net "M_DDR3_NODE1_MA10")
	)
	(segment
		(start 72.15378 -52.2351)
		(end 72.45858 -52.2351)
		(width 0.2286)
		(layer "F.Cu")
		(net "M_DDR3_NODE1_MA10")
	)
	(segment
		(start 72.45858 -52.2351)
		(end 75.766422 -48.927258)
		(width 0.2286)
		(layer "F.Cu")
		(net "M_DDR3_NODE1_MA10")
	)
	(segment
		(start 71.416672 -52.5399)
		(end 71.111872 -52.5399)
		(width 0.2286)
		(layer "F.Cu")
		(net "M_DDR3_NODE1_MA10")
	)
	(segment
		(start 76.76896 -46.26483)
		(end 76.76896 -33.955736)
		(width 0.2286)
		(layer "F.Cu")
		(net "M_DDR3_NODE1_MA10")
	)
	(segment
		(start 70.012052 -52.90312)
		(end 70.012052 -52.597812)
		(width 0.2286)
		(layer "F.Cu")
		(net "M_DDR3_NODE1_MA10")
	)
	(segment
		(start 61.885576 -62.116462)
		(end 62.018672 -61.983366)
		(width 0.1016)
		(layer "F.Cu")
		(net "M_DDR3_NODE1_MA10")
	)
	(segment
		(start 75.766422 -48.358298)
		(end 76.022962 -48.101758)
		(width 0.2286)
		(layer "F.Cu")
		(net "M_DDR3_NODE1_MA10")
	)
	(segment
		(start 76.76896 -47.432722)
		(end 76.553314 -47.217076)
		(width 0.2286)
		(layer "F.Cu")
		(net "M_DDR3_NODE1_MA10")
	)
	(segment
		(start 70.012052 -52.597812)
		(end 71.111872 -51.497992)
		(width 0.2286)
		(layer "F.Cu")
		(net "M_DDR3_NODE1_MA10")
	)
	(segment
		(start 62.018672 -61.983366)
		(end 62.018672 -60.924694)
		(width 0.1016)
		(layer "F.Cu")
		(net "M_DDR3_NODE1_MA10")
	)
	(segment
		(start 69.739256 -54.097174)
		(end 70.596506 -54.097174)
		(width 0.2286)
		(layer "F.Cu")
		(net "M_DDR3_NODE1_MA10")
	)
	(segment
		(start 62.738 -58.035444)
		(end 62.738 -56.011572)
		(width 0.2286)
		(layer "F.Cu")
		(net "M_DDR3_NODE1_MA10")
	)
	(segment
		(start 70.533006 -53.118766)
		(end 70.227698 -53.118766)
		(width 0.2286)
		(layer "F.Cu")
		(net "M_DDR3_NODE1_MA10")
	)
	(segment
		(start 76.76896 -33.955736)
		(end 76.94422 -33.780476)
		(width 0.2286)
		(layer "F.Cu")
		(net "M_DDR3_NODE1_MA10")
	)
	(via
		(at 76.94422 -33.780476)
		(size 0.508)
		(drill 0.254)
		(layers "F.Cu" "B.Cu")
		(net "M_DDR3_NODE1_MA10")
	)
	(via
		(at 77.01788 -24.992838)
		(size 0.508)
		(drill 0.254)
		(layers "F.Cu" "B.Cu")
		(net "M_DDR3_NODE1_MA10")
	)
	(segment
		(start 77.01788 -33.706816)
		(end 76.94422 -33.780476)
		(width 0.2286)
		(layer "In2.Cu")
		(net "M_DDR3_NODE1_MA10")
	)
	(segment
		(start 77.01788 -24.992838)
		(end 77.01788 -33.706816)
		(width 0.2286)
		(layer "In2.Cu")
		(net "M_DDR3_NODE1_MA10")
	)
	(segment
		(start 50.753518 -155.270454)
		(end 51.300888 -155.817824)
		(width 0.127)
		(layer "F.Cu")
		(net "CLK_100M_NIC1_NODE1_DN")
	)
	(segment
		(start 133.334252 -125.25375)
		(end 133.130036 -125.25375)
		(width 0.127)
		(layer "F.Cu")
		(net "CLK_100M_NIC1_NODE1_DN")
	)
	(segment
		(start 132.851652 -124.975366)
		(end 132.851652 -122.637042)
		(width 0.127)
		(layer "F.Cu")
		(net "CLK_100M_NIC1_NODE1_DN")
	)
	(segment
		(start 49.85512 -155.270454)
		(end 50.753518 -155.270454)
		(width 0.127)
		(layer "F.Cu")
		(net "CLK_100M_NIC1_NODE1_DN")
	)
	(segment
		(start 51.300888 -155.817824)
		(end 52.568602 -155.817824)
		(width 0.127)
		(layer "F.Cu")
		(net "CLK_100M_NIC1_NODE1_DN")
	)
	(segment
		(start 132.699252 -121.623582)
		(end 132.753862 -121.568972)
		(width 0.127)
		(layer "F.Cu")
		(net "CLK_100M_NIC1_NODE1_DN")
	)
	(segment
		(start 133.130036 -125.25375)
		(end 132.851652 -124.975366)
		(width 0.127)
		(layer "F.Cu")
		(net "CLK_100M_NIC1_NODE1_DN")
	)
	(segment
		(start 132.851652 -122.637042)
		(end 132.699252 -122.484642)
		(width 0.127)
		(layer "F.Cu")
		(net "CLK_100M_NIC1_NODE1_DN")
	)
	(segment
		(start 132.753862 -121.568972)
		(end 132.753862 -121.064528)
		(width 0.127)
		(layer "F.Cu")
		(net "CLK_100M_NIC1_NODE1_DN")
	)
	(segment
		(start 49.757584 -155.172918)
		(end 49.85512 -155.270454)
		(width 0.127)
		(layer "F.Cu")
		(net "CLK_100M_NIC1_NODE1_DN")
	)
	(segment
		(start 49.117504 -155.172918)
		(end 49.757584 -155.172918)
		(width 0.127)
		(layer "F.Cu")
		(net "CLK_100M_NIC1_NODE1_DN")
	)
	(segment
		(start 132.699252 -122.484642)
		(end 132.699252 -121.623582)
		(width 0.127)
		(layer "F.Cu")
		(net "CLK_100M_NIC1_NODE1_DN")
	)
	(segment
		(start 52.568602 -155.817824)
		(end 53.061616 -155.32481)
		(width 0.127)
		(layer "F.Cu")
		(net "CLK_100M_NIC1_NODE1_DN")
	)
	(via
		(at 133.334252 -125.25375)
		(size 0.508)
		(drill 0.254)
		(layers "F.Cu" "B.Cu")
		(net "CLK_100M_NIC1_NODE1_DN")
	)
	(via
		(at 53.061616 -155.32481)
		(size 0.508)
		(drill 0.254)
		(layers "F.Cu" "B.Cu")
		(net "CLK_100M_NIC1_NODE1_DN")
	)
	(segment
		(start 132.84454 -126.573026)
		(end 132.84454 -126.251716)
		(width 0.127)
		(layer "In2.Cu")
		(net "CLK_100M_NIC1_NODE1_DN")
	)
	(segment
		(start 79.0321 -160.27527)
		(end 80.354678 -160.27527)
		(width 0.127)
		(layer "In2.Cu")
		(net "CLK_100M_NIC1_NODE1_DN")
	)
	(segment
		(start 78.534006 -159.777176)
		(end 79.0321 -160.27527)
		(width 0.127)
		(layer "In2.Cu")
		(net "CLK_100M_NIC1_NODE1_DN")
	)
	(segment
		(start 51.98364 -156.154628)
		(end 51.98364 -158.360364)
		(width 0.127)
		(layer "In2.Cu")
		(net "CLK_100M_NIC1_NODE1_DN")
	)
	(segment
		(start 53.061616 -155.32481)
		(end 52.572666 -155.81376)
		(width 0.127)
		(layer "In2.Cu")
		(net "CLK_100M_NIC1_NODE1_DN")
	)
	(segment
		(start 67.700398 -164.338508)
		(end 71.381874 -164.338508)
		(width 0.127)
		(layer "In2.Cu")
		(net "CLK_100M_NIC1_NODE1_DN")
	)
	(segment
		(start 80.354678 -160.27527)
		(end 81.066894 -159.563054)
		(width 0.127)
		(layer "In2.Cu")
		(net "CLK_100M_NIC1_NODE1_DN")
	)
	(segment
		(start 132.84454 -126.251716)
		(end 132.845302 -126.250954)
		(width 0.127)
		(layer "In2.Cu")
		(net "CLK_100M_NIC1_NODE1_DN")
	)
	(segment
		(start 132.845302 -126.250954)
		(end 132.845302 -125.489462)
		(width 0.127)
		(layer "In2.Cu")
		(net "CLK_100M_NIC1_NODE1_DN")
	)
	(segment
		(start 52.572666 -155.81376)
		(end 52.324508 -155.81376)
		(width 0.127)
		(layer "In2.Cu")
		(net "CLK_100M_NIC1_NODE1_DN")
	)
	(segment
		(start 71.381874 -164.338508)
		(end 75.943206 -159.777176)
		(width 0.127)
		(layer "In2.Cu")
		(net "CLK_100M_NIC1_NODE1_DN")
	)
	(segment
		(start 62.798452 -165.51275)
		(end 66.526156 -165.51275)
		(width 0.127)
		(layer "In2.Cu")
		(net "CLK_100M_NIC1_NODE1_DN")
	)
	(segment
		(start 84.56168 -158.932372)
		(end 84.56168 -151.158702)
		(width 0.127)
		(layer "In2.Cu")
		(net "CLK_100M_NIC1_NODE1_DN")
	)
	(segment
		(start 52.324508 -155.81376)
		(end 51.98364 -156.154628)
		(width 0.127)
		(layer "In2.Cu")
		(net "CLK_100M_NIC1_NODE1_DN")
	)
	(segment
		(start 132.845302 -125.489462)
		(end 133.081014 -125.25375)
		(width 0.127)
		(layer "In2.Cu")
		(net "CLK_100M_NIC1_NODE1_DN")
	)
	(segment
		(start 119.12346 -144.054576)
		(end 119.12346 -139.542266)
		(width 0.127)
		(layer "In2.Cu")
		(net "CLK_100M_NIC1_NODE1_DN")
	)
	(segment
		(start 119.12346 -139.542266)
		(end 131.35864 -127.307086)
		(width 0.127)
		(layer "In2.Cu")
		(net "CLK_100M_NIC1_NODE1_DN")
	)
	(segment
		(start 83.930998 -159.563054)
		(end 84.56168 -158.932372)
		(width 0.127)
		(layer "In2.Cu")
		(net "CLK_100M_NIC1_NODE1_DN")
	)
	(segment
		(start 51.98364 -158.360364)
		(end 53.6321 -160.008824)
		(width 0.127)
		(layer "In2.Cu")
		(net "CLK_100M_NIC1_NODE1_DN")
	)
	(segment
		(start 131.35864 -127.307086)
		(end 132.11048 -127.307086)
		(width 0.127)
		(layer "In2.Cu")
		(net "CLK_100M_NIC1_NODE1_DN")
	)
	(segment
		(start 66.526156 -165.51275)
		(end 67.700398 -164.338508)
		(width 0.127)
		(layer "In2.Cu")
		(net "CLK_100M_NIC1_NODE1_DN")
	)
	(segment
		(start 61.566552 -164.28085)
		(end 62.798452 -165.51275)
		(width 0.127)
		(layer "In2.Cu")
		(net "CLK_100M_NIC1_NODE1_DN")
	)
	(segment
		(start 84.56168 -151.158702)
		(end 88.97366 -146.746722)
		(width 0.127)
		(layer "In2.Cu")
		(net "CLK_100M_NIC1_NODE1_DN")
	)
	(segment
		(start 116.431314 -146.746722)
		(end 119.12346 -144.054576)
		(width 0.127)
		(layer "In2.Cu")
		(net "CLK_100M_NIC1_NODE1_DN")
	)
	(segment
		(start 88.97366 -146.746722)
		(end 116.431314 -146.746722)
		(width 0.127)
		(layer "In2.Cu")
		(net "CLK_100M_NIC1_NODE1_DN")
	)
	(segment
		(start 132.11048 -127.307086)
		(end 132.84454 -126.573026)
		(width 0.127)
		(layer "In2.Cu")
		(net "CLK_100M_NIC1_NODE1_DN")
	)
	(segment
		(start 53.6321 -160.008824)
		(end 53.6321 -162.530028)
		(width 0.127)
		(layer "In2.Cu")
		(net "CLK_100M_NIC1_NODE1_DN")
	)
	(segment
		(start 53.6321 -162.530028)
		(end 55.382922 -164.28085)
		(width 0.127)
		(layer "In2.Cu")
		(net "CLK_100M_NIC1_NODE1_DN")
	)
	(segment
		(start 75.943206 -159.777176)
		(end 78.534006 -159.777176)
		(width 0.127)
		(layer "In2.Cu")
		(net "CLK_100M_NIC1_NODE1_DN")
	)
	(segment
		(start 55.382922 -164.28085)
		(end 61.566552 -164.28085)
		(width 0.127)
		(layer "In2.Cu")
		(net "CLK_100M_NIC1_NODE1_DN")
	)
	(segment
		(start 133.081014 -125.25375)
		(end 133.334252 -125.25375)
		(width 0.127)
		(layer "In2.Cu")
		(net "CLK_100M_NIC1_NODE1_DN")
	)
	(segment
		(start 81.066894 -159.563054)
		(end 83.930998 -159.563054)
		(width 0.127)
		(layer "In2.Cu")
		(net "CLK_100M_NIC1_NODE1_DN")
	)
	(segment
		(start 80.80375 -154.990292)
		(end 81.410048 -155.59659)
		(width 0.254)
		(layer "F.Cu")
		(net "P5V_STB_NODE1_SS")
	)
	(segment
		(start 81.514188 -155.959302)
		(end 81.410048 -155.855162)
		(width 0.254)
		(layer "F.Cu")
		(net "P5V_STB_NODE1_SS")
	)
	(segment
		(start 80.298036 -154.990292)
		(end 80.80375 -154.990292)
		(width 0.254)
		(layer "F.Cu")
		(net "P5V_STB_NODE1_SS")
	)
	(segment
		(start 82.051144 -155.959302)
		(end 81.514188 -155.959302)
		(width 0.254)
		(layer "F.Cu")
		(net "P5V_STB_NODE1_SS")
	)
	(segment
		(start 81.410048 -155.59659)
		(end 81.410048 -155.855162)
		(width 0.254)
		(layer "F.Cu")
		(net "P5V_STB_NODE1_SS")
	)
	(via
		(at 81.410048 -155.855162)
		(size 0.508)
		(drill 0.254)
		(layers "F.Cu" "B.Cu")
		(net "P5V_STB_NODE1_SS")
	)
	(segment
		(start 105.191814 -178.093624)
		(end 103.103172 -178.093624)
		(width 0.1016)
		(layer "F.Cu")
		(net "N21700943")
	)
	(segment
		(start 105.236772 -178.048666)
		(end 105.315512 -177.969926)
		(width 0.1016)
		(layer "F.Cu")
		(net "N21700943")
	)
	(segment
		(start 105.236772 -178.048666)
		(end 105.191814 -178.093624)
		(width 0.1016)
		(layer "F.Cu")
		(net "N21700943")
	)
	(segment
		(start 106.026458 -177.969926)
		(end 106.026458 -176.965102)
		(width 0.1016)
		(layer "F.Cu")
		(net "N21700943")
	)
	(segment
		(start 105.315512 -177.969926)
		(end 106.026458 -177.969926)
		(width 0.1016)
		(layer "F.Cu")
		(net "N21700943")
	)
	(via
		(at 105.236772 -178.048666)
		(size 0.508)
		(drill 0.254)
		(layers "F.Cu" "B.Cu")
		(net "N21700943")
	)
	(segment
		(start 65.341754 -129.659126)
		(end 64.940942 -129.258314)
		(width 0.1016)
		(layer "F.Cu")
		(net "BMC_ROMA19")
	)
	(segment
		(start 65.341754 -129.659634)
		(end 65.341754 -129.659126)
		(width 0.1016)
		(layer "F.Cu")
		(net "BMC_ROMA19")
	)
	(via
		(at 66.194686 -123.482862)
		(size 0.6604)
		(drill 0.3302)
		(layers "F.Cu" "B.Cu")
		(net "BMC_ROMA19")
	)
	(via
		(at 64.940942 -129.258314)
		(size 0.49022)
		(drill 0.254)
		(layers "F.Cu" "B.Cu")
		(net "BMC_ROMA19")
	)
	(segment
		(start 66.194686 -123.074938)
		(end 66.194686 -123.482862)
		(width 0.1016)
		(layer "B.Cu")
		(net "BMC_ROMA19")
	)
	(segment
		(start 65.559686 -126.683262)
		(end 65.737486 -126.505462)
		(width 0.1016)
		(layer "B.Cu")
		(net "BMC_ROMA19")
	)
	(segment
		(start 67.286886 -121.444512)
		(end 67.286886 -121.982738)
		(width 0.1016)
		(layer "B.Cu")
		(net "BMC_ROMA19")
	)
	(segment
		(start 67.286886 -121.982738)
		(end 66.194686 -123.074938)
		(width 0.1016)
		(layer "B.Cu")
		(net "BMC_ROMA19")
	)
	(segment
		(start 64.940942 -129.258314)
		(end 64.940942 -129.054606)
		(width 0.1016)
		(layer "B.Cu")
		(net "BMC_ROMA19")
	)
	(segment
		(start 64.940942 -129.054606)
		(end 65.65392 -128.341628)
		(width 0.1016)
		(layer "B.Cu")
		(net "BMC_ROMA19")
	)
	(segment
		(start 65.559686 -127.221234)
		(end 65.559686 -126.683262)
		(width 0.1016)
		(layer "B.Cu")
		(net "BMC_ROMA19")
	)
	(segment
		(start 65.65392 -127.315468)
		(end 65.559686 -127.221234)
		(width 0.1016)
		(layer "B.Cu")
		(net "BMC_ROMA19")
	)
	(segment
		(start 66.194686 -123.686062)
		(end 66.194686 -123.482862)
		(width 0.1016)
		(layer "B.Cu")
		(net "BMC_ROMA19")
	)
	(segment
		(start 65.737486 -126.505462)
		(end 65.737486 -124.143262)
		(width 0.1016)
		(layer "B.Cu")
		(net "BMC_ROMA19")
	)
	(segment
		(start 65.737486 -124.143262)
		(end 66.194686 -123.686062)
		(width 0.1016)
		(layer "B.Cu")
		(net "BMC_ROMA19")
	)
	(segment
		(start 65.65392 -128.341628)
		(end 65.65392 -127.315468)
		(width 0.1016)
		(layer "B.Cu")
		(net "BMC_ROMA19")
	)
	(segment
		(start 73.96988 -68.080128)
		(end 74.34834 -67.701668)
		(width 0.1016)
		(layer "F.Cu")
		(net "M1_DQ_NODE1_DQ55")
	)
	(segment
		(start 95.250254 -27.909266)
		(end 95.5294 -27.63012)
		(width 0.1651)
		(layer "F.Cu")
		(net "M1_DQ_NODE1_DQ55")
	)
	(segment
		(start 95.250254 -29.149802)
		(end 95.250254 -27.909266)
		(width 0.1651)
		(layer "F.Cu")
		(net "M1_DQ_NODE1_DQ55")
	)
	(segment
		(start 73.247758 -68.080128)
		(end 73.96988 -68.080128)
		(width 0.1016)
		(layer "F.Cu")
		(net "M1_DQ_NODE1_DQ55")
	)
	(via
		(at 74.34834 -67.701668)
		(size 0.508)
		(drill 0.254)
		(layers "F.Cu" "B.Cu")
		(net "M1_DQ_NODE1_DQ55")
	)
	(via
		(at 95.5294 -27.63012)
		(size 0.508)
		(drill 0.254)
		(layers "F.Cu" "B.Cu")
		(net "M1_DQ_NODE1_DQ55")
	)
	(segment
		(start 86.094824 -53.758084)
		(end 86.094824 -53.463444)
		(width 0.2032)
		(layer "In7.Cu")
		(net "M1_DQ_NODE1_DQ55")
	)
	(segment
		(start 80.65008 -66.095372)
		(end 80.65008 -60.824872)
		(width 0.2032)
		(layer "In7.Cu")
		(net "M1_DQ_NODE1_DQ55")
	)
	(segment
		(start 75.80884 -67.73164)
		(end 76.86548 -67.73164)
		(width 0.1016)
		(layer "In7.Cu")
		(net "M1_DQ_NODE1_DQ55")
	)
	(segment
		(start 95.34144 -36.978844)
		(end 95.34144 -27.81808)
		(width 0.2032)
		(layer "In7.Cu")
		(net "M1_DQ_NODE1_DQ55")
	)
	(segment
		(start 80.040988 -66.704464)
		(end 80.65008 -66.095372)
		(width 0.2032)
		(layer "In7.Cu")
		(net "M1_DQ_NODE1_DQ55")
	)
	(segment
		(start 89.578942 -51.696366)
		(end 89.370662 -51.488086)
		(width 0.2032)
		(layer "In7.Cu")
		(net "M1_DQ_NODE1_DQ55")
	)
	(segment
		(start 74.34834 -67.701668)
		(end 74.725276 -67.324732)
		(width 0.1016)
		(layer "In7.Cu")
		(net "M1_DQ_NODE1_DQ55")
	)
	(segment
		(start 75.401932 -67.324732)
		(end 75.80884 -67.73164)
		(width 0.1016)
		(layer "In7.Cu")
		(net "M1_DQ_NODE1_DQ55")
	)
	(segment
		(start 89.578942 -51.991006)
		(end 89.578942 -51.696366)
		(width 0.2032)
		(layer "In7.Cu")
		(net "M1_DQ_NODE1_DQ55")
	)
	(segment
		(start 86.303104 -53.966364)
		(end 86.094824 -53.758084)
		(width 0.2032)
		(layer "In7.Cu")
		(net "M1_DQ_NODE1_DQ55")
	)
	(segment
		(start 74.725276 -67.324732)
		(end 75.401932 -67.324732)
		(width 0.1016)
		(layer "In7.Cu")
		(net "M1_DQ_NODE1_DQ55")
	)
	(segment
		(start 89.076022 -51.488086)
		(end 86.597744 -53.966364)
		(width 0.2032)
		(layer "In7.Cu")
		(net "M1_DQ_NODE1_DQ55")
	)
	(segment
		(start 86.311994 -55.162958)
		(end 86.40699 -55.162958)
		(width 0.2032)
		(layer "In7.Cu")
		(net "M1_DQ_NODE1_DQ55")
	)
	(segment
		(start 86.40699 -55.162958)
		(end 89.578942 -51.991006)
		(width 0.2032)
		(layer "In7.Cu")
		(net "M1_DQ_NODE1_DQ55")
	)
	(segment
		(start 80.65008 -60.824872)
		(end 86.311994 -55.162958)
		(width 0.2032)
		(layer "In7.Cu")
		(net "M1_DQ_NODE1_DQ55")
	)
	(segment
		(start 95.9485 -43.609768)
		(end 95.9485 -37.585904)
		(width 0.2032)
		(layer "In7.Cu")
		(net "M1_DQ_NODE1_DQ55")
	)
	(segment
		(start 95.34144 -27.81808)
		(end 95.5294 -27.63012)
		(width 0.2032)
		(layer "In7.Cu")
		(net "M1_DQ_NODE1_DQ55")
	)
	(segment
		(start 76.86548 -67.73164)
		(end 77.892656 -66.704464)
		(width 0.2032)
		(layer "In7.Cu")
		(net "M1_DQ_NODE1_DQ55")
	)
	(segment
		(start 89.370662 -51.488086)
		(end 89.076022 -51.488086)
		(width 0.2032)
		(layer "In7.Cu")
		(net "M1_DQ_NODE1_DQ55")
	)
	(segment
		(start 77.892656 -66.704464)
		(end 80.040988 -66.704464)
		(width 0.2032)
		(layer "In7.Cu")
		(net "M1_DQ_NODE1_DQ55")
	)
	(segment
		(start 95.9485 -37.585904)
		(end 95.34144 -36.978844)
		(width 0.2032)
		(layer "In7.Cu")
		(net "M1_DQ_NODE1_DQ55")
	)
	(segment
		(start 86.094824 -53.463444)
		(end 95.9485 -43.609768)
		(width 0.2032)
		(layer "In7.Cu")
		(net "M1_DQ_NODE1_DQ55")
	)
	(segment
		(start 86.597744 -53.966364)
		(end 86.303104 -53.966364)
		(width 0.2032)
		(layer "In7.Cu")
		(net "M1_DQ_NODE1_DQ55")
	)
	(segment
		(start 132.353812 -121.525792)
		(end 132.353812 -121.064528)
		(width 0.127)
		(layer "F.Cu")
		(net "CLK_100M_NIC1_NODE1_DP")
	)
	(segment
		(start 132.546852 -125.005338)
		(end 132.546852 -122.763534)
		(width 0.127)
		(layer "F.Cu")
		(net "CLK_100M_NIC1_NODE1_DP")
	)
	(segment
		(start 49.117504 -155.673044)
		(end 49.75733 -155.673044)
		(width 0.127)
		(layer "F.Cu")
		(net "CLK_100M_NIC1_NODE1_DP")
	)
	(segment
		(start 52.58943 -156.122624)
		(end 53.061616 -156.59481)
		(width 0.127)
		(layer "F.Cu")
		(net "CLK_100M_NIC1_NODE1_DP")
	)
	(segment
		(start 49.85512 -155.575254)
		(end 50.627026 -155.575254)
		(width 0.127)
		(layer "F.Cu")
		(net "CLK_100M_NIC1_NODE1_DP")
	)
	(segment
		(start 49.75733 -155.673044)
		(end 49.85512 -155.575254)
		(width 0.127)
		(layer "F.Cu")
		(net "CLK_100M_NIC1_NODE1_DP")
	)
	(segment
		(start 132.29844 -125.25375)
		(end 132.546852 -125.005338)
		(width 0.127)
		(layer "F.Cu")
		(net "CLK_100M_NIC1_NODE1_DP")
	)
	(segment
		(start 132.064252 -125.25375)
		(end 132.29844 -125.25375)
		(width 0.127)
		(layer "F.Cu")
		(net "CLK_100M_NIC1_NODE1_DP")
	)
	(segment
		(start 132.394452 -121.566432)
		(end 132.353812 -121.525792)
		(width 0.127)
		(layer "F.Cu")
		(net "CLK_100M_NIC1_NODE1_DP")
	)
	(segment
		(start 50.627026 -155.575254)
		(end 51.174396 -156.122624)
		(width 0.127)
		(layer "F.Cu")
		(net "CLK_100M_NIC1_NODE1_DP")
	)
	(segment
		(start 132.394452 -122.611134)
		(end 132.394452 -121.566432)
		(width 0.127)
		(layer "F.Cu")
		(net "CLK_100M_NIC1_NODE1_DP")
	)
	(segment
		(start 132.546852 -122.763534)
		(end 132.394452 -122.611134)
		(width 0.127)
		(layer "F.Cu")
		(net "CLK_100M_NIC1_NODE1_DP")
	)
	(segment
		(start 51.174396 -156.122624)
		(end 52.58943 -156.122624)
		(width 0.127)
		(layer "F.Cu")
		(net "CLK_100M_NIC1_NODE1_DP")
	)
	(via
		(at 53.061616 -156.59481)
		(size 0.508)
		(drill 0.254)
		(layers "F.Cu" "B.Cu")
		(net "CLK_100M_NIC1_NODE1_DP")
	)
	(via
		(at 132.064252 -125.25375)
		(size 0.508)
		(drill 0.254)
		(layers "F.Cu" "B.Cu")
		(net "CLK_100M_NIC1_NODE1_DP")
	)
	(segment
		(start 126.604268 -131.46786)
		(end 126.784608 -131.46786)
		(width 0.127)
		(layer "In2.Cu")
		(net "CLK_100M_NIC1_NODE1_DP")
	)
	(segment
		(start 128.492758 -129.75971)
		(end 128.492758 -129.57937)
		(width 0.127)
		(layer "In2.Cu")
		(net "CLK_100M_NIC1_NODE1_DP")
	)
	(segment
		(start 123.187968 -135.0645)
		(end 123.457462 -134.795006)
		(width 0.127)
		(layer "In2.Cu")
		(net "CLK_100M_NIC1_NODE1_DP")
	)
	(segment
		(start 125.615446 -132.456682)
		(end 125.88494 -132.187188)
		(width 0.127)
		(layer "In2.Cu")
		(net "CLK_100M_NIC1_NODE1_DP")
	)
	(segment
		(start 122.738134 -135.333994)
		(end 123.007628 -135.0645)
		(width 0.127)
		(layer "In2.Cu")
		(net "CLK_100M_NIC1_NODE1_DP")
	)
	(segment
		(start 80.23352 -159.98317)
		(end 80.945736 -159.270954)
		(width 0.127)
		(layer "In2.Cu")
		(net "CLK_100M_NIC1_NODE1_DP")
	)
	(segment
		(start 128.492758 -129.57937)
		(end 128.762252 -129.309876)
		(width 0.127)
		(layer "In2.Cu")
		(net "CLK_100M_NIC1_NODE1_DP")
	)
	(segment
		(start 127.323596 -130.748532)
		(end 127.503936 -130.748532)
		(width 0.127)
		(layer "In2.Cu")
		(net "CLK_100M_NIC1_NODE1_DP")
	)
	(segment
		(start 66.404998 -165.22065)
		(end 67.57924 -164.046408)
		(width 0.127)
		(layer "In2.Cu")
		(net "CLK_100M_NIC1_NODE1_DP")
	)
	(segment
		(start 126.784608 -131.46786)
		(end 127.054102 -131.198366)
		(width 0.127)
		(layer "In2.Cu")
		(net "CLK_100M_NIC1_NODE1_DP")
	)
	(segment
		(start 127.054102 -131.198366)
		(end 127.054102 -131.018026)
		(width 0.127)
		(layer "In2.Cu")
		(net "CLK_100M_NIC1_NODE1_DP")
	)
	(segment
		(start 132.34162 -125.25375)
		(end 132.064252 -125.25375)
		(width 0.127)
		(layer "In2.Cu")
		(net "CLK_100M_NIC1_NODE1_DP")
	)
	(segment
		(start 131.237482 -127.014986)
		(end 131.989322 -127.014986)
		(width 0.127)
		(layer "In2.Cu")
		(net "CLK_100M_NIC1_NODE1_DP")
	)
	(segment
		(start 53.9242 -159.887666)
		(end 53.9242 -162.40887)
		(width 0.127)
		(layer "In2.Cu")
		(net "CLK_100M_NIC1_NODE1_DP")
	)
	(segment
		(start 125.165612 -132.906516)
		(end 125.345952 -132.906516)
		(width 0.127)
		(layer "In2.Cu")
		(net "CLK_100M_NIC1_NODE1_DP")
	)
	(segment
		(start 123.007628 -135.0645)
		(end 123.187968 -135.0645)
		(width 0.127)
		(layer "In2.Cu")
		(net "CLK_100M_NIC1_NODE1_DP")
	)
	(segment
		(start 52.572666 -156.10586)
		(end 52.445666 -156.10586)
		(width 0.127)
		(layer "In2.Cu")
		(net "CLK_100M_NIC1_NODE1_DP")
	)
	(segment
		(start 132.55244 -126.451868)
		(end 132.55244 -126.130558)
		(width 0.127)
		(layer "In2.Cu")
		(net "CLK_100M_NIC1_NODE1_DP")
	)
	(segment
		(start 128.042924 -130.029204)
		(end 128.223264 -130.029204)
		(width 0.127)
		(layer "In2.Cu")
		(net "CLK_100M_NIC1_NODE1_DP")
	)
	(segment
		(start 52.27574 -158.239206)
		(end 53.9242 -159.887666)
		(width 0.127)
		(layer "In2.Cu")
		(net "CLK_100M_NIC1_NODE1_DP")
	)
	(segment
		(start 122.2883 -135.783828)
		(end 122.46864 -135.783828)
		(width 0.127)
		(layer "In2.Cu")
		(net "CLK_100M_NIC1_NODE1_DP")
	)
	(segment
		(start 125.615446 -132.637022)
		(end 125.615446 -132.456682)
		(width 0.127)
		(layer "In2.Cu")
		(net "CLK_100M_NIC1_NODE1_DP")
	)
	(segment
		(start 120.214136 -137.834116)
		(end 120.418352 -137.834116)
		(width 0.127)
		(layer "In2.Cu")
		(net "CLK_100M_NIC1_NODE1_DP")
	)
	(segment
		(start 124.17679 -133.895338)
		(end 124.446284 -133.625844)
		(width 0.127)
		(layer "In2.Cu")
		(net "CLK_100M_NIC1_NODE1_DP")
	)
	(segment
		(start 67.57924 -164.046408)
		(end 71.260716 -164.046408)
		(width 0.127)
		(layer "In2.Cu")
		(net "CLK_100M_NIC1_NODE1_DP")
	)
	(segment
		(start 125.88494 -132.187188)
		(end 126.06528 -132.187188)
		(width 0.127)
		(layer "In2.Cu")
		(net "CLK_100M_NIC1_NODE1_DP")
	)
	(segment
		(start 124.446284 -133.625844)
		(end 124.626624 -133.625844)
		(width 0.127)
		(layer "In2.Cu")
		(net "CLK_100M_NIC1_NODE1_DP")
	)
	(segment
		(start 124.896118 -133.35635)
		(end 124.896118 -133.17601)
		(width 0.127)
		(layer "In2.Cu")
		(net "CLK_100M_NIC1_NODE1_DP")
	)
	(segment
		(start 62.91961 -165.22065)
		(end 66.404998 -165.22065)
		(width 0.127)
		(layer "In2.Cu")
		(net "CLK_100M_NIC1_NODE1_DP")
	)
	(segment
		(start 53.061616 -156.59481)
		(end 52.572666 -156.10586)
		(width 0.127)
		(layer "In2.Cu")
		(net "CLK_100M_NIC1_NODE1_DP")
	)
	(segment
		(start 121.299478 -136.77265)
		(end 121.568972 -136.503156)
		(width 0.127)
		(layer "In2.Cu")
		(net "CLK_100M_NIC1_NODE1_DP")
	)
	(segment
		(start 131.989322 -127.014986)
		(end 132.55244 -126.451868)
		(width 0.127)
		(layer "In2.Cu")
		(net "CLK_100M_NIC1_NODE1_DP")
	)
	(segment
		(start 132.55244 -126.130558)
		(end 132.553202 -126.129796)
		(width 0.127)
		(layer "In2.Cu")
		(net "CLK_100M_NIC1_NODE1_DP")
	)
	(segment
		(start 116.310156 -146.454622)
		(end 118.83136 -143.933418)
		(width 0.127)
		(layer "In2.Cu")
		(net "CLK_100M_NIC1_NODE1_DP")
	)
	(segment
		(start 126.334774 -131.737354)
		(end 126.604268 -131.46786)
		(width 0.127)
		(layer "In2.Cu")
		(net "CLK_100M_NIC1_NODE1_DP")
	)
	(segment
		(start 127.054102 -131.018026)
		(end 127.323596 -130.748532)
		(width 0.127)
		(layer "In2.Cu")
		(net "CLK_100M_NIC1_NODE1_DP")
	)
	(segment
		(start 118.83136 -139.421108)
		(end 119.201438 -139.05103)
		(width 0.127)
		(layer "In2.Cu")
		(net "CLK_100M_NIC1_NODE1_DP")
	)
	(segment
		(start 122.018806 -136.053322)
		(end 122.2883 -135.783828)
		(width 0.127)
		(layer "In2.Cu")
		(net "CLK_100M_NIC1_NODE1_DP")
	)
	(segment
		(start 123.457462 -134.614666)
		(end 123.726956 -134.345172)
		(width 0.127)
		(layer "In2.Cu")
		(net "CLK_100M_NIC1_NODE1_DP")
	)
	(segment
		(start 127.77343 -130.298698)
		(end 128.042924 -130.029204)
		(width 0.127)
		(layer "In2.Cu")
		(net "CLK_100M_NIC1_NODE1_DP")
	)
	(segment
		(start 124.17679 -134.075678)
		(end 124.17679 -133.895338)
		(width 0.127)
		(layer "In2.Cu")
		(net "CLK_100M_NIC1_NODE1_DP")
	)
	(segment
		(start 128.942592 -129.309876)
		(end 131.237482 -127.014986)
		(width 0.127)
		(layer "In2.Cu")
		(net "CLK_100M_NIC1_NODE1_DP")
	)
	(segment
		(start 121.749312 -136.503156)
		(end 122.018806 -136.233662)
		(width 0.127)
		(layer "In2.Cu")
		(net "CLK_100M_NIC1_NODE1_DP")
	)
	(segment
		(start 83.80984 -159.270954)
		(end 84.26958 -158.811214)
		(width 0.127)
		(layer "In2.Cu")
		(net "CLK_100M_NIC1_NODE1_DP")
	)
	(segment
		(start 84.26958 -158.811214)
		(end 84.26958 -151.037544)
		(width 0.127)
		(layer "In2.Cu")
		(net "CLK_100M_NIC1_NODE1_DP")
	)
	(segment
		(start 119.944642 -138.10361)
		(end 120.214136 -137.834116)
		(width 0.127)
		(layer "In2.Cu")
		(net "CLK_100M_NIC1_NODE1_DP")
	)
	(segment
		(start 123.907296 -134.345172)
		(end 124.17679 -134.075678)
		(width 0.127)
		(layer "In2.Cu")
		(net "CLK_100M_NIC1_NODE1_DP")
	)
	(segment
		(start 125.345952 -132.906516)
		(end 125.615446 -132.637022)
		(width 0.127)
		(layer "In2.Cu")
		(net "CLK_100M_NIC1_NODE1_DP")
	)
	(segment
		(start 128.762252 -129.309876)
		(end 128.942592 -129.309876)
		(width 0.127)
		(layer "In2.Cu")
		(net "CLK_100M_NIC1_NODE1_DP")
	)
	(segment
		(start 52.445666 -156.10586)
		(end 52.27574 -156.275786)
		(width 0.127)
		(layer "In2.Cu")
		(net "CLK_100M_NIC1_NODE1_DP")
	)
	(segment
		(start 52.27574 -156.275786)
		(end 52.27574 -158.239206)
		(width 0.127)
		(layer "In2.Cu")
		(net "CLK_100M_NIC1_NODE1_DP")
	)
	(segment
		(start 128.223264 -130.029204)
		(end 128.492758 -129.75971)
		(width 0.127)
		(layer "In2.Cu")
		(net "CLK_100M_NIC1_NODE1_DP")
	)
	(segment
		(start 61.68771 -163.98875)
		(end 62.91961 -165.22065)
		(width 0.127)
		(layer "In2.Cu")
		(net "CLK_100M_NIC1_NODE1_DP")
	)
	(segment
		(start 126.06528 -132.187188)
		(end 126.334774 -131.917694)
		(width 0.127)
		(layer "In2.Cu")
		(net "CLK_100M_NIC1_NODE1_DP")
	)
	(segment
		(start 78.655164 -159.485076)
		(end 79.153258 -159.98317)
		(width 0.127)
		(layer "In2.Cu")
		(net "CLK_100M_NIC1_NODE1_DP")
	)
	(segment
		(start 123.726956 -134.345172)
		(end 123.907296 -134.345172)
		(width 0.127)
		(layer "In2.Cu")
		(net "CLK_100M_NIC1_NODE1_DP")
	)
	(segment
		(start 79.153258 -159.98317)
		(end 80.23352 -159.98317)
		(width 0.127)
		(layer "In2.Cu")
		(net "CLK_100M_NIC1_NODE1_DP")
	)
	(segment
		(start 84.26958 -151.037544)
		(end 88.852502 -146.454622)
		(width 0.127)
		(layer "In2.Cu")
		(net "CLK_100M_NIC1_NODE1_DP")
	)
	(segment
		(start 55.50408 -163.98875)
		(end 61.68771 -163.98875)
		(width 0.127)
		(layer "In2.Cu")
		(net "CLK_100M_NIC1_NODE1_DP")
	)
	(segment
		(start 124.626624 -133.625844)
		(end 124.896118 -133.35635)
		(width 0.127)
		(layer "In2.Cu")
		(net "CLK_100M_NIC1_NODE1_DP")
	)
	(segment
		(start 88.852502 -146.454622)
		(end 116.310156 -146.454622)
		(width 0.127)
		(layer "In2.Cu")
		(net "CLK_100M_NIC1_NODE1_DP")
	)
	(segment
		(start 53.9242 -162.40887)
		(end 55.50408 -163.98875)
		(width 0.127)
		(layer "In2.Cu")
		(net "CLK_100M_NIC1_NODE1_DP")
	)
	(segment
		(start 123.457462 -134.795006)
		(end 123.457462 -134.614666)
		(width 0.127)
		(layer "In2.Cu")
		(net "CLK_100M_NIC1_NODE1_DP")
	)
	(segment
		(start 132.553202 -126.129796)
		(end 132.553202 -125.465332)
		(width 0.127)
		(layer "In2.Cu")
		(net "CLK_100M_NIC1_NODE1_DP")
	)
	(segment
		(start 126.334774 -131.917694)
		(end 126.334774 -131.737354)
		(width 0.127)
		(layer "In2.Cu")
		(net "CLK_100M_NIC1_NODE1_DP")
	)
	(segment
		(start 119.470932 -138.57732)
		(end 119.675148 -138.57732)
		(width 0.127)
		(layer "In2.Cu")
		(net "CLK_100M_NIC1_NODE1_DP")
	)
	(segment
		(start 120.418352 -137.834116)
		(end 121.299478 -136.95299)
		(width 0.127)
		(layer "In2.Cu")
		(net "CLK_100M_NIC1_NODE1_DP")
	)
	(segment
		(start 119.675148 -138.57732)
		(end 119.944642 -138.307826)
		(width 0.127)
		(layer "In2.Cu")
		(net "CLK_100M_NIC1_NODE1_DP")
	)
	(segment
		(start 119.944642 -138.307826)
		(end 119.944642 -138.10361)
		(width 0.127)
		(layer "In2.Cu")
		(net "CLK_100M_NIC1_NODE1_DP")
	)
	(segment
		(start 75.822048 -159.485076)
		(end 78.655164 -159.485076)
		(width 0.127)
		(layer "In2.Cu")
		(net "CLK_100M_NIC1_NODE1_DP")
	)
	(segment
		(start 118.83136 -143.933418)
		(end 118.83136 -139.421108)
		(width 0.127)
		(layer "In2.Cu")
		(net "CLK_100M_NIC1_NODE1_DP")
	)
	(segment
		(start 121.568972 -136.503156)
		(end 121.749312 -136.503156)
		(width 0.127)
		(layer "In2.Cu")
		(net "CLK_100M_NIC1_NODE1_DP")
	)
	(segment
		(start 132.553202 -125.465332)
		(end 132.34162 -125.25375)
		(width 0.127)
		(layer "In2.Cu")
		(net "CLK_100M_NIC1_NODE1_DP")
	)
	(segment
		(start 124.896118 -133.17601)
		(end 125.165612 -132.906516)
		(width 0.127)
		(layer "In2.Cu")
		(net "CLK_100M_NIC1_NODE1_DP")
	)
	(segment
		(start 119.201438 -138.846814)
		(end 119.470932 -138.57732)
		(width 0.127)
		(layer "In2.Cu")
		(net "CLK_100M_NIC1_NODE1_DP")
	)
	(segment
		(start 119.201438 -139.05103)
		(end 119.201438 -138.846814)
		(width 0.127)
		(layer "In2.Cu")
		(net "CLK_100M_NIC1_NODE1_DP")
	)
	(segment
		(start 122.738134 -135.514334)
		(end 122.738134 -135.333994)
		(width 0.127)
		(layer "In2.Cu")
		(net "CLK_100M_NIC1_NODE1_DP")
	)
	(segment
		(start 71.260716 -164.046408)
		(end 75.822048 -159.485076)
		(width 0.127)
		(layer "In2.Cu")
		(net "CLK_100M_NIC1_NODE1_DP")
	)
	(segment
		(start 127.77343 -130.479038)
		(end 127.77343 -130.298698)
		(width 0.127)
		(layer "In2.Cu")
		(net "CLK_100M_NIC1_NODE1_DP")
	)
	(segment
		(start 80.945736 -159.270954)
		(end 83.80984 -159.270954)
		(width 0.127)
		(layer "In2.Cu")
		(net "CLK_100M_NIC1_NODE1_DP")
	)
	(segment
		(start 122.46864 -135.783828)
		(end 122.738134 -135.514334)
		(width 0.127)
		(layer "In2.Cu")
		(net "CLK_100M_NIC1_NODE1_DP")
	)
	(segment
		(start 121.299478 -136.95299)
		(end 121.299478 -136.77265)
		(width 0.127)
		(layer "In2.Cu")
		(net "CLK_100M_NIC1_NODE1_DP")
	)
	(segment
		(start 122.018806 -136.233662)
		(end 122.018806 -136.053322)
		(width 0.127)
		(layer "In2.Cu")
		(net "CLK_100M_NIC1_NODE1_DP")
	)
	(segment
		(start 127.503936 -130.748532)
		(end 127.77343 -130.479038)
		(width 0.127)
		(layer "In2.Cu")
		(net "CLK_100M_NIC1_NODE1_DP")
	)
	(via
		(at 75.768962 -155.748736)
		(size 0.508)
		(drill 0.254)
		(layers "F.Cu" "B.Cu")
		(net "SW_P5V_STB_NODE1_PH")
	)
	(segment
		(start 66.9417 -142.459456)
		(end 67.314826 -142.832582)
		(width 0.254)
		(layer "F.Cu")
		(net "TP_BMC_NODE1_ADCVREFN")
	)
	(segment
		(start 67.314826 -143.77035)
		(end 67.314826 -145.535904)
		(width 0.254)
		(layer "F.Cu")
		(net "TP_BMC_NODE1_ADCVREFN")
	)
	(segment
		(start 67.314826 -145.535904)
		(end 67.003168 -145.847562)
		(width 0.254)
		(layer "F.Cu")
		(net "TP_BMC_NODE1_ADCVREFN")
	)
	(segment
		(start 67.314826 -142.832582)
		(end 67.314826 -143.77035)
		(width 0.1016)
		(layer "F.Cu")
		(net "TP_BMC_NODE1_ADCVREFN")
	)
	(via
		(at 67.003168 -145.847562)
		(size 0.508)
		(drill 0.254)
		(layers "F.Cu" "B.Cu")
		(net "TP_BMC_NODE1_ADCVREFN")
	)
	(segment
		(start 89.250266 -30.350714)
		(end 89.096088 -30.504892)
		(width 0.1651)
		(layer "F.Cu")
		(net "M_DDR3_NODE1_DQS5P")
	)
	(segment
		(start 89.281762 -32.506158)
		(end 89.281762 -32.504888)
		(width 0.1651)
		(layer "F.Cu")
		(net "M_DDR3_NODE1_DQS5P")
	)
	(segment
		(start 71.860664 -65.85204)
		(end 71.61403 -66.098674)
		(width 0.09906)
		(layer "F.Cu")
		(net "M_DDR3_NODE1_DQS5P")
	)
	(segment
		(start 89.096088 -30.504892)
		(end 89.096088 -31.086552)
		(width 0.1651)
		(layer "F.Cu")
		(net "M_DDR3_NODE1_DQS5P")
	)
	(segment
		(start 89.037922 -32.749998)
		(end 89.281762 -32.506158)
		(width 0.1651)
		(layer "F.Cu")
		(net "M_DDR3_NODE1_DQS5P")
	)
	(segment
		(start 71.908162 -65.85204)
		(end 71.860664 -65.85204)
		(width 0.09906)
		(layer "F.Cu")
		(net "M_DDR3_NODE1_DQS5P")
	)
	(segment
		(start 88.593168 -32.584898)
		(end 88.758268 -32.749998)
		(width 0.1651)
		(layer "F.Cu")
		(net "M_DDR3_NODE1_DQS5P")
	)
	(segment
		(start 88.593168 -31.589472)
		(end 88.593168 -32.584898)
		(width 0.1651)
		(layer "F.Cu")
		(net "M_DDR3_NODE1_DQS5P")
	)
	(segment
		(start 72.081136 -65.679066)
		(end 71.908162 -65.85204)
		(width 0.09906)
		(layer "F.Cu")
		(net "M_DDR3_NODE1_DQS5P")
	)
	(segment
		(start 88.758268 -32.749998)
		(end 89.037922 -32.749998)
		(width 0.1651)
		(layer "F.Cu")
		(net "M_DDR3_NODE1_DQS5P")
	)
	(segment
		(start 89.250266 -29.149802)
		(end 89.250266 -30.350714)
		(width 0.1651)
		(layer "F.Cu")
		(net "M_DDR3_NODE1_DQS5P")
	)
	(segment
		(start 89.096088 -31.086552)
		(end 88.593168 -31.589472)
		(width 0.1651)
		(layer "F.Cu")
		(net "M_DDR3_NODE1_DQS5P")
	)
	(via
		(at 89.281762 -32.504888)
		(size 0.508)
		(drill 0.254)
		(layers "F.Cu" "B.Cu")
		(net "M_DDR3_NODE1_DQS5P")
	)
	(via
		(at 71.61403 -66.098674)
		(size 0.508)
		(drill 0.254)
		(layers "F.Cu" "B.Cu")
		(net "M_DDR3_NODE1_DQS5P")
	)
	(segment
		(start 91.0717 -45.45584)
		(end 91.0717 -36.405566)
		(width 0.2032)
		(layer "In2.Cu")
		(net "M_DDR3_NODE1_DQS5P")
	)
	(segment
		(start 88.72093 -32.72282)
		(end 89.059258 -32.72282)
		(width 0.2032)
		(layer "In2.Cu")
		(net "M_DDR3_NODE1_DQS5P")
	)
	(segment
		(start 72.105266 -65.19672)
		(end 73.64222 -63.659766)
		(width 0.09906)
		(layer "In2.Cu")
		(net "M_DDR3_NODE1_DQS5P")
	)
	(segment
		(start 85.336634 -53.80101)
		(end 82.816446 -56.322722)
		(width 0.2032)
		(layer "In2.Cu")
		(net "M_DDR3_NODE1_DQS5P")
	)
	(segment
		(start 82.816446 -56.616854)
		(end 83.025234 -56.825642)
		(width 0.2032)
		(layer "In2.Cu")
		(net "M_DDR3_NODE1_DQS5P")
	)
	(segment
		(start 89.059258 -32.72282)
		(end 89.27719 -32.504888)
		(width 0.2032)
		(layer "In2.Cu")
		(net "M_DDR3_NODE1_DQS5P")
	)
	(segment
		(start 81.153 -58.993278)
		(end 82.054954 -58.090816)
		(width 0.2032)
		(layer "In2.Cu")
		(net "M_DDR3_NODE1_DQS5P")
	)
	(segment
		(start 73.64222 -62.834266)
		(end 74.236326 -62.24016)
		(width 0.09906)
		(layer "In2.Cu")
		(net "M_DDR3_NODE1_DQS5P")
	)
	(segment
		(start 74.236326 -62.24016)
		(end 74.236326 -62.150244)
		(width 0.09906)
		(layer "In2.Cu")
		(net "M_DDR3_NODE1_DQS5P")
	)
	(segment
		(start 84.934298 -52.83073)
		(end 85.336634 -53.232558)
		(width 0.2032)
		(layer "In2.Cu")
		(net "M_DDR3_NODE1_DQS5P")
	)
	(segment
		(start 72.105266 -66.15557)
		(end 72.105266 -65.19672)
		(width 0.09906)
		(layer "In2.Cu")
		(net "M_DDR3_NODE1_DQS5P")
	)
	(segment
		(start 81.01203 -56.754268)
		(end 81.011776 -56.186578)
		(width 0.2032)
		(layer "In2.Cu")
		(net "M_DDR3_NODE1_DQS5P")
	)
	(segment
		(start 89.27719 -32.504888)
		(end 89.281762 -32.504888)
		(width 0.2032)
		(layer "In2.Cu")
		(net "M_DDR3_NODE1_DQS5P")
	)
	(segment
		(start 90.94978 -47.83328)
		(end 90.94978 -47.22368)
		(width 0.2032)
		(layer "In2.Cu")
		(net "M_DDR3_NODE1_DQS5P")
	)
	(segment
		(start 90.94978 -46.18736)
		(end 90.94978 -45.57776)
		(width 0.2032)
		(layer "In2.Cu")
		(net "M_DDR3_NODE1_DQS5P")
	)
	(segment
		(start 71.892668 -66.368168)
		(end 72.105266 -66.15557)
		(width 0.09906)
		(layer "In2.Cu")
		(net "M_DDR3_NODE1_DQS5P")
	)
	(segment
		(start 91.0717 -49.06899)
		(end 91.0717 -47.9552)
		(width 0.2032)
		(layer "In2.Cu")
		(net "M_DDR3_NODE1_DQS5P")
	)
	(segment
		(start 85.336634 -53.232558)
		(end 85.336634 -53.80101)
		(width 0.2032)
		(layer "In2.Cu")
		(net "M_DDR3_NODE1_DQS5P")
	)
	(segment
		(start 90.94978 -45.57776)
		(end 91.0717 -45.45584)
		(width 0.2032)
		(layer "In2.Cu")
		(net "M_DDR3_NODE1_DQS5P")
	)
	(segment
		(start 77.393292 -58.993278)
		(end 81.153 -58.993278)
		(width 0.2032)
		(layer "In2.Cu")
		(net "M_DDR3_NODE1_DQS5P")
	)
	(segment
		(start 71.68515 -66.368168)
		(end 71.892668 -66.368168)
		(width 0.09906)
		(layer "In2.Cu")
		(net "M_DDR3_NODE1_DQS5P")
	)
	(segment
		(start 73.64222 -63.659766)
		(end 73.64222 -62.834266)
		(width 0.09906)
		(layer "In2.Cu")
		(net "M_DDR3_NODE1_DQS5P")
	)
	(segment
		(start 81.011776 -56.186578)
		(end 84.365846 -52.83073)
		(width 0.2032)
		(layer "In2.Cu")
		(net "M_DDR3_NODE1_DQS5P")
	)
	(segment
		(start 83.31962 -56.825388)
		(end 91.0717 -49.06899)
		(width 0.2032)
		(layer "In2.Cu")
		(net "M_DDR3_NODE1_DQS5P")
	)
	(segment
		(start 91.0717 -36.405566)
		(end 90.57259 -35.906456)
		(width 0.2032)
		(layer "In2.Cu")
		(net "M_DDR3_NODE1_DQS5P")
	)
	(segment
		(start 74.254614 -62.131956)
		(end 77.393292 -58.993278)
		(width 0.2032)
		(layer "In2.Cu")
		(net "M_DDR3_NODE1_DQS5P")
	)
	(segment
		(start 74.236326 -62.150244)
		(end 74.254614 -62.131956)
		(width 0.09906)
		(layer "In2.Cu")
		(net "M_DDR3_NODE1_DQS5P")
	)
	(segment
		(start 82.054954 -58.090816)
		(end 82.054954 -57.796684)
		(width 0.2032)
		(layer "In2.Cu")
		(net "M_DDR3_NODE1_DQS5P")
	)
	(segment
		(start 82.816446 -56.322722)
		(end 82.816446 -56.616854)
		(width 0.2032)
		(layer "In2.Cu")
		(net "M_DDR3_NODE1_DQS5P")
	)
	(segment
		(start 83.025234 -56.825642)
		(end 83.31962 -56.825388)
		(width 0.2032)
		(layer "In2.Cu")
		(net "M_DDR3_NODE1_DQS5P")
	)
	(segment
		(start 89.26957 -35.906456)
		(end 88.32088 -34.957766)
		(width 0.2032)
		(layer "In2.Cu")
		(net "M_DDR3_NODE1_DQS5P")
	)
	(segment
		(start 91.0717 -47.10176)
		(end 91.0717 -46.30928)
		(width 0.2032)
		(layer "In2.Cu")
		(net "M_DDR3_NODE1_DQS5P")
	)
	(segment
		(start 88.32088 -33.12287)
		(end 88.72093 -32.72282)
		(width 0.2032)
		(layer "In2.Cu")
		(net "M_DDR3_NODE1_DQS5P")
	)
	(segment
		(start 82.054954 -57.796684)
		(end 81.01203 -56.754268)
		(width 0.2032)
		(layer "In2.Cu")
		(net "M_DDR3_NODE1_DQS5P")
	)
	(segment
		(start 91.0717 -47.9552)
		(end 90.94978 -47.83328)
		(width 0.2032)
		(layer "In2.Cu")
		(net "M_DDR3_NODE1_DQS5P")
	)
	(segment
		(start 90.57259 -35.906456)
		(end 89.26957 -35.906456)
		(width 0.2032)
		(layer "In2.Cu")
		(net "M_DDR3_NODE1_DQS5P")
	)
	(segment
		(start 84.365846 -52.83073)
		(end 84.934298 -52.83073)
		(width 0.2032)
		(layer "In2.Cu")
		(net "M_DDR3_NODE1_DQS5P")
	)
	(segment
		(start 90.94978 -47.22368)
		(end 91.0717 -47.10176)
		(width 0.2032)
		(layer "In2.Cu")
		(net "M_DDR3_NODE1_DQS5P")
	)
	(segment
		(start 71.61403 -66.297048)
		(end 71.68515 -66.368168)
		(width 0.09906)
		(layer "In2.Cu")
		(net "M_DDR3_NODE1_DQS5P")
	)
	(segment
		(start 91.0717 -46.30928)
		(end 90.94978 -46.18736)
		(width 0.2032)
		(layer "In2.Cu")
		(net "M_DDR3_NODE1_DQS5P")
	)
	(segment
		(start 71.61403 -66.098674)
		(end 71.61403 -66.297048)
		(width 0.09906)
		(layer "In2.Cu")
		(net "M_DDR3_NODE1_DQS5P")
	)
	(segment
		(start 88.32088 -34.957766)
		(end 88.32088 -33.12287)
		(width 0.2032)
		(layer "In2.Cu")
		(net "M_DDR3_NODE1_DQS5P")
	)
	(via
		(at 100.174806 -153.429462)
		(size 0.508)
		(drill 0.254)
		(layers "F.Cu" "B.Cu")
		(net "SW_P1V8_STB_NODE1_BT")
	)
	(segment
		(start 81.20761 -153.444956)
		(end 81.303876 -153.444956)
		(width 0.254)
		(layer "F.Cu")
		(net "P5V_STB_NODE1_FB")
	)
	(segment
		(start 81.303876 -153.444956)
		(end 81.621376 -153.762456)
		(width 0.254)
		(layer "F.Cu")
		(net "P5V_STB_NODE1_FB")
	)
	(segment
		(start 80.298036 -153.990294)
		(end 80.662272 -153.990294)
		(width 0.254)
		(layer "F.Cu")
		(net "P5V_STB_NODE1_FB")
	)
	(segment
		(start 81.621376 -153.762456)
		(end 82.163412 -153.762456)
		(width 0.254)
		(layer "F.Cu")
		(net "P5V_STB_NODE1_FB")
	)
	(segment
		(start 82.163412 -153.762456)
		(end 82.163412 -153.517854)
		(width 0.254)
		(layer "F.Cu")
		(net "P5V_STB_NODE1_FB")
	)
	(segment
		(start 80.662272 -153.990294)
		(end 81.20761 -153.444956)
		(width 0.254)
		(layer "F.Cu")
		(net "P5V_STB_NODE1_FB")
	)
	(segment
		(start 82.829146 -151.688292)
		(end 82.829146 -152.684734)
		(width 0.254)
		(layer "F.Cu")
		(net "P5V_STB_NODE1_FB")
	)
	(segment
		(start 82.163412 -153.517854)
		(end 82.829146 -152.85212)
		(width 0.254)
		(layer "F.Cu")
		(net "P5V_STB_NODE1_FB")
	)
	(segment
		(start 82.829146 -152.85212)
		(end 82.829146 -152.684734)
		(width 0.254)
		(layer "F.Cu")
		(net "P5V_STB_NODE1_FB")
	)
	(via
		(at 81.303876 -153.444956)
		(size 0.508)
		(drill 0.254)
		(layers "F.Cu" "B.Cu")
		(net "P5V_STB_NODE1_FB")
	)
	(segment
		(start 97.774252 -178.046126)
		(end 97.819972 -178.091846)
		(width 0.1016)
		(layer "F.Cu")
		(net "N21698939")
	)
	(segment
		(start 97.819972 -178.091846)
		(end 97.819972 -178.093624)
		(width 0.1016)
		(layer "F.Cu")
		(net "N21698939")
	)
	(segment
		(start 95.930466 -178.096672)
		(end 95.981012 -178.046126)
		(width 0.1016)
		(layer "F.Cu")
		(net "N21698939")
	)
	(segment
		(start 94.851982 -176.338992)
		(end 94.851982 -177.354992)
		(width 0.1016)
		(layer "F.Cu")
		(net "N21698939")
	)
	(segment
		(start 95.981012 -178.046126)
		(end 97.774252 -178.046126)
		(width 0.1016)
		(layer "F.Cu")
		(net "N21698939")
	)
	(segment
		(start 94.851982 -177.354992)
		(end 95.120968 -177.354992)
		(width 0.1016)
		(layer "F.Cu")
		(net "N21698939")
	)
	(segment
		(start 95.120968 -177.354992)
		(end 95.862648 -178.096672)
		(width 0.1016)
		(layer "F.Cu")
		(net "N21698939")
	)
	(segment
		(start 95.862648 -178.096672)
		(end 95.930466 -178.096672)
		(width 0.1016)
		(layer "F.Cu")
		(net "N21698939")
	)
	(via
		(at 95.930466 -178.096672)
		(size 0.508)
		(drill 0.254)
		(layers "F.Cu" "B.Cu")
		(net "N21698939")
	)
	(segment
		(start 60.541916 -130.45948)
		(end 60.541916 -130.458972)
		(width 0.381)
		(layer "F.Cu")
		(net "BMC_NODE1_HPLLAV33")
	)
	(segment
		(start 60.541916 -130.458972)
		(end 60.141104 -130.05816)
		(width 0.381)
		(layer "F.Cu")
		(net "BMC_NODE1_HPLLAV33")
	)
	(via
		(at 60.141104 -130.05816)
		(size 0.49022)
		(drill 0.254)
		(layers "F.Cu" "B.Cu")
		(net "BMC_NODE1_HPLLAV33")
	)
	(via
		(at 56.949086 -124.930662)
		(size 0.508)
		(drill 0.254)
		(layers "F.Cu" "B.Cu")
		(net "BMC_NODE1_HPLLAV33")
	)
	(segment
		(start 54.515258 -68.503038)
		(end 54.881526 -68.869306)
		(width 0.1016)
		(layer "F.Cu")
		(net "M1_DQ_NODE1_DQ19")
	)
	(segment
		(start 55.9308 -23.764494)
		(end 55.929022 -23.764494)
		(width 0.1651)
		(layer "F.Cu")
		(net "M1_DQ_NODE1_DQ19")
	)
	(segment
		(start 55.929022 -23.764494)
		(end 55.540402 -23.375874)
		(width 0.1651)
		(layer "F.Cu")
		(net "M1_DQ_NODE1_DQ19")
	)
	(segment
		(start 54.881526 -68.869306)
		(end 54.891686 -68.869306)
		(width 0.1016)
		(layer "F.Cu")
		(net "M1_DQ_NODE1_DQ19")
	)
	(segment
		(start 55.540402 -23.375874)
		(end 55.540402 -22.864318)
		(width 0.1651)
		(layer "F.Cu")
		(net "M1_DQ_NODE1_DQ19")
	)
	(segment
		(start 55.349902 -22.673818)
		(end 55.349902 -20.94992)
		(width 0.1651)
		(layer "F.Cu")
		(net "M1_DQ_NODE1_DQ19")
	)
	(segment
		(start 54.497986 -68.503038)
		(end 54.515258 -68.503038)
		(width 0.1016)
		(layer "F.Cu")
		(net "M1_DQ_NODE1_DQ19")
	)
	(segment
		(start 55.540402 -22.864318)
		(end 55.349902 -22.673818)
		(width 0.1651)
		(layer "F.Cu")
		(net "M1_DQ_NODE1_DQ19")
	)
	(segment
		(start 55.349902 -20.94992)
		(end 55.350156 -20.94992)
		(width 0.1651)
		(layer "F.Cu")
		(net "M1_DQ_NODE1_DQ19")
	)
	(via
		(at 55.9308 -23.764494)
		(size 0.508)
		(drill 0.254)
		(layers "F.Cu" "B.Cu")
		(net "M1_DQ_NODE1_DQ19")
	)
	(via
		(at 54.891686 -68.869306)
		(size 0.508)
		(drill 0.254)
		(layers "F.Cu" "B.Cu")
		(net "M1_DQ_NODE1_DQ19")
	)
	(segment
		(start 51.234594 -46.53153)
		(end 51.45024 -46.315884)
		(width 0.2032)
		(layer "In7.Cu")
		(net "M1_DQ_NODE1_DQ19")
	)
	(segment
		(start 50.57648 -41.206166)
		(end 50.57648 -40.911526)
		(width 0.2032)
		(layer "In7.Cu")
		(net "M1_DQ_NODE1_DQ19")
	)
	(segment
		(start 57.12079 -64.581024)
		(end 57.382664 -64.31915)
		(width 0.2032)
		(layer "In7.Cu")
		(net "M1_DQ_NODE1_DQ19")
	)
	(segment
		(start 56.06034 -23.966678)
		(end 55.9308 -23.837138)
		(width 0.2032)
		(layer "In7.Cu")
		(net "M1_DQ_NODE1_DQ19")
	)
	(segment
		(start 50.78476 -41.414446)
		(end 50.57648 -41.206166)
		(width 0.2032)
		(layer "In7.Cu")
		(net "M1_DQ_NODE1_DQ19")
	)
	(segment
		(start 56.060594 -23.966678)
		(end 56.06034 -23.966678)
		(width 0.2032)
		(layer "In7.Cu")
		(net "M1_DQ_NODE1_DQ19")
	)
	(segment
		(start 50.644806 -45.79493)
		(end 50.42916 -45.579284)
		(width 0.2032)
		(layer "In7.Cu")
		(net "M1_DQ_NODE1_DQ19")
	)
	(segment
		(start 51.234594 -45.79493)
		(end 50.644806 -45.79493)
		(width 0.2032)
		(layer "In7.Cu")
		(net "M1_DQ_NODE1_DQ19")
	)
	(segment
		(start 51.45024 -40.494966)
		(end 51.45024 -40.009826)
		(width 0.2032)
		(layer "In7.Cu")
		(net "M1_DQ_NODE1_DQ19")
	)
	(segment
		(start 56.53024 -30.511242)
		(end 57.58434 -29.457142)
		(width 0.2032)
		(layer "In7.Cu")
		(net "M1_DQ_NODE1_DQ19")
	)
	(segment
		(start 57.585102 -26.902918)
		(end 57.585102 -25.491186)
		(width 0.2032)
		(layer "In7.Cu")
		(net "M1_DQ_NODE1_DQ19")
	)
	(segment
		(start 50.57648 -40.911526)
		(end 50.78476 -40.703246)
		(width 0.2032)
		(layer "In7.Cu")
		(net "M1_DQ_NODE1_DQ19")
	)
	(segment
		(start 50.644806 -46.53153)
		(end 51.234594 -46.53153)
		(width 0.2032)
		(layer "In7.Cu")
		(net "M1_DQ_NODE1_DQ19")
	)
	(segment
		(start 51.24196 -41.414446)
		(end 50.78476 -41.414446)
		(width 0.2032)
		(layer "In7.Cu")
		(net "M1_DQ_NODE1_DQ19")
	)
	(segment
		(start 56.90489 -64.797178)
		(end 57.12079 -64.581024)
		(width 0.1016)
		(layer "In7.Cu")
		(net "M1_DQ_NODE1_DQ19")
	)
	(segment
		(start 57.382664 -64.31915)
		(end 57.382664 -62.607698)
		(width 0.2032)
		(layer "In7.Cu")
		(net "M1_DQ_NODE1_DQ19")
	)
	(segment
		(start 56.397144 -65.304924)
		(end 56.90489 -64.797178)
		(width 0.1016)
		(layer "In7.Cu")
		(net "M1_DQ_NODE1_DQ19")
	)
	(segment
		(start 51.45024 -46.010576)
		(end 51.234594 -45.79493)
		(width 0.2032)
		(layer "In7.Cu")
		(net "M1_DQ_NODE1_DQ19")
	)
	(segment
		(start 50.644806 -47.26813)
		(end 50.42916 -47.052484)
		(width 0.2032)
		(layer "In7.Cu")
		(net "M1_DQ_NODE1_DQ19")
	)
	(segment
		(start 57.58434 -29.457142)
		(end 57.58434 -26.90368)
		(width 0.2032)
		(layer "In7.Cu")
		(net "M1_DQ_NODE1_DQ19")
	)
	(segment
		(start 50.42916 -45.579284)
		(end 50.42916 -45.273976)
		(width 0.2032)
		(layer "In7.Cu")
		(net "M1_DQ_NODE1_DQ19")
	)
	(segment
		(start 51.45024 -44.537376)
		(end 51.234594 -44.32173)
		(width 0.2032)
		(layer "In7.Cu")
		(net "M1_DQ_NODE1_DQ19")
	)
	(segment
		(start 51.45024 -41.622726)
		(end 51.24196 -41.414446)
		(width 0.2032)
		(layer "In7.Cu")
		(net "M1_DQ_NODE1_DQ19")
	)
	(segment
		(start 51.45024 -44.842684)
		(end 51.45024 -44.537376)
		(width 0.2032)
		(layer "In7.Cu")
		(net "M1_DQ_NODE1_DQ19")
	)
	(segment
		(start 50.42916 -45.273976)
		(end 50.644806 -45.05833)
		(width 0.2032)
		(layer "In7.Cu")
		(net "M1_DQ_NODE1_DQ19")
	)
	(segment
		(start 51.45024 -40.009826)
		(end 55.49138 -35.968686)
		(width 0.2032)
		(layer "In7.Cu")
		(net "M1_DQ_NODE1_DQ19")
	)
	(segment
		(start 56.53024 -33.128458)
		(end 56.53024 -30.511242)
		(width 0.2032)
		(layer "In7.Cu")
		(net "M1_DQ_NODE1_DQ19")
	)
	(segment
		(start 57.58434 -26.90368)
		(end 57.585102 -26.902918)
		(width 0.2032)
		(layer "In7.Cu")
		(net "M1_DQ_NODE1_DQ19")
	)
	(segment
		(start 57.585102 -25.491186)
		(end 56.060594 -23.966678)
		(width 0.2032)
		(layer "In7.Cu")
		(net "M1_DQ_NODE1_DQ19")
	)
	(segment
		(start 50.42916 -47.052484)
		(end 50.42916 -46.747176)
		(width 0.2032)
		(layer "In7.Cu")
		(net "M1_DQ_NODE1_DQ19")
	)
	(segment
		(start 54.891686 -68.869306)
		(end 56.397144 -67.363848)
		(width 0.1016)
		(layer "In7.Cu")
		(net "M1_DQ_NODE1_DQ19")
	)
	(segment
		(start 50.42916 -49.416716)
		(end 50.42916 -48.220376)
		(width 0.2032)
		(layer "In7.Cu")
		(net "M1_DQ_NODE1_DQ19")
	)
	(segment
		(start 50.42916 -43.800776)
		(end 50.644806 -43.58513)
		(width 0.2032)
		(layer "In7.Cu")
		(net "M1_DQ_NODE1_DQ19")
	)
	(segment
		(start 55.49138 -35.968686)
		(end 55.49138 -34.167318)
		(width 0.2032)
		(layer "In7.Cu")
		(net "M1_DQ_NODE1_DQ19")
	)
	(segment
		(start 50.42916 -48.220376)
		(end 50.644806 -48.00473)
		(width 0.2032)
		(layer "In7.Cu")
		(net "M1_DQ_NODE1_DQ19")
	)
	(segment
		(start 50.644806 -44.32173)
		(end 50.42916 -44.106084)
		(width 0.2032)
		(layer "In7.Cu")
		(net "M1_DQ_NODE1_DQ19")
	)
	(segment
		(start 51.24196 -40.703246)
		(end 51.45024 -40.494966)
		(width 0.2032)
		(layer "In7.Cu")
		(net "M1_DQ_NODE1_DQ19")
	)
	(segment
		(start 51.234594 -44.32173)
		(end 50.644806 -44.32173)
		(width 0.2032)
		(layer "In7.Cu")
		(net "M1_DQ_NODE1_DQ19")
	)
	(segment
		(start 55.49138 -34.167318)
		(end 56.53024 -33.128458)
		(width 0.2032)
		(layer "In7.Cu")
		(net "M1_DQ_NODE1_DQ19")
	)
	(segment
		(start 56.24576 -55.233316)
		(end 50.42916 -49.416716)
		(width 0.2032)
		(layer "In7.Cu")
		(net "M1_DQ_NODE1_DQ19")
	)
	(segment
		(start 50.644806 -45.05833)
		(end 51.234594 -45.05833)
		(width 0.2032)
		(layer "In7.Cu")
		(net "M1_DQ_NODE1_DQ19")
	)
	(segment
		(start 50.42916 -46.747176)
		(end 50.644806 -46.53153)
		(width 0.2032)
		(layer "In7.Cu")
		(net "M1_DQ_NODE1_DQ19")
	)
	(segment
		(start 55.9308 -23.837138)
		(end 55.9308 -23.764494)
		(width 0.2032)
		(layer "In7.Cu")
		(net "M1_DQ_NODE1_DQ19")
	)
	(segment
		(start 51.234594 -47.26813)
		(end 50.644806 -47.26813)
		(width 0.2032)
		(layer "In7.Cu")
		(net "M1_DQ_NODE1_DQ19")
	)
	(segment
		(start 57.382664 -62.607698)
		(end 56.24576 -61.470794)
		(width 0.2032)
		(layer "In7.Cu")
		(net "M1_DQ_NODE1_DQ19")
	)
	(segment
		(start 51.45024 -47.483776)
		(end 51.234594 -47.26813)
		(width 0.2032)
		(layer "In7.Cu")
		(net "M1_DQ_NODE1_DQ19")
	)
	(segment
		(start 56.397144 -67.363848)
		(end 56.397144 -65.304924)
		(width 0.1016)
		(layer "In7.Cu")
		(net "M1_DQ_NODE1_DQ19")
	)
	(segment
		(start 50.644806 -43.58513)
		(end 51.234594 -43.58513)
		(width 0.2032)
		(layer "In7.Cu")
		(net "M1_DQ_NODE1_DQ19")
	)
	(segment
		(start 51.234594 -48.00473)
		(end 51.45024 -47.789084)
		(width 0.2032)
		(layer "In7.Cu")
		(net "M1_DQ_NODE1_DQ19")
	)
	(segment
		(start 51.45024 -43.369484)
		(end 51.45024 -41.622726)
		(width 0.2032)
		(layer "In7.Cu")
		(net "M1_DQ_NODE1_DQ19")
	)
	(segment
		(start 51.45024 -47.789084)
		(end 51.45024 -47.483776)
		(width 0.2032)
		(layer "In7.Cu")
		(net "M1_DQ_NODE1_DQ19")
	)
	(segment
		(start 51.234594 -43.58513)
		(end 51.45024 -43.369484)
		(width 0.2032)
		(layer "In7.Cu")
		(net "M1_DQ_NODE1_DQ19")
	)
	(segment
		(start 51.45024 -46.315884)
		(end 51.45024 -46.010576)
		(width 0.2032)
		(layer "In7.Cu")
		(net "M1_DQ_NODE1_DQ19")
	)
	(segment
		(start 50.644806 -48.00473)
		(end 51.234594 -48.00473)
		(width 0.2032)
		(layer "In7.Cu")
		(net "M1_DQ_NODE1_DQ19")
	)
	(segment
		(start 56.24576 -61.470794)
		(end 56.24576 -55.233316)
		(width 0.2032)
		(layer "In7.Cu")
		(net "M1_DQ_NODE1_DQ19")
	)
	(segment
		(start 50.78476 -40.703246)
		(end 51.24196 -40.703246)
		(width 0.2032)
		(layer "In7.Cu")
		(net "M1_DQ_NODE1_DQ19")
	)
	(segment
		(start 50.42916 -44.106084)
		(end 50.42916 -43.800776)
		(width 0.2032)
		(layer "In7.Cu")
		(net "M1_DQ_NODE1_DQ19")
	)
	(segment
		(start 51.234594 -45.05833)
		(end 51.45024 -44.842684)
		(width 0.2032)
		(layer "In7.Cu")
		(net "M1_DQ_NODE1_DQ19")
	)
	(segment
		(start 102.596188 -157.697678)
		(end 102.596188 -157.061154)
		(width 0.1016)
		(layer "F.Cu")
		(net "FM_CPLD_NODE1_P1V8_STB_S_EN")
	)
	(segment
		(start 102.596188 -157.061154)
		(end 102.591616 -157.056582)
		(width 0.1016)
		(layer "F.Cu")
		(net "FM_CPLD_NODE1_P1V8_STB_S_EN")
	)
	(segment
		(start 102.591616 -157.056582)
		(end 102.591616 -156.249878)
		(width 0.1016)
		(layer "F.Cu")
		(net "FM_CPLD_NODE1_P1V8_STB_S_EN")
	)
	(via
		(at 102.591616 -157.056582)
		(size 0.508)
		(drill 0.254)
		(layers "F.Cu" "B.Cu")
		(net "FM_CPLD_NODE1_P1V8_STB_S_EN")
	)
	(via
		(at 76.656184 -153.394918)
		(size 0.508)
		(drill 0.254)
		(layers "F.Cu" "B.Cu")
		(net "SW_P5V_STB_NODE1_BT")
	)
	(segment
		(start 64.788542 -146.544792)
		(end 64.788542 -144.504918)
		(width 0.1016)
		(layer "F.Cu")
		(net "BMC_NODE1_ADCREXT")
	)
	(segment
		(start 64.788542 -144.504918)
		(end 64.162686 -143.879062)
		(width 0.1016)
		(layer "F.Cu")
		(net "BMC_NODE1_ADCREXT")
	)
	(segment
		(start 65.958212 -147.714462)
		(end 64.788542 -146.544792)
		(width 0.1016)
		(layer "F.Cu")
		(net "BMC_NODE1_ADCREXT")
	)
	(segment
		(start 65.305686 -148.076412)
		(end 65.596262 -148.076412)
		(width 0.1016)
		(layer "F.Cu")
		(net "BMC_NODE1_ADCREXT")
	)
	(segment
		(start 64.162686 -142.880334)
		(end 63.741808 -142.459456)
		(width 0.1016)
		(layer "F.Cu")
		(net "BMC_NODE1_ADCREXT")
	)
	(segment
		(start 65.596262 -148.076412)
		(end 65.958212 -147.714462)
		(width 0.1016)
		(layer "F.Cu")
		(net "BMC_NODE1_ADCREXT")
	)
	(segment
		(start 64.162686 -143.879062)
		(end 64.162686 -142.880334)
		(width 0.1016)
		(layer "F.Cu")
		(net "BMC_NODE1_ADCREXT")
	)
	(via
		(at 65.958212 -147.714462)
		(size 0.508)
		(drill 0.254)
		(layers "F.Cu" "B.Cu")
		(net "BMC_NODE1_ADCREXT")
	)
	(segment
		(start 60.21705 -83.476846)
		(end 60.21705 -83.469226)
		(width 0.3048)
		(layer "F.Cu")
		(net "A_CPU_NODE1_HV_GPIO_RCOMP")
	)
	(segment
		(start 60.21705 -83.469226)
		(end 60.59043 -83.095846)
		(width 0.3048)
		(layer "F.Cu")
		(net "A_CPU_NODE1_HV_GPIO_RCOMP")
	)
	(via
		(at 58.484262 -83.468464)
		(size 0.6604)
		(drill 0.3302)
		(layers "F.Cu" "B.Cu")
		(net "A_CPU_NODE1_HV_GPIO_RCOMP")
	)
	(via
		(at 60.59043 -83.095846)
		(size 0.508)
		(drill 0.254)
		(layers "F.Cu" "B.Cu")
		(net "A_CPU_NODE1_HV_GPIO_RCOMP")
	)
	(segment
		(start 60.015628 -83.670648)
		(end 59.821572 -83.670648)
		(width 0.381)
		(layer "B.Cu")
		(net "A_CPU_NODE1_HV_GPIO_RCOMP")
	)
	(segment
		(start 59.821572 -83.670648)
		(end 58.686446 -83.670648)
		(width 0.1016)
		(layer "B.Cu")
		(net "A_CPU_NODE1_HV_GPIO_RCOMP")
	)
	(segment
		(start 60.59043 -83.095846)
		(end 60.015628 -83.670648)
		(width 0.381)
		(layer "B.Cu")
		(net "A_CPU_NODE1_HV_GPIO_RCOMP")
	)
	(segment
		(start 58.686446 -83.670648)
		(end 58.484262 -83.468464)
		(width 0.1016)
		(layer "B.Cu")
		(net "A_CPU_NODE1_HV_GPIO_RCOMP")
	)
	(segment
		(start 44.37634 -26.847546)
		(end 44.37634 -26.99893)
		(width 0.1651)
		(layer "F.Cu")
		(net "M1_DQ_NODE1_DQ7")
	)
	(segment
		(start 45.450252 -28.072842)
		(end 45.450252 -29.149802)
		(width 0.1651)
		(layer "F.Cu")
		(net "M1_DQ_NODE1_DQ7")
	)
	(segment
		(start 44.37634 -26.99893)
		(end 45.450252 -28.072842)
		(width 0.1651)
		(layer "F.Cu")
		(net "M1_DQ_NODE1_DQ7")
	)
	(segment
		(start 47.839122 -66.598038)
		(end 47.839122 -66.590418)
		(width 0.1016)
		(layer "F.Cu")
		(net "M1_DQ_NODE1_DQ7")
	)
	(segment
		(start 47.839122 -66.590418)
		(end 47.465742 -66.217038)
		(width 0.1016)
		(layer "F.Cu")
		(net "M1_DQ_NODE1_DQ7")
	)
	(via
		(at 44.37634 -26.847546)
		(size 0.508)
		(drill 0.254)
		(layers "F.Cu" "B.Cu")
		(net "M1_DQ_NODE1_DQ7")
	)
	(via
		(at 47.465742 -66.217038)
		(size 0.508)
		(drill 0.254)
		(layers "F.Cu" "B.Cu")
		(net "M1_DQ_NODE1_DQ7")
	)
	(segment
		(start 32.600138 -31.862014)
		(end 32.21228 -32.249872)
		(width 0.2032)
		(layer "In7.Cu")
		(net "M1_DQ_NODE1_DQ7")
	)
	(segment
		(start 44.131738 -29.682694)
		(end 41.773602 -29.682694)
		(width 0.2032)
		(layer "In7.Cu")
		(net "M1_DQ_NODE1_DQ7")
	)
	(segment
		(start 44.37634 -29.438092)
		(end 44.131738 -29.682694)
		(width 0.2032)
		(layer "In7.Cu")
		(net "M1_DQ_NODE1_DQ7")
	)
	(segment
		(start 44.754292 -61.654182)
		(end 44.754292 -62.352174)
		(width 0.2032)
		(layer "In7.Cu")
		(net "M1_DQ_NODE1_DQ7")
	)
	(segment
		(start 48.326802 -64.951102)
		(end 48.326802 -65.412112)
		(width 0.1016)
		(layer "In7.Cu")
		(net "M1_DQ_NODE1_DQ7")
	)
	(segment
		(start 33.425892 -31.34106)
		(end 34.061654 -31.976822)
		(width 0.2032)
		(layer "In7.Cu")
		(net "M1_DQ_NODE1_DQ7")
	)
	(segment
		(start 42.82694 -28.486862)
		(end 43.042586 -28.702508)
		(width 0.2032)
		(layer "In7.Cu")
		(net "M1_DQ_NODE1_DQ7")
	)
	(segment
		(start 47.521876 -66.217038)
		(end 47.465742 -66.217038)
		(width 0.1016)
		(layer "In7.Cu")
		(net "M1_DQ_NODE1_DQ7")
	)
	(segment
		(start 48.326802 -65.412112)
		(end 47.521876 -66.217038)
		(width 0.1016)
		(layer "In7.Cu")
		(net "M1_DQ_NODE1_DQ7")
	)
	(segment
		(start 44.37634 -26.847546)
		(end 44.37634 -27.750262)
		(width 0.2032)
		(layer "In7.Cu")
		(net "M1_DQ_NODE1_DQ7")
	)
	(segment
		(start 32.21228 -32.249872)
		(end 32.21228 -53.925216)
		(width 0.2032)
		(layer "In7.Cu")
		(net "M1_DQ_NODE1_DQ7")
	)
	(segment
		(start 47.636938 -64.626236)
		(end 48.001936 -64.626236)
		(width 0.1016)
		(layer "In7.Cu")
		(net "M1_DQ_NODE1_DQ7")
	)
	(segment
		(start 43.042586 -27.965908)
		(end 42.82694 -28.181554)
		(width 0.2032)
		(layer "In7.Cu")
		(net "M1_DQ_NODE1_DQ7")
	)
	(segment
		(start 44.160694 -27.965908)
		(end 43.042586 -27.965908)
		(width 0.2032)
		(layer "In7.Cu")
		(net "M1_DQ_NODE1_DQ7")
	)
	(segment
		(start 45.56125 -62.855094)
		(end 46.445932 -63.739776)
		(width 0.1016)
		(layer "In7.Cu")
		(net "M1_DQ_NODE1_DQ7")
	)
	(segment
		(start 42.035984 -60.240164)
		(end 42.777156 -60.240164)
		(width 0.2032)
		(layer "In7.Cu")
		(net "M1_DQ_NODE1_DQ7")
	)
	(segment
		(start 32.904938 -31.862014)
		(end 32.600138 -31.862014)
		(width 0.2032)
		(layer "In7.Cu")
		(net "M1_DQ_NODE1_DQ7")
	)
	(segment
		(start 33.8455 -32.497776)
		(end 33.5407 -32.497776)
		(width 0.2032)
		(layer "In7.Cu")
		(net "M1_DQ_NODE1_DQ7")
	)
	(segment
		(start 44.160694 -28.702508)
		(end 44.37634 -28.918154)
		(width 0.2032)
		(layer "In7.Cu")
		(net "M1_DQ_NODE1_DQ7")
	)
	(segment
		(start 43.042586 -28.702508)
		(end 44.160694 -28.702508)
		(width 0.2032)
		(layer "In7.Cu")
		(net "M1_DQ_NODE1_DQ7")
	)
	(segment
		(start 32.21228 -53.925216)
		(end 37.088572 -58.801508)
		(width 0.2032)
		(layer "In7.Cu")
		(net "M1_DQ_NODE1_DQ7")
	)
	(segment
		(start 46.445932 -63.739776)
		(end 46.750478 -63.739776)
		(width 0.1016)
		(layer "In7.Cu")
		(net "M1_DQ_NODE1_DQ7")
	)
	(segment
		(start 37.088572 -58.801508)
		(end 40.597328 -58.801508)
		(width 0.2032)
		(layer "In7.Cu")
		(net "M1_DQ_NODE1_DQ7")
	)
	(segment
		(start 45.257212 -62.855094)
		(end 45.56125 -62.855094)
		(width 0.1016)
		(layer "In7.Cu")
		(net "M1_DQ_NODE1_DQ7")
	)
	(segment
		(start 34.061654 -32.281622)
		(end 33.8455 -32.497776)
		(width 0.2032)
		(layer "In7.Cu")
		(net "M1_DQ_NODE1_DQ7")
	)
	(segment
		(start 44.442634 -61.342524)
		(end 44.754292 -61.654182)
		(width 0.2032)
		(layer "In7.Cu")
		(net "M1_DQ_NODE1_DQ7")
	)
	(segment
		(start 48.001936 -64.626236)
		(end 48.326802 -64.951102)
		(width 0.1016)
		(layer "In7.Cu")
		(net "M1_DQ_NODE1_DQ7")
	)
	(segment
		(start 41.773602 -29.682694)
		(end 40.689022 -30.767274)
		(width 0.2032)
		(layer "In7.Cu")
		(net "M1_DQ_NODE1_DQ7")
	)
	(segment
		(start 46.750478 -63.739776)
		(end 47.636938 -64.626236)
		(width 0.1016)
		(layer "In7.Cu")
		(net "M1_DQ_NODE1_DQ7")
	)
	(segment
		(start 43.879516 -61.342524)
		(end 44.442634 -61.342524)
		(width 0.2032)
		(layer "In7.Cu")
		(net "M1_DQ_NODE1_DQ7")
	)
	(segment
		(start 33.5407 -32.497776)
		(end 32.904938 -31.862014)
		(width 0.2032)
		(layer "In7.Cu")
		(net "M1_DQ_NODE1_DQ7")
	)
	(segment
		(start 40.597328 -58.801508)
		(end 42.035984 -60.240164)
		(width 0.2032)
		(layer "In7.Cu")
		(net "M1_DQ_NODE1_DQ7")
	)
	(segment
		(start 40.689022 -30.767274)
		(end 33.694878 -30.767274)
		(width 0.2032)
		(layer "In7.Cu")
		(net "M1_DQ_NODE1_DQ7")
	)
	(segment
		(start 42.82694 -28.181554)
		(end 42.82694 -28.486862)
		(width 0.2032)
		(layer "In7.Cu")
		(net "M1_DQ_NODE1_DQ7")
	)
	(segment
		(start 33.694878 -30.767274)
		(end 33.425892 -31.03626)
		(width 0.2032)
		(layer "In7.Cu")
		(net "M1_DQ_NODE1_DQ7")
	)
	(segment
		(start 44.754292 -62.352174)
		(end 45.257212 -62.855094)
		(width 0.2032)
		(layer "In7.Cu")
		(net "M1_DQ_NODE1_DQ7")
	)
	(segment
		(start 33.425892 -31.03626)
		(end 33.425892 -31.34106)
		(width 0.2032)
		(layer "In7.Cu")
		(net "M1_DQ_NODE1_DQ7")
	)
	(segment
		(start 34.061654 -31.976822)
		(end 34.061654 -32.281622)
		(width 0.2032)
		(layer "In7.Cu")
		(net "M1_DQ_NODE1_DQ7")
	)
	(segment
		(start 42.777156 -60.240164)
		(end 43.879516 -61.342524)
		(width 0.2032)
		(layer "In7.Cu")
		(net "M1_DQ_NODE1_DQ7")
	)
	(segment
		(start 44.37634 -27.750262)
		(end 44.160694 -27.965908)
		(width 0.2032)
		(layer "In7.Cu")
		(net "M1_DQ_NODE1_DQ7")
	)
	(segment
		(start 44.37634 -28.918154)
		(end 44.37634 -29.438092)
		(width 0.2032)
		(layer "In7.Cu")
		(net "M1_DQ_NODE1_DQ7")
	)
	(via
		(at 99.427538 -155.441142)
		(size 0.508)
		(drill 0.254)
		(layers "F.Cu" "B.Cu")
		(net "SW_P1V8_STB_NODE1_PH")
	)
	(segment
		(start 79.077566 -157.02661)
		(end 79.072994 -157.022038)
		(width 0.254)
		(layer "F.Cu")
		(net "P5V_STB_NODE1_EN_P")
	)
	(segment
		(start 79.072994 -156.215334)
		(end 79.072994 -157.022038)
		(width 0.254)
		(layer "F.Cu")
		(net "P5V_STB_NODE1_EN_P")
	)
	(segment
		(start 79.077566 -157.663134)
		(end 79.077566 -157.02661)
		(width 0.254)
		(layer "F.Cu")
		(net "P5V_STB_NODE1_EN_P")
	)
	(via
		(at 79.072994 -157.022038)
		(size 0.508)
		(drill 0.254)
		(layers "F.Cu" "B.Cu")
		(net "P5V_STB_NODE1_EN_P")
	)
	(via
		(at 111.934752 -173.847252)
		(size 0.508)
		(drill 0.254)
		(layers "F.Cu" "B.Cu")
		(net "N21699716")
	)
	(segment
		(start 114.682524 -174.27956)
		(end 114.80292 -174.399956)
		(width 0.1016)
		(layer "B.Cu")
		(net "N21699716")
	)
	(segment
		(start 113.52276 -174.27956)
		(end 114.682524 -174.27956)
		(width 0.1016)
		(layer "B.Cu")
		(net "N21699716")
	)
	(segment
		(start 114.80292 -174.819818)
		(end 114.693192 -174.929546)
		(width 0.1016)
		(layer "B.Cu")
		(net "N21699716")
	)
	(segment
		(start 114.80292 -174.399956)
		(end 114.80292 -174.819818)
		(width 0.1016)
		(layer "B.Cu")
		(net "N21699716")
	)
	(segment
		(start 111.609124 -173.521624)
		(end 111.934752 -173.847252)
		(width 0.1016)
		(layer "B.Cu")
		(net "N21699716")
	)
	(segment
		(start 112.454182 -173.847252)
		(end 111.934752 -173.847252)
		(width 0.1016)
		(layer "B.Cu")
		(net "N21699716")
	)
	(segment
		(start 112.88649 -174.27956)
		(end 112.454182 -173.847252)
		(width 0.1016)
		(layer "B.Cu")
		(net "N21699716")
	)
	(segment
		(start 110.84941 -173.521624)
		(end 111.609124 -173.521624)
		(width 0.1016)
		(layer "B.Cu")
		(net "N21699716")
	)
	(segment
		(start 114.693192 -174.929546)
		(end 113.52276 -174.929546)
		(width 0.1016)
		(layer "B.Cu")
		(net "N21699716")
	)
	(segment
		(start 113.52276 -174.27956)
		(end 112.88649 -174.27956)
		(width 0.1016)
		(layer "B.Cu")
		(net "N21699716")
	)
	(segment
		(start 57.461912 -147.774152)
		(end 57.6834 -147.552664)
		(width 0.1016)
		(layer "F.Cu")
		(net "BMC_NODE1_DACRSET")
	)
	(segment
		(start 62.55258 -146.946366)
		(end 61.772038 -146.946366)
		(width 0.1016)
		(layer "F.Cu")
		(net "BMC_NODE1_DACRSET")
	)
	(segment
		(start 62.941708 -143.259556)
		(end 62.94374 -143.259556)
		(width 0.1016)
		(layer "F.Cu")
		(net "BMC_NODE1_DACRSET")
	)
	(segment
		(start 58.037476 -147.198588)
		(end 57.6834 -147.552664)
		(width 0.1016)
		(layer "F.Cu")
		(net "BMC_NODE1_DACRSET")
	)
	(segment
		(start 62.94374 -143.259556)
		(end 63.0047 -143.320516)
		(width 0.1016)
		(layer "F.Cu")
		(net "BMC_NODE1_DACRSET")
	)
	(segment
		(start 63.0047 -146.494246)
		(end 62.55258 -146.946366)
		(width 0.1016)
		(layer "F.Cu")
		(net "BMC_NODE1_DACRSET")
	)
	(segment
		(start 61.519816 -147.198588)
		(end 58.037476 -147.198588)
		(width 0.1016)
		(layer "F.Cu")
		(net "BMC_NODE1_DACRSET")
	)
	(segment
		(start 63.0047 -143.320516)
		(end 63.0047 -146.494246)
		(width 0.1016)
		(layer "F.Cu")
		(net "BMC_NODE1_DACRSET")
	)
	(segment
		(start 61.772038 -146.946366)
		(end 61.519816 -147.198588)
		(width 0.1016)
		(layer "F.Cu")
		(net "BMC_NODE1_DACRSET")
	)
	(segment
		(start 57.461912 -148.290788)
		(end 57.461912 -147.774152)
		(width 0.1016)
		(layer "F.Cu")
		(net "BMC_NODE1_DACRSET")
	)
	(via
		(at 57.6834 -147.552664)
		(size 0.508)
		(drill 0.254)
		(layers "F.Cu" "B.Cu")
		(net "BMC_NODE1_DACRSET")
	)
	(segment
		(start 73.265284 -71.809864)
		(end 73.888346 -71.809864)
		(width 0.1016)
		(layer "F.Cu")
		(net "M1_DQ_NODE1_DQ56")
	)
	(segment
		(start 97.755202 -23.389082)
		(end 97.348802 -22.982682)
		(width 0.1651)
		(layer "F.Cu")
		(net "M1_DQ_NODE1_DQ56")
	)
	(segment
		(start 73.888346 -71.809864)
		(end 74.141584 -72.063102)
		(width 0.1016)
		(layer "F.Cu")
		(net "M1_DQ_NODE1_DQ56")
	)
	(segment
		(start 72.543162 -71.400162)
		(end 72.855582 -71.400162)
		(width 0.1016)
		(layer "F.Cu")
		(net "M1_DQ_NODE1_DQ56")
	)
	(segment
		(start 76.491084 -71.215758)
		(end 76.491084 -71.050658)
		(width 0.1016)
		(layer "F.Cu")
		(net "M1_DQ_NODE1_DQ56")
	)
	(segment
		(start 97.755202 -24.240998)
		(end 97.755202 -23.389082)
		(width 0.1651)
		(layer "F.Cu")
		(net "M1_DQ_NODE1_DQ56")
	)
	(segment
		(start 97.348802 -20.95119)
		(end 97.350072 -20.94992)
		(width 0.1651)
		(layer "F.Cu")
		(net "M1_DQ_NODE1_DQ56")
	)
	(segment
		(start 74.141584 -72.063102)
		(end 75.64374 -72.063102)
		(width 0.1016)
		(layer "F.Cu")
		(net "M1_DQ_NODE1_DQ56")
	)
	(segment
		(start 75.64374 -72.063102)
		(end 76.491084 -71.215758)
		(width 0.1016)
		(layer "F.Cu")
		(net "M1_DQ_NODE1_DQ56")
	)
	(segment
		(start 97.348802 -22.982682)
		(end 97.348802 -20.95119)
		(width 0.1651)
		(layer "F.Cu")
		(net "M1_DQ_NODE1_DQ56")
	)
	(segment
		(start 76.491084 -71.050658)
		(end 76.637642 -70.9041)
		(width 0.1016)
		(layer "F.Cu")
		(net "M1_DQ_NODE1_DQ56")
	)
	(segment
		(start 72.855582 -71.400162)
		(end 73.265284 -71.809864)
		(width 0.1016)
		(layer "F.Cu")
		(net "M1_DQ_NODE1_DQ56")
	)
	(via
		(at 76.637642 -70.9041)
		(size 0.508)
		(drill 0.254)
		(layers "F.Cu" "B.Cu")
		(net "M1_DQ_NODE1_DQ56")
	)
	(via
		(at 97.755202 -24.240998)
		(size 0.508)
		(drill 0.254)
		(layers "F.Cu" "B.Cu")
		(net "M1_DQ_NODE1_DQ56")
	)
	(segment
		(start 98.2472 -34.593276)
		(end 98.2472 -46.560232)
		(width 0.2032)
		(layer "In7.Cu")
		(net "M1_DQ_NODE1_DQ56")
	)
	(segment
		(start 97.503742 -23.989538)
		(end 97.092008 -23.989538)
		(width 0.2032)
		(layer "In7.Cu")
		(net "M1_DQ_NODE1_DQ56")
	)
	(segment
		(start 98.159062 -31.756858)
		(end 97.996502 -31.919418)
		(width 0.2032)
		(layer "In7.Cu")
		(net "M1_DQ_NODE1_DQ56")
	)
	(segment
		(start 76.637642 -70.328028)
		(end 76.637642 -70.9041)
		(width 0.2032)
		(layer "In7.Cu")
		(net "M1_DQ_NODE1_DQ56")
	)
	(segment
		(start 94.6023 -51.210972)
		(end 94.89694 -51.210972)
		(width 0.2032)
		(layer "In7.Cu")
		(net "M1_DQ_NODE1_DQ56")
	)
	(segment
		(start 97.996502 -31.919418)
		(end 97.996502 -34.342578)
		(width 0.2032)
		(layer "In7.Cu")
		(net "M1_DQ_NODE1_DQ56")
	)
	(segment
		(start 97.933002 -25.538938)
		(end 97.933002 -26.572718)
		(width 0.2032)
		(layer "In7.Cu")
		(net "M1_DQ_NODE1_DQ56")
	)
	(segment
		(start 98.532442 -24.39416)
		(end 98.2472 -24.679402)
		(width 0.2032)
		(layer "In7.Cu")
		(net "M1_DQ_NODE1_DQ56")
	)
	(segment
		(start 84.719922 -61.432186)
		(end 83.69046 -62.461648)
		(width 0.2032)
		(layer "In7.Cu")
		(net "M1_DQ_NODE1_DQ56")
	)
	(segment
		(start 97.755202 -24.240998)
		(end 97.503742 -23.989538)
		(width 0.2032)
		(layer "In7.Cu")
		(net "M1_DQ_NODE1_DQ56")
	)
	(segment
		(start 96.9137 -23.33117)
		(end 97.126552 -23.118318)
		(width 0.2032)
		(layer "In7.Cu")
		(net "M1_DQ_NODE1_DQ56")
	)
	(segment
		(start 97.092008 -23.989538)
		(end 96.9137 -23.81123)
		(width 0.2032)
		(layer "In7.Cu")
		(net "M1_DQ_NODE1_DQ56")
	)
	(segment
		(start 98.273362 -23.118318)
		(end 98.532442 -23.377398)
		(width 0.2032)
		(layer "In7.Cu")
		(net "M1_DQ_NODE1_DQ56")
	)
	(segment
		(start 95.10522 -51.419252)
		(end 95.10522 -51.713892)
		(width 0.2032)
		(layer "In7.Cu")
		(net "M1_DQ_NODE1_DQ56")
	)
	(segment
		(start 77.89164 -69.07403)
		(end 76.637642 -70.328028)
		(width 0.2032)
		(layer "In7.Cu")
		(net "M1_DQ_NODE1_DQ56")
	)
	(segment
		(start 83.69046 -63.863474)
		(end 84.10956 -64.282574)
		(width 0.2032)
		(layer "In7.Cu")
		(net "M1_DQ_NODE1_DQ56")
	)
	(segment
		(start 96.914462 -23.81123)
		(end 96.914462 -23.33117)
		(width 0.2032)
		(layer "In7.Cu")
		(net "M1_DQ_NODE1_DQ56")
	)
	(segment
		(start 98.2472 -25.22474)
		(end 97.933002 -25.538938)
		(width 0.2032)
		(layer "In7.Cu")
		(net "M1_DQ_NODE1_DQ56")
	)
	(segment
		(start 81.196942 -69.07403)
		(end 77.89164 -69.07403)
		(width 0.2032)
		(layer "In7.Cu")
		(net "M1_DQ_NODE1_DQ56")
	)
	(segment
		(start 98.159062 -26.798778)
		(end 98.159062 -31.756858)
		(width 0.2032)
		(layer "In7.Cu")
		(net "M1_DQ_NODE1_DQ56")
	)
	(segment
		(start 84.10956 -66.161412)
		(end 81.196942 -69.07403)
		(width 0.2032)
		(layer "In7.Cu")
		(net "M1_DQ_NODE1_DQ56")
	)
	(segment
		(start 91.64066 -55.178452)
		(end 91.64066 -55.536084)
		(width 0.2032)
		(layer "In7.Cu")
		(net "M1_DQ_NODE1_DQ56")
	)
	(segment
		(start 91.552522 -53.96611)
		(end 91.847162 -53.96611)
		(width 0.2032)
		(layer "In7.Cu")
		(net "M1_DQ_NODE1_DQ56")
	)
	(segment
		(start 84.10956 -64.282574)
		(end 84.10956 -66.161412)
		(width 0.2032)
		(layer "In7.Cu")
		(net "M1_DQ_NODE1_DQ56")
	)
	(segment
		(start 97.996502 -34.342578)
		(end 98.2472 -34.593276)
		(width 0.2032)
		(layer "In7.Cu")
		(net "M1_DQ_NODE1_DQ56")
	)
	(segment
		(start 98.2472 -24.679402)
		(end 98.2472 -25.22474)
		(width 0.2032)
		(layer "In7.Cu")
		(net "M1_DQ_NODE1_DQ56")
	)
	(segment
		(start 91.344242 -53.46319)
		(end 91.344242 -53.75783)
		(width 0.2032)
		(layer "In7.Cu")
		(net "M1_DQ_NODE1_DQ56")
	)
	(segment
		(start 97.126552 -23.118318)
		(end 98.273362 -23.118318)
		(width 0.2032)
		(layer "In7.Cu")
		(net "M1_DQ_NODE1_DQ56")
	)
	(segment
		(start 91.847162 -53.96611)
		(end 94.6023 -51.210972)
		(width 0.2032)
		(layer "In7.Cu")
		(net "M1_DQ_NODE1_DQ56")
	)
	(segment
		(start 97.933002 -26.572718)
		(end 98.159062 -26.798778)
		(width 0.2032)
		(layer "In7.Cu")
		(net "M1_DQ_NODE1_DQ56")
	)
	(segment
		(start 96.9137 -23.81123)
		(end 96.914462 -23.81123)
		(width 0.2032)
		(layer "In7.Cu")
		(net "M1_DQ_NODE1_DQ56")
	)
	(segment
		(start 85.744558 -61.432186)
		(end 84.719922 -61.432186)
		(width 0.2032)
		(layer "In7.Cu")
		(net "M1_DQ_NODE1_DQ56")
	)
	(segment
		(start 91.64066 -55.536084)
		(end 85.744558 -61.432186)
		(width 0.2032)
		(layer "In7.Cu")
		(net "M1_DQ_NODE1_DQ56")
	)
	(segment
		(start 83.69046 -62.461648)
		(end 83.69046 -63.863474)
		(width 0.2032)
		(layer "In7.Cu")
		(net "M1_DQ_NODE1_DQ56")
	)
	(segment
		(start 91.344242 -53.75783)
		(end 91.552522 -53.96611)
		(width 0.2032)
		(layer "In7.Cu")
		(net "M1_DQ_NODE1_DQ56")
	)
	(segment
		(start 96.914462 -23.33117)
		(end 96.9137 -23.33117)
		(width 0.2032)
		(layer "In7.Cu")
		(net "M1_DQ_NODE1_DQ56")
	)
	(segment
		(start 98.532442 -23.377398)
		(end 98.532442 -24.39416)
		(width 0.2032)
		(layer "In7.Cu")
		(net "M1_DQ_NODE1_DQ56")
	)
	(segment
		(start 95.10522 -51.713892)
		(end 91.64066 -55.178452)
		(width 0.2032)
		(layer "In7.Cu")
		(net "M1_DQ_NODE1_DQ56")
	)
	(segment
		(start 94.89694 -51.210972)
		(end 95.10522 -51.419252)
		(width 0.2032)
		(layer "In7.Cu")
		(net "M1_DQ_NODE1_DQ56")
	)
	(segment
		(start 98.2472 -46.560232)
		(end 91.344242 -53.46319)
		(width 0.2032)
		(layer "In7.Cu")
		(net "M1_DQ_NODE1_DQ56")
	)
	(segment
		(start 103.816658 -155.024836)
		(end 104.322372 -155.024836)
		(width 0.254)
		(layer "F.Cu")
		(net "P1V8_STB_NODE1_SS")
	)
	(segment
		(start 104.92867 -155.631134)
		(end 104.92867 -155.889706)
		(width 0.254)
		(layer "F.Cu")
		(net "P1V8_STB_NODE1_SS")
	)
	(segment
		(start 104.322372 -155.024836)
		(end 104.92867 -155.631134)
		(width 0.254)
		(layer "F.Cu")
		(net "P1V8_STB_NODE1_SS")
	)
	(segment
		(start 105.258616 -156.219652)
		(end 104.92867 -155.889706)
		(width 0.254)
		(layer "F.Cu")
		(net "P1V8_STB_NODE1_SS")
	)
	(segment
		(start 105.56367 -156.219652)
		(end 105.258616 -156.219652)
		(width 0.254)
		(layer "F.Cu")
		(net "P1V8_STB_NODE1_SS")
	)
	(via
		(at 104.92867 -155.889706)
		(size 0.508)
		(drill 0.254)
		(layers "F.Cu" "B.Cu")
		(net "P1V8_STB_NODE1_SS")
	)
	(segment
		(start 78.41869 -158.464758)
		(end 78.420214 -158.463234)
		(width 0.254)
		(layer "F.Cu")
		(net "P5V_STB_NODE1_EN")
	)
	(segment
		(start 80.253078 -151.268684)
		(end 80.06461 -151.457152)
		(width 0.254)
		(layer "F.Cu")
		(net "P5V_STB_NODE1_EN")
	)
	(segment
		(start 80.06461 -151.457152)
		(end 80.06461 -151.70277)
		(width 0.254)
		(layer "F.Cu")
		(net "P5V_STB_NODE1_EN")
	)
	(segment
		(start 81.06029 -151.704548)
		(end 81.034128 -151.70277)
		(width 0.254)
		(layer "F.Cu")
		(net "P5V_STB_NODE1_EN")
	)
	(segment
		(start 81.034128 -151.70277)
		(end 80.06461 -151.70277)
		(width 0.254)
		(layer "F.Cu")
		(net "P5V_STB_NODE1_EN")
	)
	(segment
		(start 78.420214 -158.463234)
		(end 79.077566 -158.463234)
		(width 0.254)
		(layer "F.Cu")
		(net "P5V_STB_NODE1_EN")
	)
	(segment
		(start 77.517244 -158.464758)
		(end 78.41869 -158.464758)
		(width 0.254)
		(layer "F.Cu")
		(net "P5V_STB_NODE1_EN")
	)
	(segment
		(start 80.253078 -150.908258)
		(end 80.253078 -151.268684)
		(width 0.254)
		(layer "F.Cu")
		(net "P5V_STB_NODE1_EN")
	)
	(via
		(at 78.420214 -158.463234)
		(size 0.508)
		(drill 0.254)
		(layers "F.Cu" "B.Cu")
		(net "P5V_STB_NODE1_EN")
	)
	(via
		(at 80.253078 -150.908258)
		(size 0.508)
		(drill 0.254)
		(layers "F.Cu" "B.Cu")
		(net "P5V_STB_NODE1_EN")
	)
	(segment
		(start 84.59978 -158.683706)
		(end 82.905092 -160.378394)
		(width 0.254)
		(layer "B.Cu")
		(net "P5V_STB_NODE1_EN")
	)
	(segment
		(start 84.59978 -151.78278)
		(end 84.59978 -158.683706)
		(width 0.254)
		(layer "B.Cu")
		(net "P5V_STB_NODE1_EN")
	)
	(segment
		(start 83.725258 -150.908258)
		(end 84.59978 -151.78278)
		(width 0.254)
		(layer "B.Cu")
		(net "P5V_STB_NODE1_EN")
	)
	(segment
		(start 80.253078 -150.908258)
		(end 83.725258 -150.908258)
		(width 0.254)
		(layer "B.Cu")
		(net "P5V_STB_NODE1_EN")
	)
	(segment
		(start 79.315818 -160.378394)
		(end 78.420214 -159.48279)
		(width 0.254)
		(layer "B.Cu")
		(net "P5V_STB_NODE1_EN")
	)
	(segment
		(start 78.420214 -159.48279)
		(end 78.420214 -158.463234)
		(width 0.254)
		(layer "B.Cu")
		(net "P5V_STB_NODE1_EN")
	)
	(segment
		(start 82.905092 -160.378394)
		(end 79.315818 -160.378394)
		(width 0.254)
		(layer "B.Cu")
		(net "P5V_STB_NODE1_EN")
	)
	(via
		(at 106.268774 -175.483012)
		(size 0.6604)
		(drill 0.3302)
		(layers "F.Cu" "B.Cu")
		(net "N21698979")
	)
	(segment
		(start 106.053128 -175.267366)
		(end 106.268774 -175.483012)
		(width 0.1016)
		(layer "B.Cu")
		(net "N21698979")
	)
	(segment
		(start 106.388408 -175.363378)
		(end 106.268774 -175.483012)
		(width 0.1016)
		(layer "B.Cu")
		(net "N21698979")
	)
	(segment
		(start 103.36276 -174.944532)
		(end 103.95585 -174.944532)
		(width 0.1016)
		(layer "B.Cu")
		(net "N21698979")
	)
	(segment
		(start 106.388408 -174.156116)
		(end 106.388408 -175.363378)
		(width 0.1016)
		(layer "B.Cu")
		(net "N21698979")
	)
	(segment
		(start 103.95585 -174.944532)
		(end 104.278684 -175.267366)
		(width 0.1016)
		(layer "B.Cu")
		(net "N21698979")
	)
	(segment
		(start 104.278684 -175.267366)
		(end 106.053128 -175.267366)
		(width 0.1016)
		(layer "B.Cu")
		(net "N21698979")
	)
	(segment
		(start 57.321958 -128.859534)
		(end 56.822086 -128.359662)
		(width 0.3683)
		(layer "F.Cu")
		(net "BMC_NODE1_MPLLAV33")
	)
	(segment
		(start 57.34177 -128.859534)
		(end 57.321958 -128.859534)
		(width 0.3683)
		(layer "F.Cu")
		(net "BMC_NODE1_MPLLAV33")
	)
	(via
		(at 56.822086 -128.359662)
		(size 0.49022)
		(drill 0.254)
		(layers "F.Cu" "B.Cu")
		(net "BMC_NODE1_MPLLAV33")
	)
	(via
		(at 54.155086 -126.581662)
		(size 0.6604)
		(drill 0.3302)
		(layers "F.Cu" "B.Cu")
		(net "BMC_NODE1_MPLLAV33")
	)
	(segment
		(start 94.350078 -20.94992)
		(end 94.350078 -22.151086)
		(width 0.1651)
		(layer "F.Cu")
		(net "M_DDR3_NODE1_DQS6P")
	)
	(segment
		(start 75.82281 -68.093844)
		(end 75.82281 -67.107054)
		(width 0.09906)
		(layer "F.Cu")
		(net "M_DDR3_NODE1_DQS6P")
	)
	(segment
		(start 94.350078 -22.151086)
		(end 94.196154 -22.30501)
		(width 0.1651)
		(layer "F.Cu")
		(net "M_DDR3_NODE1_DQS6P")
	)
	(segment
		(start 76.033376 -65.094104)
		(end 76.27874 -65.339468)
		(width 0.09906)
		(layer "F.Cu")
		(net "M_DDR3_NODE1_DQS6P")
	)
	(segment
		(start 75.82281 -67.107054)
		(end 76.127102 -66.802762)
		(width 0.09906)
		(layer "F.Cu")
		(net "M_DDR3_NODE1_DQS6P")
	)
	(segment
		(start 75.82281 -65.179702)
		(end 75.908408 -65.094104)
		(width 0.09906)
		(layer "F.Cu")
		(net "M_DDR3_NODE1_DQS6P")
	)
	(segment
		(start 75.82281 -65.694052)
		(end 75.82281 -65.179702)
		(width 0.09906)
		(layer "F.Cu")
		(net "M_DDR3_NODE1_DQS6P")
	)
	(segment
		(start 94.196154 -22.814534)
		(end 94.685104 -23.303484)
		(width 0.1651)
		(layer "F.Cu")
		(net "M_DDR3_NODE1_DQS6P")
	)
	(segment
		(start 72.901556 -68.691506)
		(end 73.56348 -69.034914)
		(width 0.09906)
		(layer "F.Cu")
		(net "M_DDR3_NODE1_DQS6P")
	)
	(segment
		(start 73.56348 -69.034914)
		(end 73.773538 -69.034914)
		(width 0.09906)
		(layer "F.Cu")
		(net "M_DDR3_NODE1_DQS6P")
	)
	(segment
		(start 75.908408 -65.094104)
		(end 76.033376 -65.094104)
		(width 0.09906)
		(layer "F.Cu")
		(net "M_DDR3_NODE1_DQS6P")
	)
	(segment
		(start 76.127102 -66.802762)
		(end 76.127102 -65.998344)
		(width 0.09906)
		(layer "F.Cu")
		(net "M_DDR3_NODE1_DQS6P")
	)
	(segment
		(start 94.196154 -22.30501)
		(end 94.196154 -22.814534)
		(width 0.1651)
		(layer "F.Cu")
		(net "M_DDR3_NODE1_DQS6P")
	)
	(segment
		(start 73.919842 -68.88861)
		(end 75.028044 -68.88861)
		(width 0.09906)
		(layer "F.Cu")
		(net "M_DDR3_NODE1_DQS6P")
	)
	(segment
		(start 75.028044 -68.88861)
		(end 75.82281 -68.093844)
		(width 0.09906)
		(layer "F.Cu")
		(net "M_DDR3_NODE1_DQS6P")
	)
	(segment
		(start 73.773538 -69.034914)
		(end 73.919842 -68.88861)
		(width 0.09906)
		(layer "F.Cu")
		(net "M_DDR3_NODE1_DQS6P")
	)
	(segment
		(start 76.127102 -65.998344)
		(end 75.82281 -65.694052)
		(width 0.09906)
		(layer "F.Cu")
		(net "M_DDR3_NODE1_DQS6P")
	)
	(via
		(at 94.685104 -23.303484)
		(size 0.508)
		(drill 0.254)
		(layers "F.Cu" "B.Cu")
		(net "M_DDR3_NODE1_DQS6P")
	)
	(via
		(at 76.27874 -65.339468)
		(size 0.508)
		(drill 0.254)
		(layers "F.Cu" "B.Cu")
		(net "M_DDR3_NODE1_DQS6P")
	)
	(segment
		(start 94.191582 -24.007318)
		(end 94.191582 -23.512018)
		(width 0.2032)
		(layer "In7.Cu")
		(net "M_DDR3_NODE1_DQS6P")
	)
	(segment
		(start 86.033356 -46.646846)
		(end 86.883748 -46.646846)
		(width 0.2032)
		(layer "In7.Cu")
		(net "M_DDR3_NODE1_DQS6P")
	)
	(segment
		(start 77.016864 -63.20282)
		(end 77.016864 -63.189612)
		(width 0.09906)
		(layer "In7.Cu")
		(net "M_DDR3_NODE1_DQS6P")
	)
	(segment
		(start 86.883748 -46.646846)
		(end 87.297514 -46.23308)
		(width 0.2032)
		(layer "In7.Cu")
		(net "M_DDR3_NODE1_DQS6P")
	)
	(segment
		(start 87.297514 -46.23308)
		(end 87.297514 -45.382688)
		(width 0.2032)
		(layer "In7.Cu")
		(net "M_DDR3_NODE1_DQS6P")
	)
	(segment
		(start 76.278232 -65.33896)
		(end 76.278232 -65.224152)
		(width 0.09906)
		(layer "In7.Cu")
		(net "M_DDR3_NODE1_DQS6P")
	)
	(segment
		(start 90.897202 -39.585138)
		(end 91.252802 -39.229538)
		(width 0.2032)
		(layer "In7.Cu")
		(net "M_DDR3_NODE1_DQS6P")
	)
	(segment
		(start 88.33993 -45.173646)
		(end 88.771222 -44.742354)
		(width 0.2032)
		(layer "In7.Cu")
		(net "M_DDR3_NODE1_DQS6P")
	)
	(segment
		(start 76.374244 -65.12814)
		(end 76.64196 -65.12814)
		(width 0.09906)
		(layer "In7.Cu")
		(net "M_DDR3_NODE1_DQS6P")
	)
	(segment
		(start 88.770968 -44.203366)
		(end 88.770968 -43.511724)
		(width 0.2032)
		(layer "In7.Cu")
		(net "M_DDR3_NODE1_DQS6P")
	)
	(segment
		(start 91.252802 -39.229538)
		(end 91.252802 -29.261562)
		(width 0.2032)
		(layer "In7.Cu")
		(net "M_DDR3_NODE1_DQS6P")
	)
	(segment
		(start 91.55938 -26.883614)
		(end 92.146882 -26.883614)
		(width 0.2032)
		(layer "In7.Cu")
		(net "M_DDR3_NODE1_DQS6P")
	)
	(segment
		(start 76.64196 -65.12814)
		(end 76.953364 -64.816736)
		(width 0.09906)
		(layer "In7.Cu")
		(net "M_DDR3_NODE1_DQS6P")
	)
	(segment
		(start 92.164662 -41.907714)
		(end 92.164662 -41.339262)
		(width 0.2032)
		(layer "In7.Cu")
		(net "M_DDR3_NODE1_DQS6P")
	)
	(segment
		(start 91.763088 -40.937688)
		(end 90.49004 -40.937688)
		(width 0.2032)
		(layer "In7.Cu")
		(net "M_DDR3_NODE1_DQS6P")
	)
	(segment
		(start 87.297514 -45.382688)
		(end 87.50681 -45.173392)
		(width 0.2032)
		(layer "In7.Cu")
		(net "M_DDR3_NODE1_DQS6P")
	)
	(segment
		(start 91.044522 -27.398472)
		(end 91.55938 -26.883614)
		(width 0.2032)
		(layer "In7.Cu")
		(net "M_DDR3_NODE1_DQS6P")
	)
	(segment
		(start 91.763088 -42.309288)
		(end 92.164662 -41.907714)
		(width 0.2032)
		(layer "In7.Cu")
		(net "M_DDR3_NODE1_DQS6P")
	)
	(segment
		(start 77.016864 -59.155584)
		(end 77.50302 -58.669428)
		(width 0.2032)
		(layer "In7.Cu")
		(net "M_DDR3_NODE1_DQS6P")
	)
	(segment
		(start 87.800942 -45.173392)
		(end 88.33993 -45.173646)
		(width 0.2032)
		(layer "In7.Cu")
		(net "M_DDR3_NODE1_DQS6P")
	)
	(segment
		(start 93.818202 -24.380698)
		(end 94.191582 -24.007318)
		(width 0.2032)
		(layer "In7.Cu")
		(net "M_DDR3_NODE1_DQS6P")
	)
	(segment
		(start 77.50302 -55.177436)
		(end 84.56676 -48.113696)
		(width 0.2032)
		(layer "In7.Cu")
		(net "M_DDR3_NODE1_DQS6P")
	)
	(segment
		(start 91.044522 -29.053282)
		(end 91.044522 -27.398472)
		(width 0.2032)
		(layer "In7.Cu")
		(net "M_DDR3_NODE1_DQS6P")
	)
	(segment
		(start 93.32976 -24.380698)
		(end 93.818202 -24.380698)
		(width 0.2032)
		(layer "In7.Cu")
		(net "M_DDR3_NODE1_DQS6P")
	)
	(segment
		(start 90.28684 -39.880032)
		(end 90.581734 -39.585138)
		(width 0.2032)
		(layer "In7.Cu")
		(net "M_DDR3_NODE1_DQS6P")
	)
	(segment
		(start 90.28684 -40.734488)
		(end 90.28684 -39.880032)
		(width 0.2032)
		(layer "In7.Cu")
		(net "M_DDR3_NODE1_DQS6P")
	)
	(segment
		(start 76.27874 -65.339468)
		(end 76.278232 -65.33896)
		(width 0.09906)
		(layer "In7.Cu")
		(net "M_DDR3_NODE1_DQS6P")
	)
	(segment
		(start 76.953364 -64.816736)
		(end 76.953364 -63.26632)
		(width 0.09906)
		(layer "In7.Cu")
		(net "M_DDR3_NODE1_DQS6P")
	)
	(segment
		(start 76.953364 -63.26632)
		(end 77.016864 -63.20282)
		(width 0.09906)
		(layer "In7.Cu")
		(net "M_DDR3_NODE1_DQS6P")
	)
	(segment
		(start 88.771222 -44.742354)
		(end 88.770968 -44.203366)
		(width 0.2032)
		(layer "In7.Cu")
		(net "M_DDR3_NODE1_DQS6P")
	)
	(segment
		(start 94.191582 -23.512018)
		(end 94.400116 -23.303484)
		(width 0.2032)
		(layer "In7.Cu")
		(net "M_DDR3_NODE1_DQS6P")
	)
	(segment
		(start 84.56676 -48.113696)
		(end 84.56676 -48.113442)
		(width 0.2032)
		(layer "In7.Cu")
		(net "M_DDR3_NODE1_DQS6P")
	)
	(segment
		(start 90.581734 -39.585138)
		(end 90.897202 -39.585138)
		(width 0.2032)
		(layer "In7.Cu")
		(net "M_DDR3_NODE1_DQS6P")
	)
	(segment
		(start 92.146882 -26.883614)
		(end 92.99448 -26.036016)
		(width 0.2032)
		(layer "In7.Cu")
		(net "M_DDR3_NODE1_DQS6P")
	)
	(segment
		(start 92.99448 -24.715978)
		(end 93.32976 -24.380698)
		(width 0.2032)
		(layer "In7.Cu")
		(net "M_DDR3_NODE1_DQS6P")
	)
	(segment
		(start 89.973404 -42.309288)
		(end 91.763088 -42.309288)
		(width 0.2032)
		(layer "In7.Cu")
		(net "M_DDR3_NODE1_DQS6P")
	)
	(segment
		(start 91.252802 -29.261562)
		(end 91.044522 -29.053282)
		(width 0.2032)
		(layer "In7.Cu")
		(net "M_DDR3_NODE1_DQS6P")
	)
	(segment
		(start 94.400116 -23.303484)
		(end 94.685104 -23.303484)
		(width 0.2032)
		(layer "In7.Cu")
		(net "M_DDR3_NODE1_DQS6P")
	)
	(segment
		(start 87.50681 -45.173392)
		(end 87.800942 -45.173392)
		(width 0.2032)
		(layer "In7.Cu")
		(net "M_DDR3_NODE1_DQS6P")
	)
	(segment
		(start 76.278232 -65.224152)
		(end 76.374244 -65.12814)
		(width 0.09906)
		(layer "In7.Cu")
		(net "M_DDR3_NODE1_DQS6P")
	)
	(segment
		(start 84.56676 -48.113442)
		(end 86.033356 -46.646846)
		(width 0.2032)
		(layer "In7.Cu")
		(net "M_DDR3_NODE1_DQS6P")
	)
	(segment
		(start 88.770968 -43.511724)
		(end 89.973404 -42.309288)
		(width 0.2032)
		(layer "In7.Cu")
		(net "M_DDR3_NODE1_DQS6P")
	)
	(segment
		(start 92.164662 -41.339262)
		(end 91.763088 -40.937688)
		(width 0.2032)
		(layer "In7.Cu")
		(net "M_DDR3_NODE1_DQS6P")
	)
	(segment
		(start 77.016864 -63.189612)
		(end 77.016864 -59.155584)
		(width 0.2032)
		(layer "In7.Cu")
		(net "M_DDR3_NODE1_DQS6P")
	)
	(segment
		(start 90.49004 -40.937688)
		(end 90.28684 -40.734488)
		(width 0.2032)
		(layer "In7.Cu")
		(net "M_DDR3_NODE1_DQS6P")
	)
	(segment
		(start 92.99448 -26.036016)
		(end 92.99448 -24.715978)
		(width 0.2032)
		(layer "In7.Cu")
		(net "M_DDR3_NODE1_DQS6P")
	)
	(segment
		(start 77.50302 -58.669428)
		(end 77.50302 -55.177436)
		(width 0.2032)
		(layer "In7.Cu")
		(net "M_DDR3_NODE1_DQS6P")
	)
	(segment
		(start 104.514142 -158.677102)
		(end 104.91724 -158.677102)
		(width 0.254)
		(layer "F.Cu")
		(net "P1V8_STB_NODE1_VREG5")
	)
	(segment
		(start 104.839516 -154.823668)
		(end 104.540812 -154.524964)
		(width 0.254)
		(layer "F.Cu")
		(net "P1V8_STB_NODE1_VREG5")
	)
	(segment
		(start 104.91724 -158.677102)
		(end 105.779316 -157.815026)
		(width 0.254)
		(layer "F.Cu")
		(net "P1V8_STB_NODE1_VREG5")
	)
	(segment
		(start 106.122724 -157.471618)
		(end 106.122724 -155.93568)
		(width 0.254)
		(layer "F.Cu")
		(net "P1V8_STB_NODE1_VREG5")
	)
	(segment
		(start 105.682034 -154.823668)
		(end 104.839516 -154.823668)
		(width 0.254)
		(layer "F.Cu")
		(net "P1V8_STB_NODE1_VREG5")
	)
	(segment
		(start 105.682034 -155.49499)
		(end 105.682034 -154.823668)
		(width 0.254)
		(layer "F.Cu")
		(net "P1V8_STB_NODE1_VREG5")
	)
	(segment
		(start 105.779316 -157.815026)
		(end 106.122724 -157.471618)
		(width 0.254)
		(layer "F.Cu")
		(net "P1V8_STB_NODE1_VREG5")
	)
	(segment
		(start 104.540812 -154.524964)
		(end 103.816658 -154.524964)
		(width 0.254)
		(layer "F.Cu")
		(net "P1V8_STB_NODE1_VREG5")
	)
	(segment
		(start 106.122724 -155.93568)
		(end 105.682034 -155.49499)
		(width 0.254)
		(layer "F.Cu")
		(net "P1V8_STB_NODE1_VREG5")
	)
	(via
		(at 105.779316 -157.815026)
		(size 0.508)
		(drill 0.254)
		(layers "F.Cu" "B.Cu")
		(net "P1V8_STB_NODE1_VREG5")
	)
	(segment
		(start 81.894172 -158.205932)
		(end 82.129884 -157.97022)
		(width 0.254)
		(layer "F.Cu")
		(net "P5V_STB_NODE1_VREG5")
	)
	(segment
		(start 80.99552 -158.642558)
		(end 81.44637 -158.642558)
		(width 0.254)
		(layer "F.Cu")
		(net "P5V_STB_NODE1_VREG5")
	)
	(segment
		(start 81.882996 -158.205932)
		(end 81.894172 -158.205932)
		(width 0.254)
		(layer "F.Cu")
		(net "P5V_STB_NODE1_VREG5")
	)
	(segment
		(start 81.271618 -154.49042)
		(end 81.305654 -154.524456)
		(width 0.254)
		(layer "F.Cu")
		(net "P5V_STB_NODE1_VREG5")
	)
	(segment
		(start 82.187542 -154.80792)
		(end 82.187542 -154.99969)
		(width 0.254)
		(layer "F.Cu")
		(net "P5V_STB_NODE1_VREG5")
	)
	(segment
		(start 82.738722 -155.55087)
		(end 82.738722 -157.361382)
		(width 0.254)
		(layer "F.Cu")
		(net "P5V_STB_NODE1_VREG5")
	)
	(segment
		(start 82.738722 -157.361382)
		(end 82.129884 -157.97022)
		(width 0.254)
		(layer "F.Cu")
		(net "P5V_STB_NODE1_VREG5")
	)
	(segment
		(start 81.44637 -158.642558)
		(end 81.882996 -158.205932)
		(width 0.254)
		(layer "F.Cu")
		(net "P5V_STB_NODE1_VREG5")
	)
	(segment
		(start 80.298036 -154.49042)
		(end 81.271618 -154.49042)
		(width 0.254)
		(layer "F.Cu")
		(net "P5V_STB_NODE1_VREG5")
	)
	(segment
		(start 81.305654 -154.524456)
		(end 81.904078 -154.524456)
		(width 0.254)
		(layer "F.Cu")
		(net "P5V_STB_NODE1_VREG5")
	)
	(segment
		(start 82.187542 -154.99969)
		(end 82.738722 -155.55087)
		(width 0.254)
		(layer "F.Cu")
		(net "P5V_STB_NODE1_VREG5")
	)
	(segment
		(start 81.904078 -154.524456)
		(end 82.187542 -154.80792)
		(width 0.254)
		(layer "F.Cu")
		(net "P5V_STB_NODE1_VREG5")
	)
	(via
		(at 82.129884 -157.97022)
		(size 0.508)
		(drill 0.254)
		(layers "F.Cu" "B.Cu")
		(net "P5V_STB_NODE1_VREG5")
	)
	(via
		(at 145.159476 -168.547034)
		(size 0.6604)
		(drill 0.3302)
		(layers "F.Cu" "B.Cu")
		(net "N21698757")
	)
	(segment
		(start 147.618958 -170.156632)
		(end 147.618958 -169.520362)
		(width 0.1016)
		(layer "B.Cu")
		(net "N21698757")
	)
	(segment
		(start 147.17903 -170.59656)
		(end 147.618958 -170.156632)
		(width 0.1016)
		(layer "B.Cu")
		(net "N21698757")
	)
	(segment
		(start 145.569432 -168.95699)
		(end 145.159476 -168.547034)
		(width 0.1016)
		(layer "B.Cu")
		(net "N21698757")
	)
	(segment
		(start 142.71752 -169.965624)
		(end 143.348456 -170.59656)
		(width 0.1016)
		(layer "B.Cu")
		(net "N21698757")
	)
	(segment
		(start 145.14576 -170.59656)
		(end 147.17903 -170.59656)
		(width 0.1016)
		(layer "B.Cu")
		(net "N21698757")
	)
	(segment
		(start 147.618958 -169.520362)
		(end 147.055586 -168.95699)
		(width 0.1016)
		(layer "B.Cu")
		(net "N21698757")
	)
	(segment
		(start 147.055586 -168.95699)
		(end 145.569432 -168.95699)
		(width 0.1016)
		(layer "B.Cu")
		(net "N21698757")
	)
	(segment
		(start 142.47241 -169.965624)
		(end 142.71752 -169.965624)
		(width 0.1016)
		(layer "B.Cu")
		(net "N21698757")
	)
	(segment
		(start 143.348456 -170.59656)
		(end 145.14576 -170.59656)
		(width 0.1016)
		(layer "B.Cu")
		(net "N21698757")
	)
	(segment
		(start 66.9417 -143.259556)
		(end 66.33845 -143.862806)
		(width 0.254)
		(layer "F.Cu")
		(net "TP_BMC_NODE1_ADCVREFP")
	)
	(segment
		(start 66.33845 -143.862806)
		(end 66.33845 -144.539716)
		(width 0.254)
		(layer "F.Cu")
		(net "TP_BMC_NODE1_ADCVREFP")
	)
	(via
		(at 66.33845 -144.539716)
		(size 0.508)
		(drill 0.254)
		(layers "F.Cu" "B.Cu")
		(net "TP_BMC_NODE1_ADCVREFP")
	)
	(segment
		(start 72.579992 -73.761854)
		(end 72.579992 -72.729598)
		(width 0.1016)
		(layer "F.Cu")
		(net "M1_DQ_NODE1_DQ60")
	)
	(segment
		(start 72.901556 -74.083418)
		(end 72.579992 -73.761854)
		(width 0.1016)
		(layer "F.Cu")
		(net "M1_DQ_NODE1_DQ60")
	)
	(segment
		(start 96.45015 -29.149802)
		(end 96.45015 -27.172666)
		(width 0.1651)
		(layer "F.Cu")
		(net "M1_DQ_NODE1_DQ60")
	)
	(segment
		(start 96.45015 -27.172666)
		(end 96.198182 -26.920698)
		(width 0.1651)
		(layer "F.Cu")
		(net "M1_DQ_NODE1_DQ60")
	)
	(segment
		(start 72.579992 -72.729598)
		(end 72.677528 -72.632062)
		(width 0.1016)
		(layer "F.Cu")
		(net "M1_DQ_NODE1_DQ60")
	)
	(via
		(at 96.198182 -26.920698)
		(size 0.508)
		(drill 0.254)
		(layers "F.Cu" "B.Cu")
		(net "M1_DQ_NODE1_DQ60")
	)
	(via
		(at 72.677528 -72.632062)
		(size 0.508)
		(drill 0.254)
		(layers "F.Cu" "B.Cu")
		(net "M1_DQ_NODE1_DQ60")
	)
	(segment
		(start 96.683322 -30.441138)
		(end 96.40316 -30.160976)
		(width 0.2032)
		(layer "In7.Cu")
		(net "M1_DQ_NODE1_DQ60")
	)
	(segment
		(start 76.593192 -68.71081)
		(end 77.50302 -67.800982)
		(width 0.2032)
		(layer "In7.Cu")
		(net "M1_DQ_NODE1_DQ60")
	)
	(segment
		(start 90.365072 -50.927508)
		(end 90.365072 -50.632868)
		(width 0.2032)
		(layer "In7.Cu")
		(net "M1_DQ_NODE1_DQ60")
	)
	(segment
		(start 96.40316 -27.125676)
		(end 96.198182 -26.920698)
		(width 0.2032)
		(layer "In7.Cu")
		(net "M1_DQ_NODE1_DQ60")
	)
	(segment
		(start 96.683322 -35.005518)
		(end 96.683322 -30.441138)
		(width 0.2032)
		(layer "In7.Cu")
		(net "M1_DQ_NODE1_DQ60")
	)
	(segment
		(start 73.412604 -70.40118)
		(end 73.910444 -69.90334)
		(width 0.2032)
		(layer "In7.Cu")
		(net "M1_DQ_NODE1_DQ60")
	)
	(segment
		(start 96.750886 -46.258734)
		(end 96.750886 -45.964094)
		(width 0.2032)
		(layer "In7.Cu")
		(net "M1_DQ_NODE1_DQ60")
	)
	(segment
		(start 96.9772 -44.02074)
		(end 96.9772 -35.299396)
		(width 0.2032)
		(layer "In7.Cu")
		(net "M1_DQ_NODE1_DQ60")
	)
	(segment
		(start 73.46188 -69.158104)
		(end 73.46188 -68.88353)
		(width 0.2032)
		(layer "In7.Cu")
		(net "M1_DQ_NODE1_DQ60")
	)
	(segment
		(start 81.72958 -61.278516)
		(end 82.1436 -60.864496)
		(width 0.2032)
		(layer "In7.Cu")
		(net "M1_DQ_NODE1_DQ60")
	)
	(segment
		(start 74.694542 -69.13626)
		(end 74.989182 -69.13626)
		(width 0.2032)
		(layer "In7.Cu")
		(net "M1_DQ_NODE1_DQ60")
	)
	(segment
		(start 73.912222 -69.90334)
		(end 73.912222 -69.6087)
		(width 0.2032)
		(layer "In7.Cu")
		(net "M1_DQ_NODE1_DQ60")
	)
	(segment
		(start 96.247966 -45.755814)
		(end 90.867992 -51.135788)
		(width 0.2032)
		(layer "In7.Cu")
		(net "M1_DQ_NODE1_DQ60")
	)
	(segment
		(start 96.9772 -35.299396)
		(end 96.683322 -35.005518)
		(width 0.2032)
		(layer "In7.Cu")
		(net "M1_DQ_NODE1_DQ60")
	)
	(segment
		(start 73.412604 -71.896986)
		(end 73.412604 -70.40118)
		(width 0.2032)
		(layer "In7.Cu")
		(net "M1_DQ_NODE1_DQ60")
	)
	(segment
		(start 90.867992 -51.135788)
		(end 90.573352 -51.135788)
		(width 0.2032)
		(layer "In7.Cu")
		(net "M1_DQ_NODE1_DQ60")
	)
	(segment
		(start 80.383126 -67.800982)
		(end 81.72958 -66.454528)
		(width 0.2032)
		(layer "In7.Cu")
		(net "M1_DQ_NODE1_DQ60")
	)
	(segment
		(start 73.910444 -69.90334)
		(end 73.912222 -69.90334)
		(width 0.2032)
		(layer "In7.Cu")
		(net "M1_DQ_NODE1_DQ60")
	)
	(segment
		(start 81.72958 -66.454528)
		(end 81.72958 -61.278516)
		(width 0.2032)
		(layer "In7.Cu")
		(net "M1_DQ_NODE1_DQ60")
	)
	(segment
		(start 74.989182 -69.13626)
		(end 75.414632 -68.71081)
		(width 0.2032)
		(layer "In7.Cu")
		(net "M1_DQ_NODE1_DQ60")
	)
	(segment
		(start 74.111866 -68.553584)
		(end 74.694542 -69.13626)
		(width 0.2032)
		(layer "In7.Cu")
		(net "M1_DQ_NODE1_DQ60")
	)
	(segment
		(start 96.750886 -45.964094)
		(end 96.542606 -45.755814)
		(width 0.2032)
		(layer "In7.Cu")
		(net "M1_DQ_NODE1_DQ60")
	)
	(segment
		(start 73.912476 -69.6087)
		(end 73.46188 -69.158104)
		(width 0.2032)
		(layer "In7.Cu")
		(net "M1_DQ_NODE1_DQ60")
	)
	(segment
		(start 73.46188 -68.88353)
		(end 73.791826 -68.553584)
		(width 0.2032)
		(layer "In7.Cu")
		(net "M1_DQ_NODE1_DQ60")
	)
	(segment
		(start 90.365072 -50.632868)
		(end 96.9772 -44.02074)
		(width 0.2032)
		(layer "In7.Cu")
		(net "M1_DQ_NODE1_DQ60")
	)
	(segment
		(start 75.414632 -68.71081)
		(end 76.593192 -68.71081)
		(width 0.2032)
		(layer "In7.Cu")
		(net "M1_DQ_NODE1_DQ60")
	)
	(segment
		(start 72.677528 -72.632062)
		(end 73.412604 -71.896986)
		(width 0.2032)
		(layer "In7.Cu")
		(net "M1_DQ_NODE1_DQ60")
	)
	(segment
		(start 96.542606 -45.755814)
		(end 96.247966 -45.755814)
		(width 0.2032)
		(layer "In7.Cu")
		(net "M1_DQ_NODE1_DQ60")
	)
	(segment
		(start 82.1436 -60.864496)
		(end 82.145124 -60.864496)
		(width 0.2032)
		(layer "In7.Cu")
		(net "M1_DQ_NODE1_DQ60")
	)
	(segment
		(start 73.791826 -68.553584)
		(end 74.111866 -68.553584)
		(width 0.2032)
		(layer "In7.Cu")
		(net "M1_DQ_NODE1_DQ60")
	)
	(segment
		(start 96.40316 -30.160976)
		(end 96.40316 -27.125676)
		(width 0.2032)
		(layer "In7.Cu")
		(net "M1_DQ_NODE1_DQ60")
	)
	(segment
		(start 82.145124 -60.864496)
		(end 96.750886 -46.258734)
		(width 0.2032)
		(layer "In7.Cu")
		(net "M1_DQ_NODE1_DQ60")
	)
	(segment
		(start 90.573352 -51.135788)
		(end 90.365072 -50.927508)
		(width 0.2032)
		(layer "In7.Cu")
		(net "M1_DQ_NODE1_DQ60")
	)
	(segment
		(start 73.912222 -69.6087)
		(end 73.912476 -69.6087)
		(width 0.2032)
		(layer "In7.Cu")
		(net "M1_DQ_NODE1_DQ60")
	)
	(segment
		(start 77.50302 -67.800982)
		(end 80.383126 -67.800982)
		(width 0.2032)
		(layer "In7.Cu")
		(net "M1_DQ_NODE1_DQ60")
	)
	(segment
		(start 106.347768 -152.886664)
		(end 106.347768 -152.719278)
		(width 0.254)
		(layer "F.Cu")
		(net "P1V8_STB_NODE1_FB")
	)
	(segment
		(start 104.180894 -154.024838)
		(end 104.408732 -153.797)
		(width 0.254)
		(layer "F.Cu")
		(net "P1V8_STB_NODE1_FB")
	)
	(segment
		(start 105.682034 -153.797)
		(end 105.682034 -153.552398)
		(width 0.254)
		(layer "F.Cu")
		(net "P1V8_STB_NODE1_FB")
	)
	(segment
		(start 103.816658 -154.024838)
		(end 104.180894 -154.024838)
		(width 0.254)
		(layer "F.Cu")
		(net "P1V8_STB_NODE1_FB")
	)
	(segment
		(start 106.347768 -152.719278)
		(end 106.347768 -151.7142)
		(width 0.254)
		(layer "F.Cu")
		(net "P1V8_STB_NODE1_FB")
	)
	(segment
		(start 104.846882 -153.797)
		(end 105.682034 -153.797)
		(width 0.254)
		(layer "F.Cu")
		(net "P1V8_STB_NODE1_FB")
	)
	(segment
		(start 104.408732 -153.797)
		(end 104.846882 -153.797)
		(width 0.254)
		(layer "F.Cu")
		(net "P1V8_STB_NODE1_FB")
	)
	(segment
		(start 105.682034 -153.552398)
		(end 106.347768 -152.886664)
		(width 0.254)
		(layer "F.Cu")
		(net "P1V8_STB_NODE1_FB")
	)
	(via
		(at 104.846882 -153.797)
		(size 0.508)
		(drill 0.254)
		(layers "F.Cu" "B.Cu")
		(net "P1V8_STB_NODE1_FB")
	)
	(via
		(at 152.582626 -171.489624)
		(size 0.508)
		(drill 0.254)
		(layers "F.Cu" "B.Cu")
		(net "N21698959")
	)
	(segment
		(start 152.175718 -171.896532)
		(end 152.582626 -171.489624)
		(width 0.1016)
		(layer "B.Cu")
		(net "N21698959")
	)
	(segment
		(start 150.98776 -171.896532)
		(end 152.175718 -171.896532)
		(width 0.1016)
		(layer "B.Cu")
		(net "N21698959")
	)
	(segment
		(start 146.877024 -171.246546)
		(end 147.52701 -171.896532)
		(width 0.1016)
		(layer "B.Cu")
		(net "N21698959")
	)
	(segment
		(start 152.582626 -171.489624)
		(end 153.66111 -171.489624)
		(width 0.1016)
		(layer "B.Cu")
		(net "N21698959")
	)
	(segment
		(start 145.14576 -171.246546)
		(end 146.877024 -171.246546)
		(width 0.1016)
		(layer "B.Cu")
		(net "N21698959")
	)
	(segment
		(start 147.52701 -171.896532)
		(end 150.98776 -171.896532)
		(width 0.1016)
		(layer "B.Cu")
		(net "N21698959")
	)
	(segment
		(start 63.741808 -141.65961)
		(end 63.74257 -141.65961)
		(width 0.381)
		(layer "F.Cu")
		(net "BMC_NODE1_ADCAV33")
	)
	(segment
		(start 63.74257 -141.65961)
		(end 64.148716 -142.065756)
		(width 0.381)
		(layer "F.Cu")
		(net "BMC_NODE1_ADCAV33")
	)
	(via
		(at 64.148716 -142.065756)
		(size 0.49022)
		(drill 0.254)
		(layers "F.Cu" "B.Cu")
		(net "BMC_NODE1_ADCAV33")
	)
	(via
		(at 64.95034 -145.893282)
		(size 0.6604)
		(drill 0.3302)
		(layers "F.Cu" "B.Cu")
		(net "BMC_NODE1_ADCAV33")
	)
	(segment
		(start 50.88636 -62.41796)
		(end 50.88636 -63.158624)
		(width 0.1016)
		(layer "F.Cu")
		(net "M1_DQ_NODE1_DQ13")
	)
	(segment
		(start 45.701712 -26.154888)
		(end 47.250096 -27.703272)
		(width 0.1651)
		(layer "F.Cu")
		(net "M1_DQ_NODE1_DQ13")
	)
	(segment
		(start 45.13072 -25.848056)
		(end 45.437552 -26.154888)
		(width 0.1651)
		(layer "F.Cu")
		(net "M1_DQ_NODE1_DQ13")
	)
	(segment
		(start 47.250096 -27.703272)
		(end 47.250096 -29.149802)
		(width 0.1651)
		(layer "F.Cu")
		(net "M1_DQ_NODE1_DQ13")
	)
	(segment
		(start 50.46599 -61.99759)
		(end 50.88636 -62.41796)
		(width 0.1016)
		(layer "F.Cu")
		(net "M1_DQ_NODE1_DQ13")
	)
	(segment
		(start 45.437552 -26.154888)
		(end 45.701712 -26.154888)
		(width 0.1651)
		(layer "F.Cu")
		(net "M1_DQ_NODE1_DQ13")
	)
	(via
		(at 45.13072 -25.848056)
		(size 0.508)
		(drill 0.254)
		(layers "F.Cu" "B.Cu")
		(net "M1_DQ_NODE1_DQ13")
	)
	(via
		(at 50.46599 -61.99759)
		(size 0.508)
		(drill 0.254)
		(layers "F.Cu" "B.Cu")
		(net "M1_DQ_NODE1_DQ13")
	)
	(segment
		(start 48.444658 -63.214758)
		(end 48.444658 -62.609476)
		(width 0.2032)
		(layer "In2.Cu")
		(net "M1_DQ_NODE1_DQ13")
	)
	(segment
		(start 41.7068 -27.236928)
		(end 41.7068 -28.204922)
		(width 0.2032)
		(layer "In2.Cu")
		(net "M1_DQ_NODE1_DQ13")
	)
	(segment
		(start 48.236378 -63.423038)
		(end 48.444658 -63.214758)
		(width 0.2032)
		(layer "In2.Cu")
		(net "M1_DQ_NODE1_DQ13")
	)
	(segment
		(start 42.869612 -26.074116)
		(end 41.7068 -27.236928)
		(width 0.2032)
		(layer "In2.Cu")
		(net "M1_DQ_NODE1_DQ13")
	)
	(segment
		(start 40.652954 -28.695396)
		(end 37.71138 -31.63697)
		(width 0.2032)
		(layer "In2.Cu")
		(net "M1_DQ_NODE1_DQ13")
	)
	(segment
		(start 44.90466 -26.074116)
		(end 42.869612 -26.074116)
		(width 0.2032)
		(layer "In2.Cu")
		(net "M1_DQ_NODE1_DQ13")
	)
	(segment
		(start 37.71138 -31.63697)
		(end 37.71138 -32.862012)
		(width 0.2032)
		(layer "In2.Cu")
		(net "M1_DQ_NODE1_DQ13")
	)
	(segment
		(start 50.062384 -62.401196)
		(end 50.46599 -61.99759)
		(width 0.2032)
		(layer "In2.Cu")
		(net "M1_DQ_NODE1_DQ13")
	)
	(segment
		(start 44.029376 -62.401196)
		(end 44.419266 -62.401196)
		(width 0.2032)
		(layer "In2.Cu")
		(net "M1_DQ_NODE1_DQ13")
	)
	(segment
		(start 43.708066 -62.722506)
		(end 44.029376 -62.401196)
		(width 0.2032)
		(layer "In2.Cu")
		(net "M1_DQ_NODE1_DQ13")
	)
	(segment
		(start 47.941738 -63.423038)
		(end 48.236378 -63.423038)
		(width 0.2032)
		(layer "In2.Cu")
		(net "M1_DQ_NODE1_DQ13")
	)
	(segment
		(start 38.275768 -61.252862)
		(end 41.76649 -61.252862)
		(width 0.2032)
		(layer "In2.Cu")
		(net "M1_DQ_NODE1_DQ13")
	)
	(segment
		(start 31.65094 -57.277508)
		(end 34.803842 -60.43041)
		(width 0.2032)
		(layer "In2.Cu")
		(net "M1_DQ_NODE1_DQ13")
	)
	(segment
		(start 42.505376 -62.401196)
		(end 42.996866 -62.401196)
		(width 0.2032)
		(layer "In2.Cu")
		(net "M1_DQ_NODE1_DQ13")
	)
	(segment
		(start 48.652938 -62.401196)
		(end 50.062384 -62.401196)
		(width 0.2032)
		(layer "In2.Cu")
		(net "M1_DQ_NODE1_DQ13")
	)
	(segment
		(start 42.05986 -61.546232)
		(end 42.05986 -61.95568)
		(width 0.2032)
		(layer "In2.Cu")
		(net "M1_DQ_NODE1_DQ13")
	)
	(segment
		(start 41.216326 -28.695396)
		(end 40.652954 -28.695396)
		(width 0.2032)
		(layer "In2.Cu")
		(net "M1_DQ_NODE1_DQ13")
	)
	(segment
		(start 43.318176 -62.722506)
		(end 43.708066 -62.722506)
		(width 0.2032)
		(layer "In2.Cu")
		(net "M1_DQ_NODE1_DQ13")
	)
	(segment
		(start 45.130466 -62.722506)
		(end 45.451776 -62.401196)
		(width 0.2032)
		(layer "In2.Cu")
		(net "M1_DQ_NODE1_DQ13")
	)
	(segment
		(start 31.65094 -38.922452)
		(end 31.65094 -57.277508)
		(width 0.2032)
		(layer "In2.Cu")
		(net "M1_DQ_NODE1_DQ13")
	)
	(segment
		(start 47.525178 -62.401196)
		(end 47.733458 -62.609476)
		(width 0.2032)
		(layer "In2.Cu")
		(net "M1_DQ_NODE1_DQ13")
	)
	(segment
		(start 34.803842 -60.43041)
		(end 37.453316 -60.43041)
		(width 0.2032)
		(layer "In2.Cu")
		(net "M1_DQ_NODE1_DQ13")
	)
	(segment
		(start 47.733458 -63.214758)
		(end 47.941738 -63.423038)
		(width 0.2032)
		(layer "In2.Cu")
		(net "M1_DQ_NODE1_DQ13")
	)
	(segment
		(start 42.05986 -61.95568)
		(end 42.505376 -62.401196)
		(width 0.2032)
		(layer "In2.Cu")
		(net "M1_DQ_NODE1_DQ13")
	)
	(segment
		(start 42.996866 -62.401196)
		(end 43.318176 -62.722506)
		(width 0.2032)
		(layer "In2.Cu")
		(net "M1_DQ_NODE1_DQ13")
	)
	(segment
		(start 45.451776 -62.401196)
		(end 47.525178 -62.401196)
		(width 0.2032)
		(layer "In2.Cu")
		(net "M1_DQ_NODE1_DQ13")
	)
	(segment
		(start 37.453316 -60.43041)
		(end 38.275768 -61.252862)
		(width 0.2032)
		(layer "In2.Cu")
		(net "M1_DQ_NODE1_DQ13")
	)
	(segment
		(start 37.71138 -32.862012)
		(end 31.65094 -38.922452)
		(width 0.2032)
		(layer "In2.Cu")
		(net "M1_DQ_NODE1_DQ13")
	)
	(segment
		(start 48.444658 -62.609476)
		(end 48.652938 -62.401196)
		(width 0.2032)
		(layer "In2.Cu")
		(net "M1_DQ_NODE1_DQ13")
	)
	(segment
		(start 47.733458 -62.609476)
		(end 47.733458 -63.214758)
		(width 0.2032)
		(layer "In2.Cu")
		(net "M1_DQ_NODE1_DQ13")
	)
	(segment
		(start 44.740576 -62.722506)
		(end 45.130466 -62.722506)
		(width 0.2032)
		(layer "In2.Cu")
		(net "M1_DQ_NODE1_DQ13")
	)
	(segment
		(start 45.13072 -25.848056)
		(end 44.90466 -26.074116)
		(width 0.2032)
		(layer "In2.Cu")
		(net "M1_DQ_NODE1_DQ13")
	)
	(segment
		(start 41.76649 -61.252862)
		(end 42.05986 -61.546232)
		(width 0.2032)
		(layer "In2.Cu")
		(net "M1_DQ_NODE1_DQ13")
	)
	(segment
		(start 41.7068 -28.204922)
		(end 41.216326 -28.695396)
		(width 0.2032)
		(layer "In2.Cu")
		(net "M1_DQ_NODE1_DQ13")
	)
	(segment
		(start 44.419266 -62.401196)
		(end 44.740576 -62.722506)
		(width 0.2032)
		(layer "In2.Cu")
		(net "M1_DQ_NODE1_DQ13")
	)
	(via
		(at 95.928942 -174.33417)
		(size 0.6604)
		(drill 0.3302)
		(layers "F.Cu" "B.Cu")
		(net "N21701261")
	)
	(segment
		(start 95.176086 -174.156624)
		(end 95.353632 -174.33417)
		(width 0.1016)
		(layer "B.Cu")
		(net "N21701261")
	)
	(segment
		(start 96.654366 -174.294546)
		(end 96.614742 -174.33417)
		(width 0.1016)
		(layer "B.Cu")
		(net "N21701261")
	)
	(segment
		(start 94.851982 -174.156624)
		(end 95.176086 -174.156624)
		(width 0.1016)
		(layer "B.Cu")
		(net "N21701261")
	)
	(segment
		(start 96.614742 -174.33417)
		(end 95.928942 -174.33417)
		(width 0.1016)
		(layer "B.Cu")
		(net "N21701261")
	)
	(segment
		(start 95.353632 -174.33417)
		(end 95.928942 -174.33417)
		(width 0.1016)
		(layer "B.Cu")
		(net "N21701261")
	)
	(segment
		(start 97.52076 -174.294546)
		(end 96.654366 -174.294546)
		(width 0.1016)
		(layer "B.Cu")
		(net "N21701261")
	)
	(segment
		(start 70.525132 -127.65913)
		(end 70.538848 -127.65913)
		(width 0.3048)
		(layer "F.Cu")
		(net "BMC_NODE1_VCC_1V8_PCIEA")
	)
	(segment
		(start 72.541892 -127.25908)
		(end 72.941942 -126.85903)
		(width 0.3048)
		(layer "F.Cu")
		(net "BMC_NODE1_VCC_1V8_PCIEA")
	)
	(segment
		(start 72.541892 -127.259588)
		(end 72.541892 -127.25908)
		(width 0.3048)
		(layer "F.Cu")
		(net "BMC_NODE1_VCC_1V8_PCIEA")
	)
	(segment
		(start 70.141846 -128.042416)
		(end 70.525132 -127.65913)
		(width 0.3048)
		(layer "F.Cu")
		(net "BMC_NODE1_VCC_1V8_PCIEA")
	)
	(segment
		(start 70.141846 -128.059434)
		(end 70.141846 -128.042416)
		(width 0.3048)
		(layer "F.Cu")
		(net "BMC_NODE1_VCC_1V8_PCIEA")
	)
	(via
		(at 76.253086 -125.946662)
		(size 0.508)
		(drill 0.254)
		(layers "F.Cu" "B.Cu")
		(net "BMC_NODE1_VCC_1V8_PCIEA")
	)
	(via
		(at 75.53198 -126.635002)
		(size 0.508)
		(drill 0.254)
		(layers "F.Cu" "B.Cu")
		(net "BMC_NODE1_VCC_1V8_PCIEA")
	)
	(via
		(at 73.154286 -125.895862)
		(size 0.508)
		(drill 0.254)
		(layers "F.Cu" "B.Cu")
		(net "BMC_NODE1_VCC_1V8_PCIEA")
	)
	(via
		(at 72.941942 -126.85903)
		(size 0.49022)
		(drill 0.254)
		(layers "F.Cu" "B.Cu")
		(net "BMC_NODE1_VCC_1V8_PCIEA")
	)
	(via
		(at 70.538848 -127.65913)
		(size 0.49022)
		(drill 0.254)
		(layers "F.Cu" "B.Cu")
		(net "BMC_NODE1_VCC_1V8_PCIEA")
	)
	(segment
		(start 41.250108 -30.222952)
		(end 41.250108 -29.149802)
		(width 0.1651)
		(layer "F.Cu")
		(net "M1_DQ_NODE1_DQ4")
	)
	(segment
		(start 40.43426 -31.0388)
		(end 41.250108 -30.222952)
		(width 0.1651)
		(layer "F.Cu")
		(net "M1_DQ_NODE1_DQ4")
	)
	(segment
		(start 50.525426 -66.215006)
		(end 50.919126 -65.821306)
		(width 0.1016)
		(layer "F.Cu")
		(net "M1_DQ_NODE1_DQ4")
	)
	(segment
		(start 40.43426 -32.456374)
		(end 40.43426 -31.0388)
		(width 0.1651)
		(layer "F.Cu")
		(net "M1_DQ_NODE1_DQ4")
	)
	(segment
		(start 50.525426 -66.217038)
		(end 50.525426 -66.215006)
		(width 0.1016)
		(layer "F.Cu")
		(net "M1_DQ_NODE1_DQ4")
	)
	(via
		(at 40.43426 -32.456374)
		(size 0.508)
		(drill 0.254)
		(layers "F.Cu" "B.Cu")
		(net "M1_DQ_NODE1_DQ4")
	)
	(via
		(at 50.919126 -65.821306)
		(size 0.508)
		(drill 0.254)
		(layers "F.Cu" "B.Cu")
		(net "M1_DQ_NODE1_DQ4")
	)
	(segment
		(start 33.697926 -40.71747)
		(end 34.739834 -40.71747)
		(width 0.2032)
		(layer "In7.Cu")
		(net "M1_DQ_NODE1_DQ4")
	)
	(segment
		(start 41.126156 -57.530746)
		(end 37.730684 -57.530746)
		(width 0.2032)
		(layer "In7.Cu")
		(net "M1_DQ_NODE1_DQ4")
	)
	(segment
		(start 34.95548 -37.811964)
		(end 34.739834 -37.596318)
		(width 0.2032)
		(layer "In7.Cu")
		(net "M1_DQ_NODE1_DQ4")
	)
	(segment
		(start 35.720528 -37.03955)
		(end 40.303704 -32.456374)
		(width 0.2032)
		(layer "In7.Cu")
		(net "M1_DQ_NODE1_DQ4")
	)
	(segment
		(start 42.963846 -58.891932)
		(end 42.487342 -58.891932)
		(width 0.2032)
		(layer "In7.Cu")
		(net "M1_DQ_NODE1_DQ4")
	)
	(segment
		(start 34.434526 -37.596318)
		(end 34.21888 -37.811964)
		(width 0.2032)
		(layer "In7.Cu")
		(net "M1_DQ_NODE1_DQ4")
	)
	(segment
		(start 37.730684 -57.530746)
		(end 33.48228 -53.282342)
		(width 0.2032)
		(layer "In7.Cu")
		(net "M1_DQ_NODE1_DQ4")
	)
	(segment
		(start 44.527216 -59.950096)
		(end 44.02201 -59.950096)
		(width 0.2032)
		(layer "In7.Cu")
		(net "M1_DQ_NODE1_DQ4")
	)
	(segment
		(start 35.199574 -36.823396)
		(end 35.415728 -37.03955)
		(width 0.2032)
		(layer "In7.Cu")
		(net "M1_DQ_NODE1_DQ4")
	)
	(segment
		(start 34.739834 -40.71747)
		(end 34.95548 -40.501824)
		(width 0.2032)
		(layer "In7.Cu")
		(net "M1_DQ_NODE1_DQ4")
	)
	(segment
		(start 48.84928 -64.27089)
		(end 46.85919 -62.2808)
		(width 0.1016)
		(layer "In7.Cu")
		(net "M1_DQ_NODE1_DQ4")
	)
	(segment
		(start 36.891468 -33.784794)
		(end 37.178996 -33.784794)
		(width 0.2032)
		(layer "In7.Cu")
		(net "M1_DQ_NODE1_DQ4")
	)
	(segment
		(start 33.48228 -37.193982)
		(end 36.891468 -33.784794)
		(width 0.2032)
		(layer "In7.Cu")
		(net "M1_DQ_NODE1_DQ4")
	)
	(segment
		(start 50.919126 -65.821306)
		(end 50.40249 -66.337942)
		(width 0.1016)
		(layer "In7.Cu")
		(net "M1_DQ_NODE1_DQ4")
	)
	(segment
		(start 42.487342 -58.891932)
		(end 41.126156 -57.530746)
		(width 0.2032)
		(layer "In7.Cu")
		(net "M1_DQ_NODE1_DQ4")
	)
	(segment
		(start 48.84928 -66.570098)
		(end 48.84928 -64.27089)
		(width 0.1016)
		(layer "In7.Cu")
		(net "M1_DQ_NODE1_DQ4")
	)
	(segment
		(start 34.95548 -40.501824)
		(end 34.95548 -37.811964)
		(width 0.2032)
		(layer "In7.Cu")
		(net "M1_DQ_NODE1_DQ4")
	)
	(segment
		(start 50.40249 -66.568574)
		(end 49.96307 -67.007994)
		(width 0.1016)
		(layer "In7.Cu")
		(net "M1_DQ_NODE1_DQ4")
	)
	(segment
		(start 33.48228 -40.933116)
		(end 33.697926 -40.71747)
		(width 0.2032)
		(layer "In7.Cu")
		(net "M1_DQ_NODE1_DQ4")
	)
	(segment
		(start 35.199574 -36.518596)
		(end 35.199574 -36.823396)
		(width 0.2032)
		(layer "In7.Cu")
		(net "M1_DQ_NODE1_DQ4")
	)
	(segment
		(start 49.287176 -67.007994)
		(end 48.84928 -66.570098)
		(width 0.1016)
		(layer "In7.Cu")
		(net "M1_DQ_NODE1_DQ4")
	)
	(segment
		(start 35.415728 -37.03955)
		(end 35.720528 -37.03955)
		(width 0.2032)
		(layer "In7.Cu")
		(net "M1_DQ_NODE1_DQ4")
	)
	(segment
		(start 34.21888 -39.765224)
		(end 34.003234 -39.98087)
		(width 0.2032)
		(layer "In7.Cu")
		(net "M1_DQ_NODE1_DQ4")
	)
	(segment
		(start 33.48228 -53.282342)
		(end 33.48228 -40.933116)
		(width 0.2032)
		(layer "In7.Cu")
		(net "M1_DQ_NODE1_DQ4")
	)
	(segment
		(start 46.85919 -62.2808)
		(end 46.85792 -62.2808)
		(width 0.2032)
		(layer "In7.Cu")
		(net "M1_DQ_NODE1_DQ4")
	)
	(segment
		(start 44.02201 -59.950096)
		(end 42.963846 -58.891932)
		(width 0.2032)
		(layer "In7.Cu")
		(net "M1_DQ_NODE1_DQ4")
	)
	(segment
		(start 49.96307 -67.007994)
		(end 49.287176 -67.007994)
		(width 0.1016)
		(layer "In7.Cu")
		(net "M1_DQ_NODE1_DQ4")
	)
	(segment
		(start 33.48228 -39.765224)
		(end 33.48228 -37.193982)
		(width 0.2032)
		(layer "In7.Cu")
		(net "M1_DQ_NODE1_DQ4")
	)
	(segment
		(start 40.303704 -32.456374)
		(end 40.43426 -32.456374)
		(width 0.2032)
		(layer "In7.Cu")
		(net "M1_DQ_NODE1_DQ4")
	)
	(segment
		(start 37.412422 -34.305748)
		(end 35.199574 -36.518596)
		(width 0.2032)
		(layer "In7.Cu")
		(net "M1_DQ_NODE1_DQ4")
	)
	(segment
		(start 37.178996 -33.784794)
		(end 37.412422 -34.01822)
		(width 0.2032)
		(layer "In7.Cu")
		(net "M1_DQ_NODE1_DQ4")
	)
	(segment
		(start 34.739834 -37.596318)
		(end 34.434526 -37.596318)
		(width 0.2032)
		(layer "In7.Cu")
		(net "M1_DQ_NODE1_DQ4")
	)
	(segment
		(start 50.40249 -66.337942)
		(end 50.40249 -66.568574)
		(width 0.1016)
		(layer "In7.Cu")
		(net "M1_DQ_NODE1_DQ4")
	)
	(segment
		(start 46.85792 -62.2808)
		(end 44.527216 -59.950096)
		(width 0.2032)
		(layer "In7.Cu")
		(net "M1_DQ_NODE1_DQ4")
	)
	(segment
		(start 34.003234 -39.98087)
		(end 33.697926 -39.98087)
		(width 0.2032)
		(layer "In7.Cu")
		(net "M1_DQ_NODE1_DQ4")
	)
	(segment
		(start 33.697926 -39.98087)
		(end 33.48228 -39.765224)
		(width 0.2032)
		(layer "In7.Cu")
		(net "M1_DQ_NODE1_DQ4")
	)
	(segment
		(start 34.21888 -37.811964)
		(end 34.21888 -39.765224)
		(width 0.2032)
		(layer "In7.Cu")
		(net "M1_DQ_NODE1_DQ4")
	)
	(segment
		(start 37.412422 -34.01822)
		(end 37.412422 -34.305748)
		(width 0.2032)
		(layer "In7.Cu")
		(net "M1_DQ_NODE1_DQ4")
	)
	(via
		(at 97.756472 -171.559982)
		(size 0.6604)
		(drill 0.3302)
		(layers "F.Cu" "B.Cu")
		(net "N21701263")
	)
	(segment
		(start 96.542352 -172.124624)
		(end 97.106994 -171.559982)
		(width 0.1016)
		(layer "B.Cu")
		(net "N21701263")
	)
	(segment
		(start 97.106994 -171.559982)
		(end 97.756472 -171.559982)
		(width 0.1016)
		(layer "B.Cu")
		(net "N21701263")
	)
	(segment
		(start 94.851982 -172.124624)
		(end 96.542352 -172.124624)
		(width 0.1016)
		(layer "B.Cu")
		(net "N21701263")
	)
	(segment
		(start 97.52076 -172.994574)
		(end 97.52076 -171.795694)
		(width 0.1016)
		(layer "B.Cu")
		(net "N21701263")
	)
	(segment
		(start 97.52076 -171.795694)
		(end 97.756472 -171.559982)
		(width 0.1016)
		(layer "B.Cu")
		(net "N21701263")
	)
	(segment
		(start 68.5419 -127.252222)
		(end 68.936108 -126.858014)
		(width 0.381)
		(layer "F.Cu")
		(net "BMC_NODE1_VCC_1V8_PCIE")
	)
	(segment
		(start 68.5419 -127.259588)
		(end 68.5419 -127.252222)
		(width 0.381)
		(layer "F.Cu")
		(net "BMC_NODE1_VCC_1V8_PCIE")
	)
	(segment
		(start 68.5419 -126.459488)
		(end 68.5419 -126.444248)
		(width 0.3683)
		(layer "F.Cu")
		(net "BMC_NODE1_VCC_1V8_PCIE")
	)
	(segment
		(start 69.341746 -128.059434)
		(end 69.342508 -128.059434)
		(width 0.381)
		(layer "F.Cu")
		(net "BMC_NODE1_VCC_1V8_PCIE")
	)
	(segment
		(start 69.342508 -128.059434)
		(end 69.743828 -127.658114)
		(width 0.381)
		(layer "F.Cu")
		(net "BMC_NODE1_VCC_1V8_PCIE")
	)
	(segment
		(start 68.927218 -126.05893)
		(end 68.942966 -126.05893)
		(width 0.3683)
		(layer "F.Cu")
		(net "BMC_NODE1_VCC_1V8_PCIE")
	)
	(segment
		(start 68.5419 -126.444248)
		(end 68.927218 -126.05893)
		(width 0.3683)
		(layer "F.Cu")
		(net "BMC_NODE1_VCC_1V8_PCIE")
	)
	(via
		(at 69.743828 -127.658114)
		(size 0.49022)
		(drill 0.254)
		(layers "F.Cu" "B.Cu")
		(net "BMC_NODE1_VCC_1V8_PCIE")
	)
	(via
		(at 68.942966 -126.05893)
		(size 0.49022)
		(drill 0.254)
		(layers "F.Cu" "B.Cu")
		(net "BMC_NODE1_VCC_1V8_PCIE")
	)
	(via
		(at 68.936108 -126.858014)
		(size 0.49022)
		(drill 0.254)
		(layers "F.Cu" "B.Cu")
		(net "BMC_NODE1_VCC_1V8_PCIE")
	)
	(via
		(at 69.555614 -126.490222)
		(size 0.6604)
		(drill 0.3302)
		(layers "F.Cu" "B.Cu")
		(net "BMC_NODE1_VCC_1V8_PCIE")
	)
	(segment
		(start 64.06515 -63.31077)
		(end 64.06515 -63.008002)
		(width 0.1016)
		(layer "F.Cu")
		(net "M_DDR3_NODE1_CKE0")
	)
	(segment
		(start 68.867782 -23.567898)
		(end 68.550282 -23.250398)
		(width 0.1651)
		(layer "F.Cu")
		(net "M_DDR3_NODE1_CKE0")
	)
	(segment
		(start 64.401192 -63.898526)
		(end 64.401192 -63.646812)
		(width 0.1016)
		(layer "F.Cu")
		(net "M_DDR3_NODE1_CKE0")
	)
	(segment
		(start 64.401192 -63.646812)
		(end 64.06515 -63.31077)
		(width 0.1016)
		(layer "F.Cu")
		(net "M_DDR3_NODE1_CKE0")
	)
	(segment
		(start 65.485772 -60.904628)
		(end 65.928748 -60.461652)
		(width 0.1016)
		(layer "F.Cu")
		(net "M_DDR3_NODE1_CKE0")
	)
	(segment
		(start 65.928748 -60.461652)
		(end 65.928748 -57.805574)
		(width 0.1016)
		(layer "F.Cu")
		(net "M_DDR3_NODE1_CKE0")
	)
	(segment
		(start 65.485772 -61.58738)
		(end 65.485772 -60.904628)
		(width 0.1016)
		(layer "F.Cu")
		(net "M_DDR3_NODE1_CKE0")
	)
	(segment
		(start 64.06515 -63.008002)
		(end 65.485772 -61.58738)
		(width 0.1016)
		(layer "F.Cu")
		(net "M_DDR3_NODE1_CKE0")
	)
	(segment
		(start 65.148968 -57.025794)
		(end 65.148968 -56.506364)
		(width 0.1016)
		(layer "F.Cu")
		(net "M_DDR3_NODE1_CKE0")
	)
	(segment
		(start 65.928748 -57.805574)
		(end 65.148968 -57.025794)
		(width 0.1016)
		(layer "F.Cu")
		(net "M_DDR3_NODE1_CKE0")
	)
	(segment
		(start 68.550282 -23.250398)
		(end 68.550282 -20.94992)
		(width 0.1651)
		(layer "F.Cu")
		(net "M_DDR3_NODE1_CKE0")
	)
	(via
		(at 65.148968 -56.506364)
		(size 0.508)
		(drill 0.254)
		(layers "F.Cu" "B.Cu")
		(net "M_DDR3_NODE1_CKE0")
	)
	(via
		(at 68.867782 -23.567898)
		(size 0.508)
		(drill 0.254)
		(layers "F.Cu" "B.Cu")
		(net "M_DDR3_NODE1_CKE0")
	)
	(segment
		(start 65.148968 -55.828692)
		(end 65.148968 -56.506364)
		(width 0.2032)
		(layer "In2.Cu")
		(net "M_DDR3_NODE1_CKE0")
	)
	(segment
		(start 70.503542 -21.386038)
		(end 76.682854 -21.386038)
		(width 0.2032)
		(layer "In2.Cu")
		(net "M_DDR3_NODE1_CKE0")
	)
	(segment
		(start 77.70622 -24.39416)
		(end 77.70622 -32.406082)
		(width 0.2032)
		(layer "In2.Cu")
		(net "M_DDR3_NODE1_CKE0")
	)
	(segment
		(start 77.70622 -32.406082)
		(end 77.73162 -32.431482)
		(width 0.2032)
		(layer "In2.Cu")
		(net "M_DDR3_NODE1_CKE0")
	)
	(segment
		(start 69.060822 -23.374858)
		(end 69.424042 -23.374858)
		(width 0.2032)
		(layer "In2.Cu")
		(net "M_DDR3_NODE1_CKE0")
	)
	(segment
		(start 68.867782 -23.567898)
		(end 69.060822 -23.374858)
		(width 0.2032)
		(layer "In2.Cu")
		(net "M_DDR3_NODE1_CKE0")
	)
	(segment
		(start 70.918324 -51.481736)
		(end 69.495924 -51.481736)
		(width 0.2032)
		(layer "In2.Cu")
		(net "M_DDR3_NODE1_CKE0")
	)
	(segment
		(start 76.682854 -21.386038)
		(end 77.56398 -22.267164)
		(width 0.2032)
		(layer "In2.Cu")
		(net "M_DDR3_NODE1_CKE0")
	)
	(segment
		(start 69.723762 -22.165818)
		(end 70.503542 -21.386038)
		(width 0.2032)
		(layer "In2.Cu")
		(net "M_DDR3_NODE1_CKE0")
	)
	(segment
		(start 77.56398 -22.267164)
		(end 77.56398 -24.25192)
		(width 0.2032)
		(layer "In2.Cu")
		(net "M_DDR3_NODE1_CKE0")
	)
	(segment
		(start 77.73162 -32.431482)
		(end 77.73162 -41.495726)
		(width 0.2032)
		(layer "In2.Cu")
		(net "M_DDR3_NODE1_CKE0")
	)
	(segment
		(start 77.73162 -41.495726)
		(end 77.1144 -42.112946)
		(width 0.2032)
		(layer "In2.Cu")
		(net "M_DDR3_NODE1_CKE0")
	)
	(segment
		(start 69.723762 -23.075138)
		(end 69.723762 -22.165818)
		(width 0.2032)
		(layer "In2.Cu")
		(net "M_DDR3_NODE1_CKE0")
	)
	(segment
		(start 77.56398 -24.25192)
		(end 77.70622 -24.39416)
		(width 0.2032)
		(layer "In2.Cu")
		(net "M_DDR3_NODE1_CKE0")
	)
	(segment
		(start 69.495924 -51.481736)
		(end 65.148968 -55.828692)
		(width 0.2032)
		(layer "In2.Cu")
		(net "M_DDR3_NODE1_CKE0")
	)
	(segment
		(start 77.1144 -45.28566)
		(end 70.918324 -51.481736)
		(width 0.2032)
		(layer "In2.Cu")
		(net "M_DDR3_NODE1_CKE0")
	)
	(segment
		(start 69.424042 -23.374858)
		(end 69.723762 -23.075138)
		(width 0.2032)
		(layer "In2.Cu")
		(net "M_DDR3_NODE1_CKE0")
	)
	(segment
		(start 77.1144 -42.112946)
		(end 77.1144 -45.28566)
		(width 0.2032)
		(layer "In2.Cu")
		(net "M_DDR3_NODE1_CKE0")
	)
	(via
		(at 89.33942 -171.464478)
		(size 0.6604)
		(drill 0.3302)
		(layers "F.Cu" "B.Cu")
		(net "N21700927")
	)
	(via
		(at 83.123278 -170.791632)
		(size 0.508)
		(drill 0.254)
		(layers "F.Cu" "B.Cu")
		(net "N21700927")
	)
	(segment
		(start 87.74176 -171.769532)
		(end 89.034366 -171.769532)
		(width 0.1016)
		(layer "B.Cu")
		(net "N21700927")
	)
	(segment
		(start 84.948522 -172.616876)
		(end 85.920326 -172.616876)
		(width 0.1016)
		(layer "B.Cu")
		(net "N21700927")
	)
	(segment
		(start 81.89976 -170.46956)
		(end 83.000342 -170.46956)
		(width 0.1016)
		(layer "B.Cu")
		(net "N21700927")
	)
	(segment
		(start 89.034366 -171.769532)
		(end 89.33942 -171.464478)
		(width 0.1016)
		(layer "B.Cu")
		(net "N21700927")
	)
	(segment
		(start 82.948018 -171.119546)
		(end 83.123278 -170.944286)
		(width 0.1016)
		(layer "B.Cu")
		(net "N21700927")
	)
	(segment
		(start 85.920326 -172.616876)
		(end 86.371684 -172.165518)
		(width 0.1016)
		(layer "B.Cu")
		(net "N21700927")
	)
	(segment
		(start 86.612222 -172.165518)
		(end 87.008208 -171.769532)
		(width 0.1016)
		(layer "B.Cu")
		(net "N21700927")
	)
	(segment
		(start 87.008208 -171.769532)
		(end 87.74176 -171.769532)
		(width 0.1016)
		(layer "B.Cu")
		(net "N21700927")
	)
	(segment
		(start 83.123278 -170.592496)
		(end 83.123278 -170.791632)
		(width 0.1016)
		(layer "B.Cu")
		(net "N21700927")
	)
	(segment
		(start 89.33942 -171.464478)
		(end 89.758012 -171.045886)
		(width 0.1016)
		(layer "B.Cu")
		(net "N21700927")
	)
	(segment
		(start 86.371684 -172.165518)
		(end 86.612222 -172.165518)
		(width 0.1016)
		(layer "B.Cu")
		(net "N21700927")
	)
	(segment
		(start 90.41257 -170.140122)
		(end 90.41257 -169.958512)
		(width 0.1016)
		(layer "B.Cu")
		(net "N21700927")
	)
	(segment
		(start 89.758012 -170.79468)
		(end 90.41257 -170.140122)
		(width 0.1016)
		(layer "B.Cu")
		(net "N21700927")
	)
	(segment
		(start 83.123278 -170.944286)
		(end 83.123278 -170.791632)
		(width 0.1016)
		(layer "B.Cu")
		(net "N21700927")
	)
	(segment
		(start 89.758012 -171.045886)
		(end 89.758012 -170.79468)
		(width 0.1016)
		(layer "B.Cu")
		(net "N21700927")
	)
	(segment
		(start 83.000342 -170.46956)
		(end 83.123278 -170.592496)
		(width 0.1016)
		(layer "B.Cu")
		(net "N21700927")
	)
	(segment
		(start 81.89976 -171.119546)
		(end 82.948018 -171.119546)
		(width 0.1016)
		(layer "B.Cu")
		(net "N21700927")
	)
	(segment
		(start 83.123278 -170.791632)
		(end 84.948522 -172.616876)
		(width 0.1016)
		(layer "B.Cu")
		(net "N21700927")
	)
	(segment
		(start 63.476886 -143.524478)
		(end 63.476886 -144.437862)
		(width 0.4572)
		(layer "F.Cu")
		(net "BMC_NODE1_DACAV33")
	)
	(segment
		(start 63.741808 -143.259556)
		(end 63.476886 -143.524478)
		(width 0.4572)
		(layer "F.Cu")
		(net "BMC_NODE1_DACAV33")
	)
	(segment
		(start 63.731902 -144.692878)
		(end 63.476886 -144.437862)
		(width 0.508)
		(layer "F.Cu")
		(net "BMC_NODE1_DACAV33")
	)
	(segment
		(start 61.891164 -147.81022)
		(end 62.286134 -147.41525)
		(width 0.508)
		(layer "F.Cu")
		(net "BMC_NODE1_DACAV33")
	)
	(segment
		(start 61.891164 -148.121624)
		(end 61.891164 -149.137624)
		(width 0.508)
		(layer "F.Cu")
		(net "BMC_NODE1_DACAV33")
	)
	(segment
		(start 63.731902 -146.889978)
		(end 63.731902 -144.692878)
		(width 0.508)
		(layer "F.Cu")
		(net "BMC_NODE1_DACAV33")
	)
	(segment
		(start 62.141862 -141.65961)
		(end 62.139576 -141.65961)
		(width 0.4064)
		(layer "F.Cu")
		(net "BMC_NODE1_DACAV33")
	)
	(segment
		(start 61.891164 -148.121624)
		(end 61.891164 -147.81022)
		(width 0.508)
		(layer "F.Cu")
		(net "BMC_NODE1_DACAV33")
	)
	(segment
		(start 62.286134 -147.41525)
		(end 63.20663 -147.41525)
		(width 0.508)
		(layer "F.Cu")
		(net "BMC_NODE1_DACAV33")
	)
	(segment
		(start 63.20663 -147.41525)
		(end 63.731902 -146.889978)
		(width 0.508)
		(layer "F.Cu")
		(net "BMC_NODE1_DACAV33")
	)
	(segment
		(start 62.139576 -141.65961)
		(end 61.74105 -142.058136)
		(width 0.4064)
		(layer "F.Cu")
		(net "BMC_NODE1_DACAV33")
	)
	(via
		(at 61.74105 -142.058136)
		(size 0.49022)
		(drill 0.254)
		(layers "F.Cu" "B.Cu")
		(net "BMC_NODE1_DACAV33")
	)
	(via
		(at 61.670184 -149.796246)
		(size 0.508)
		(drill 0.254)
		(layers "F.Cu" "B.Cu")
		(net "BMC_NODE1_DACAV33")
	)
	(via
		(at 63.476886 -144.437862)
		(size 0.508)
		(drill 0.254)
		(layers "F.Cu" "B.Cu")
		(net "BMC_NODE1_DACAV33")
	)
	(segment
		(start 63.476886 -144.412462)
		(end 63.476886 -144.437862)
		(width 0.508)
		(layer "In7.Cu")
		(net "BMC_NODE1_DACAV33")
	)
	(segment
		(start 62.321948 -143.663924)
		(end 62.728348 -143.663924)
		(width 0.508)
		(layer "In7.Cu")
		(net "BMC_NODE1_DACAV33")
	)
	(segment
		(start 61.74105 -142.058136)
		(end 61.74105 -143.083026)
		(width 0.508)
		(layer "In7.Cu")
		(net "BMC_NODE1_DACAV33")
	)
	(segment
		(start 62.728348 -143.663924)
		(end 63.476886 -144.412462)
		(width 0.508)
		(layer "In7.Cu")
		(net "BMC_NODE1_DACAV33")
	)
	(segment
		(start 61.74105 -143.083026)
		(end 62.321948 -143.663924)
		(width 0.508)
		(layer "In7.Cu")
		(net "BMC_NODE1_DACAV33")
	)
	(segment
		(start 50.949098 -90.4748)
		(end 50.949098 -89.097358)
		(width 0.1016)
		(layer "F.Cu")
		(net "PD_NODE1_NTB_PERN")
	)
	(segment
		(start 52.657248 -87.881206)
		(end 53.274214 -88.498172)
		(width 0.1016)
		(layer "F.Cu")
		(net "PD_NODE1_NTB_PERN")
	)
	(segment
		(start 39.843964 -84.181442)
		(end 38.603682 -85.421724)
		(width 0.1016)
		(layer "F.Cu")
		(net "PD_NODE1_NTB_PERN")
	)
	(segment
		(start 42.905426 -84.96173)
		(end 42.69613 -84.752434)
		(width 0.1016)
		(layer "F.Cu")
		(net "PD_NODE1_NTB_PERN")
	)
	(segment
		(start 50.949098 -89.097358)
		(end 51.606196 -88.44026)
		(width 0.1016)
		(layer "F.Cu")
		(net "PD_NODE1_NTB_PERN")
	)
	(segment
		(start 53.398928 -86.862666)
		(end 52.883562 -86.862666)
		(width 0.1016)
		(layer "F.Cu")
		(net "PD_NODE1_NTB_PERN")
	)
	(segment
		(start 50.681382 -88.44026)
		(end 50.679604 -88.438482)
		(width 0.1016)
		(layer "F.Cu")
		(net "PD_NODE1_NTB_PERN")
	)
	(segment
		(start 44.167552 -86.526116)
		(end 45.230796 -86.526116)
		(width 0.1016)
		(layer "F.Cu")
		(net "PD_NODE1_NTB_PERN")
	)
	(segment
		(start 52.076096 -87.714836)
		(end 52.411376 -87.714836)
		(width 0.1016)
		(layer "F.Cu")
		(net "PD_NODE1_NTB_PERN")
	)
	(segment
		(start 45.230796 -86.526116)
		(end 45.613066 -86.143846)
		(width 0.1016)
		(layer "F.Cu")
		(net "PD_NODE1_NTB_PERN")
	)
	(segment
		(start 45.841158 -88.57996)
		(end 45.841158 -88.302338)
		(width 0.1016)
		(layer "F.Cu")
		(net "PD_NODE1_NTB_PERN")
	)
	(segment
		(start 42.69613 -84.752434)
		(end 42.69613 -84.443316)
		(width 0.1016)
		(layer "F.Cu")
		(net "PD_NODE1_NTB_PERN")
	)
	(segment
		(start 45.613066 -86.08187)
		(end 46.31309 -85.381846)
		(width 0.1016)
		(layer "F.Cu")
		(net "PD_NODE1_NTB_PERN")
	)
	(segment
		(start 48.832008 -87.341964)
		(end 48.891444 -87.341964)
		(width 0.1016)
		(layer "F.Cu")
		(net "PD_NODE1_NTB_PERN")
	)
	(segment
		(start 44.527978 -87.005414)
		(end 44.18838 -87.005414)
		(width 0.1016)
		(layer "F.Cu")
		(net "PD_NODE1_NTB_PERN")
	)
	(segment
		(start 52.883562 -86.862666)
		(end 52.778914 -86.862666)
		(width 0.1016)
		(layer "F.Cu")
		(net "PD_NODE1_NTB_PERN")
	)
	(segment
		(start 47.103284 -88.44026)
		(end 47.097188 -88.434164)
		(width 0.1016)
		(layer "F.Cu")
		(net "PD_NODE1_NTB_PERN")
	)
	(segment
		(start 46.730158 -88.813386)
		(end 46.074584 -88.813386)
		(width 0.1016)
		(layer "F.Cu")
		(net "PD_NODE1_NTB_PERN")
	)
	(segment
		(start 41.95572 -84.181442)
		(end 39.843964 -84.181442)
		(width 0.1016)
		(layer "F.Cu")
		(net "PD_NODE1_NTB_PERN")
	)
	(segment
		(start 38.603682 -85.421724)
		(end 38.22954 -85.421724)
		(width 0.1016)
		(layer "F.Cu")
		(net "PD_NODE1_NTB_PERN")
	)
	(segment
		(start 45.613066 -86.143846)
		(end 45.613066 -86.08187)
		(width 0.1016)
		(layer "F.Cu")
		(net "PD_NODE1_NTB_PERN")
	)
	(segment
		(start 42.905426 -85.549994)
		(end 42.905426 -84.96173)
		(width 0.1016)
		(layer "F.Cu")
		(net "PD_NODE1_NTB_PERN")
	)
	(segment
		(start 47.103284 -88.44026)
		(end 47.103284 -89.397586)
		(width 0.1016)
		(layer "F.Cu")
		(net "PD_NODE1_NTB_PERN")
	)
	(segment
		(start 43.796204 -86.613238)
		(end 43.796204 -86.440772)
		(width 0.1016)
		(layer "F.Cu")
		(net "PD_NODE1_NTB_PERN")
	)
	(segment
		(start 47.103284 -89.397586)
		(end 47.04715 -89.45372)
		(width 0.1016)
		(layer "F.Cu")
		(net "PD_NODE1_NTB_PERN")
	)
	(segment
		(start 50.203608 -88.699594)
		(end 50.021236 -88.881966)
		(width 0.1016)
		(layer "F.Cu")
		(net "PD_NODE1_NTB_PERN")
	)
	(segment
		(start 47.097188 -88.434164)
		(end 47.097188 -87.700358)
		(width 0.1016)
		(layer "F.Cu")
		(net "PD_NODE1_NTB_PERN")
	)
	(segment
		(start 44.08043 -86.613238)
		(end 44.167552 -86.526116)
		(width 0.1016)
		(layer "F.Cu")
		(net "PD_NODE1_NTB_PERN")
	)
	(segment
		(start 53.274214 -88.498172)
		(end 54.062122 -88.498172)
		(width 0.1016)
		(layer "F.Cu")
		(net "PD_NODE1_NTB_PERN")
	)
	(segment
		(start 54.115716 -88.551766)
		(end 54.115716 -87.647018)
		(width 0.1016)
		(layer "F.Cu")
		(net "PD_NODE1_NTB_PERN")
	)
	(segment
		(start 44.90085 -87.241888)
		(end 44.764452 -87.241888)
		(width 0.1016)
		(layer "F.Cu")
		(net "PD_NODE1_NTB_PERN")
	)
	(segment
		(start 43.796204 -86.613238)
		(end 44.08043 -86.613238)
		(width 0.1016)
		(layer "F.Cu")
		(net "PD_NODE1_NTB_PERN")
	)
	(segment
		(start 50.021236 -88.881966)
		(end 49.200308 -88.881966)
		(width 0.1016)
		(layer "F.Cu")
		(net "PD_NODE1_NTB_PERN")
	)
	(segment
		(start 47.103284 -88.44026)
		(end 46.730158 -88.813386)
		(width 0.1016)
		(layer "F.Cu")
		(net "PD_NODE1_NTB_PERN")
	)
	(segment
		(start 48.56734 -88.355932)
		(end 48.56734 -87.606632)
		(width 0.1016)
		(layer "F.Cu")
		(net "PD_NODE1_NTB_PERN")
	)
	(segment
		(start 51.606196 -88.44026)
		(end 50.681382 -88.44026)
		(width 0.1016)
		(layer "F.Cu")
		(net "PD_NODE1_NTB_PERN")
	)
	(segment
		(start 43.796204 -86.440772)
		(end 42.905426 -85.549994)
		(width 0.1016)
		(layer "F.Cu")
		(net "PD_NODE1_NTB_PERN")
	)
	(segment
		(start 52.411376 -87.714836)
		(end 52.577746 -87.881206)
		(width 0.1016)
		(layer "F.Cu")
		(net "PD_NODE1_NTB_PERN")
	)
	(segment
		(start 54.115716 -87.647018)
		(end 54.062884 -87.594186)
		(width 0.1016)
		(layer "F.Cu")
		(net "PD_NODE1_NTB_PERN")
	)
	(segment
		(start 51.606196 -88.184736)
		(end 52.076096 -87.714836)
		(width 0.1016)
		(layer "F.Cu")
		(net "PD_NODE1_NTB_PERN")
	)
	(segment
		(start 46.074584 -88.813386)
		(end 45.841158 -88.57996)
		(width 0.1016)
		(layer "F.Cu")
		(net "PD_NODE1_NTB_PERN")
	)
	(segment
		(start 54.062884 -87.594186)
		(end 54.062884 -87.526622)
		(width 0.1016)
		(layer "F.Cu")
		(net "PD_NODE1_NTB_PERN")
	)
	(segment
		(start 42.69613 -84.443316)
		(end 42.194988 -83.942174)
		(width 0.1016)
		(layer "F.Cu")
		(net "PD_NODE1_NTB_PERN")
	)
	(segment
		(start 45.207682 -87.214456)
		(end 44.928282 -87.214456)
		(width 0.1016)
		(layer "F.Cu")
		(net "PD_NODE1_NTB_PERN")
	)
	(segment
		(start 49.143666 -87.594186)
		(end 49.559972 -87.594186)
		(width 0.1016)
		(layer "F.Cu")
		(net "PD_NODE1_NTB_PERN")
	)
	(segment
		(start 48.891444 -87.341964)
		(end 49.143666 -87.594186)
		(width 0.1016)
		(layer "F.Cu")
		(net "PD_NODE1_NTB_PERN")
	)
	(segment
		(start 37.1475 -84.339684)
		(end 38.22954 -85.421724)
		(width 0.1016)
		(layer "F.Cu")
		(net "PD_NODE1_NTB_PERN")
	)
	(segment
		(start 49.200308 -88.881966)
		(end 49.017936 -88.699594)
		(width 0.1016)
		(layer "F.Cu")
		(net "PD_NODE1_NTB_PERN")
	)
	(segment
		(start 36.202874 -84.339684)
		(end 37.1475 -84.339684)
		(width 0.1016)
		(layer "F.Cu")
		(net "PD_NODE1_NTB_PERN")
	)
	(segment
		(start 49.017936 -88.699594)
		(end 48.911002 -88.699594)
		(width 0.1016)
		(layer "F.Cu")
		(net "PD_NODE1_NTB_PERN")
	)
	(segment
		(start 50.679604 -88.438482)
		(end 50.418492 -88.699594)
		(width 0.1016)
		(layer "F.Cu")
		(net "PD_NODE1_NTB_PERN")
	)
	(segment
		(start 48.911002 -88.699594)
		(end 48.56734 -88.355932)
		(width 0.1016)
		(layer "F.Cu")
		(net "PD_NODE1_NTB_PERN")
	)
	(segment
		(start 52.778914 -86.862666)
		(end 52.491132 -87.150448)
		(width 0.1016)
		(layer "F.Cu")
		(net "PD_NODE1_NTB_PERN")
	)
	(segment
		(start 45.749718 -87.241888)
		(end 45.235114 -87.241888)
		(width 0.1016)
		(layer "F.Cu")
		(net "PD_NODE1_NTB_PERN")
	)
	(segment
		(start 47.04715 -89.45372)
		(end 47.04715 -90.669364)
		(width 0.1016)
		(layer "F.Cu")
		(net "PD_NODE1_NTB_PERN")
	)
	(segment
		(start 46.208188 -87.700358)
		(end 45.749718 -87.241888)
		(width 0.1016)
		(layer "F.Cu")
		(net "PD_NODE1_NTB_PERN")
	)
	(segment
		(start 51.64963 -87.150448)
		(end 51.503072 -87.00389)
		(width 0.1016)
		(layer "F.Cu")
		(net "PD_NODE1_NTB_PERN")
	)
	(segment
		(start 47.32655 -90.948764)
		(end 50.475134 -90.948764)
		(width 0.1016)
		(layer "F.Cu")
		(net "PD_NODE1_NTB_PERN")
	)
	(segment
		(start 46.208188 -87.935308)
		(end 46.208188 -87.700358)
		(width 0.1016)
		(layer "F.Cu")
		(net "PD_NODE1_NTB_PERN")
	)
	(segment
		(start 51.606196 -88.44026)
		(end 51.606196 -88.184736)
		(width 0.1016)
		(layer "F.Cu")
		(net "PD_NODE1_NTB_PERN")
	)
	(segment
		(start 44.764452 -87.241888)
		(end 44.527978 -87.005414)
		(width 0.1016)
		(layer "F.Cu")
		(net "PD_NODE1_NTB_PERN")
	)
	(segment
		(start 45.841158 -88.302338)
		(end 46.208188 -87.935308)
		(width 0.1016)
		(layer "F.Cu")
		(net "PD_NODE1_NTB_PERN")
	)
	(segment
		(start 44.928282 -87.214456)
		(end 44.90085 -87.241888)
		(width 0.1016)
		(layer "F.Cu")
		(net "PD_NODE1_NTB_PERN")
	)
	(segment
		(start 50.418492 -88.699594)
		(end 50.203608 -88.699594)
		(width 0.1016)
		(layer "F.Cu")
		(net "PD_NODE1_NTB_PERN")
	)
	(segment
		(start 50.475134 -90.948764)
		(end 50.949098 -90.4748)
		(width 0.1016)
		(layer "F.Cu")
		(net "PD_NODE1_NTB_PERN")
	)
	(segment
		(start 54.062122 -88.498172)
		(end 54.115716 -88.551766)
		(width 0.1016)
		(layer "F.Cu")
		(net "PD_NODE1_NTB_PERN")
	)
	(segment
		(start 52.491132 -87.150448)
		(end 51.64963 -87.150448)
		(width 0.1016)
		(layer "F.Cu")
		(net "PD_NODE1_NTB_PERN")
	)
	(segment
		(start 48.56734 -87.606632)
		(end 48.832008 -87.341964)
		(width 0.1016)
		(layer "F.Cu")
		(net "PD_NODE1_NTB_PERN")
	)
	(segment
		(start 42.194988 -83.942174)
		(end 41.95572 -84.181442)
		(width 0.1016)
		(layer "F.Cu")
		(net "PD_NODE1_NTB_PERN")
	)
	(segment
		(start 44.18838 -87.005414)
		(end 43.796204 -86.613238)
		(width 0.1016)
		(layer "F.Cu")
		(net "PD_NODE1_NTB_PERN")
	)
	(segment
		(start 52.577746 -87.881206)
		(end 52.657248 -87.881206)
		(width 0.1016)
		(layer "F.Cu")
		(net "PD_NODE1_NTB_PERN")
	)
	(segment
		(start 47.04715 -90.669364)
		(end 47.32655 -90.948764)
		(width 0.1016)
		(layer "F.Cu")
		(net "PD_NODE1_NTB_PERN")
	)
	(segment
		(start 54.062884 -87.526622)
		(end 53.398928 -86.862666)
		(width 0.1016)
		(layer "F.Cu")
		(net "PD_NODE1_NTB_PERN")
	)
	(segment
		(start 45.235114 -87.241888)
		(end 45.207682 -87.214456)
		(width 0.1016)
		(layer "F.Cu")
		(net "PD_NODE1_NTB_PERN")
	)
	(via
		(at 38.22954 -85.421724)
		(size 0.508)
		(drill 0.254)
		(layers "F.Cu" "B.Cu")
		(net "PD_NODE1_NTB_PERN")
	)
	(segment
		(start 51.811682 -66.598038)
		(end 51.811682 -66.629026)
		(width 0.1016)
		(layer "F.Cu")
		(net "M1_DQ_NODE1_DQ1")
	)
	(segment
		(start 42.515282 -23.329138)
		(end 42.150284 -22.96414)
		(width 0.1651)
		(layer "F.Cu")
		(net "M1_DQ_NODE1_DQ1")
	)
	(segment
		(start 42.515282 -23.659338)
		(end 42.515282 -23.329138)
		(width 0.1651)
		(layer "F.Cu")
		(net "M1_DQ_NODE1_DQ1")
	)
	(segment
		(start 51.457606 -66.983102)
		(end 51.410108 -66.983102)
		(width 0.1016)
		(layer "F.Cu")
		(net "M1_DQ_NODE1_DQ1")
	)
	(segment
		(start 51.811682 -66.629026)
		(end 51.457606 -66.983102)
		(width 0.1016)
		(layer "F.Cu")
		(net "M1_DQ_NODE1_DQ1")
	)
	(segment
		(start 42.150284 -22.96414)
		(end 42.150284 -20.94992)
		(width 0.1651)
		(layer "F.Cu")
		(net "M1_DQ_NODE1_DQ1")
	)
	(via
		(at 51.410108 -66.983102)
		(size 0.508)
		(drill 0.254)
		(layers "F.Cu" "B.Cu")
		(net "M1_DQ_NODE1_DQ1")
	)
	(via
		(at 42.515282 -23.659338)
		(size 0.508)
		(drill 0.254)
		(layers "F.Cu" "B.Cu")
		(net "M1_DQ_NODE1_DQ1")
	)
	(segment
		(start 47.52594 -57.9374)
		(end 48.641 -59.05246)
		(width 0.2032)
		(layer "In7.Cu")
		(net "M1_DQ_NODE1_DQ1")
	)
	(segment
		(start 50.83556 -63.49746)
		(end 50.83556 -64.022478)
		(width 0.1016)
		(layer "In7.Cu")
		(net "M1_DQ_NODE1_DQ1")
	)
	(segment
		(start 48.641 -59.05246)
		(end 48.641 -59.654948)
		(width 0.2032)
		(layer "In7.Cu")
		(net "M1_DQ_NODE1_DQ1")
	)
	(segment
		(start 45.79366 -24.66975)
		(end 45.79366 -25.496012)
		(width 0.2032)
		(layer "In7.Cu")
		(net "M1_DQ_NODE1_DQ1")
	)
	(segment
		(start 49.1617 -61.080396)
		(end 49.398174 -61.31687)
		(width 0.2032)
		(layer "In7.Cu")
		(net "M1_DQ_NODE1_DQ1")
	)
	(segment
		(start 49.1617 -60.175648)
		(end 49.1617 -61.080396)
		(width 0.2032)
		(layer "In7.Cu")
		(net "M1_DQ_NODE1_DQ1")
	)
	(segment
		(start 47.071534 -57.9374)
		(end 47.52594 -57.9374)
		(width 0.2032)
		(layer "In7.Cu")
		(net "M1_DQ_NODE1_DQ1")
	)
	(segment
		(start 37.84854 -46.849792)
		(end 38.05682 -47.058072)
		(width 0.2032)
		(layer "In7.Cu")
		(net "M1_DQ_NODE1_DQ1")
	)
	(segment
		(start 51.7906 -64.977518)
		(end 51.7906 -66.60261)
		(width 0.1016)
		(layer "In7.Cu")
		(net "M1_DQ_NODE1_DQ1")
	)
	(segment
		(start 45.79366 -25.496012)
		(end 46.76648 -26.468832)
		(width 0.2032)
		(layer "In7.Cu")
		(net "M1_DQ_NODE1_DQ1")
	)
	(segment
		(start 36.63442 -43.803824)
		(end 36.63442 -46.641512)
		(width 0.2032)
		(layer "In7.Cu")
		(net "M1_DQ_NODE1_DQ1")
	)
	(segment
		(start 51.7906 -66.60261)
		(end 51.410108 -66.983102)
		(width 0.1016)
		(layer "In7.Cu")
		(net "M1_DQ_NODE1_DQ1")
	)
	(segment
		(start 37.5539 -46.138592)
		(end 37.34562 -45.930312)
		(width 0.2032)
		(layer "In7.Cu")
		(net "M1_DQ_NODE1_DQ1")
	)
	(segment
		(start 37.34562 -45.930312)
		(end 37.34562 -43.803824)
		(width 0.2032)
		(layer "In7.Cu")
		(net "M1_DQ_NODE1_DQ1")
	)
	(segment
		(start 50.83556 -64.022478)
		(end 51.7906 -64.977518)
		(width 0.1016)
		(layer "In7.Cu")
		(net "M1_DQ_NODE1_DQ1")
	)
	(segment
		(start 38.05682 -42.352468)
		(end 38.05682 -45.930312)
		(width 0.2032)
		(layer "In7.Cu")
		(net "M1_DQ_NODE1_DQ1")
	)
	(segment
		(start 48.641 -59.654948)
		(end 49.1617 -60.175648)
		(width 0.2032)
		(layer "In7.Cu")
		(net "M1_DQ_NODE1_DQ1")
	)
	(segment
		(start 46.76648 -33.642808)
		(end 38.05682 -42.352468)
		(width 0.2032)
		(layer "In7.Cu")
		(net "M1_DQ_NODE1_DQ1")
	)
	(segment
		(start 43.22826 -23.660354)
		(end 43.535092 -23.967186)
		(width 0.2032)
		(layer "In7.Cu")
		(net "M1_DQ_NODE1_DQ1")
	)
	(segment
		(start 38.05682 -45.930312)
		(end 37.84854 -46.138592)
		(width 0.2032)
		(layer "In7.Cu")
		(net "M1_DQ_NODE1_DQ1")
	)
	(segment
		(start 36.8427 -46.849792)
		(end 37.84854 -46.849792)
		(width 0.2032)
		(layer "In7.Cu")
		(net "M1_DQ_NODE1_DQ1")
	)
	(segment
		(start 49.610264 -61.52896)
		(end 49.610264 -62.272164)
		(width 0.1016)
		(layer "In7.Cu")
		(net "M1_DQ_NODE1_DQ1")
	)
	(segment
		(start 36.63442 -46.641512)
		(end 36.8427 -46.849792)
		(width 0.2032)
		(layer "In7.Cu")
		(net "M1_DQ_NODE1_DQ1")
	)
	(segment
		(start 37.84854 -46.138592)
		(end 37.5539 -46.138592)
		(width 0.2032)
		(layer "In7.Cu")
		(net "M1_DQ_NODE1_DQ1")
	)
	(segment
		(start 43.22826 -23.659338)
		(end 43.22826 -23.660354)
		(width 0.2032)
		(layer "In7.Cu")
		(net "M1_DQ_NODE1_DQ1")
	)
	(segment
		(start 38.05682 -47.058072)
		(end 38.05682 -51.839622)
		(width 0.2032)
		(layer "In7.Cu")
		(net "M1_DQ_NODE1_DQ1")
	)
	(segment
		(start 39.641272 -53.424074)
		(end 42.558208 -53.424074)
		(width 0.2032)
		(layer "In7.Cu")
		(net "M1_DQ_NODE1_DQ1")
	)
	(segment
		(start 37.14242 -43.600624)
		(end 36.83762 -43.600624)
		(width 0.2032)
		(layer "In7.Cu")
		(net "M1_DQ_NODE1_DQ1")
	)
	(segment
		(start 45.091096 -23.967186)
		(end 45.79366 -24.66975)
		(width 0.2032)
		(layer "In7.Cu")
		(net "M1_DQ_NODE1_DQ1")
	)
	(segment
		(start 37.34562 -43.803824)
		(end 37.14242 -43.600624)
		(width 0.2032)
		(layer "In7.Cu")
		(net "M1_DQ_NODE1_DQ1")
	)
	(segment
		(start 43.535092 -23.967186)
		(end 45.091096 -23.967186)
		(width 0.2032)
		(layer "In7.Cu")
		(net "M1_DQ_NODE1_DQ1")
	)
	(segment
		(start 42.515282 -23.659338)
		(end 43.22826 -23.659338)
		(width 0.2032)
		(layer "In7.Cu")
		(net "M1_DQ_NODE1_DQ1")
	)
	(segment
		(start 36.83762 -43.600624)
		(end 36.63442 -43.803824)
		(width 0.2032)
		(layer "In7.Cu")
		(net "M1_DQ_NODE1_DQ1")
	)
	(segment
		(start 42.558208 -53.424074)
		(end 47.071534 -57.9374)
		(width 0.2032)
		(layer "In7.Cu")
		(net "M1_DQ_NODE1_DQ1")
	)
	(segment
		(start 49.610264 -62.272164)
		(end 50.83556 -63.49746)
		(width 0.1016)
		(layer "In7.Cu")
		(net "M1_DQ_NODE1_DQ1")
	)
	(segment
		(start 38.05682 -51.839622)
		(end 39.641272 -53.424074)
		(width 0.2032)
		(layer "In7.Cu")
		(net "M1_DQ_NODE1_DQ1")
	)
	(segment
		(start 49.398174 -61.31687)
		(end 49.610264 -61.52896)
		(width 0.1016)
		(layer "In7.Cu")
		(net "M1_DQ_NODE1_DQ1")
	)
	(segment
		(start 46.76648 -26.468832)
		(end 46.76648 -33.642808)
		(width 0.2032)
		(layer "In7.Cu")
		(net "M1_DQ_NODE1_DQ1")
	)
	(segment
		(start 59.741816 -128.859026)
		(end 59.741816 -128.859534)
		(width 0.3556)
		(layer "F.Cu")
		(net "BMC_NODE1_V1PLLAV12")
	)
	(segment
		(start 58.941716 -128.058926)
		(end 58.941716 -128.059434)
		(width 0.3556)
		(layer "F.Cu")
		(net "BMC_NODE1_V1PLLAV12")
	)
	(segment
		(start 58.540904 -127.658114)
		(end 58.941716 -128.058926)
		(width 0.3556)
		(layer "F.Cu")
		(net "BMC_NODE1_V1PLLAV12")
	)
	(segment
		(start 58.942224 -128.059434)
		(end 59.741816 -128.859026)
		(width 0.3556)
		(layer "F.Cu")
		(net "BMC_NODE1_V1PLLAV12")
	)
	(segment
		(start 58.941716 -128.059434)
		(end 58.942224 -128.059434)
		(width 0.3556)
		(layer "F.Cu")
		(net "BMC_NODE1_V1PLLAV12")
	)
	(via
		(at 58.540904 -127.658114)
		(size 0.49022)
		(drill 0.254)
		(layers "F.Cu" "B.Cu")
		(net "BMC_NODE1_V1PLLAV12")
	)
	(via
		(at 51.721512 -120.902222)
		(size 0.6604)
		(drill 0.3302)
		(layers "F.Cu" "B.Cu")
		(net "BMC_NODE1_V1PLLAV12")
	)
	(segment
		(start 54.028086 -122.752612)
		(end 55.044086 -122.752612)
		(width 0.508)
		(layer "B.Cu")
		(net "BMC_NODE1_V1PLLAV12")
	)
	(segment
		(start 55.044086 -122.752612)
		(end 55.787036 -122.752612)
		(width 0.508)
		(layer "B.Cu")
		(net "BMC_NODE1_V1PLLAV12")
	)
	(segment
		(start 58.236866 -122.650758)
		(end 58.70194 -123.115832)
		(width 0.381)
		(layer "B.Cu")
		(net "BMC_NODE1_V1PLLAV12")
	)
	(segment
		(start 51.691286 -122.289062)
		(end 51.691286 -120.932448)
		(width 0.1016)
		(layer "B.Cu")
		(net "BMC_NODE1_V1PLLAV12")
	)
	(segment
		(start 55.88889 -122.650758)
		(end 58.236866 -122.650758)
		(width 0.381)
		(layer "B.Cu")
		(net "BMC_NODE1_V1PLLAV12")
	)
	(segment
		(start 52.885086 -122.752612)
		(end 52.421536 -122.289062)
		(width 0.508)
		(layer "B.Cu")
		(net "BMC_NODE1_V1PLLAV12")
	)
	(segment
		(start 58.70194 -123.192286)
		(end 58.727086 -123.217432)
		(width 0.381)
		(layer "B.Cu")
		(net "BMC_NODE1_V1PLLAV12")
	)
	(segment
		(start 55.787036 -122.752612)
		(end 55.88889 -122.650758)
		(width 0.381)
		(layer "B.Cu")
		(net "BMC_NODE1_V1PLLAV12")
	)
	(segment
		(start 52.421536 -122.289062)
		(end 51.691286 -122.289062)
		(width 0.508)
		(layer "B.Cu")
		(net "BMC_NODE1_V1PLLAV12")
	)
	(segment
		(start 51.691286 -120.932448)
		(end 51.721512 -120.902222)
		(width 0.1016)
		(layer "B.Cu")
		(net "BMC_NODE1_V1PLLAV12")
	)
	(segment
		(start 58.727086 -127.471932)
		(end 58.540904 -127.658114)
		(width 0.381)
		(layer "B.Cu")
		(net "BMC_NODE1_V1PLLAV12")
	)
	(segment
		(start 54.028086 -122.752612)
		(end 52.885086 -122.752612)
		(width 0.508)
		(layer "B.Cu")
		(net "BMC_NODE1_V1PLLAV12")
	)
	(segment
		(start 58.70194 -123.115832)
		(end 58.70194 -123.192286)
		(width 0.381)
		(layer "B.Cu")
		(net "BMC_NODE1_V1PLLAV12")
	)
	(segment
		(start 58.727086 -123.217432)
		(end 58.727086 -127.471932)
		(width 0.381)
		(layer "B.Cu")
		(net "BMC_NODE1_V1PLLAV12")
	)
	(segment
		(start 49.971198 -63.854584)
		(end 49.971198 -63.378842)
		(width 0.1016)
		(layer "F.Cu")
		(net "M1_DQ_NODE1_DQ15")
	)
	(segment
		(start 49.617122 -61.144658)
		(end 50.46599 -60.29579)
		(width 0.1016)
		(layer "F.Cu")
		(net "M1_DQ_NODE1_DQ15")
	)
	(segment
		(start 49.617122 -62.305438)
		(end 49.617122 -61.144658)
		(width 0.1016)
		(layer "F.Cu")
		(net "M1_DQ_NODE1_DQ15")
	)
	(segment
		(start 50.23104 -63.119)
		(end 50.23104 -62.919356)
		(width 0.1016)
		(layer "F.Cu")
		(net "M1_DQ_NODE1_DQ15")
	)
	(segment
		(start 50.850292 -29.149802)
		(end 50.850292 -26.988008)
		(width 0.1651)
		(layer "F.Cu")
		(net "M1_DQ_NODE1_DQ15")
	)
	(segment
		(start 50.798222 -26.935938)
		(end 50.798222 -26.323798)
		(width 0.1651)
		(layer "F.Cu")
		(net "M1_DQ_NODE1_DQ15")
	)
	(segment
		(start 49.777904 -64.047878)
		(end 49.971198 -63.854584)
		(width 0.1016)
		(layer "F.Cu")
		(net "M1_DQ_NODE1_DQ15")
	)
	(segment
		(start 49.971198 -63.378842)
		(end 50.23104 -63.119)
		(width 0.1016)
		(layer "F.Cu")
		(net "M1_DQ_NODE1_DQ15")
	)
	(segment
		(start 50.850292 -26.988008)
		(end 50.798222 -26.935938)
		(width 0.1651)
		(layer "F.Cu")
		(net "M1_DQ_NODE1_DQ15")
	)
	(segment
		(start 50.23104 -62.919356)
		(end 49.617122 -62.305438)
		(width 0.1016)
		(layer "F.Cu")
		(net "M1_DQ_NODE1_DQ15")
	)
	(via
		(at 50.798222 -26.323798)
		(size 0.508)
		(drill 0.254)
		(layers "F.Cu" "B.Cu")
		(net "M1_DQ_NODE1_DQ15")
	)
	(via
		(at 50.46599 -60.29579)
		(size 0.508)
		(drill 0.254)
		(layers "F.Cu" "B.Cu")
		(net "M1_DQ_NODE1_DQ15")
	)
	(segment
		(start 41.160192 -39.914068)
		(end 41.505378 -40.259254)
		(width 0.2032)
		(layer "In2.Cu")
		(net "M1_DQ_NODE1_DQ15")
	)
	(segment
		(start 46.778164 -56.519318)
		(end 45.094398 -54.835552)
		(width 0.2032)
		(layer "In2.Cu")
		(net "M1_DQ_NODE1_DQ15")
	)
	(segment
		(start 44.273216 -55.362856)
		(end 43.979084 -55.362856)
		(width 0.2032)
		(layer "In2.Cu")
		(net "M1_DQ_NODE1_DQ15")
	)
	(segment
		(start 43.770296 -55.154068)
		(end 43.770296 -54.859936)
		(width 0.2032)
		(layer "In2.Cu")
		(net "M1_DQ_NODE1_DQ15")
	)
	(segment
		(start 43.014138 -38.750494)
		(end 42.668952 -38.405308)
		(width 0.2032)
		(layer "In2.Cu")
		(net "M1_DQ_NODE1_DQ15")
	)
	(segment
		(start 38.90518 -52.401216)
		(end 38.90518 -41.87444)
		(width 0.2032)
		(layer "In2.Cu")
		(net "M1_DQ_NODE1_DQ15")
	)
	(segment
		(start 42.511218 -39.253414)
		(end 42.805858 -39.253414)
		(width 0.2032)
		(layer "In2.Cu")
		(net "M1_DQ_NODE1_DQ15")
	)
	(segment
		(start 44.218352 -37.763196)
		(end 44.218352 -38.032944)
		(width 0.2032)
		(layer "In2.Cu")
		(net "M1_DQ_NODE1_DQ15")
	)
	(segment
		(start 48.23968 -57.504838)
		(end 47.4472 -56.712358)
		(width 0.1016)
		(layer "In2.Cu")
		(net "M1_DQ_NODE1_DQ15")
	)
	(segment
		(start 38.90518 -41.87444)
		(end 40.865552 -39.914068)
		(width 0.2032)
		(layer "In2.Cu")
		(net "M1_DQ_NODE1_DQ15")
	)
	(segment
		(start 40.152828 -51.637184)
		(end 39.937436 -51.637184)
		(width 0.2032)
		(layer "In2.Cu")
		(net "M1_DQ_NODE1_DQ15")
	)
	(segment
		(start 45.094398 -54.835552)
		(end 44.800266 -54.835552)
		(width 0.2032)
		(layer "In2.Cu")
		(net "M1_DQ_NODE1_DQ15")
	)
	(segment
		(start 49.276 -59.1058)
		(end 49.276 -58.749184)
		(width 0.1016)
		(layer "In2.Cu")
		(net "M1_DQ_NODE1_DQ15")
	)
	(segment
		(start 49.276 -58.749184)
		(end 48.23968 -57.712864)
		(width 0.1016)
		(layer "In2.Cu")
		(net "M1_DQ_NODE1_DQ15")
	)
	(segment
		(start 42.94378 -54.136544)
		(end 42.652188 -54.136544)
		(width 0.2032)
		(layer "In2.Cu")
		(net "M1_DQ_NODE1_DQ15")
	)
	(segment
		(start 39.649908 -51.924712)
		(end 39.649908 -52.140104)
		(width 0.2032)
		(layer "In2.Cu")
		(net "M1_DQ_NODE1_DQ15")
	)
	(segment
		(start 43.437556 -53.642768)
		(end 42.94378 -54.136544)
		(width 0.2032)
		(layer "In2.Cu")
		(net "M1_DQ_NODE1_DQ15")
	)
	(segment
		(start 40.865552 -39.914068)
		(end 41.160192 -39.914068)
		(width 0.2032)
		(layer "In2.Cu")
		(net "M1_DQ_NODE1_DQ15")
	)
	(segment
		(start 41.505378 -40.259254)
		(end 41.800018 -40.259254)
		(width 0.2032)
		(layer "In2.Cu")
		(net "M1_DQ_NODE1_DQ15")
	)
	(segment
		(start 46.578774 -37.554916)
		(end 51.54676 -32.58693)
		(width 0.2032)
		(layer "In2.Cu")
		(net "M1_DQ_NODE1_DQ15")
	)
	(segment
		(start 42.668952 -38.405308)
		(end 42.668952 -38.110668)
		(width 0.2032)
		(layer "In2.Cu")
		(net "M1_DQ_NODE1_DQ15")
	)
	(segment
		(start 40.865298 -54.361334)
		(end 38.90518 -52.401216)
		(width 0.2032)
		(layer "In2.Cu")
		(net "M1_DQ_NODE1_DQ15")
	)
	(segment
		(start 43.901614 -53.642768)
		(end 43.437556 -53.642768)
		(width 0.2032)
		(layer "In2.Cu")
		(net "M1_DQ_NODE1_DQ15")
	)
	(segment
		(start 51.54676 -32.58693)
		(end 51.54676 -28.59659)
		(width 0.2032)
		(layer "In2.Cu")
		(net "M1_DQ_NODE1_DQ15")
	)
	(segment
		(start 51.54676 -28.59659)
		(end 50.90922 -27.95905)
		(width 0.2032)
		(layer "In2.Cu")
		(net "M1_DQ_NODE1_DQ15")
	)
	(segment
		(start 45.137832 -37.554916)
		(end 46.578774 -37.554916)
		(width 0.2032)
		(layer "In2.Cu")
		(net "M1_DQ_NODE1_DQ15")
	)
	(segment
		(start 44.426632 -38.241224)
		(end 44.721272 -38.241224)
		(width 0.2032)
		(layer "In2.Cu")
		(net "M1_DQ_NODE1_DQ15")
	)
	(segment
		(start 43.979084 -55.362856)
		(end 43.770296 -55.154068)
		(width 0.2032)
		(layer "In2.Cu")
		(net "M1_DQ_NODE1_DQ15")
	)
	(segment
		(start 41.368218 -54.153054)
		(end 41.159938 -54.361334)
		(width 0.2032)
		(layer "In2.Cu")
		(net "M1_DQ_NODE1_DQ15")
	)
	(segment
		(start 44.297346 -54.0385)
		(end 43.901614 -53.642768)
		(width 0.2032)
		(layer "In2.Cu")
		(net "M1_DQ_NODE1_DQ15")
	)
	(segment
		(start 43.224704 -37.554916)
		(end 44.010072 -37.554916)
		(width 0.2032)
		(layer "In2.Cu")
		(net "M1_DQ_NODE1_DQ15")
	)
	(segment
		(start 41.368218 -53.858414)
		(end 41.368218 -54.153054)
		(width 0.2032)
		(layer "In2.Cu")
		(net "M1_DQ_NODE1_DQ15")
	)
	(segment
		(start 42.805858 -39.253414)
		(end 43.014138 -39.045134)
		(width 0.2032)
		(layer "In2.Cu")
		(net "M1_DQ_NODE1_DQ15")
	)
	(segment
		(start 42.668952 -38.110668)
		(end 43.224704 -37.554916)
		(width 0.2032)
		(layer "In2.Cu")
		(net "M1_DQ_NODE1_DQ15")
	)
	(segment
		(start 42.008298 -40.050974)
		(end 42.008298 -39.756334)
		(width 0.2032)
		(layer "In2.Cu")
		(net "M1_DQ_NODE1_DQ15")
	)
	(segment
		(start 42.166032 -38.908228)
		(end 42.511218 -39.253414)
		(width 0.2032)
		(layer "In2.Cu")
		(net "M1_DQ_NODE1_DQ15")
	)
	(segment
		(start 41.871392 -38.908228)
		(end 42.166032 -38.908228)
		(width 0.2032)
		(layer "In2.Cu")
		(net "M1_DQ_NODE1_DQ15")
	)
	(segment
		(start 44.929552 -37.763196)
		(end 45.137832 -37.554916)
		(width 0.2032)
		(layer "In2.Cu")
		(net "M1_DQ_NODE1_DQ15")
	)
	(segment
		(start 46.971204 -56.712358)
		(end 46.778164 -56.519318)
		(width 0.1016)
		(layer "In2.Cu")
		(net "M1_DQ_NODE1_DQ15")
	)
	(segment
		(start 44.800266 -54.835552)
		(end 44.273216 -55.362856)
		(width 0.2032)
		(layer "In2.Cu")
		(net "M1_DQ_NODE1_DQ15")
	)
	(segment
		(start 50.90922 -27.95905)
		(end 50.90922 -26.433018)
		(width 0.2032)
		(layer "In2.Cu")
		(net "M1_DQ_NODE1_DQ15")
	)
	(segment
		(start 50.46599 -60.29579)
		(end 49.276 -59.1058)
		(width 0.1016)
		(layer "In2.Cu")
		(net "M1_DQ_NODE1_DQ15")
	)
	(segment
		(start 41.159938 -54.361334)
		(end 40.865298 -54.361334)
		(width 0.2032)
		(layer "In2.Cu")
		(net "M1_DQ_NODE1_DQ15")
	)
	(segment
		(start 44.297346 -54.332632)
		(end 44.297346 -54.0385)
		(width 0.2032)
		(layer "In2.Cu")
		(net "M1_DQ_NODE1_DQ15")
	)
	(segment
		(start 44.929552 -38.032944)
		(end 44.929552 -37.763196)
		(width 0.2032)
		(layer "In2.Cu")
		(net "M1_DQ_NODE1_DQ15")
	)
	(segment
		(start 42.652188 -54.136544)
		(end 40.152828 -51.637184)
		(width 0.2032)
		(layer "In2.Cu")
		(net "M1_DQ_NODE1_DQ15")
	)
	(segment
		(start 44.218352 -38.032944)
		(end 44.426632 -38.241224)
		(width 0.2032)
		(layer "In2.Cu")
		(net "M1_DQ_NODE1_DQ15")
	)
	(segment
		(start 42.008298 -39.756334)
		(end 41.663112 -39.411148)
		(width 0.2032)
		(layer "In2.Cu")
		(net "M1_DQ_NODE1_DQ15")
	)
	(segment
		(start 43.014138 -39.045134)
		(end 43.014138 -38.750494)
		(width 0.2032)
		(layer "In2.Cu")
		(net "M1_DQ_NODE1_DQ15")
	)
	(segment
		(start 41.663112 -39.116508)
		(end 41.871392 -38.908228)
		(width 0.2032)
		(layer "In2.Cu")
		(net "M1_DQ_NODE1_DQ15")
	)
	(segment
		(start 44.010072 -37.554916)
		(end 44.218352 -37.763196)
		(width 0.2032)
		(layer "In2.Cu")
		(net "M1_DQ_NODE1_DQ15")
	)
	(segment
		(start 39.649908 -52.140104)
		(end 41.368218 -53.858414)
		(width 0.2032)
		(layer "In2.Cu")
		(net "M1_DQ_NODE1_DQ15")
	)
	(segment
		(start 50.90922 -26.433018)
		(end 50.8 -26.323798)
		(width 0.2032)
		(layer "In2.Cu")
		(net "M1_DQ_NODE1_DQ15")
	)
	(segment
		(start 47.4472 -56.712358)
		(end 46.971204 -56.712358)
		(width 0.1016)
		(layer "In2.Cu")
		(net "M1_DQ_NODE1_DQ15")
	)
	(segment
		(start 43.770296 -54.859936)
		(end 44.297346 -54.332632)
		(width 0.2032)
		(layer "In2.Cu")
		(net "M1_DQ_NODE1_DQ15")
	)
	(segment
		(start 50.8 -26.323798)
		(end 50.798222 -26.323798)
		(width 0.2032)
		(layer "In2.Cu")
		(net "M1_DQ_NODE1_DQ15")
	)
	(segment
		(start 39.937436 -51.637184)
		(end 39.649908 -51.924712)
		(width 0.2032)
		(layer "In2.Cu")
		(net "M1_DQ_NODE1_DQ15")
	)
	(segment
		(start 48.23968 -57.712864)
		(end 48.23968 -57.504838)
		(width 0.1016)
		(layer "In2.Cu")
		(net "M1_DQ_NODE1_DQ15")
	)
	(segment
		(start 41.663112 -39.411148)
		(end 41.663112 -39.116508)
		(width 0.2032)
		(layer "In2.Cu")
		(net "M1_DQ_NODE1_DQ15")
	)
	(segment
		(start 44.721272 -38.241224)
		(end 44.929552 -38.032944)
		(width 0.2032)
		(layer "In2.Cu")
		(net "M1_DQ_NODE1_DQ15")
	)
	(segment
		(start 41.800018 -40.259254)
		(end 42.008298 -40.050974)
		(width 0.2032)
		(layer "In2.Cu")
		(net "M1_DQ_NODE1_DQ15")
	)
	(segment
		(start 61.743082 -65.455038)
		(end 61.743082 -65.486788)
		(width 0.2032)
		(layer "F.Cu")
		(net "N29180194")
	)
	(segment
		(start 61.743082 -65.486788)
		(end 61.393832 -65.836038)
		(width 0.2032)
		(layer "F.Cu")
		(net "N29180194")
	)
	(segment
		(start 61.393832 -65.836038)
		(end 61.369702 -65.836038)
		(width 0.2032)
		(layer "F.Cu")
		(net "N29180194")
	)
	(via
		(at 61.369702 -65.836038)
		(size 0.508)
		(drill 0.254)
		(layers "F.Cu" "B.Cu")
		(net "N29180194")
	)
	(via
		(at 62.109604 -65.71107)
		(size 0.6604)
		(drill 0.3302)
		(layers "F.Cu" "B.Cu")
		(net "N29180194")
	)
	(segment
		(start 63.537592 -64.799718)
		(end 63.098172 -64.360298)
		(width 0.2032)
		(layer "B.Cu")
		(net "N29180194")
	)
	(segment
		(start 61.984636 -65.836038)
		(end 62.109604 -65.71107)
		(width 0.2032)
		(layer "B.Cu")
		(net "N29180194")
	)
	(segment
		(start 62.458346 -64.360298)
		(end 62.120272 -64.698372)
		(width 0.2032)
		(layer "B.Cu")
		(net "N29180194")
	)
	(segment
		(start 61.369702 -65.836038)
		(end 61.984636 -65.836038)
		(width 0.2032)
		(layer "B.Cu")
		(net "N29180194")
	)
	(segment
		(start 63.721488 -62.728856)
		(end 63.712598 -62.719966)
		(width 0.2032)
		(layer "B.Cu")
		(net "N29180194")
	)
	(segment
		(start 63.721488 -64.799718)
		(end 63.537592 -64.799718)
		(width 0.2032)
		(layer "B.Cu")
		(net "N29180194")
	)
	(segment
		(start 63.098172 -64.360298)
		(end 62.458346 -64.360298)
		(width 0.2032)
		(layer "B.Cu")
		(net "N29180194")
	)
	(segment
		(start 63.721488 -64.799718)
		(end 63.721488 -63.783718)
		(width 0.2032)
		(layer "B.Cu")
		(net "N29180194")
	)
	(segment
		(start 62.120272 -65.700402)
		(end 62.109604 -65.71107)
		(width 0.2032)
		(layer "B.Cu")
		(net "N29180194")
	)
	(segment
		(start 63.721488 -63.783718)
		(end 63.721488 -62.728856)
		(width 0.2032)
		(layer "B.Cu")
		(net "N29180194")
	)
	(segment
		(start 62.120272 -64.698372)
		(end 62.120272 -65.700402)
		(width 0.2032)
		(layer "B.Cu")
		(net "N29180194")
	)
	(segment
		(start 66.903092 -87.687658)
		(end 66.649092 -87.941658)
		(width 0.1016)
		(layer "F.Cu")
		(net "H_CPU_NODE1_ERR1_R")
	)
	(segment
		(start 66.677032 -88.383872)
		(end 66.677032 -88.82634)
		(width 0.1016)
		(layer "F.Cu")
		(net "H_CPU_NODE1_ERR1_R")
	)
	(segment
		(start 68.10883 -92.026994)
		(end 68.10883 -92.514166)
		(width 0.1016)
		(layer "F.Cu")
		(net "H_CPU_NODE1_ERR1_R")
	)
	(segment
		(start 66.888106 -89.598754)
		(end 66.888106 -90.80627)
		(width 0.1016)
		(layer "F.Cu")
		(net "H_CPU_NODE1_ERR1_R")
	)
	(segment
		(start 66.623692 -88.87968)
		(end 66.623692 -89.33434)
		(width 0.1016)
		(layer "F.Cu")
		(net "H_CPU_NODE1_ERR1_R")
	)
	(segment
		(start 73.337166 -96.309942)
		(end 73.238868 -96.309942)
		(width 0.1016)
		(layer "F.Cu")
		(net "H_CPU_NODE1_ERR1_R")
	)
	(segment
		(start 72.2757 -95.346774)
		(end 72.2757 -95.27286)
		(width 0.1016)
		(layer "F.Cu")
		(net "H_CPU_NODE1_ERR1_R")
	)
	(segment
		(start 68.10883 -92.514166)
		(end 68.457318 -92.862654)
		(width 0.1016)
		(layer "F.Cu")
		(net "H_CPU_NODE1_ERR1_R")
	)
	(segment
		(start 66.649092 -87.941658)
		(end 66.649092 -88.355932)
		(width 0.1016)
		(layer "F.Cu")
		(net "H_CPU_NODE1_ERR1_R")
	)
	(segment
		(start 68.457318 -92.862654)
		(end 70.599554 -92.862654)
		(width 0.1016)
		(layer "F.Cu")
		(net "H_CPU_NODE1_ERR1_R")
	)
	(segment
		(start 70.599554 -92.862654)
		(end 71.085202 -93.348302)
		(width 0.1016)
		(layer "F.Cu")
		(net "H_CPU_NODE1_ERR1_R")
	)
	(segment
		(start 66.903092 -87.341964)
		(end 66.903092 -87.687658)
		(width 0.1016)
		(layer "F.Cu")
		(net "H_CPU_NODE1_ERR1_R")
	)
	(segment
		(start 66.623692 -89.33434)
		(end 66.888106 -89.598754)
		(width 0.1016)
		(layer "F.Cu")
		(net "H_CPU_NODE1_ERR1_R")
	)
	(segment
		(start 72.24776 -95.24492)
		(end 72.24776 -94.51086)
		(width 0.1016)
		(layer "F.Cu")
		(net "H_CPU_NODE1_ERR1_R")
	)
	(segment
		(start 72.2757 -95.27286)
		(end 72.24776 -95.24492)
		(width 0.1016)
		(layer "F.Cu")
		(net "H_CPU_NODE1_ERR1_R")
	)
	(segment
		(start 66.649092 -88.355932)
		(end 66.677032 -88.383872)
		(width 0.1016)
		(layer "F.Cu")
		(net "H_CPU_NODE1_ERR1_R")
	)
	(segment
		(start 66.888106 -90.80627)
		(end 68.10883 -92.026994)
		(width 0.1016)
		(layer "F.Cu")
		(net "H_CPU_NODE1_ERR1_R")
	)
	(segment
		(start 73.238868 -96.309942)
		(end 72.2757 -95.346774)
		(width 0.1016)
		(layer "F.Cu")
		(net "H_CPU_NODE1_ERR1_R")
	)
	(segment
		(start 66.677032 -88.82634)
		(end 66.623692 -88.87968)
		(width 0.1016)
		(layer "F.Cu")
		(net "H_CPU_NODE1_ERR1_R")
	)
	(segment
		(start 72.24776 -94.51086)
		(end 71.085202 -93.348302)
		(width 0.1016)
		(layer "F.Cu")
		(net "H_CPU_NODE1_ERR1_R")
	)
	(via
		(at 71.130668 -91.081606)
		(size 0.6604)
		(drill 0.3302)
		(layers "F.Cu" "B.Cu")
		(net "H_CPU_NODE1_ERR1_R")
	)
	(via
		(at 71.085202 -93.348302)
		(size 0.508)
		(drill 0.254)
		(layers "F.Cu" "B.Cu")
		(net "H_CPU_NODE1_ERR1_R")
	)
	(segment
		(start 70.946772 -90.37828)
		(end 71.130668 -90.562176)
		(width 0.1016)
		(layer "B.Cu")
		(net "H_CPU_NODE1_ERR1_R")
	)
	(segment
		(start 71.085202 -93.348302)
		(end 71.130668 -93.302836)
		(width 0.1016)
		(layer "B.Cu")
		(net "H_CPU_NODE1_ERR1_R")
	)
	(segment
		(start 71.130668 -93.302836)
		(end 71.130668 -91.081606)
		(width 0.1016)
		(layer "B.Cu")
		(net "H_CPU_NODE1_ERR1_R")
	)
	(segment
		(start 70.566534 -88.83142)
		(end 70.566534 -88.936068)
		(width 0.1016)
		(layer "B.Cu")
		(net "H_CPU_NODE1_ERR1_R")
	)
	(segment
		(start 70.566534 -88.936068)
		(end 70.946772 -89.316306)
		(width 0.1016)
		(layer "B.Cu")
		(net "H_CPU_NODE1_ERR1_R")
	)
	(segment
		(start 70.946772 -89.316306)
		(end 70.946772 -90.37828)
		(width 0.1016)
		(layer "B.Cu")
		(net "H_CPU_NODE1_ERR1_R")
	)
	(segment
		(start 71.130668 -90.562176)
		(end 71.130668 -91.081606)
		(width 0.1016)
		(layer "B.Cu")
		(net "H_CPU_NODE1_ERR1_R")
	)
	(segment
		(start 47.192692 -65.345564)
		(end 47.192692 -65.21704)
		(width 0.1016)
		(layer "F.Cu")
		(net "M1_DQ_NODE1_DQ0")
	)
	(segment
		(start 47.839122 -65.836038)
		(end 47.683166 -65.836038)
		(width 0.1016)
		(layer "F.Cu")
		(net "M1_DQ_NODE1_DQ0")
	)
	(segment
		(start 41.550082 -25.682702)
		(end 41.550082 -20.94992)
		(width 0.1651)
		(layer "F.Cu")
		(net "M1_DQ_NODE1_DQ0")
	)
	(segment
		(start 41.72712 -25.85974)
		(end 41.550082 -25.682702)
		(width 0.1651)
		(layer "F.Cu")
		(net "M1_DQ_NODE1_DQ0")
	)
	(segment
		(start 47.683166 -65.836038)
		(end 47.192692 -65.345564)
		(width 0.1016)
		(layer "F.Cu")
		(net "M1_DQ_NODE1_DQ0")
	)
	(via
		(at 41.72712 -25.85974)
		(size 0.508)
		(drill 0.254)
		(layers "F.Cu" "B.Cu")
		(net "M1_DQ_NODE1_DQ0")
	)
	(via
		(at 47.192692 -65.21704)
		(size 0.508)
		(drill 0.254)
		(layers "F.Cu" "B.Cu")
		(net "M1_DQ_NODE1_DQ0")
	)
	(segment
		(start 39.363904 -28.110942)
		(end 39.363904 -28.361386)
		(width 0.2032)
		(layer "In7.Cu")
		(net "M1_DQ_NODE1_DQ0")
	)
	(segment
		(start 39.77132 -60.587636)
		(end 39.47668 -60.882276)
		(width 0.2032)
		(layer "In7.Cu")
		(net "M1_DQ_NODE1_DQ0")
	)
	(segment
		(start 46.578012 -65.21704)
		(end 47.192692 -65.21704)
		(width 0.1016)
		(layer "In7.Cu")
		(net "M1_DQ_NODE1_DQ0")
	)
	(segment
		(start 35.680904 -28.110942)
		(end 35.465258 -27.895296)
		(width 0.2032)
		(layer "In7.Cu")
		(net "M1_DQ_NODE1_DQ0")
	)
	(segment
		(start 39.363904 -28.361386)
		(end 39.148258 -28.577032)
		(width 0.2032)
		(layer "In7.Cu")
		(net "M1_DQ_NODE1_DQ0")
	)
	(segment
		(start 39.57955 -27.895296)
		(end 39.363904 -28.110942)
		(width 0.2032)
		(layer "In7.Cu")
		(net "M1_DQ_NODE1_DQ0")
	)
	(segment
		(start 37.36975 -28.577032)
		(end 37.154104 -28.361386)
		(width 0.2032)
		(layer "In7.Cu")
		(net "M1_DQ_NODE1_DQ0")
	)
	(segment
		(start 41.555416 -61.408056)
		(end 44.430442 -64.283082)
		(width 0.1016)
		(layer "In7.Cu")
		(net "M1_DQ_NODE1_DQ0")
	)
	(segment
		(start 38.10635 -27.895296)
		(end 37.890704 -28.110942)
		(width 0.2032)
		(layer "In7.Cu")
		(net "M1_DQ_NODE1_DQ0")
	)
	(segment
		(start 40.100504 -28.110942)
		(end 39.884858 -27.895296)
		(width 0.2032)
		(layer "In7.Cu")
		(net "M1_DQ_NODE1_DQ0")
	)
	(segment
		(start 36.182554 -60.074048)
		(end 39.562532 -60.074048)
		(width 0.2032)
		(layer "In7.Cu")
		(net "M1_DQ_NODE1_DQ0")
	)
	(segment
		(start 36.417504 -28.110942)
		(end 36.417504 -28.361386)
		(width 0.2032)
		(layer "In7.Cu")
		(net "M1_DQ_NODE1_DQ0")
	)
	(segment
		(start 39.562532 -60.074048)
		(end 39.77132 -60.282836)
		(width 0.2032)
		(layer "In7.Cu")
		(net "M1_DQ_NODE1_DQ0")
	)
	(segment
		(start 30.94228 -31.666434)
		(end 30.94228 -54.833774)
		(width 0.2032)
		(layer "In7.Cu")
		(net "M1_DQ_NODE1_DQ0")
	)
	(segment
		(start 38.627304 -28.110942)
		(end 38.411658 -27.895296)
		(width 0.2032)
		(layer "In7.Cu")
		(net "M1_DQ_NODE1_DQ0")
	)
	(segment
		(start 34.031682 -28.577032)
		(end 30.94228 -31.666434)
		(width 0.2032)
		(layer "In7.Cu")
		(net "M1_DQ_NODE1_DQ0")
	)
	(segment
		(start 34.944304 -28.361386)
		(end 34.728658 -28.577032)
		(width 0.2032)
		(layer "In7.Cu")
		(net "M1_DQ_NODE1_DQ0")
	)
	(segment
		(start 41.33088 -27.956764)
		(end 40.710612 -28.577032)
		(width 0.2032)
		(layer "In7.Cu")
		(net "M1_DQ_NODE1_DQ0")
	)
	(segment
		(start 38.84295 -28.577032)
		(end 38.627304 -28.361386)
		(width 0.2032)
		(layer "In7.Cu")
		(net "M1_DQ_NODE1_DQ0")
	)
	(segment
		(start 39.148258 -28.577032)
		(end 38.84295 -28.577032)
		(width 0.2032)
		(layer "In7.Cu")
		(net "M1_DQ_NODE1_DQ0")
	)
	(segment
		(start 39.47668 -60.882276)
		(end 39.47668 -61.187076)
		(width 0.2032)
		(layer "In7.Cu")
		(net "M1_DQ_NODE1_DQ0")
	)
	(segment
		(start 36.938458 -27.895296)
		(end 36.63315 -27.895296)
		(width 0.2032)
		(layer "In7.Cu")
		(net "M1_DQ_NODE1_DQ0")
	)
	(segment
		(start 37.154104 -28.361386)
		(end 37.154104 -28.110942)
		(width 0.2032)
		(layer "In7.Cu")
		(net "M1_DQ_NODE1_DQ0")
	)
	(segment
		(start 41.33088 -26.25598)
		(end 41.33088 -27.956764)
		(width 0.2032)
		(layer "In7.Cu")
		(net "M1_DQ_NODE1_DQ0")
	)
	(segment
		(start 36.63315 -27.895296)
		(end 36.417504 -28.110942)
		(width 0.2032)
		(layer "In7.Cu")
		(net "M1_DQ_NODE1_DQ0")
	)
	(segment
		(start 37.675058 -28.577032)
		(end 37.36975 -28.577032)
		(width 0.2032)
		(layer "In7.Cu")
		(net "M1_DQ_NODE1_DQ0")
	)
	(segment
		(start 39.77132 -60.282836)
		(end 39.77132 -60.587636)
		(width 0.2032)
		(layer "In7.Cu")
		(net "M1_DQ_NODE1_DQ0")
	)
	(segment
		(start 37.890704 -28.361386)
		(end 37.675058 -28.577032)
		(width 0.2032)
		(layer "In7.Cu")
		(net "M1_DQ_NODE1_DQ0")
	)
	(segment
		(start 35.15995 -27.895296)
		(end 34.944304 -28.110942)
		(width 0.2032)
		(layer "In7.Cu")
		(net "M1_DQ_NODE1_DQ0")
	)
	(segment
		(start 39.47668 -61.187076)
		(end 39.692834 -61.40323)
		(width 0.2032)
		(layer "In7.Cu")
		(net "M1_DQ_NODE1_DQ0")
	)
	(segment
		(start 39.884858 -27.895296)
		(end 39.57955 -27.895296)
		(width 0.2032)
		(layer "In7.Cu")
		(net "M1_DQ_NODE1_DQ0")
	)
	(segment
		(start 45.644054 -64.283082)
		(end 46.578012 -65.21704)
		(width 0.1016)
		(layer "In7.Cu")
		(net "M1_DQ_NODE1_DQ0")
	)
	(segment
		(start 38.627304 -28.361386)
		(end 38.627304 -28.110942)
		(width 0.2032)
		(layer "In7.Cu")
		(net "M1_DQ_NODE1_DQ0")
	)
	(segment
		(start 39.997634 -61.40323)
		(end 40.292274 -61.10859)
		(width 0.2032)
		(layer "In7.Cu")
		(net "M1_DQ_NODE1_DQ0")
	)
	(segment
		(start 35.89655 -28.577032)
		(end 35.680904 -28.361386)
		(width 0.2032)
		(layer "In7.Cu")
		(net "M1_DQ_NODE1_DQ0")
	)
	(segment
		(start 44.430442 -64.283082)
		(end 45.644054 -64.283082)
		(width 0.1016)
		(layer "In7.Cu")
		(net "M1_DQ_NODE1_DQ0")
	)
	(segment
		(start 40.710612 -28.577032)
		(end 40.31615 -28.577032)
		(width 0.2032)
		(layer "In7.Cu")
		(net "M1_DQ_NODE1_DQ0")
	)
	(segment
		(start 40.89654 -61.408056)
		(end 41.555416 -61.408056)
		(width 0.2032)
		(layer "In7.Cu")
		(net "M1_DQ_NODE1_DQ0")
	)
	(segment
		(start 40.100504 -28.361386)
		(end 40.100504 -28.110942)
		(width 0.2032)
		(layer "In7.Cu")
		(net "M1_DQ_NODE1_DQ0")
	)
	(segment
		(start 40.31615 -28.577032)
		(end 40.100504 -28.361386)
		(width 0.2032)
		(layer "In7.Cu")
		(net "M1_DQ_NODE1_DQ0")
	)
	(segment
		(start 34.944304 -28.110942)
		(end 34.944304 -28.361386)
		(width 0.2032)
		(layer "In7.Cu")
		(net "M1_DQ_NODE1_DQ0")
	)
	(segment
		(start 40.292274 -61.10859)
		(end 40.597074 -61.10859)
		(width 0.2032)
		(layer "In7.Cu")
		(net "M1_DQ_NODE1_DQ0")
	)
	(segment
		(start 36.417504 -28.361386)
		(end 36.201858 -28.577032)
		(width 0.2032)
		(layer "In7.Cu")
		(net "M1_DQ_NODE1_DQ0")
	)
	(segment
		(start 41.72712 -25.85974)
		(end 41.33088 -26.25598)
		(width 0.2032)
		(layer "In7.Cu")
		(net "M1_DQ_NODE1_DQ0")
	)
	(segment
		(start 40.597074 -61.10859)
		(end 40.89654 -61.408056)
		(width 0.2032)
		(layer "In7.Cu")
		(net "M1_DQ_NODE1_DQ0")
	)
	(segment
		(start 30.94228 -54.833774)
		(end 36.182554 -60.074048)
		(width 0.2032)
		(layer "In7.Cu")
		(net "M1_DQ_NODE1_DQ0")
	)
	(segment
		(start 37.890704 -28.110942)
		(end 37.890704 -28.361386)
		(width 0.2032)
		(layer "In7.Cu")
		(net "M1_DQ_NODE1_DQ0")
	)
	(segment
		(start 37.154104 -28.110942)
		(end 36.938458 -27.895296)
		(width 0.2032)
		(layer "In7.Cu")
		(net "M1_DQ_NODE1_DQ0")
	)
	(segment
		(start 38.411658 -27.895296)
		(end 38.10635 -27.895296)
		(width 0.2032)
		(layer "In7.Cu")
		(net "M1_DQ_NODE1_DQ0")
	)
	(segment
		(start 34.728658 -28.577032)
		(end 34.031682 -28.577032)
		(width 0.2032)
		(layer "In7.Cu")
		(net "M1_DQ_NODE1_DQ0")
	)
	(segment
		(start 35.680904 -28.361386)
		(end 35.680904 -28.110942)
		(width 0.2032)
		(layer "In7.Cu")
		(net "M1_DQ_NODE1_DQ0")
	)
	(segment
		(start 36.201858 -28.577032)
		(end 35.89655 -28.577032)
		(width 0.2032)
		(layer "In7.Cu")
		(net "M1_DQ_NODE1_DQ0")
	)
	(segment
		(start 35.465258 -27.895296)
		(end 35.15995 -27.895296)
		(width 0.2032)
		(layer "In7.Cu")
		(net "M1_DQ_NODE1_DQ0")
	)
	(segment
		(start 39.692834 -61.40323)
		(end 39.997634 -61.40323)
		(width 0.2032)
		(layer "In7.Cu")
		(net "M1_DQ_NODE1_DQ0")
	)
	(segment
		(start 95.361506 -176.083976)
		(end 95.676974 -176.083976)
		(width 0.1016)
		(layer "F.Cu")
		(net "N21698906")
	)
	(segment
		(start 95.930974 -176.337976)
		(end 96.416622 -176.823624)
		(width 0.1016)
		(layer "F.Cu")
		(net "N21698906")
	)
	(segment
		(start 94.851982 -174.306992)
		(end 94.851982 -175.322992)
		(width 0.1016)
		(layer "F.Cu")
		(net "N21698906")
	)
	(segment
		(start 96.416622 -176.823624)
		(end 97.819972 -176.823624)
		(width 0.1016)
		(layer "F.Cu")
		(net "N21698906")
	)
	(segment
		(start 94.851982 -175.574452)
		(end 95.361506 -176.083976)
		(width 0.1016)
		(layer "F.Cu")
		(net "N21698906")
	)
	(segment
		(start 94.851982 -175.322992)
		(end 94.851982 -175.574452)
		(width 0.1016)
		(layer "F.Cu")
		(net "N21698906")
	)
	(segment
		(start 95.676974 -176.083976)
		(end 95.930974 -176.337976)
		(width 0.1016)
		(layer "F.Cu")
		(net "N21698906")
	)
	(via
		(at 95.930974 -176.337976)
		(size 0.508)
		(drill 0.254)
		(layers "F.Cu" "B.Cu")
		(net "N21698906")
	)
	(segment
		(start 67.30492 -30.959044)
		(end 68.268088 -30.959044)
		(width 0.254)
		(layer "F.Cu")
		(net "P1V5_NODE1_DDR3_VREF_A_A")
	)
	(segment
		(start 68.268088 -30.959044)
		(end 68.32854 -30.898592)
		(width 0.254)
		(layer "F.Cu")
		(net "P1V5_NODE1_DDR3_VREF_A_A")
	)
	(segment
		(start 67.30492 -30.708854)
		(end 67.30492 -30.959044)
		(width 0.254)
		(layer "F.Cu")
		(net "P1V5_NODE1_DDR3_VREF_A_A")
	)
	(segment
		(start 67.650106 -29.149802)
		(end 67.650106 -30.363668)
		(width 0.254)
		(layer "F.Cu")
		(net "P1V5_NODE1_DDR3_VREF_A_A")
	)
	(segment
		(start 67.650106 -30.363668)
		(end 67.30492 -30.708854)
		(width 0.254)
		(layer "F.Cu")
		(net "P1V5_NODE1_DDR3_VREF_A_A")
	)
	(via
		(at 67.30492 -30.959044)
		(size 0.508)
		(drill 0.254)
		(layers "F.Cu" "B.Cu")
		(net "P1V5_NODE1_DDR3_VREF_A_A")
	)
	(via
		(at 68.32854 -30.898592)
		(size 0.508)
		(drill 0.254)
		(layers "F.Cu" "B.Cu")
		(net "P1V5_NODE1_DDR3_VREF_A_A")
	)
	(segment
		(start 58.23077 -82.333846)
		(end 58.23077 -82.341466)
		(width 0.3048)
		(layer "F.Cu")
		(net "A_CPU_NODE1_MV_GPIO_RCOMP")
	)
	(segment
		(start 58.23077 -82.341466)
		(end 58.60415 -82.714846)
		(width 0.3048)
		(layer "F.Cu")
		(net "A_CPU_NODE1_MV_GPIO_RCOMP")
	)
	(via
		(at 58.60415 -82.714846)
		(size 0.508)
		(drill 0.254)
		(layers "F.Cu" "B.Cu")
		(net "A_CPU_NODE1_MV_GPIO_RCOMP")
	)
	(via
		(at 58.021728 -81.652872)
		(size 0.6604)
		(drill 0.3302)
		(layers "F.Cu" "B.Cu")
		(net "A_CPU_NODE1_MV_GPIO_RCOMP")
	)
	(segment
		(start 57.852818 -83.016344)
		(end 58.154316 -82.714846)
		(width 0.381)
		(layer "B.Cu")
		(net "A_CPU_NODE1_MV_GPIO_RCOMP")
	)
	(segment
		(start 58.154316 -82.714846)
		(end 58.60415 -82.714846)
		(width 0.381)
		(layer "B.Cu")
		(net "A_CPU_NODE1_MV_GPIO_RCOMP")
	)
	(segment
		(start 58.021728 -82.132424)
		(end 58.021728 -81.652872)
		(width 0.1016)
		(layer "B.Cu")
		(net "A_CPU_NODE1_MV_GPIO_RCOMP")
	)
	(segment
		(start 58.60415 -82.714846)
		(end 58.021728 -82.132424)
		(width 0.1016)
		(layer "B.Cu")
		(net "A_CPU_NODE1_MV_GPIO_RCOMP")
	)
	(segment
		(start 57.852818 -84.625688)
		(end 57.852818 -83.016344)
		(width 0.381)
		(layer "B.Cu")
		(net "A_CPU_NODE1_MV_GPIO_RCOMP")
	)
	(segment
		(start 122.421142 -171.603416)
		(end 122.052842 -171.971716)
		(width 0.1016)
		(layer "F.Cu")
		(net "N21699069")
	)
	(segment
		(start 120.60936 -171.971716)
		(end 121.755916 -171.971716)
		(width 0.1016)
		(layer "F.Cu")
		(net "N21699069")
	)
	(segment
		(start 122.052842 -171.971716)
		(end 121.755916 -171.971716)
		(width 0.1016)
		(layer "F.Cu")
		(net "N21699069")
	)
	(segment
		(start 123.30811 -171.603416)
		(end 122.421142 -171.603416)
		(width 0.1016)
		(layer "F.Cu")
		(net "N21699069")
	)
	(via
		(at 121.755916 -171.971716)
		(size 0.508)
		(drill 0.254)
		(layers "F.Cu" "B.Cu")
		(net "N21699069")
	)
	(segment
		(start 123.224036 -139.27455)
		(end 122.735086 -139.7635)
		(width 0.127)
		(layer "F.Cu")
		(net "P2E_CPU_BMC_NODE1_RX_DP")
	)
	(segment
		(start 75.98537 -120.270778)
		(end 75.58532 -119.870728)
		(width 0.127)
		(layer "F.Cu")
		(net "P2E_CPU_BMC_NODE1_RX_DP")
	)
	(segment
		(start 76.893674 -120.270778)
		(end 75.98537 -120.270778)
		(width 0.127)
		(layer "F.Cu")
		(net "P2E_CPU_BMC_NODE1_RX_DP")
	)
	(segment
		(start 124.624846 -140.927836)
		(end 123.682252 -139.985242)
		(width 0.127)
		(layer "F.Cu")
		(net "P2E_CPU_BMC_NODE1_RX_DP")
	)
	(segment
		(start 125.787912 -140.975588)
		(end 125.076712 -140.975588)
		(width 0.127)
		(layer "F.Cu")
		(net "P2E_CPU_BMC_NODE1_RX_DP")
	)
	(segment
		(start 125.02896 -140.927836)
		(end 124.624846 -140.927836)
		(width 0.127)
		(layer "F.Cu")
		(net "P2E_CPU_BMC_NODE1_RX_DP")
	)
	(segment
		(start 123.682252 -139.985242)
		(end 123.682252 -139.477242)
		(width 0.127)
		(layer "F.Cu")
		(net "P2E_CPU_BMC_NODE1_RX_DP")
	)
	(segment
		(start 125.076712 -140.975588)
		(end 125.02896 -140.927836)
		(width 0.127)
		(layer "F.Cu")
		(net "P2E_CPU_BMC_NODE1_RX_DP")
	)
	(segment
		(start 123.47956 -139.27455)
		(end 123.224036 -139.27455)
		(width 0.127)
		(layer "F.Cu")
		(net "P2E_CPU_BMC_NODE1_RX_DP")
	)
	(segment
		(start 77.122274 -120.042178)
		(end 76.893674 -120.270778)
		(width 0.127)
		(layer "F.Cu")
		(net "P2E_CPU_BMC_NODE1_RX_DP")
	)
	(segment
		(start 123.682252 -139.477242)
		(end 123.47956 -139.27455)
		(width 0.127)
		(layer "F.Cu")
		(net "P2E_CPU_BMC_NODE1_RX_DP")
	)
	(via
		(at 122.735086 -139.7635)
		(size 0.508)
		(drill 0.254)
		(layers "F.Cu" "B.Cu")
		(net "P2E_CPU_BMC_NODE1_RX_DP")
	)
	(via
		(at 77.122274 -120.042178)
		(size 0.508)
		(drill 0.254)
		(layers "F.Cu" "B.Cu")
		(net "P2E_CPU_BMC_NODE1_RX_DP")
	)
	(segment
		(start 75.712066 -121.016776)
		(end 75.774042 -120.577356)
		(width 0.127)
		(layer "In7.Cu")
		(net "P2E_CPU_BMC_NODE1_RX_DP")
	)
	(segment
		(start 84.97062 -129.65049)
		(end 83.44916 -128.765808)
		(width 0.127)
		(layer "In7.Cu")
		(net "P2E_CPU_BMC_NODE1_RX_DP")
	)
	(segment
		(start 109.564932 -144.472152)
		(end 103.076502 -143.905478)
		(width 0.127)
		(layer "In7.Cu")
		(net "P2E_CPU_BMC_NODE1_RX_DP")
	)
	(segment
		(start 75.920092 -121.538238)
		(end 75.712066 -121.016776)
		(width 0.127)
		(layer "In7.Cu")
		(net "P2E_CPU_BMC_NODE1_RX_DP")
	)
	(segment
		(start 89.88044 -135.028178)
		(end 89.5223 -134.392416)
		(width 0.127)
		(layer "In7.Cu")
		(net "P2E_CPU_BMC_NODE1_RX_DP")
	)
	(segment
		(start 93.101922 -141.039342)
		(end 92.249498 -140.035788)
		(width 0.127)
		(layer "In7.Cu")
		(net "P2E_CPU_BMC_NODE1_RX_DP")
	)
	(segment
		(start 89.5223 -134.392416)
		(end 87.90178 -132.771642)
		(width 0.127)
		(layer "In7.Cu")
		(net "P2E_CPU_BMC_NODE1_RX_DP")
	)
	(segment
		(start 76.077826 -120.277128)
		(end 76.887324 -120.277128)
		(width 0.127)
		(layer "In7.Cu")
		(net "P2E_CPU_BMC_NODE1_RX_DP")
	)
	(segment
		(start 77.264768 -122.091196)
		(end 76.767944 -122.053604)
		(width 0.127)
		(layer "In7.Cu")
		(net "P2E_CPU_BMC_NODE1_RX_DP")
	)
	(segment
		(start 109.809534 -144.472152)
		(end 109.564932 -144.472152)
		(width 0.127)
		(layer "In7.Cu")
		(net "P2E_CPU_BMC_NODE1_RX_DP")
	)
	(segment
		(start 103.076502 -143.905478)
		(end 101.684836 -142.298674)
		(width 0.127)
		(layer "In7.Cu")
		(net "P2E_CPU_BMC_NODE1_RX_DP")
	)
	(segment
		(start 96.085152 -141.834616)
		(end 93.101922 -141.039342)
		(width 0.127)
		(layer "In7.Cu")
		(net "P2E_CPU_BMC_NODE1_RX_DP")
	)
	(segment
		(start 99.854004 -141.956282)
		(end 96.151954 -141.844522)
		(width 0.127)
		(layer "In7.Cu")
		(net "P2E_CPU_BMC_NODE1_RX_DP")
	)
	(segment
		(start 120.242076 -139.27455)
		(end 114.799872 -143.600678)
		(width 0.127)
		(layer "In7.Cu")
		(net "P2E_CPU_BMC_NODE1_RX_DP")
	)
	(segment
		(start 87.90178 -132.771642)
		(end 84.97062 -129.65049)
		(width 0.127)
		(layer "In7.Cu")
		(net "P2E_CPU_BMC_NODE1_RX_DP")
	)
	(segment
		(start 76.887324 -120.277128)
		(end 77.122274 -120.042178)
		(width 0.127)
		(layer "In7.Cu")
		(net "P2E_CPU_BMC_NODE1_RX_DP")
	)
	(segment
		(start 79.215488 -123.019312)
		(end 77.264768 -122.091196)
		(width 0.127)
		(layer "In7.Cu")
		(net "P2E_CPU_BMC_NODE1_RX_DP")
	)
	(segment
		(start 76.767944 -122.053604)
		(end 75.920092 -121.538238)
		(width 0.127)
		(layer "In7.Cu")
		(net "P2E_CPU_BMC_NODE1_RX_DP")
	)
	(segment
		(start 96.151954 -141.844522)
		(end 96.085152 -141.834616)
		(width 0.127)
		(layer "In7.Cu")
		(net "P2E_CPU_BMC_NODE1_RX_DP")
	)
	(segment
		(start 89.93886 -135.833358)
		(end 89.88044 -135.028178)
		(width 0.127)
		(layer "In7.Cu")
		(net "P2E_CPU_BMC_NODE1_RX_DP")
	)
	(segment
		(start 83.44916 -128.765808)
		(end 82.50428 -127.314452)
		(width 0.127)
		(layer "In7.Cu")
		(net "P2E_CPU_BMC_NODE1_RX_DP")
	)
	(segment
		(start 101.684836 -142.298674)
		(end 99.854004 -141.956282)
		(width 0.127)
		(layer "In7.Cu")
		(net "P2E_CPU_BMC_NODE1_RX_DP")
	)
	(segment
		(start 122.735086 -139.7635)
		(end 122.246136 -139.27455)
		(width 0.127)
		(layer "In7.Cu")
		(net "P2E_CPU_BMC_NODE1_RX_DP")
	)
	(segment
		(start 122.246136 -139.27455)
		(end 120.242076 -139.27455)
		(width 0.127)
		(layer "In7.Cu")
		(net "P2E_CPU_BMC_NODE1_RX_DP")
	)
	(segment
		(start 92.249498 -140.035788)
		(end 91.924886 -139.258802)
		(width 0.127)
		(layer "In7.Cu")
		(net "P2E_CPU_BMC_NODE1_RX_DP")
	)
	(segment
		(start 114.799872 -143.600678)
		(end 114.17681 -144.032224)
		(width 0.127)
		(layer "In7.Cu")
		(net "P2E_CPU_BMC_NODE1_RX_DP")
	)
	(segment
		(start 82.50428 -127.314452)
		(end 79.215488 -123.019312)
		(width 0.127)
		(layer "In7.Cu")
		(net "P2E_CPU_BMC_NODE1_RX_DP")
	)
	(segment
		(start 75.774042 -120.577356)
		(end 76.077826 -120.277128)
		(width 0.127)
		(layer "In7.Cu")
		(net "P2E_CPU_BMC_NODE1_RX_DP")
	)
	(segment
		(start 90.355928 -137.198608)
		(end 89.93886 -135.833358)
		(width 0.127)
		(layer "In7.Cu")
		(net "P2E_CPU_BMC_NODE1_RX_DP")
	)
	(segment
		(start 91.924886 -139.258802)
		(end 90.355928 -137.198608)
		(width 0.127)
		(layer "In7.Cu")
		(net "P2E_CPU_BMC_NODE1_RX_DP")
	)
	(segment
		(start 114.17681 -144.032224)
		(end 109.809534 -144.472152)
		(width 0.127)
		(layer "In7.Cu")
		(net "P2E_CPU_BMC_NODE1_RX_DP")
	)
	(segment
		(start 48.942244 -88.103964)
		(end 49.390046 -88.551766)
		(width 0.1016)
		(layer "F.Cu")
		(net "PD_NODE1_NTB_PERP")
	)
	(segment
		(start 51.6001 -87.700358)
		(end 51.879246 -87.421212)
		(width 0.1016)
		(layer "F.Cu")
		(net "PD_NODE1_NTB_PERP")
	)
	(segment
		(start 50.7111 -87.700358)
		(end 50.7111 -87.095838)
		(width 0.1016)
		(layer "F.Cu")
		(net "PD_NODE1_NTB_PERP")
	)
	(segment
		(start 49.021492 -86.129368)
		(end 49.36617 -86.474046)
		(width 0.1016)
		(layer "F.Cu")
		(net "PD_NODE1_NTB_PERP")
	)
	(segment
		(start 48.646842 -86.129368)
		(end 49.021492 -86.129368)
		(width 0.1016)
		(layer "F.Cu")
		(net "PD_NODE1_NTB_PERP")
	)
	(segment
		(start 53.394356 -87.341964)
		(end 53.445156 -87.392764)
		(width 0.1016)
		(layer "F.Cu")
		(net "PD_NODE1_NTB_PERP")
	)
	(segment
		(start 50.7111 -87.095838)
		(end 50.803048 -87.00389)
		(width 0.1016)
		(layer "F.Cu")
		(net "PD_NODE1_NTB_PERP")
	)
	(segment
		(start 43.249088 -84.02193)
		(end 42.781474 -84.02193)
		(width 0.1016)
		(layer "F.Cu")
		(net "PD_NODE1_NTB_PERP")
	)
	(segment
		(start 46.300136 -87.00389)
		(end 46.300136 -86.85911)
		(width 0.1016)
		(layer "F.Cu")
		(net "PD_NODE1_NTB_PERP")
	)
	(segment
		(start 49.36617 -86.474046)
		(end 50.273204 -86.474046)
		(width 0.1016)
		(layer "F.Cu")
		(net "PD_NODE1_NTB_PERP")
	)
	(segment
		(start 46.300136 -86.85911)
		(end 46.769528 -86.389718)
		(width 0.1016)
		(layer "F.Cu")
		(net "PD_NODE1_NTB_PERP")
	)
	(segment
		(start 45.613066 -85.564472)
		(end 45.613066 -85.381846)
		(width 0.1016)
		(layer "F.Cu")
		(net "PD_NODE1_NTB_PERP")
	)
	(segment
		(start 49.761902 -88.402668)
		(end 50.21834 -88.402668)
		(width 0.1016)
		(layer "F.Cu")
		(net "PD_NODE1_NTB_PERP")
	)
	(segment
		(start 51.879246 -87.421212)
		(end 52.584858 -87.421212)
		(width 0.1016)
		(layer "F.Cu")
		(net "PD_NODE1_NTB_PERP")
	)
	(segment
		(start 44.881038 -86.2965)
		(end 45.613066 -85.564472)
		(width 0.1016)
		(layer "F.Cu")
		(net "PD_NODE1_NTB_PERP")
	)
	(segment
		(start 45.923962 -84.619846)
		(end 45.613066 -84.930742)
		(width 0.1016)
		(layer "F.Cu")
		(net "PD_NODE1_NTB_PERP")
	)
	(segment
		(start 46.769528 -86.389718)
		(end 46.886368 -86.389718)
		(width 0.1016)
		(layer "F.Cu")
		(net "PD_NODE1_NTB_PERP")
	)
	(segment
		(start 47.00016 -87.00389)
		(end 47.004732 -87.00389)
		(width 0.1016)
		(layer "F.Cu")
		(net "PD_NODE1_NTB_PERP")
	)
	(segment
		(start 46.176692 -88.438482)
		(end 46.58614 -88.029034)
		(width 0.1016)
		(layer "F.Cu")
		(net "PD_NODE1_NTB_PERP")
	)
	(segment
		(start 36.166552 -83.294982)
		(end 37.845746 -83.294982)
		(width 0.1016)
		(layer "F.Cu")
		(net "PD_NODE1_NTB_PERP")
	)
	(segment
		(start 50.7111 -87.909908)
		(end 50.7111 -87.700358)
		(width 0.1016)
		(layer "F.Cu")
		(net "PD_NODE1_NTB_PERP")
	)
	(segment
		(start 46.300136 -87.00389)
		(end 47.00016 -87.00389)
		(width 0.1016)
		(layer "F.Cu")
		(net "PD_NODE1_NTB_PERP")
	)
	(segment
		(start 47.54626 -86.462362)
		(end 48.313848 -86.462362)
		(width 0.1016)
		(layer "F.Cu")
		(net "PD_NODE1_NTB_PERP")
	)
	(segment
		(start 47.248064 -85.55482)
		(end 46.31309 -84.619846)
		(width 0.1016)
		(layer "F.Cu")
		(net "PD_NODE1_NTB_PERP")
	)
	(segment
		(start 46.886368 -86.389718)
		(end 47.248064 -86.028022)
		(width 0.1016)
		(layer "F.Cu")
		(net "PD_NODE1_NTB_PERP")
	)
	(segment
		(start 46.58614 -88.029034)
		(end 46.58614 -87.57412)
		(width 0.1016)
		(layer "F.Cu")
		(net "PD_NODE1_NTB_PERP")
	)
	(segment
		(start 53.445156 -87.392764)
		(end 53.445156 -88.103964)
		(width 0.1016)
		(layer "F.Cu")
		(net "PD_NODE1_NTB_PERP")
	)
	(segment
		(start 52.923694 -87.341964)
		(end 53.394356 -87.341964)
		(width 0.1016)
		(layer "F.Cu")
		(net "PD_NODE1_NTB_PERP")
	)
	(segment
		(start 43.920156 -85.919818)
		(end 44.296838 -86.2965)
		(width 0.1016)
		(layer "F.Cu")
		(net "PD_NODE1_NTB_PERP")
	)
	(segment
		(start 51.499516 -87.700358)
		(end 51.6001 -87.700358)
		(width 0.1016)
		(layer "F.Cu")
		(net "PD_NODE1_NTB_PERP")
	)
	(segment
		(start 50.273204 -86.474046)
		(end 50.803048 -87.00389)
		(width 0.1016)
		(layer "F.Cu")
		(net "PD_NODE1_NTB_PERP")
	)
	(segment
		(start 52.714652 -87.551006)
		(end 52.923694 -87.341964)
		(width 0.1016)
		(layer "F.Cu")
		(net "PD_NODE1_NTB_PERP")
	)
	(segment
		(start 45.613066 -84.930742)
		(end 45.613066 -85.381846)
		(width 0.1016)
		(layer "F.Cu")
		(net "PD_NODE1_NTB_PERP")
	)
	(segment
		(start 46.31309 -84.619846)
		(end 45.923962 -84.619846)
		(width 0.1016)
		(layer "F.Cu")
		(net "PD_NODE1_NTB_PERP")
	)
	(segment
		(start 43.45813 -84.230972)
		(end 43.249088 -84.02193)
		(width 0.1016)
		(layer "F.Cu")
		(net "PD_NODE1_NTB_PERP")
	)
	(segment
		(start 42.781474 -84.02193)
		(end 42.369232 -83.609688)
		(width 0.1016)
		(layer "F.Cu")
		(net "PD_NODE1_NTB_PERP")
	)
	(segment
		(start 41.80967 -83.861656)
		(end 38.41242 -83.861656)
		(width 0.1016)
		(layer "F.Cu")
		(net "PD_NODE1_NTB_PERP")
	)
	(segment
		(start 46.300136 -87.288116)
		(end 46.300136 -87.00389)
		(width 0.1016)
		(layer "F.Cu")
		(net "PD_NODE1_NTB_PERP")
	)
	(segment
		(start 42.369232 -83.609688)
		(end 42.061638 -83.609688)
		(width 0.1016)
		(layer "F.Cu")
		(net "PD_NODE1_NTB_PERP")
	)
	(segment
		(start 50.21834 -88.402668)
		(end 50.7111 -87.909908)
		(width 0.1016)
		(layer "F.Cu")
		(net "PD_NODE1_NTB_PERP")
	)
	(segment
		(start 46.58614 -87.57412)
		(end 46.300136 -87.288116)
		(width 0.1016)
		(layer "F.Cu")
		(net "PD_NODE1_NTB_PERP")
	)
	(segment
		(start 44.296838 -86.2965)
		(end 44.881038 -86.2965)
		(width 0.1016)
		(layer "F.Cu")
		(net "PD_NODE1_NTB_PERP")
	)
	(segment
		(start 49.612804 -88.551766)
		(end 49.761902 -88.402668)
		(width 0.1016)
		(layer "F.Cu")
		(net "PD_NODE1_NTB_PERP")
	)
	(segment
		(start 47.004732 -87.00389)
		(end 47.54626 -86.462362)
		(width 0.1016)
		(layer "F.Cu")
		(net "PD_NODE1_NTB_PERP")
	)
	(segment
		(start 47.248064 -86.028022)
		(end 47.248064 -85.55482)
		(width 0.1016)
		(layer "F.Cu")
		(net "PD_NODE1_NTB_PERP")
	)
	(segment
		(start 52.584858 -87.421212)
		(end 52.714652 -87.551006)
		(width 0.1016)
		(layer "F.Cu")
		(net "PD_NODE1_NTB_PERP")
	)
	(segment
		(start 50.803048 -87.00389)
		(end 51.499516 -87.700358)
		(width 0.1016)
		(layer "F.Cu")
		(net "PD_NODE1_NTB_PERP")
	)
	(segment
		(start 37.845746 -83.294982)
		(end 38.41242 -83.861656)
		(width 0.1016)
		(layer "F.Cu")
		(net "PD_NODE1_NTB_PERP")
	)
	(segment
		(start 48.313848 -86.462362)
		(end 48.646842 -86.129368)
		(width 0.1016)
		(layer "F.Cu")
		(net "PD_NODE1_NTB_PERP")
	)
	(segment
		(start 49.390046 -88.551766)
		(end 49.612804 -88.551766)
		(width 0.1016)
		(layer "F.Cu")
		(net "PD_NODE1_NTB_PERP")
	)
	(segment
		(start 42.061638 -83.609688)
		(end 41.80967 -83.861656)
		(width 0.1016)
		(layer "F.Cu")
		(net "PD_NODE1_NTB_PERP")
	)
	(segment
		(start 44.469304 -84.701634)
		(end 43.45813 -84.701634)
		(width 0.1016)
		(layer "F.Cu")
		(net "PD_NODE1_NTB_PERP")
	)
	(segment
		(start 45.149516 -85.381846)
		(end 44.469304 -84.701634)
		(width 0.1016)
		(layer "F.Cu")
		(net "PD_NODE1_NTB_PERP")
	)
	(segment
		(start 43.45813 -84.701634)
		(end 43.45813 -84.230972)
		(width 0.1016)
		(layer "F.Cu")
		(net "PD_NODE1_NTB_PERP")
	)
	(segment
		(start 45.613066 -85.381846)
		(end 45.149516 -85.381846)
		(width 0.1016)
		(layer "F.Cu")
		(net "PD_NODE1_NTB_PERP")
	)
	(via
		(at 38.41242 -83.861656)
		(size 0.508)
		(drill 0.254)
		(layers "F.Cu" "B.Cu")
		(net "PD_NODE1_NTB_PERP")
	)
	(segment
		(start 71.345044 -68.324222)
		(end 71.345044 -68.351654)
		(width 0.1016)
		(layer "F.Cu")
		(net "M1_DQ_NODE1_DQ45")
	)
	(segment
		(start 71.345044 -68.351654)
		(end 70.978776 -68.717922)
		(width 0.1016)
		(layer "F.Cu")
		(net "M1_DQ_NODE1_DQ45")
	)
	(segment
		(start 87.450168 -29.149802)
		(end 87.450168 -30.586172)
		(width 0.1651)
		(layer "F.Cu")
		(net "M1_DQ_NODE1_DQ45")
	)
	(segment
		(start 87.450168 -30.586172)
		(end 87.310722 -30.725618)
		(width 0.1651)
		(layer "F.Cu")
		(net "M1_DQ_NODE1_DQ45")
	)
	(via
		(at 87.310722 -30.725618)
		(size 0.508)
		(drill 0.254)
		(layers "F.Cu" "B.Cu")
		(net "M1_DQ_NODE1_DQ45")
	)
	(via
		(at 70.978776 -68.717922)
		(size 0.508)
		(drill 0.254)
		(layers "F.Cu" "B.Cu")
		(net "M1_DQ_NODE1_DQ45")
	)
	(segment
		(start 89.29878 -41.149778)
		(end 89.29878 -40.855138)
		(width 0.2032)
		(layer "In2.Cu")
		(net "M1_DQ_NODE1_DQ45")
	)
	(segment
		(start 89.0905 -39.935658)
		(end 89.29878 -39.727378)
		(width 0.2032)
		(layer "In2.Cu")
		(net "M1_DQ_NODE1_DQ45")
	)
	(segment
		(start 83.764882 -50.973228)
		(end 84.059522 -50.973228)
		(width 0.2032)
		(layer "In2.Cu")
		(net "M1_DQ_NODE1_DQ45")
	)
	(segment
		(start 76.596494 -57.341008)
		(end 77.397102 -57.341008)
		(width 0.2032)
		(layer "In2.Cu")
		(net "M1_DQ_NODE1_DQ45")
	)
	(segment
		(start 84.562442 -50.175668)
		(end 85.108034 -49.630076)
		(width 0.2032)
		(layer "In2.Cu")
		(net "M1_DQ_NODE1_DQ45")
	)
	(segment
		(start 86.499954 -48.238156)
		(end 89.29878 -45.43933)
		(width 0.2032)
		(layer "In2.Cu")
		(net "M1_DQ_NODE1_DQ45")
	)
	(segment
		(start 86.66988 -31.365698)
		(end 87.30996 -30.725618)
		(width 0.2032)
		(layer "In2.Cu")
		(net "M1_DQ_NODE1_DQ45")
	)
	(segment
		(start 86.66988 -35.64636)
		(end 86.66988 -31.365698)
		(width 0.2032)
		(layer "In2.Cu")
		(net "M1_DQ_NODE1_DQ45")
	)
	(segment
		(start 70.978776 -68.717922)
		(end 70.753224 -68.49237)
		(width 0.1016)
		(layer "In2.Cu")
		(net "M1_DQ_NODE1_DQ45")
	)
	(segment
		(start 84.059522 -50.973228)
		(end 84.239354 -51.15306)
		(width 0.2032)
		(layer "In2.Cu")
		(net "M1_DQ_NODE1_DQ45")
	)
	(segment
		(start 89.0905 -42.780458)
		(end 89.29878 -42.572178)
		(width 0.2032)
		(layer "In2.Cu")
		(net "M1_DQ_NODE1_DQ45")
	)
	(segment
		(start 89.29878 -42.572178)
		(end 89.29878 -42.277538)
		(width 0.2032)
		(layer "In2.Cu")
		(net "M1_DQ_NODE1_DQ45")
	)
	(segment
		(start 69.45249 -64.341248)
		(end 70.443344 -63.350394)
		(width 0.2032)
		(layer "In2.Cu")
		(net "M1_DQ_NODE1_DQ45")
	)
	(segment
		(start 89.0905 -44.914058)
		(end 88.66124 -44.914058)
		(width 0.2032)
		(layer "In2.Cu")
		(net "M1_DQ_NODE1_DQ45")
	)
	(segment
		(start 88.66124 -41.358058)
		(end 89.0905 -41.358058)
		(width 0.2032)
		(layer "In2.Cu")
		(net "M1_DQ_NODE1_DQ45")
	)
	(segment
		(start 88.45296 -41.860978)
		(end 88.45296 -41.566338)
		(width 0.2032)
		(layer "In2.Cu")
		(net "M1_DQ_NODE1_DQ45")
	)
	(segment
		(start 88.66124 -43.491658)
		(end 88.45296 -43.283378)
		(width 0.2032)
		(layer "In2.Cu")
		(net "M1_DQ_NODE1_DQ45")
	)
	(segment
		(start 89.0905 -47.659544)
		(end 89.0905 -47.362364)
		(width 0.2032)
		(layer "In2.Cu")
		(net "M1_DQ_NODE1_DQ45")
	)
	(segment
		(start 89.29878 -38.27526)
		(end 86.66988 -35.64636)
		(width 0.2032)
		(layer "In2.Cu")
		(net "M1_DQ_NODE1_DQ45")
	)
	(segment
		(start 88.45296 -44.411138)
		(end 88.66124 -44.202858)
		(width 0.2032)
		(layer "In2.Cu")
		(net "M1_DQ_NODE1_DQ45")
	)
	(segment
		(start 89.29878 -39.727378)
		(end 89.29878 -38.27526)
		(width 0.2032)
		(layer "In2.Cu")
		(net "M1_DQ_NODE1_DQ45")
	)
	(segment
		(start 70.752716 -68.49237)
		(end 70.235572 -67.975226)
		(width 0.1016)
		(layer "In2.Cu")
		(net "M1_DQ_NODE1_DQ45")
	)
	(segment
		(start 70.753224 -68.49237)
		(end 70.752716 -68.49237)
		(width 0.1016)
		(layer "In2.Cu")
		(net "M1_DQ_NODE1_DQ45")
	)
	(segment
		(start 69.173344 -67.975226)
		(end 68.584064 -67.385946)
		(width 0.1016)
		(layer "In2.Cu")
		(net "M1_DQ_NODE1_DQ45")
	)
	(segment
		(start 87.120222 -49.630076)
		(end 89.0905 -47.659544)
		(width 0.2032)
		(layer "In2.Cu")
		(net "M1_DQ_NODE1_DQ45")
	)
	(segment
		(start 86.499954 -48.532796)
		(end 86.499954 -48.238156)
		(width 0.2032)
		(layer "In2.Cu")
		(net "M1_DQ_NODE1_DQ45")
	)
	(segment
		(start 70.443344 -63.350394)
		(end 71.195438 -63.350394)
		(width 0.2032)
		(layer "In2.Cu")
		(net "M1_DQ_NODE1_DQ45")
	)
	(segment
		(start 84.562442 -50.470308)
		(end 84.562442 -50.175668)
		(width 0.2032)
		(layer "In2.Cu")
		(net "M1_DQ_NODE1_DQ45")
	)
	(segment
		(start 88.66124 -42.069258)
		(end 88.45296 -41.860978)
		(width 0.2032)
		(layer "In2.Cu")
		(net "M1_DQ_NODE1_DQ45")
	)
	(segment
		(start 88.66124 -42.780458)
		(end 89.0905 -42.780458)
		(width 0.2032)
		(layer "In2.Cu")
		(net "M1_DQ_NODE1_DQ45")
	)
	(segment
		(start 88.66124 -40.646858)
		(end 88.45296 -40.438578)
		(width 0.2032)
		(layer "In2.Cu")
		(net "M1_DQ_NODE1_DQ45")
	)
	(segment
		(start 88.884252 -47.15383)
		(end 88.590374 -47.15383)
		(width 0.2032)
		(layer "In2.Cu")
		(net "M1_DQ_NODE1_DQ45")
	)
	(segment
		(start 89.0905 -41.358058)
		(end 89.29878 -41.149778)
		(width 0.2032)
		(layer "In2.Cu")
		(net "M1_DQ_NODE1_DQ45")
	)
	(segment
		(start 68.584064 -65.058798)
		(end 69.301614 -64.341248)
		(width 0.1016)
		(layer "In2.Cu")
		(net "M1_DQ_NODE1_DQ45")
	)
	(segment
		(start 89.29878 -43.994578)
		(end 89.29878 -43.699938)
		(width 0.2032)
		(layer "In2.Cu")
		(net "M1_DQ_NODE1_DQ45")
	)
	(segment
		(start 84.239354 -51.15306)
		(end 84.533994 -51.15306)
		(width 0.2032)
		(layer "In2.Cu")
		(net "M1_DQ_NODE1_DQ45")
	)
	(segment
		(start 89.0905 -40.646858)
		(end 88.66124 -40.646858)
		(width 0.2032)
		(layer "In2.Cu")
		(net "M1_DQ_NODE1_DQ45")
	)
	(segment
		(start 87.30996 -30.725618)
		(end 87.310722 -30.725618)
		(width 0.2032)
		(layer "In2.Cu")
		(net "M1_DQ_NODE1_DQ45")
	)
	(segment
		(start 84.742274 -50.65014)
		(end 84.562442 -50.470308)
		(width 0.2032)
		(layer "In2.Cu")
		(net "M1_DQ_NODE1_DQ45")
	)
	(segment
		(start 88.45296 -43.283378)
		(end 88.45296 -42.988738)
		(width 0.2032)
		(layer "In2.Cu")
		(net "M1_DQ_NODE1_DQ45")
	)
	(segment
		(start 89.29878 -43.699938)
		(end 89.0905 -43.491658)
		(width 0.2032)
		(layer "In2.Cu")
		(net "M1_DQ_NODE1_DQ45")
	)
	(segment
		(start 86.708488 -48.74133)
		(end 86.499954 -48.532796)
		(width 0.2032)
		(layer "In2.Cu")
		(net "M1_DQ_NODE1_DQ45")
	)
	(segment
		(start 84.533994 -51.15306)
		(end 84.742274 -50.94478)
		(width 0.2032)
		(layer "In2.Cu")
		(net "M1_DQ_NODE1_DQ45")
	)
	(segment
		(start 72.13346 -61.804042)
		(end 76.596494 -57.341008)
		(width 0.2032)
		(layer "In2.Cu")
		(net "M1_DQ_NODE1_DQ45")
	)
	(segment
		(start 71.195438 -63.350394)
		(end 72.13346 -62.412372)
		(width 0.2032)
		(layer "In2.Cu")
		(net "M1_DQ_NODE1_DQ45")
	)
	(segment
		(start 88.45296 -40.143938)
		(end 88.66124 -39.935658)
		(width 0.2032)
		(layer "In2.Cu")
		(net "M1_DQ_NODE1_DQ45")
	)
	(segment
		(start 89.0905 -44.202858)
		(end 89.29878 -43.994578)
		(width 0.2032)
		(layer "In2.Cu")
		(net "M1_DQ_NODE1_DQ45")
	)
	(segment
		(start 89.0905 -47.362364)
		(end 89.092786 -47.362364)
		(width 0.2032)
		(layer "In2.Cu")
		(net "M1_DQ_NODE1_DQ45")
	)
	(segment
		(start 89.29878 -45.43933)
		(end 89.29878 -45.122338)
		(width 0.2032)
		(layer "In2.Cu")
		(net "M1_DQ_NODE1_DQ45")
	)
	(segment
		(start 88.45296 -40.438578)
		(end 88.45296 -40.143938)
		(width 0.2032)
		(layer "In2.Cu")
		(net "M1_DQ_NODE1_DQ45")
	)
	(segment
		(start 68.584064 -67.385946)
		(end 68.584064 -65.058798)
		(width 0.1016)
		(layer "In2.Cu")
		(net "M1_DQ_NODE1_DQ45")
	)
	(segment
		(start 84.742274 -50.94478)
		(end 84.742274 -50.65014)
		(width 0.2032)
		(layer "In2.Cu")
		(net "M1_DQ_NODE1_DQ45")
	)
	(segment
		(start 89.092786 -47.362364)
		(end 88.884252 -47.15383)
		(width 0.2032)
		(layer "In2.Cu")
		(net "M1_DQ_NODE1_DQ45")
	)
	(segment
		(start 88.590374 -47.15383)
		(end 87.002874 -48.74133)
		(width 0.2032)
		(layer "In2.Cu")
		(net "M1_DQ_NODE1_DQ45")
	)
	(segment
		(start 89.29878 -40.855138)
		(end 89.0905 -40.646858)
		(width 0.2032)
		(layer "In2.Cu")
		(net "M1_DQ_NODE1_DQ45")
	)
	(segment
		(start 88.66124 -39.935658)
		(end 89.0905 -39.935658)
		(width 0.2032)
		(layer "In2.Cu")
		(net "M1_DQ_NODE1_DQ45")
	)
	(segment
		(start 89.0905 -42.069258)
		(end 88.66124 -42.069258)
		(width 0.2032)
		(layer "In2.Cu")
		(net "M1_DQ_NODE1_DQ45")
	)
	(segment
		(start 72.13346 -62.412372)
		(end 72.13346 -61.804042)
		(width 0.2032)
		(layer "In2.Cu")
		(net "M1_DQ_NODE1_DQ45")
	)
	(segment
		(start 77.397102 -57.341008)
		(end 83.764882 -50.973228)
		(width 0.2032)
		(layer "In2.Cu")
		(net "M1_DQ_NODE1_DQ45")
	)
	(segment
		(start 89.29878 -42.277538)
		(end 89.0905 -42.069258)
		(width 0.2032)
		(layer "In2.Cu")
		(net "M1_DQ_NODE1_DQ45")
	)
	(segment
		(start 70.235572 -67.975226)
		(end 69.173344 -67.975226)
		(width 0.1016)
		(layer "In2.Cu")
		(net "M1_DQ_NODE1_DQ45")
	)
	(segment
		(start 85.108034 -49.630076)
		(end 87.120222 -49.630076)
		(width 0.2032)
		(layer "In2.Cu")
		(net "M1_DQ_NODE1_DQ45")
	)
	(segment
		(start 88.66124 -44.914058)
		(end 88.45296 -44.705778)
		(width 0.2032)
		(layer "In2.Cu")
		(net "M1_DQ_NODE1_DQ45")
	)
	(segment
		(start 89.0905 -43.491658)
		(end 88.66124 -43.491658)
		(width 0.2032)
		(layer "In2.Cu")
		(net "M1_DQ_NODE1_DQ45")
	)
	(segment
		(start 88.45296 -41.566338)
		(end 88.66124 -41.358058)
		(width 0.2032)
		(layer "In2.Cu")
		(net "M1_DQ_NODE1_DQ45")
	)
	(segment
		(start 89.29878 -45.122338)
		(end 89.0905 -44.914058)
		(width 0.2032)
		(layer "In2.Cu")
		(net "M1_DQ_NODE1_DQ45")
	)
	(segment
		(start 88.45296 -42.988738)
		(end 88.66124 -42.780458)
		(width 0.2032)
		(layer "In2.Cu")
		(net "M1_DQ_NODE1_DQ45")
	)
	(segment
		(start 87.002874 -48.74133)
		(end 86.708488 -48.74133)
		(width 0.2032)
		(layer "In2.Cu")
		(net "M1_DQ_NODE1_DQ45")
	)
	(segment
		(start 69.301614 -64.341248)
		(end 69.45249 -64.341248)
		(width 0.2032)
		(layer "In2.Cu")
		(net "M1_DQ_NODE1_DQ45")
	)
	(segment
		(start 88.45296 -44.705778)
		(end 88.45296 -44.411138)
		(width 0.2032)
		(layer "In2.Cu")
		(net "M1_DQ_NODE1_DQ45")
	)
	(segment
		(start 88.66124 -44.202858)
		(end 89.0905 -44.202858)
		(width 0.2032)
		(layer "In2.Cu")
		(net "M1_DQ_NODE1_DQ45")
	)
	(segment
		(start 23.10257 -67.946778)
		(end 23.10257 -70.98665)
		(width 0.1016)
		(layer "F.Cu")
		(net "SMB_BMC_NODE1_DDC_CLK")
	)
	(segment
		(start 19.920458 -64.472566)
		(end 20.413726 -64.472566)
		(width 0.1016)
		(layer "F.Cu")
		(net "SMB_BMC_NODE1_DDC_CLK")
	)
	(segment
		(start 20.413726 -65.257934)
		(end 20.61591 -65.460118)
		(width 0.1016)
		(layer "F.Cu")
		(net "SMB_BMC_NODE1_DDC_CLK")
	)
	(segment
		(start 62.141862 -142.459456)
		(end 61.775086 -142.826232)
		(width 0.1016)
		(layer "F.Cu")
		(net "SMB_BMC_NODE1_DDC_CLK")
	)
	(segment
		(start 18.992596 -63.993776)
		(end 19.441668 -63.993776)
		(width 0.1016)
		(layer "F.Cu")
		(net "SMB_BMC_NODE1_DDC_CLK")
	)
	(segment
		(start 20.413726 -64.472566)
		(end 20.413726 -65.257934)
		(width 0.1016)
		(layer "F.Cu")
		(net "SMB_BMC_NODE1_DDC_CLK")
	)
	(segment
		(start 61.775086 -142.826232)
		(end 61.775086 -145.800572)
		(width 0.1016)
		(layer "F.Cu")
		(net "SMB_BMC_NODE1_DDC_CLK")
	)
	(segment
		(start 20.61591 -65.460118)
		(end 23.10257 -67.946778)
		(width 0.1016)
		(layer "F.Cu")
		(net "SMB_BMC_NODE1_DDC_CLK")
	)
	(segment
		(start 19.441668 -63.993776)
		(end 19.920458 -64.472566)
		(width 0.1016)
		(layer "F.Cu")
		(net "SMB_BMC_NODE1_DDC_CLK")
	)
	(via
		(at 61.775086 -145.800572)
		(size 0.508)
		(drill 0.254)
		(layers "F.Cu" "B.Cu")
		(net "SMB_BMC_NODE1_DDC_CLK")
	)
	(via
		(at 20.61591 -65.460118)
		(size 0.508)
		(drill 0.254)
		(layers "F.Cu" "B.Cu")
		(net "SMB_BMC_NODE1_DDC_CLK")
	)
	(segment
		(start 17.82318 -68.651628)
		(end 18.02638 -68.854828)
		(width 0.1143)
		(layer "In6.Cu")
		(net "SMB_BMC_NODE1_DDC_CLK")
	)
	(segment
		(start 17.03832 -78.31709)
		(end 15.903956 -78.31709)
		(width 0.1143)
		(layer "In6.Cu")
		(net "SMB_BMC_NODE1_DDC_CLK")
	)
	(segment
		(start 20.8915 -69.604128)
		(end 17.8181 -69.604128)
		(width 0.1143)
		(layer "In6.Cu")
		(net "SMB_BMC_NODE1_DDC_CLK")
	)
	(segment
		(start 20.2438 -141.881098)
		(end 21.77542 -141.881098)
		(width 0.1143)
		(layer "In6.Cu")
		(net "SMB_BMC_NODE1_DDC_CLK")
	)
	(segment
		(start 17.7546 -67.153028)
		(end 17.9578 -67.356228)
		(width 0.1143)
		(layer "In6.Cu")
		(net "SMB_BMC_NODE1_DDC_CLK")
	)
	(segment
		(start 17.82318 -68.308728)
		(end 17.82318 -68.651628)
		(width 0.1143)
		(layer "In6.Cu")
		(net "SMB_BMC_NODE1_DDC_CLK")
	)
	(segment
		(start 19.775424 -141.412722)
		(end 20.2438 -141.881098)
		(width 0.1143)
		(layer "In6.Cu")
		(net "SMB_BMC_NODE1_DDC_CLK")
	)
	(segment
		(start 12.04976 -139.778232)
		(end 12.11072 -139.839192)
		(width 0.1143)
		(layer "In6.Cu")
		(net "SMB_BMC_NODE1_DDC_CLK")
	)
	(segment
		(start 17.69364 -70.662546)
		(end 17.913096 -70.882002)
		(width 0.1143)
		(layer "In6.Cu")
		(net "SMB_BMC_NODE1_DDC_CLK")
	)
	(segment
		(start 19.576288 -67.886072)
		(end 19.356832 -68.105528)
		(width 0.1143)
		(layer "In6.Cu")
		(net "SMB_BMC_NODE1_DDC_CLK")
	)
	(segment
		(start 30.168088 -141.578838)
		(end 35.886898 -147.297648)
		(width 0.1143)
		(layer "In6.Cu")
		(net "SMB_BMC_NODE1_DDC_CLK")
	)
	(segment
		(start 17.24152 -78.11389)
		(end 17.03832 -78.31709)
		(width 0.1143)
		(layer "In6.Cu")
		(net "SMB_BMC_NODE1_DDC_CLK")
	)
	(segment
		(start 17.9578 -67.356228)
		(end 19.356832 -67.356228)
		(width 0.1143)
		(layer "In6.Cu")
		(net "SMB_BMC_NODE1_DDC_CLK")
	)
	(segment
		(start 15.903956 -76.06919)
		(end 18.53438 -76.06919)
		(width 0.1143)
		(layer "In6.Cu")
		(net "SMB_BMC_NODE1_DDC_CLK")
	)
	(segment
		(start 39.3065 -148.33727)
		(end 39.3065 -148.34362)
		(width 0.1143)
		(layer "In6.Cu")
		(net "SMB_BMC_NODE1_DDC_CLK")
	)
	(segment
		(start 6.5659 -136.36625)
		(end 9.977882 -139.778232)
		(width 0.1143)
		(layer "In6.Cu")
		(net "SMB_BMC_NODE1_DDC_CLK")
	)
	(segment
		(start 9.977882 -139.778232)
		(end 12.04976 -139.778232)
		(width 0.1143)
		(layer "In6.Cu")
		(net "SMB_BMC_NODE1_DDC_CLK")
	)
	(segment
		(start 49.068482 -150.474426)
		(end 49.31156 -150.231348)
		(width 0.1143)
		(layer "In6.Cu")
		(net "SMB_BMC_NODE1_DDC_CLK")
	)
	(segment
		(start 17.69364 -71.850758)
		(end 17.69364 -72.664574)
		(width 0.1143)
		(layer "In6.Cu")
		(net "SMB_BMC_NODE1_DDC_CLK")
	)
	(segment
		(start 54.607968 -149.741636)
		(end 55.65394 -148.695664)
		(width 0.1143)
		(layer "In6.Cu")
		(net "SMB_BMC_NODE1_DDC_CLK")
	)
	(segment
		(start 16.688308 -73.979786)
		(end 16.378428 -73.979786)
		(width 0.1143)
		(layer "In6.Cu")
		(net "SMB_BMC_NODE1_DDC_CLK")
	)
	(segment
		(start 21.0947 -69.400928)
		(end 20.8915 -69.604128)
		(width 0.1143)
		(layer "In6.Cu")
		(net "SMB_BMC_NODE1_DDC_CLK")
	)
	(segment
		(start 21.0947 -69.058028)
		(end 21.0947 -69.400928)
		(width 0.1143)
		(layer "In6.Cu")
		(net "SMB_BMC_NODE1_DDC_CLK")
	)
	(segment
		(start 18.53438 -76.81849)
		(end 15.903956 -76.81849)
		(width 0.1143)
		(layer "In6.Cu")
		(net "SMB_BMC_NODE1_DDC_CLK")
	)
	(segment
		(start 18.53438 -76.06919)
		(end 18.73758 -76.27239)
		(width 0.1143)
		(layer "In6.Cu")
		(net "SMB_BMC_NODE1_DDC_CLK")
	)
	(segment
		(start 17.913096 -71.631302)
		(end 17.69364 -71.850758)
		(width 0.1143)
		(layer "In6.Cu")
		(net "SMB_BMC_NODE1_DDC_CLK")
	)
	(segment
		(start 16.378428 -73.979786)
		(end 15.6845 -74.673714)
		(width 0.1143)
		(layer "In6.Cu")
		(net "SMB_BMC_NODE1_DDC_CLK")
	)
	(segment
		(start 17.8181 -69.604128)
		(end 17.69364 -69.728588)
		(width 0.1143)
		(layer "In6.Cu")
		(net "SMB_BMC_NODE1_DDC_CLK")
	)
	(segment
		(start 12.55268 -140.283438)
		(end 15.721076 -140.283438)
		(width 0.1143)
		(layer "In6.Cu")
		(net "SMB_BMC_NODE1_DDC_CLK")
	)
	(segment
		(start 58.787284 -148.695664)
		(end 61.682376 -145.800572)
		(width 0.1143)
		(layer "In6.Cu")
		(net "SMB_BMC_NODE1_DDC_CLK")
	)
	(segment
		(start 15.721076 -140.283438)
		(end 16.85036 -141.412722)
		(width 0.1143)
		(layer "In6.Cu")
		(net "SMB_BMC_NODE1_DDC_CLK")
	)
	(segment
		(start 6.5659 -96.892872)
		(end 6.5659 -136.36625)
		(width 0.1143)
		(layer "In6.Cu")
		(net "SMB_BMC_NODE1_DDC_CLK")
	)
	(segment
		(start 40.37838 -149.354794)
		(end 40.37838 -149.509226)
		(width 0.1143)
		(layer "In6.Cu")
		(net "SMB_BMC_NODE1_DDC_CLK")
	)
	(segment
		(start 22.07768 -141.578838)
		(end 30.168088 -141.578838)
		(width 0.1143)
		(layer "In6.Cu")
		(net "SMB_BMC_NODE1_DDC_CLK")
	)
	(segment
		(start 20.8915 -68.854828)
		(end 21.0947 -69.058028)
		(width 0.1143)
		(layer "In6.Cu")
		(net "SMB_BMC_NODE1_DDC_CLK")
	)
	(segment
		(start 15.6845 -75.849734)
		(end 15.903956 -76.06919)
		(width 0.1143)
		(layer "In6.Cu")
		(net "SMB_BMC_NODE1_DDC_CLK")
	)
	(segment
		(start 17.218406 -73.139808)
		(end 17.218406 -73.450196)
		(width 0.1143)
		(layer "In6.Cu")
		(net "SMB_BMC_NODE1_DDC_CLK")
	)
	(segment
		(start 38.266878 -147.297648)
		(end 39.3065 -148.33727)
		(width 0.1143)
		(layer "In6.Cu")
		(net "SMB_BMC_NODE1_DDC_CLK")
	)
	(segment
		(start 18.177764 -74.409554)
		(end 18.177764 -74.719688)
		(width 0.1143)
		(layer "In6.Cu")
		(net "SMB_BMC_NODE1_DDC_CLK")
	)
	(segment
		(start 18.177764 -74.719688)
		(end 17.9578 -74.939652)
		(width 0.1143)
		(layer "In6.Cu")
		(net "SMB_BMC_NODE1_DDC_CLK")
	)
	(segment
		(start 17.03832 -77.56779)
		(end 17.24152 -77.77099)
		(width 0.1143)
		(layer "In6.Cu")
		(net "SMB_BMC_NODE1_DDC_CLK")
	)
	(segment
		(start 16.85036 -141.412722)
		(end 19.775424 -141.412722)
		(width 0.1143)
		(layer "In6.Cu")
		(net "SMB_BMC_NODE1_DDC_CLK")
	)
	(segment
		(start 19.20748 -71.411846)
		(end 18.988024 -71.631302)
		(width 0.1143)
		(layer "In6.Cu")
		(net "SMB_BMC_NODE1_DDC_CLK")
	)
	(segment
		(start 17.913096 -70.882002)
		(end 18.988024 -70.882002)
		(width 0.1143)
		(layer "In6.Cu")
		(net "SMB_BMC_NODE1_DDC_CLK")
	)
	(segment
		(start 15.903956 -78.31709)
		(end 15.6845 -78.536546)
		(width 0.1143)
		(layer "In6.Cu")
		(net "SMB_BMC_NODE1_DDC_CLK")
	)
	(segment
		(start 52.29225 -149.741636)
		(end 54.607968 -149.741636)
		(width 0.1143)
		(layer "In6.Cu")
		(net "SMB_BMC_NODE1_DDC_CLK")
	)
	(segment
		(start 15.6845 -87.733124)
		(end 12.06754 -91.350084)
		(width 0.1143)
		(layer "In6.Cu")
		(net "SMB_BMC_NODE1_DDC_CLK")
	)
	(segment
		(start 17.24152 -77.77099)
		(end 17.24152 -78.11389)
		(width 0.1143)
		(layer "In6.Cu")
		(net "SMB_BMC_NODE1_DDC_CLK")
	)
	(segment
		(start 18.02638 -68.854828)
		(end 20.8915 -68.854828)
		(width 0.1143)
		(layer "In6.Cu")
		(net "SMB_BMC_NODE1_DDC_CLK")
	)
	(segment
		(start 39.56939 -148.60016)
		(end 39.735252 -148.766022)
		(width 0.1143)
		(layer "In6.Cu")
		(net "SMB_BMC_NODE1_DDC_CLK")
	)
	(segment
		(start 17.64792 -74.939652)
		(end 16.688308 -73.979786)
		(width 0.1143)
		(layer "In6.Cu")
		(net "SMB_BMC_NODE1_DDC_CLK")
	)
	(segment
		(start 15.903956 -77.56779)
		(end 17.03832 -77.56779)
		(width 0.1143)
		(layer "In6.Cu")
		(net "SMB_BMC_NODE1_DDC_CLK")
	)
	(segment
		(start 15.6845 -77.348334)
		(end 15.903956 -77.56779)
		(width 0.1143)
		(layer "In6.Cu")
		(net "SMB_BMC_NODE1_DDC_CLK")
	)
	(segment
		(start 18.73758 -76.27239)
		(end 18.73758 -76.61529)
		(width 0.1143)
		(layer "In6.Cu")
		(net "SMB_BMC_NODE1_DDC_CLK")
	)
	(segment
		(start 17.9578 -65.460118)
		(end 17.7546 -65.663318)
		(width 0.1143)
		(layer "In6.Cu")
		(net "SMB_BMC_NODE1_DDC_CLK")
	)
	(segment
		(start 18.988024 -70.882002)
		(end 19.20748 -71.101458)
		(width 0.1143)
		(layer "In6.Cu")
		(net "SMB_BMC_NODE1_DDC_CLK")
	)
	(segment
		(start 17.69364 -69.728588)
		(end 17.69364 -70.662546)
		(width 0.1143)
		(layer "In6.Cu")
		(net "SMB_BMC_NODE1_DDC_CLK")
	)
	(segment
		(start 18.73758 -76.61529)
		(end 18.53438 -76.81849)
		(width 0.1143)
		(layer "In6.Cu")
		(net "SMB_BMC_NODE1_DDC_CLK")
	)
	(segment
		(start 61.682376 -145.800572)
		(end 61.775086 -145.800572)
		(width 0.1143)
		(layer "In6.Cu")
		(net "SMB_BMC_NODE1_DDC_CLK")
	)
	(segment
		(start 19.576288 -67.575684)
		(end 19.576288 -67.886072)
		(width 0.1143)
		(layer "In6.Cu")
		(net "SMB_BMC_NODE1_DDC_CLK")
	)
	(segment
		(start 39.789608 -148.766022)
		(end 40.37838 -149.354794)
		(width 0.1143)
		(layer "In6.Cu")
		(net "SMB_BMC_NODE1_DDC_CLK")
	)
	(segment
		(start 15.903956 -76.81849)
		(end 15.6845 -77.037946)
		(width 0.1143)
		(layer "In6.Cu")
		(net "SMB_BMC_NODE1_DDC_CLK")
	)
	(segment
		(start 17.69364 -72.664574)
		(end 17.218406 -73.139808)
		(width 0.1143)
		(layer "In6.Cu")
		(net "SMB_BMC_NODE1_DDC_CLK")
	)
	(segment
		(start 51.802538 -150.231348)
		(end 52.29225 -149.741636)
		(width 0.1143)
		(layer "In6.Cu")
		(net "SMB_BMC_NODE1_DDC_CLK")
	)
	(segment
		(start 15.6845 -78.536546)
		(end 15.6845 -87.733124)
		(width 0.1143)
		(layer "In6.Cu")
		(net "SMB_BMC_NODE1_DDC_CLK")
	)
	(segment
		(start 15.6845 -74.673714)
		(end 15.6845 -75.849734)
		(width 0.1143)
		(layer "In6.Cu")
		(net "SMB_BMC_NODE1_DDC_CLK")
	)
	(segment
		(start 12.11072 -139.841478)
		(end 12.55268 -140.283438)
		(width 0.1143)
		(layer "In6.Cu")
		(net "SMB_BMC_NODE1_DDC_CLK")
	)
	(segment
		(start 41.34358 -150.474426)
		(end 49.068482 -150.474426)
		(width 0.1143)
		(layer "In6.Cu")
		(net "SMB_BMC_NODE1_DDC_CLK")
	)
	(segment
		(start 21.77542 -141.881098)
		(end 22.07768 -141.578838)
		(width 0.1143)
		(layer "In6.Cu")
		(net "SMB_BMC_NODE1_DDC_CLK")
	)
	(segment
		(start 20.61591 -65.460118)
		(end 17.9578 -65.460118)
		(width 0.1143)
		(layer "In6.Cu")
		(net "SMB_BMC_NODE1_DDC_CLK")
	)
	(segment
		(start 35.886898 -147.297648)
		(end 38.266878 -147.297648)
		(width 0.1143)
		(layer "In6.Cu")
		(net "SMB_BMC_NODE1_DDC_CLK")
	)
	(segment
		(start 17.9578 -74.939652)
		(end 17.64792 -74.939652)
		(width 0.1143)
		(layer "In6.Cu")
		(net "SMB_BMC_NODE1_DDC_CLK")
	)
	(segment
		(start 12.06754 -91.350084)
		(end 12.06754 -91.391232)
		(width 0.1143)
		(layer "In6.Cu")
		(net "SMB_BMC_NODE1_DDC_CLK")
	)
	(segment
		(start 39.56304 -148.60016)
		(end 39.56939 -148.60016)
		(width 0.1143)
		(layer "In6.Cu")
		(net "SMB_BMC_NODE1_DDC_CLK")
	)
	(segment
		(start 17.218406 -73.450196)
		(end 18.177764 -74.409554)
		(width 0.1143)
		(layer "In6.Cu")
		(net "SMB_BMC_NODE1_DDC_CLK")
	)
	(segment
		(start 49.31156 -150.231348)
		(end 51.802538 -150.231348)
		(width 0.1143)
		(layer "In6.Cu")
		(net "SMB_BMC_NODE1_DDC_CLK")
	)
	(segment
		(start 40.37838 -149.509226)
		(end 41.34358 -150.474426)
		(width 0.1143)
		(layer "In6.Cu")
		(net "SMB_BMC_NODE1_DDC_CLK")
	)
	(segment
		(start 39.735252 -148.766022)
		(end 39.789608 -148.766022)
		(width 0.1143)
		(layer "In6.Cu")
		(net "SMB_BMC_NODE1_DDC_CLK")
	)
	(segment
		(start 15.6845 -77.037946)
		(end 15.6845 -77.348334)
		(width 0.1143)
		(layer "In6.Cu")
		(net "SMB_BMC_NODE1_DDC_CLK")
	)
	(segment
		(start 17.7546 -65.663318)
		(end 17.7546 -67.153028)
		(width 0.1143)
		(layer "In6.Cu")
		(net "SMB_BMC_NODE1_DDC_CLK")
	)
	(segment
		(start 18.988024 -71.631302)
		(end 17.913096 -71.631302)
		(width 0.1143)
		(layer "In6.Cu")
		(net "SMB_BMC_NODE1_DDC_CLK")
	)
	(segment
		(start 39.3065 -148.34362)
		(end 39.56304 -148.60016)
		(width 0.1143)
		(layer "In6.Cu")
		(net "SMB_BMC_NODE1_DDC_CLK")
	)
	(segment
		(start 18.02638 -68.105528)
		(end 17.82318 -68.308728)
		(width 0.1143)
		(layer "In6.Cu")
		(net "SMB_BMC_NODE1_DDC_CLK")
	)
	(segment
		(start 55.65394 -148.695664)
		(end 58.787284 -148.695664)
		(width 0.1143)
		(layer "In6.Cu")
		(net "SMB_BMC_NODE1_DDC_CLK")
	)
	(segment
		(start 19.356832 -68.105528)
		(end 18.02638 -68.105528)
		(width 0.1143)
		(layer "In6.Cu")
		(net "SMB_BMC_NODE1_DDC_CLK")
	)
	(segment
		(start 19.20748 -71.101458)
		(end 19.20748 -71.411846)
		(width 0.1143)
		(layer "In6.Cu")
		(net "SMB_BMC_NODE1_DDC_CLK")
	)
	(segment
		(start 12.11072 -139.839192)
		(end 12.11072 -139.841478)
		(width 0.1143)
		(layer "In6.Cu")
		(net "SMB_BMC_NODE1_DDC_CLK")
	)
	(segment
		(start 19.356832 -67.356228)
		(end 19.576288 -67.575684)
		(width 0.1143)
		(layer "In6.Cu")
		(net "SMB_BMC_NODE1_DDC_CLK")
	)
	(segment
		(start 12.06754 -91.391232)
		(end 6.5659 -96.892872)
		(width 0.1143)
		(layer "In6.Cu")
		(net "SMB_BMC_NODE1_DDC_CLK")
	)
	(segment
		(start 69.821044 -68.324222)
		(end 69.821044 -68.351654)
		(width 0.1016)
		(layer "F.Cu")
		(net "M1_DQ_NODE1_DQ44")
	)
	(segment
		(start 69.821044 -68.351654)
		(end 69.454776 -68.717922)
		(width 0.1016)
		(layer "F.Cu")
		(net "M1_DQ_NODE1_DQ44")
	)
	(segment
		(start 86.85022 -29.149802)
		(end 86.85022 -27.889708)
		(width 0.1651)
		(layer "F.Cu")
		(net "M1_DQ_NODE1_DQ44")
	)
	(segment
		(start 87.14486 -27.595068)
		(end 87.14486 -26.556716)
		(width 0.1651)
		(layer "F.Cu")
		(net "M1_DQ_NODE1_DQ44")
	)
	(segment
		(start 86.85022 -27.889708)
		(end 87.14486 -27.595068)
		(width 0.1651)
		(layer "F.Cu")
		(net "M1_DQ_NODE1_DQ44")
	)
	(segment
		(start 87.14486 -26.556716)
		(end 86.4743 -25.886156)
		(width 0.1651)
		(layer "F.Cu")
		(net "M1_DQ_NODE1_DQ44")
	)
	(via
		(at 86.4743 -25.886156)
		(size 0.508)
		(drill 0.254)
		(layers "F.Cu" "B.Cu")
		(net "M1_DQ_NODE1_DQ44")
	)
	(via
		(at 69.454776 -68.717922)
		(size 0.508)
		(drill 0.254)
		(layers "F.Cu" "B.Cu")
		(net "M1_DQ_NODE1_DQ44")
	)
	(segment
		(start 86.31428 -39.262812)
		(end 86.11108 -39.466012)
		(width 0.2032)
		(layer "In2.Cu")
		(net "M1_DQ_NODE1_DQ44")
	)
	(segment
		(start 86.11108 -41.849294)
		(end 85.9028 -42.057574)
		(width 0.2032)
		(layer "In2.Cu")
		(net "M1_DQ_NODE1_DQ44")
	)
	(segment
		(start 85.60816 -42.768774)
		(end 86.614 -42.768774)
		(width 0.2032)
		(layer "In2.Cu")
		(net "M1_DQ_NODE1_DQ44")
	)
	(segment
		(start 76.867004 -56.068722)
		(end 85.39988 -47.535846)
		(width 0.2032)
		(layer "In2.Cu")
		(net "M1_DQ_NODE1_DQ44")
	)
	(segment
		(start 69.30771 -68.570856)
		(end 69.137022 -68.570856)
		(width 0.1016)
		(layer "In2.Cu")
		(net "M1_DQ_NODE1_DQ44")
	)
	(segment
		(start 67.830446 -66.429636)
		(end 67.41668 -66.01587)
		(width 0.1016)
		(layer "In2.Cu")
		(net "M1_DQ_NODE1_DQ44")
	)
	(segment
		(start 70.07606 -62.113668)
		(end 70.07606 -61.764164)
		(width 0.2032)
		(layer "In2.Cu")
		(net "M1_DQ_NODE1_DQ44")
	)
	(segment
		(start 69.137022 -68.570856)
		(end 67.830446 -67.26428)
		(width 0.1016)
		(layer "In2.Cu")
		(net "M1_DQ_NODE1_DQ44")
	)
	(segment
		(start 86.61908 -39.262812)
		(end 86.31428 -39.262812)
		(width 0.2032)
		(layer "In2.Cu")
		(net "M1_DQ_NODE1_DQ44")
	)
	(segment
		(start 85.39988 -30.047438)
		(end 87.440262 -28.007056)
		(width 0.2032)
		(layer "In2.Cu")
		(net "M1_DQ_NODE1_DQ44")
	)
	(segment
		(start 87.440262 -26.852118)
		(end 86.4743 -25.886156)
		(width 0.2032)
		(layer "In2.Cu")
		(net "M1_DQ_NODE1_DQ44")
	)
	(segment
		(start 67.830446 -67.26428)
		(end 67.830446 -66.429636)
		(width 0.1016)
		(layer "In2.Cu")
		(net "M1_DQ_NODE1_DQ44")
	)
	(segment
		(start 76.0349 -56.068722)
		(end 76.867004 -56.068722)
		(width 0.2032)
		(layer "In2.Cu")
		(net "M1_DQ_NODE1_DQ44")
	)
	(segment
		(start 69.09689 -63.092838)
		(end 70.07606 -62.113668)
		(width 0.2032)
		(layer "In2.Cu")
		(net "M1_DQ_NODE1_DQ44")
	)
	(segment
		(start 86.11108 -39.466012)
		(end 86.11108 -41.849294)
		(width 0.2032)
		(layer "In2.Cu")
		(net "M1_DQ_NODE1_DQ44")
	)
	(segment
		(start 85.9028 -42.057574)
		(end 85.60816 -42.057574)
		(width 0.2032)
		(layer "In2.Cu")
		(net "M1_DQ_NODE1_DQ44")
	)
	(segment
		(start 85.60816 -42.057574)
		(end 85.39988 -41.849294)
		(width 0.2032)
		(layer "In2.Cu")
		(net "M1_DQ_NODE1_DQ44")
	)
	(segment
		(start 69.454776 -68.717922)
		(end 69.30771 -68.570856)
		(width 0.1016)
		(layer "In2.Cu")
		(net "M1_DQ_NODE1_DQ44")
	)
	(segment
		(start 70.709028 -61.131196)
		(end 70.972426 -61.131196)
		(width 0.2032)
		(layer "In2.Cu")
		(net "M1_DQ_NODE1_DQ44")
	)
	(segment
		(start 85.39988 -42.977054)
		(end 85.60816 -42.768774)
		(width 0.2032)
		(layer "In2.Cu")
		(net "M1_DQ_NODE1_DQ44")
	)
	(segment
		(start 86.82228 -42.560494)
		(end 86.82228 -39.466012)
		(width 0.2032)
		(layer "In2.Cu")
		(net "M1_DQ_NODE1_DQ44")
	)
	(segment
		(start 70.07606 -61.764164)
		(end 70.709028 -61.131196)
		(width 0.2032)
		(layer "In2.Cu")
		(net "M1_DQ_NODE1_DQ44")
	)
	(segment
		(start 67.41668 -66.01587)
		(end 67.41668 -64.441324)
		(width 0.1016)
		(layer "In2.Cu")
		(net "M1_DQ_NODE1_DQ44")
	)
	(segment
		(start 85.39988 -47.535846)
		(end 85.39988 -42.977054)
		(width 0.2032)
		(layer "In2.Cu")
		(net "M1_DQ_NODE1_DQ44")
	)
	(segment
		(start 87.440262 -28.007056)
		(end 87.440262 -26.852118)
		(width 0.2032)
		(layer "In2.Cu")
		(net "M1_DQ_NODE1_DQ44")
	)
	(segment
		(start 68.19265 -63.665354)
		(end 68.524374 -63.665354)
		(width 0.1016)
		(layer "In2.Cu")
		(net "M1_DQ_NODE1_DQ44")
	)
	(segment
		(start 70.972426 -61.131196)
		(end 76.0349 -56.068722)
		(width 0.2032)
		(layer "In2.Cu")
		(net "M1_DQ_NODE1_DQ44")
	)
	(segment
		(start 85.39988 -41.849294)
		(end 85.39988 -30.047438)
		(width 0.2032)
		(layer "In2.Cu")
		(net "M1_DQ_NODE1_DQ44")
	)
	(segment
		(start 86.614 -42.768774)
		(end 86.82228 -42.560494)
		(width 0.2032)
		(layer "In2.Cu")
		(net "M1_DQ_NODE1_DQ44")
	)
	(segment
		(start 67.41668 -64.441324)
		(end 68.19265 -63.665354)
		(width 0.1016)
		(layer "In2.Cu")
		(net "M1_DQ_NODE1_DQ44")
	)
	(segment
		(start 86.82228 -39.466012)
		(end 86.61908 -39.262812)
		(width 0.2032)
		(layer "In2.Cu")
		(net "M1_DQ_NODE1_DQ44")
	)
	(segment
		(start 68.524374 -63.665354)
		(end 69.09689 -63.092838)
		(width 0.1016)
		(layer "In2.Cu")
		(net "M1_DQ_NODE1_DQ44")
	)
	(via
		(at 50.078894 -118.269512)
		(size 0.508)
		(drill 0.254)
		(layers "F.Cu" "B.Cu")
		(net "BMC_NODE1_OSC1_VDD")
	)
	(segment
		(start 58.519568 -88.650826)
		(end 58.519568 -89.351358)
		(width 0.1016)
		(layer "F.Cu")
		(net "PD_CPU_NODE1_DFX_GPIO_GRP1_4")
	)
	(segment
		(start 58.536078 -89.367868)
		(end 58.536078 -90.099896)
		(width 0.1016)
		(layer "F.Cu")
		(net "PD_CPU_NODE1_DFX_GPIO_GRP1_4")
	)
	(segment
		(start 58.519568 -89.351358)
		(end 58.536078 -89.367868)
		(width 0.1016)
		(layer "F.Cu")
		(net "PD_CPU_NODE1_DFX_GPIO_GRP1_4")
	)
	(segment
		(start 58.536078 -90.099896)
		(end 58.485278 -90.150696)
		(width 0.1016)
		(layer "F.Cu")
		(net "PD_CPU_NODE1_DFX_GPIO_GRP1_4")
	)
	(segment
		(start 58.292238 -91.430348)
		(end 58.292238 -92.311474)
		(width 0.1016)
		(layer "F.Cu")
		(net "PD_CPU_NODE1_DFX_GPIO_GRP1_4")
	)
	(segment
		(start 58.485278 -91.237308)
		(end 58.292238 -91.430348)
		(width 0.1016)
		(layer "F.Cu")
		(net "PD_CPU_NODE1_DFX_GPIO_GRP1_4")
	)
	(segment
		(start 59.216544 -93.961966)
		(end 59.216544 -93.23578)
		(width 0.1016)
		(layer "F.Cu")
		(net "PD_CPU_NODE1_DFX_GPIO_GRP1_4")
	)
	(segment
		(start 61.145166 -95.890588)
		(end 59.216544 -93.961966)
		(width 0.1016)
		(layer "F.Cu")
		(net "PD_CPU_NODE1_DFX_GPIO_GRP1_4")
	)
	(segment
		(start 61.145166 -96.309942)
		(end 61.145166 -95.890588)
		(width 0.1016)
		(layer "F.Cu")
		(net "PD_CPU_NODE1_DFX_GPIO_GRP1_4")
	)
	(segment
		(start 58.618628 -88.551766)
		(end 58.519568 -88.650826)
		(width 0.1016)
		(layer "F.Cu")
		(net "PD_CPU_NODE1_DFX_GPIO_GRP1_4")
	)
	(segment
		(start 58.485278 -90.150696)
		(end 58.485278 -91.237308)
		(width 0.1016)
		(layer "F.Cu")
		(net "PD_CPU_NODE1_DFX_GPIO_GRP1_4")
	)
	(segment
		(start 58.292238 -92.311474)
		(end 59.216544 -93.23578)
		(width 0.1016)
		(layer "F.Cu")
		(net "PD_CPU_NODE1_DFX_GPIO_GRP1_4")
	)
	(via
		(at 59.216544 -93.23578)
		(size 0.508)
		(drill 0.254)
		(layers "F.Cu" "B.Cu")
		(net "PD_CPU_NODE1_DFX_GPIO_GRP1_4")
	)
	(segment
		(start 77.2414 -73.237852)
		(end 77.2414 -72.990964)
		(width 0.09906)
		(layer "F.Cu")
		(net "M_DDR3_NODE1_DQS7P")
	)
	(segment
		(start 77.368146 -72.864218)
		(end 77.503528 -72.864218)
		(width 0.09906)
		(layer "F.Cu")
		(net "M_DDR3_NODE1_DQS7P")
	)
	(segment
		(start 98.696272 -30.676088)
		(end 98.696272 -30.504892)
		(width 0.1651)
		(layer "F.Cu")
		(net "M_DDR3_NODE1_DQS7P")
	)
	(segment
		(start 73.30567 -73.733152)
		(end 76.7461 -73.733152)
		(width 0.09906)
		(layer "F.Cu")
		(net "M_DDR3_NODE1_DQS7P")
	)
	(segment
		(start 98.696272 -30.504892)
		(end 98.850196 -30.350968)
		(width 0.1651)
		(layer "F.Cu")
		(net "M_DDR3_NODE1_DQS7P")
	)
	(segment
		(start 100.625402 -32.13862)
		(end 100.625402 -31.745936)
		(width 0.1651)
		(layer "F.Cu")
		(net "M_DDR3_NODE1_DQS7P")
	)
	(segment
		(start 101.114352 -32.62757)
		(end 100.625402 -32.13862)
		(width 0.1651)
		(layer "F.Cu")
		(net "M_DDR3_NODE1_DQS7P")
	)
	(segment
		(start 99.218242 -31.198058)
		(end 98.696272 -30.676088)
		(width 0.1651)
		(layer "F.Cu")
		(net "M_DDR3_NODE1_DQS7P")
	)
	(segment
		(start 73.011538 -73.3044)
		(end 73.011538 -73.43902)
		(width 0.09906)
		(layer "F.Cu")
		(net "M_DDR3_NODE1_DQS7P")
	)
	(segment
		(start 72.901556 -73.194418)
		(end 73.011538 -73.3044)
		(width 0.09906)
		(layer "F.Cu")
		(net "M_DDR3_NODE1_DQS7P")
	)
	(segment
		(start 98.850196 -30.350968)
		(end 98.850196 -29.149802)
		(width 0.1651)
		(layer "F.Cu")
		(net "M_DDR3_NODE1_DQS7P")
	)
	(segment
		(start 100.077524 -31.198058)
		(end 99.218242 -31.198058)
		(width 0.1651)
		(layer "F.Cu")
		(net "M_DDR3_NODE1_DQS7P")
	)
	(segment
		(start 76.7461 -73.733152)
		(end 77.2414 -73.237852)
		(width 0.09906)
		(layer "F.Cu")
		(net "M_DDR3_NODE1_DQS7P")
	)
	(segment
		(start 73.011538 -73.43902)
		(end 73.30567 -73.733152)
		(width 0.09906)
		(layer "F.Cu")
		(net "M_DDR3_NODE1_DQS7P")
	)
	(segment
		(start 100.625402 -31.745936)
		(end 100.077524 -31.198058)
		(width 0.1651)
		(layer "F.Cu")
		(net "M_DDR3_NODE1_DQS7P")
	)
	(segment
		(start 77.2414 -72.990964)
		(end 77.368146 -72.864218)
		(width 0.09906)
		(layer "F.Cu")
		(net "M_DDR3_NODE1_DQS7P")
	)
	(via
		(at 77.503528 -72.864218)
		(size 0.508)
		(drill 0.254)
		(layers "F.Cu" "B.Cu")
		(net "M_DDR3_NODE1_DQS7P")
	)
	(via
		(at 101.114352 -32.62757)
		(size 0.508)
		(drill 0.254)
		(layers "F.Cu" "B.Cu")
		(net "M_DDR3_NODE1_DQS7P")
	)
	(segment
		(start 100.47478 -36.809426)
		(end 102.440232 -36.809426)
		(width 0.2032)
		(layer "In7.Cu")
		(net "M_DDR3_NODE1_DQS7P")
	)
	(segment
		(start 94.30512 -62.451996)
		(end 94.30512 -61.538612)
		(width 0.2032)
		(layer "In7.Cu")
		(net "M_DDR3_NODE1_DQS7P")
	)
	(segment
		(start 94.30512 -60.024264)
		(end 94.30512 -56.20893)
		(width 0.2032)
		(layer "In7.Cu")
		(net "M_DDR3_NODE1_DQS7P")
	)
	(segment
		(start 102.84206 -35.839654)
		(end 102.440232 -35.437826)
		(width 0.2032)
		(layer "In7.Cu")
		(net "M_DDR3_NODE1_DQS7P")
	)
	(segment
		(start 101.261926 -37.520626)
		(end 100.47478 -37.520626)
		(width 0.2032)
		(layer "In7.Cu")
		(net "M_DDR3_NODE1_DQS7P")
	)
	(segment
		(start 100.47478 -37.520626)
		(end 100.2665 -37.312346)
		(width 0.2032)
		(layer "In7.Cu")
		(net "M_DDR3_NODE1_DQS7P")
	)
	(segment
		(start 94.30512 -56.20893)
		(end 100.2665 -50.24755)
		(width 0.2032)
		(layer "In7.Cu")
		(net "M_DDR3_NODE1_DQS7P")
	)
	(segment
		(start 101.113844 -32.62757)
		(end 101.114352 -32.62757)
		(width 0.2032)
		(layer "In7.Cu")
		(net "M_DDR3_NODE1_DQS7P")
	)
	(segment
		(start 77.503528 -72.864218)
		(end 77.363574 -72.864218)
		(width 0.09906)
		(layer "In7.Cu")
		(net "M_DDR3_NODE1_DQS7P")
	)
	(segment
		(start 94.30512 -61.538612)
		(end 93.903546 -61.137038)
		(width 0.2032)
		(layer "In7.Cu")
		(net "M_DDR3_NODE1_DQS7P")
	)
	(segment
		(start 100.2665 -34.543492)
		(end 100.66782 -34.142172)
		(width 0.2032)
		(layer "In7.Cu")
		(net "M_DDR3_NODE1_DQS7P")
	)
	(segment
		(start 100.66782 -34.142172)
		(end 100.66782 -33.073594)
		(width 0.2032)
		(layer "In7.Cu")
		(net "M_DDR3_NODE1_DQS7P")
	)
	(segment
		(start 92.93352 -60.024264)
		(end 93.335094 -60.425838)
		(width 0.2032)
		(layer "In7.Cu")
		(net "M_DDR3_NODE1_DQS7P")
	)
	(segment
		(start 89.583768 -65.487804)
		(end 89.878408 -65.487804)
		(width 0.2032)
		(layer "In7.Cu")
		(net "M_DDR3_NODE1_DQS7P")
	)
	(segment
		(start 90.289888 -65.899284)
		(end 90.857832 -65.899284)
		(width 0.2032)
		(layer "In7.Cu")
		(net "M_DDR3_NODE1_DQS7P")
	)
	(segment
		(start 89.375488 -65.696084)
		(end 89.583768 -65.487804)
		(width 0.2032)
		(layer "In7.Cu")
		(net "M_DDR3_NODE1_DQS7P")
	)
	(segment
		(start 100.2665 -37.312346)
		(end 100.2665 -37.017706)
		(width 0.2032)
		(layer "In7.Cu")
		(net "M_DDR3_NODE1_DQS7P")
	)
	(segment
		(start 77.22362 -72.724264)
		(end 77.22362 -72.328024)
		(width 0.09906)
		(layer "In7.Cu")
		(net "M_DDR3_NODE1_DQS7P")
	)
	(segment
		(start 100.2665 -35.229546)
		(end 100.2665 -34.543492)
		(width 0.2032)
		(layer "In7.Cu")
		(net "M_DDR3_NODE1_DQS7P")
	)
	(segment
		(start 100.2665 -39.100506)
		(end 100.47478 -38.892226)
		(width 0.2032)
		(layer "In7.Cu")
		(net "M_DDR3_NODE1_DQS7P")
	)
	(segment
		(start 93.335094 -60.425838)
		(end 93.903546 -60.425838)
		(width 0.2032)
		(layer "In7.Cu")
		(net "M_DDR3_NODE1_DQS7P")
	)
	(segment
		(start 93.903546 -60.425838)
		(end 94.30512 -60.024264)
		(width 0.2032)
		(layer "In7.Cu")
		(net "M_DDR3_NODE1_DQS7P")
	)
	(segment
		(start 100.66782 -33.073594)
		(end 101.113844 -32.62757)
		(width 0.2032)
		(layer "In7.Cu")
		(net "M_DDR3_NODE1_DQS7P")
	)
	(segment
		(start 92.4306 -61.137038)
		(end 92.22232 -60.928758)
		(width 0.2032)
		(layer "In7.Cu")
		(net "M_DDR3_NODE1_DQS7P")
	)
	(segment
		(start 102.84206 -36.407598)
		(end 102.84206 -35.839654)
		(width 0.2032)
		(layer "In7.Cu")
		(net "M_DDR3_NODE1_DQS7P")
	)
	(segment
		(start 92.22232 -57.812686)
		(end 92.4306 -57.604406)
		(width 0.2032)
		(layer "In7.Cu")
		(net "M_DDR3_NODE1_DQS7P")
	)
	(segment
		(start 89.375488 -65.990724)
		(end 89.375488 -65.696084)
		(width 0.2032)
		(layer "In7.Cu")
		(net "M_DDR3_NODE1_DQS7P")
	)
	(segment
		(start 82.34553 -71.05777)
		(end 85.740494 -67.662806)
		(width 0.2032)
		(layer "In7.Cu")
		(net "M_DDR3_NODE1_DQS7P")
	)
	(segment
		(start 101.261926 -38.892226)
		(end 101.6635 -38.490652)
		(width 0.2032)
		(layer "In7.Cu")
		(net "M_DDR3_NODE1_DQS7P")
	)
	(segment
		(start 93.903546 -61.137038)
		(end 92.4306 -61.137038)
		(width 0.2032)
		(layer "In7.Cu")
		(net "M_DDR3_NODE1_DQS7P")
	)
	(segment
		(start 89.09431 -67.662806)
		(end 89.786968 -66.970148)
		(width 0.2032)
		(layer "In7.Cu")
		(net "M_DDR3_NODE1_DQS7P")
	)
	(segment
		(start 79.376016 -71.003668)
		(end 79.430118 -71.05777)
		(width 0.09906)
		(layer "In7.Cu")
		(net "M_DDR3_NODE1_DQS7P")
	)
	(segment
		(start 78.547976 -71.003668)
		(end 79.376016 -71.003668)
		(width 0.09906)
		(layer "In7.Cu")
		(net "M_DDR3_NODE1_DQS7P")
	)
	(segment
		(start 89.786968 -66.402204)
		(end 89.375488 -65.990724)
		(width 0.2032)
		(layer "In7.Cu")
		(net "M_DDR3_NODE1_DQS7P")
	)
	(segment
		(start 100.47478 -38.892226)
		(end 101.261926 -38.892226)
		(width 0.2032)
		(layer "In7.Cu")
		(net "M_DDR3_NODE1_DQS7P")
	)
	(segment
		(start 102.440232 -35.437826)
		(end 100.47478 -35.437826)
		(width 0.2032)
		(layer "In7.Cu")
		(net "M_DDR3_NODE1_DQS7P")
	)
	(segment
		(start 101.6635 -37.9222)
		(end 101.261926 -37.520626)
		(width 0.2032)
		(layer "In7.Cu")
		(net "M_DDR3_NODE1_DQS7P")
	)
	(segment
		(start 90.857832 -65.899284)
		(end 94.30512 -62.451996)
		(width 0.2032)
		(layer "In7.Cu")
		(net "M_DDR3_NODE1_DQS7P")
	)
	(segment
		(start 92.22232 -60.928758)
		(end 92.22232 -57.812686)
		(width 0.2032)
		(layer "In7.Cu")
		(net "M_DDR3_NODE1_DQS7P")
	)
	(segment
		(start 85.740494 -67.662806)
		(end 89.09431 -67.662806)
		(width 0.2032)
		(layer "In7.Cu")
		(net "M_DDR3_NODE1_DQS7P")
	)
	(segment
		(start 92.72524 -57.604406)
		(end 92.93352 -57.812686)
		(width 0.2032)
		(layer "In7.Cu")
		(net "M_DDR3_NODE1_DQS7P")
	)
	(segment
		(start 92.93352 -57.812686)
		(end 92.93352 -60.024264)
		(width 0.2032)
		(layer "In7.Cu")
		(net "M_DDR3_NODE1_DQS7P")
	)
	(segment
		(start 100.2665 -37.017706)
		(end 100.47478 -36.809426)
		(width 0.2032)
		(layer "In7.Cu")
		(net "M_DDR3_NODE1_DQS7P")
	)
	(segment
		(start 101.6635 -38.490652)
		(end 101.6635 -37.9222)
		(width 0.2032)
		(layer "In7.Cu")
		(net "M_DDR3_NODE1_DQS7P")
	)
	(segment
		(start 89.878408 -65.487804)
		(end 90.289888 -65.899284)
		(width 0.2032)
		(layer "In7.Cu")
		(net "M_DDR3_NODE1_DQS7P")
	)
	(segment
		(start 102.440232 -36.809426)
		(end 102.84206 -36.407598)
		(width 0.2032)
		(layer "In7.Cu")
		(net "M_DDR3_NODE1_DQS7P")
	)
	(segment
		(start 100.2665 -50.24755)
		(end 100.2665 -39.100506)
		(width 0.2032)
		(layer "In7.Cu")
		(net "M_DDR3_NODE1_DQS7P")
	)
	(segment
		(start 92.4306 -57.604406)
		(end 92.72524 -57.604406)
		(width 0.2032)
		(layer "In7.Cu")
		(net "M_DDR3_NODE1_DQS7P")
	)
	(segment
		(start 100.47478 -35.437826)
		(end 100.2665 -35.229546)
		(width 0.2032)
		(layer "In7.Cu")
		(net "M_DDR3_NODE1_DQS7P")
	)
	(segment
		(start 77.363574 -72.864218)
		(end 77.22362 -72.724264)
		(width 0.09906)
		(layer "In7.Cu")
		(net "M_DDR3_NODE1_DQS7P")
	)
	(segment
		(start 77.22362 -72.328024)
		(end 78.547976 -71.003668)
		(width 0.09906)
		(layer "In7.Cu")
		(net "M_DDR3_NODE1_DQS7P")
	)
	(segment
		(start 79.430118 -71.05777)
		(end 82.34553 -71.05777)
		(width 0.2032)
		(layer "In7.Cu")
		(net "M_DDR3_NODE1_DQS7P")
	)
	(segment
		(start 89.786968 -66.970148)
		(end 89.786968 -66.402204)
		(width 0.2032)
		(layer "In7.Cu")
		(net "M_DDR3_NODE1_DQS7P")
	)
	(segment
		(start 69.688202 -65.54851)
		(end 69.205856 -66.030856)
		(width 0.1016)
		(layer "F.Cu")
		(net "M1_DQ_NODE1_DQ46")
	)
	(segment
		(start 69.688202 -65.455038)
		(end 69.688202 -65.54851)
		(width 0.1016)
		(layer "F.Cu")
		(net "M1_DQ_NODE1_DQ46")
	)
	(segment
		(start 90.450162 -27.875738)
		(end 90.029792 -27.455368)
		(width 0.1651)
		(layer "F.Cu")
		(net "M1_DQ_NODE1_DQ46")
	)
	(segment
		(start 90.450162 -29.149802)
		(end 90.450162 -27.875738)
		(width 0.1651)
		(layer "F.Cu")
		(net "M1_DQ_NODE1_DQ46")
	)
	(via
		(at 90.029792 -27.455368)
		(size 0.508)
		(drill 0.254)
		(layers "F.Cu" "B.Cu")
		(net "M1_DQ_NODE1_DQ46")
	)
	(via
		(at 69.205856 -66.030856)
		(size 0.508)
		(drill 0.254)
		(layers "F.Cu" "B.Cu")
		(net "M1_DQ_NODE1_DQ46")
	)
	(segment
		(start 90.716354 -30.480508)
		(end 90.508074 -30.688788)
		(width 0.2032)
		(layer "In2.Cu")
		(net "M1_DQ_NODE1_DQ46")
	)
	(segment
		(start 92.4179 -49.633886)
		(end 81.692242 -60.359544)
		(width 0.2032)
		(layer "In2.Cu")
		(net "M1_DQ_NODE1_DQ46")
	)
	(segment
		(start 92.4179 -44.85259)
		(end 92.74302 -45.17771)
		(width 0.2032)
		(layer "In2.Cu")
		(net "M1_DQ_NODE1_DQ46")
	)
	(segment
		(start 90.90533 -34.541206)
		(end 91.19997 -34.541206)
		(width 0.2032)
		(layer "In2.Cu")
		(net "M1_DQ_NODE1_DQ46")
	)
	(segment
		(start 91.20886 -28.366212)
		(end 91.20886 -28.787344)
		(width 0.2032)
		(layer "In2.Cu")
		(net "M1_DQ_NODE1_DQ46")
	)
	(segment
		(start 92.4179 -45.88891)
		(end 92.4179 -46.27499)
		(width 0.2032)
		(layer "In2.Cu")
		(net "M1_DQ_NODE1_DQ46")
	)
	(segment
		(start 92.74302 -48.02251)
		(end 92.74302 -48.40859)
		(width 0.2032)
		(layer "In2.Cu")
		(net "M1_DQ_NODE1_DQ46")
	)
	(segment
		(start 91.19997 -34.541206)
		(end 91.701112 -34.040064)
		(width 0.2032)
		(layer "In2.Cu")
		(net "M1_DQ_NODE1_DQ46")
	)
	(segment
		(start 69.557646 -66.382646)
		(end 69.205856 -66.030856)
		(width 0.1016)
		(layer "In2.Cu")
		(net "M1_DQ_NODE1_DQ46")
	)
	(segment
		(start 90.508074 -31.399988)
		(end 90.716354 -31.608268)
		(width 0.2032)
		(layer "In2.Cu")
		(net "M1_DQ_NODE1_DQ46")
	)
	(segment
		(start 81.692242 -60.359544)
		(end 78.139036 -60.359544)
		(width 0.2032)
		(layer "In2.Cu")
		(net "M1_DQ_NODE1_DQ46")
	)
	(segment
		(start 91.00566 -28.990544)
		(end 89.7128 -28.990544)
		(width 0.2032)
		(layer "In2.Cu")
		(net "M1_DQ_NODE1_DQ46")
	)
	(segment
		(start 92.74302 -46.98619)
		(end 92.4179 -47.31131)
		(width 0.2032)
		(layer "In2.Cu")
		(net "M1_DQ_NODE1_DQ46")
	)
	(segment
		(start 91.20886 -28.787344)
		(end 91.00566 -28.990544)
		(width 0.2032)
		(layer "In2.Cu")
		(net "M1_DQ_NODE1_DQ46")
	)
	(segment
		(start 71.510398 -67.201288)
		(end 71.097902 -66.788792)
		(width 0.1016)
		(layer "In2.Cu")
		(net "M1_DQ_NODE1_DQ46")
	)
	(segment
		(start 92.4179 -47.69739)
		(end 92.74302 -48.02251)
		(width 0.2032)
		(layer "In2.Cu")
		(net "M1_DQ_NODE1_DQ46")
	)
	(segment
		(start 92.4179 -34.462212)
		(end 92.4179 -44.85259)
		(width 0.2032)
		(layer "In2.Cu")
		(net "M1_DQ_NODE1_DQ46")
	)
	(segment
		(start 77.22362 -61.27496)
		(end 77.22362 -61.288422)
		(width 0.2032)
		(layer "In2.Cu")
		(net "M1_DQ_NODE1_DQ46")
	)
	(segment
		(start 92.4179 -48.73371)
		(end 92.4179 -49.633886)
		(width 0.2032)
		(layer "In2.Cu")
		(net "M1_DQ_NODE1_DQ46")
	)
	(segment
		(start 89.7128 -29.701744)
		(end 90.508074 -29.701744)
		(width 0.2032)
		(layer "In2.Cu")
		(net "M1_DQ_NODE1_DQ46")
	)
	(segment
		(start 92.74302 -48.40859)
		(end 92.4179 -48.73371)
		(width 0.2032)
		(layer "In2.Cu")
		(net "M1_DQ_NODE1_DQ46")
	)
	(segment
		(start 89.7128 -28.990544)
		(end 89.50452 -29.198824)
		(width 0.2032)
		(layer "In2.Cu")
		(net "M1_DQ_NODE1_DQ46")
	)
	(segment
		(start 90.508074 -30.688788)
		(end 89.76106 -30.688788)
		(width 0.2032)
		(layer "In2.Cu")
		(net "M1_DQ_NODE1_DQ46")
	)
	(segment
		(start 74.66076 -63.217044)
		(end 74.66076 -64.836802)
		(width 0.2032)
		(layer "In2.Cu")
		(net "M1_DQ_NODE1_DQ46")
	)
	(segment
		(start 89.76106 -31.399988)
		(end 90.508074 -31.399988)
		(width 0.2032)
		(layer "In2.Cu")
		(net "M1_DQ_NODE1_DQ46")
	)
	(segment
		(start 91.198192 -33.537144)
		(end 90.69705 -34.038286)
		(width 0.2032)
		(layer "In2.Cu")
		(net "M1_DQ_NODE1_DQ46")
	)
	(segment
		(start 90.508074 -29.701744)
		(end 90.716354 -29.910024)
		(width 0.2032)
		(layer "In2.Cu")
		(net "M1_DQ_NODE1_DQ46")
	)
	(segment
		(start 92.74302 -45.17771)
		(end 92.74302 -45.56379)
		(width 0.2032)
		(layer "In2.Cu")
		(net "M1_DQ_NODE1_DQ46")
	)
	(segment
		(start 89.55278 -31.191708)
		(end 89.76106 -31.399988)
		(width 0.2032)
		(layer "In2.Cu")
		(net "M1_DQ_NODE1_DQ46")
	)
	(segment
		(start 92.4179 -46.27499)
		(end 92.74302 -46.60011)
		(width 0.2032)
		(layer "In2.Cu")
		(net "M1_DQ_NODE1_DQ46")
	)
	(segment
		(start 74.66076 -64.836802)
		(end 73.805288 -65.692274)
		(width 0.2032)
		(layer "In2.Cu")
		(net "M1_DQ_NODE1_DQ46")
	)
	(segment
		(start 89.55278 -30.897068)
		(end 89.55278 -31.191708)
		(width 0.2032)
		(layer "In2.Cu")
		(net "M1_DQ_NODE1_DQ46")
	)
	(segment
		(start 75.613768 -62.264036)
		(end 74.66076 -63.217044)
		(width 0.2032)
		(layer "In2.Cu")
		(net "M1_DQ_NODE1_DQ46")
	)
	(segment
		(start 91.701112 -34.040064)
		(end 91.995752 -34.040064)
		(width 0.2032)
		(layer "In2.Cu")
		(net "M1_DQ_NODE1_DQ46")
	)
	(segment
		(start 90.716354 -32.760666)
		(end 91.198192 -33.242504)
		(width 0.2032)
		(layer "In2.Cu")
		(net "M1_DQ_NODE1_DQ46")
	)
	(segment
		(start 92.4179 -47.31131)
		(end 92.4179 -47.69739)
		(width 0.2032)
		(layer "In2.Cu")
		(net "M1_DQ_NODE1_DQ46")
	)
	(segment
		(start 71.097902 -66.788792)
		(end 69.963284 -66.788792)
		(width 0.1016)
		(layer "In2.Cu")
		(net "M1_DQ_NODE1_DQ46")
	)
	(segment
		(start 90.165428 -28.163012)
		(end 91.00566 -28.163012)
		(width 0.2032)
		(layer "In2.Cu")
		(net "M1_DQ_NODE1_DQ46")
	)
	(segment
		(start 91.198192 -33.242504)
		(end 91.198192 -33.537144)
		(width 0.2032)
		(layer "In2.Cu")
		(net "M1_DQ_NODE1_DQ46")
	)
	(segment
		(start 90.029792 -27.455368)
		(end 90.029792 -28.027376)
		(width 0.2032)
		(layer "In2.Cu")
		(net "M1_DQ_NODE1_DQ46")
	)
	(segment
		(start 78.139036 -60.359544)
		(end 77.22362 -61.27496)
		(width 0.2032)
		(layer "In2.Cu")
		(net "M1_DQ_NODE1_DQ46")
	)
	(segment
		(start 89.50452 -29.198824)
		(end 89.50452 -29.493464)
		(width 0.2032)
		(layer "In2.Cu")
		(net "M1_DQ_NODE1_DQ46")
	)
	(segment
		(start 90.69705 -34.332926)
		(end 90.90533 -34.541206)
		(width 0.2032)
		(layer "In2.Cu")
		(net "M1_DQ_NODE1_DQ46")
	)
	(segment
		(start 90.69705 -34.038286)
		(end 90.69705 -34.332926)
		(width 0.2032)
		(layer "In2.Cu")
		(net "M1_DQ_NODE1_DQ46")
	)
	(segment
		(start 77.22362 -61.288422)
		(end 76.248006 -62.264036)
		(width 0.2032)
		(layer "In2.Cu")
		(net "M1_DQ_NODE1_DQ46")
	)
	(segment
		(start 91.00566 -28.163012)
		(end 91.20886 -28.366212)
		(width 0.2032)
		(layer "In2.Cu")
		(net "M1_DQ_NODE1_DQ46")
	)
	(segment
		(start 92.74302 -45.56379)
		(end 92.4179 -45.88891)
		(width 0.2032)
		(layer "In2.Cu")
		(net "M1_DQ_NODE1_DQ46")
	)
	(segment
		(start 69.963284 -66.788792)
		(end 69.557646 -66.383154)
		(width 0.1016)
		(layer "In2.Cu")
		(net "M1_DQ_NODE1_DQ46")
	)
	(segment
		(start 90.716354 -29.910024)
		(end 90.716354 -30.480508)
		(width 0.2032)
		(layer "In2.Cu")
		(net "M1_DQ_NODE1_DQ46")
	)
	(segment
		(start 69.557646 -66.383154)
		(end 69.557646 -66.382646)
		(width 0.1016)
		(layer "In2.Cu")
		(net "M1_DQ_NODE1_DQ46")
	)
	(segment
		(start 71.839836 -67.201288)
		(end 71.510398 -67.201288)
		(width 0.1016)
		(layer "In2.Cu")
		(net "M1_DQ_NODE1_DQ46")
	)
	(segment
		(start 73.805288 -65.692274)
		(end 73.34885 -65.692274)
		(width 0.2032)
		(layer "In2.Cu")
		(net "M1_DQ_NODE1_DQ46")
	)
	(segment
		(start 90.716354 -31.608268)
		(end 90.716354 -32.760666)
		(width 0.2032)
		(layer "In2.Cu")
		(net "M1_DQ_NODE1_DQ46")
	)
	(segment
		(start 73.34885 -65.692274)
		(end 71.839836 -67.201288)
		(width 0.1016)
		(layer "In2.Cu")
		(net "M1_DQ_NODE1_DQ46")
	)
	(segment
		(start 91.995752 -34.040064)
		(end 92.4179 -34.462212)
		(width 0.2032)
		(layer "In2.Cu")
		(net "M1_DQ_NODE1_DQ46")
	)
	(segment
		(start 92.74302 -46.60011)
		(end 92.74302 -46.98619)
		(width 0.2032)
		(layer "In2.Cu")
		(net "M1_DQ_NODE1_DQ46")
	)
	(segment
		(start 89.50452 -29.493464)
		(end 89.7128 -29.701744)
		(width 0.2032)
		(layer "In2.Cu")
		(net "M1_DQ_NODE1_DQ46")
	)
	(segment
		(start 90.029792 -28.027376)
		(end 90.165428 -28.163012)
		(width 0.2032)
		(layer "In2.Cu")
		(net "M1_DQ_NODE1_DQ46")
	)
	(segment
		(start 89.76106 -30.688788)
		(end 89.55278 -30.897068)
		(width 0.2032)
		(layer "In2.Cu")
		(net "M1_DQ_NODE1_DQ46")
	)
	(segment
		(start 76.248006 -62.264036)
		(end 75.613768 -62.264036)
		(width 0.2032)
		(layer "In2.Cu")
		(net "M1_DQ_NODE1_DQ46")
	)
	(via
		(at 51.964336 -117.469412)
		(size 0.508)
		(drill 0.254)
		(layers "F.Cu" "B.Cu")
		(net "BMC_NODE1_OSC1_EN")
	)
	(segment
		(start 102.822502 -23.847298)
		(end 102.451662 -24.218138)
		(width 0.1016)
		(layer "F.Cu")
		(net "SMB_DIMM_NODE1_DAT")
	)
	(segment
		(start 13.9192 -6.488938)
		(end 13.88237 -6.488938)
		(width 0.1016)
		(layer "F.Cu")
		(net "SMB_DIMM_NODE1_DAT")
	)
	(segment
		(start 13.88237 -6.488938)
		(end 13.139674 -5.746242)
		(width 0.1016)
		(layer "F.Cu")
		(net "SMB_DIMM_NODE1_DAT")
	)
	(segment
		(start 13.139674 -5.746242)
		(end 12.54379 -5.746242)
		(width 0.1016)
		(layer "F.Cu")
		(net "SMB_DIMM_NODE1_DAT")
	)
	(segment
		(start 102.451662 -24.218138)
		(end 102.451662 -29.149802)
		(width 0.1016)
		(layer "F.Cu")
		(net "SMB_DIMM_NODE1_DAT")
	)
	(segment
		(start 11.52017 -4.722622)
		(end 11.52017 -4.721352)
		(width 0.1016)
		(layer "F.Cu")
		(net "SMB_DIMM_NODE1_DAT")
	)
	(segment
		(start 102.451662 -29.149802)
		(end 102.450138 -29.149802)
		(width 0.1016)
		(layer "F.Cu")
		(net "SMB_DIMM_NODE1_DAT")
	)
	(segment
		(start 12.54379 -5.746242)
		(end 11.52017 -4.722622)
		(width 0.1016)
		(layer "F.Cu")
		(net "SMB_DIMM_NODE1_DAT")
	)
	(via
		(at 13.9192 -6.488938)
		(size 0.508)
		(drill 0.254)
		(layers "F.Cu" "B.Cu")
		(net "SMB_DIMM_NODE1_DAT")
	)
	(via
		(at 102.822502 -23.847298)
		(size 0.508)
		(drill 0.254)
		(layers "F.Cu" "B.Cu")
		(net "SMB_DIMM_NODE1_DAT")
	)
	(via
		(at 101.90988 -16.54937)
		(size 0.508)
		(drill 0.254)
		(layers "F.Cu" "B.Cu")
		(net "SMB_DIMM_NODE1_DAT")
	)
	(segment
		(start 103.189532 -17.829022)
		(end 103.189532 -23.345394)
		(width 0.1016)
		(layer "B.Cu")
		(net "SMB_DIMM_NODE1_DAT")
	)
	(segment
		(start 101.90988 -16.54937)
		(end 103.189532 -17.829022)
		(width 0.1016)
		(layer "B.Cu")
		(net "SMB_DIMM_NODE1_DAT")
	)
	(segment
		(start 103.189532 -23.345394)
		(end 102.822502 -23.712424)
		(width 0.1016)
		(layer "B.Cu")
		(net "SMB_DIMM_NODE1_DAT")
	)
	(segment
		(start 102.822502 -23.712424)
		(end 102.822502 -23.847298)
		(width 0.1016)
		(layer "B.Cu")
		(net "SMB_DIMM_NODE1_DAT")
	)
	(segment
		(start 64.514476 -18.1229)
		(end 67.03568 -17.176496)
		(width 0.1143)
		(layer "In6.Cu")
		(net "SMB_DIMM_NODE1_DAT")
	)
	(segment
		(start 101.681026 -16.778224)
		(end 101.90988 -16.54937)
		(width 0.1143)
		(layer "In6.Cu")
		(net "SMB_DIMM_NODE1_DAT")
	)
	(segment
		(start 67.03568 -17.176496)
		(end 98.88982 -17.176496)
		(width 0.1143)
		(layer "In6.Cu")
		(net "SMB_DIMM_NODE1_DAT")
	)
	(segment
		(start 27.134566 -15.536926)
		(end 29.72054 -18.1229)
		(width 0.1143)
		(layer "In6.Cu")
		(net "SMB_DIMM_NODE1_DAT")
	)
	(segment
		(start 98.88982 -17.176496)
		(end 99.288092 -16.778224)
		(width 0.1143)
		(layer "In6.Cu")
		(net "SMB_DIMM_NODE1_DAT")
	)
	(segment
		(start 22.967188 -15.536926)
		(end 27.134566 -15.536926)
		(width 0.1143)
		(layer "In6.Cu")
		(net "SMB_DIMM_NODE1_DAT")
	)
	(segment
		(start 99.288092 -16.778224)
		(end 101.681026 -16.778224)
		(width 0.1143)
		(layer "In6.Cu")
		(net "SMB_DIMM_NODE1_DAT")
	)
	(segment
		(start 13.9192 -6.488938)
		(end 22.967188 -15.536926)
		(width 0.1143)
		(layer "In6.Cu")
		(net "SMB_DIMM_NODE1_DAT")
	)
	(segment
		(start 29.72054 -18.1229)
		(end 64.514476 -18.1229)
		(width 0.1143)
		(layer "In6.Cu")
		(net "SMB_DIMM_NODE1_DAT")
	)
	(segment
		(start 62.45098 -88.522302)
		(end 62.09538 -88.877902)
		(width 0.1016)
		(layer "F.Cu")
		(net "LPC_CPU_NODE1_CLKRUN_L")
	)
	(segment
		(start 62.597284 -91.141804)
		(end 62.597284 -93.506036)
		(width 0.1016)
		(layer "F.Cu")
		(net "LPC_CPU_NODE1_CLKRUN_L")
	)
	(segment
		(start 62.09538 -88.877902)
		(end 62.09538 -90.6399)
		(width 0.1016)
		(layer "F.Cu")
		(net "LPC_CPU_NODE1_CLKRUN_L")
	)
	(segment
		(start 62.597284 -93.506036)
		(end 63.971424 -94.880176)
		(width 0.1016)
		(layer "F.Cu")
		(net "LPC_CPU_NODE1_CLKRUN_L")
	)
	(segment
		(start 65.209166 -96.117918)
		(end 63.971424 -94.880176)
		(width 0.1016)
		(layer "F.Cu")
		(net "LPC_CPU_NODE1_CLKRUN_L")
	)
	(segment
		(start 62.45098 -88.103964)
		(end 62.45098 -88.522302)
		(width 0.1016)
		(layer "F.Cu")
		(net "LPC_CPU_NODE1_CLKRUN_L")
	)
	(segment
		(start 65.209166 -96.309942)
		(end 65.209166 -96.117918)
		(width 0.1016)
		(layer "F.Cu")
		(net "LPC_CPU_NODE1_CLKRUN_L")
	)
	(segment
		(start 62.09538 -90.6399)
		(end 62.597284 -91.141804)
		(width 0.1016)
		(layer "F.Cu")
		(net "LPC_CPU_NODE1_CLKRUN_L")
	)
	(via
		(at 63.971424 -94.880176)
		(size 0.762)
		(drill 0.381)
		(layers "F.Cu" "B.Cu")
		(net "LPC_CPU_NODE1_CLKRUN_L")
	)
	(segment
		(start 51.803808 -61.470286)
		(end 52.138834 -61.13526)
		(width 0.1016)
		(layer "F.Cu")
		(net "M1_DQ_NODE1_DQ24")
	)
	(segment
		(start 52.392834 -63.556642)
		(end 52.392834 -63.293752)
		(width 0.1016)
		(layer "F.Cu")
		(net "M1_DQ_NODE1_DQ24")
	)
	(segment
		(start 52.392834 -63.293752)
		(end 51.803808 -62.704726)
		(width 0.1016)
		(layer "F.Cu")
		(net "M1_DQ_NODE1_DQ24")
	)
	(segment
		(start 51.803808 -62.704726)
		(end 51.803808 -61.470286)
		(width 0.1016)
		(layer "F.Cu")
		(net "M1_DQ_NODE1_DQ24")
	)
	(segment
		(start 52.138834 -61.13526)
		(end 52.138834 -61.013086)
		(width 0.1016)
		(layer "F.Cu")
		(net "M1_DQ_NODE1_DQ24")
	)
	(segment
		(start 56.550306 -23.175722)
		(end 56.637682 -23.263098)
		(width 0.1651)
		(layer "F.Cu")
		(net "M1_DQ_NODE1_DQ24")
	)
	(segment
		(start 56.550306 -20.94992)
		(end 56.550306 -23.175722)
		(width 0.1651)
		(layer "F.Cu")
		(net "M1_DQ_NODE1_DQ24")
	)
	(via
		(at 52.138834 -61.013086)
		(size 0.508)
		(drill 0.254)
		(layers "F.Cu" "B.Cu")
		(net "M1_DQ_NODE1_DQ24")
	)
	(via
		(at 56.637682 -23.263098)
		(size 0.508)
		(drill 0.254)
		(layers "F.Cu" "B.Cu")
		(net "M1_DQ_NODE1_DQ24")
	)
	(segment
		(start 56.990742 -26.367232)
		(end 56.990742 -28.416758)
		(width 0.2032)
		(layer "In2.Cu")
		(net "M1_DQ_NODE1_DQ24")
	)
	(segment
		(start 51.691032 -59.728862)
		(end 52.138834 -60.176664)
		(width 0.1016)
		(layer "In2.Cu")
		(net "M1_DQ_NODE1_DQ24")
	)
	(segment
		(start 56.637682 -23.263098)
		(end 56.827166 -23.452582)
		(width 0.2032)
		(layer "In2.Cu")
		(net "M1_DQ_NODE1_DQ24")
	)
	(segment
		(start 43.189398 -42.979594)
		(end 43.18762 -42.979594)
		(width 0.2032)
		(layer "In2.Cu")
		(net "M1_DQ_NODE1_DQ24")
	)
	(segment
		(start 56.132476 -28.980384)
		(end 55.707026 -28.554934)
		(width 0.2032)
		(layer "In2.Cu")
		(net "M1_DQ_NODE1_DQ24")
	)
	(segment
		(start 55.412386 -28.554934)
		(end 55.204106 -28.763214)
		(width 0.2032)
		(layer "In2.Cu")
		(net "M1_DQ_NODE1_DQ24")
	)
	(segment
		(start 44.414948 -43.765724)
		(end 44.120308 -43.765724)
		(width 0.2032)
		(layer "In2.Cu")
		(net "M1_DQ_NODE1_DQ24")
	)
	(segment
		(start 43.912028 -43.557444)
		(end 43.912028 -43.262804)
		(width 0.2032)
		(layer "In2.Cu")
		(net "M1_DQ_NODE1_DQ24")
	)
	(segment
		(start 50.66538 -55.98668)
		(end 50.66538 -57.109868)
		(width 0.2032)
		(layer "In2.Cu")
		(net "M1_DQ_NODE1_DQ24")
	)
	(segment
		(start 45.306742 -41.15689)
		(end 45.012102 -41.15689)
		(width 0.2032)
		(layer "In2.Cu")
		(net "M1_DQ_NODE1_DQ24")
	)
	(segment
		(start 56.827166 -23.452582)
		(end 56.827166 -25.851104)
		(width 0.2032)
		(layer "In2.Cu")
		(net "M1_DQ_NODE1_DQ24")
	)
	(segment
		(start 55.204106 -28.763214)
		(end 55.204106 -29.057854)
		(width 0.2032)
		(layer "In2.Cu")
		(net "M1_DQ_NODE1_DQ24")
	)
	(segment
		(start 56.990742 -28.416758)
		(end 56.427116 -28.980384)
		(width 0.2032)
		(layer "In2.Cu")
		(net "M1_DQ_NODE1_DQ24")
	)
	(segment
		(start 56.98998 -26.367232)
		(end 56.990742 -26.367232)
		(width 0.2032)
		(layer "In2.Cu")
		(net "M1_DQ_NODE1_DQ24")
	)
	(segment
		(start 52.138834 -60.176664)
		(end 52.138834 -61.013086)
		(width 0.1016)
		(layer "In2.Cu")
		(net "M1_DQ_NODE1_DQ24")
	)
	(segment
		(start 50.66538 -57.786778)
		(end 51.691032 -58.81243)
		(width 0.1016)
		(layer "In2.Cu")
		(net "M1_DQ_NODE1_DQ24")
	)
	(segment
		(start 45.515022 -41.36517)
		(end 45.306742 -41.15689)
		(width 0.2032)
		(layer "In2.Cu")
		(net "M1_DQ_NODE1_DQ24")
	)
	(segment
		(start 51.691032 -58.81243)
		(end 51.691032 -59.728862)
		(width 0.1016)
		(layer "In2.Cu")
		(net "M1_DQ_NODE1_DQ24")
	)
	(segment
		(start 55.204106 -29.057854)
		(end 55.629556 -29.483304)
		(width 0.2032)
		(layer "In2.Cu")
		(net "M1_DQ_NODE1_DQ24")
	)
	(segment
		(start 56.427116 -28.980384)
		(end 56.132476 -28.980384)
		(width 0.2032)
		(layer "In2.Cu")
		(net "M1_DQ_NODE1_DQ24")
	)
	(segment
		(start 56.827166 -25.851104)
		(end 56.98998 -26.013918)
		(width 0.2032)
		(layer "In2.Cu")
		(net "M1_DQ_NODE1_DQ24")
	)
	(segment
		(start 55.47614 -32.704532)
		(end 44.414948 -43.765724)
		(width 0.2032)
		(layer "In2.Cu")
		(net "M1_DQ_NODE1_DQ24")
	)
	(segment
		(start 55.629556 -29.777944)
		(end 55.47614 -29.93136)
		(width 0.2032)
		(layer "In2.Cu")
		(net "M1_DQ_NODE1_DQ24")
	)
	(segment
		(start 45.012102 -41.15689)
		(end 43.189398 -42.979594)
		(width 0.2032)
		(layer "In2.Cu")
		(net "M1_DQ_NODE1_DQ24")
	)
	(segment
		(start 55.47614 -29.93136)
		(end 55.47614 -32.704532)
		(width 0.2032)
		(layer "In2.Cu")
		(net "M1_DQ_NODE1_DQ24")
	)
	(segment
		(start 45.515022 -41.65981)
		(end 45.515022 -41.36517)
		(width 0.2032)
		(layer "In2.Cu")
		(net "M1_DQ_NODE1_DQ24")
	)
	(segment
		(start 56.98998 -26.013918)
		(end 56.98998 -26.367232)
		(width 0.2032)
		(layer "In2.Cu")
		(net "M1_DQ_NODE1_DQ24")
	)
	(segment
		(start 55.629556 -29.483304)
		(end 55.629556 -29.777944)
		(width 0.2032)
		(layer "In2.Cu")
		(net "M1_DQ_NODE1_DQ24")
	)
	(segment
		(start 50.66538 -57.109868)
		(end 50.66538 -57.786778)
		(width 0.1016)
		(layer "In2.Cu")
		(net "M1_DQ_NODE1_DQ24")
	)
	(segment
		(start 43.912028 -43.262804)
		(end 45.515022 -41.65981)
		(width 0.2032)
		(layer "In2.Cu")
		(net "M1_DQ_NODE1_DQ24")
	)
	(segment
		(start 44.120308 -43.765724)
		(end 43.912028 -43.557444)
		(width 0.2032)
		(layer "In2.Cu")
		(net "M1_DQ_NODE1_DQ24")
	)
	(segment
		(start 55.707026 -28.554934)
		(end 55.412386 -28.554934)
		(width 0.2032)
		(layer "In2.Cu")
		(net "M1_DQ_NODE1_DQ24")
	)
	(segment
		(start 43.18762 -48.50892)
		(end 50.66538 -55.98668)
		(width 0.2032)
		(layer "In2.Cu")
		(net "M1_DQ_NODE1_DQ24")
	)
	(segment
		(start 43.18762 -42.979594)
		(end 43.18762 -48.50892)
		(width 0.2032)
		(layer "In2.Cu")
		(net "M1_DQ_NODE1_DQ24")
	)
	(via
		(at 30.5562 -145.418048)
		(size 0.508)
		(drill 0.254)
		(layers "F.Cu" "B.Cu")
		(net "LAN1_CTRL_P1V9_R")
	)
	(segment
		(start 65.093342 -27.728418)
		(end 63.894462 -27.728418)
		(width 0.1016)
		(layer "F.Cu")
		(net "PD_NODE1_DM8")
	)
	(segment
		(start 63.607442 -26.684478)
		(end 65.057782 -25.234138)
		(width 0.1016)
		(layer "F.Cu")
		(net "PD_NODE1_DM8")
	)
	(segment
		(start 63.607442 -27.441398)
		(end 63.607442 -26.684478)
		(width 0.1016)
		(layer "F.Cu")
		(net "PD_NODE1_DM8")
	)
	(segment
		(start 63.894462 -27.728418)
		(end 63.607442 -27.441398)
		(width 0.1016)
		(layer "F.Cu")
		(net "PD_NODE1_DM8")
	)
	(segment
		(start 65.250314 -29.149802)
		(end 65.250314 -27.88539)
		(width 0.1016)
		(layer "F.Cu")
		(net "PD_NODE1_DM8")
	)
	(segment
		(start 65.250314 -27.88539)
		(end 65.093342 -27.728418)
		(width 0.1016)
		(layer "F.Cu")
		(net "PD_NODE1_DM8")
	)
	(via
		(at 65.057782 -25.234138)
		(size 0.508)
		(drill 0.254)
		(layers "F.Cu" "B.Cu")
		(net "PD_NODE1_DM8")
	)
	(segment
		(start 65.594992 -28.091638)
		(end 65.594992 -25.771348)
		(width 0.1016)
		(layer "B.Cu")
		(net "PD_NODE1_DM8")
	)
	(segment
		(start 65.594992 -25.771348)
		(end 65.057782 -25.234138)
		(width 0.1016)
		(layer "B.Cu")
		(net "PD_NODE1_DM8")
	)
	(segment
		(start 55.78856 -120.765062)
		(end 55.38216 -120.358662)
		(width 0.1016)
		(layer "F.Cu")
		(net "BMC_NODE1_CLK_24M_R")
	)
	(segment
		(start 55.78856 -120.944132)
		(end 55.78856 -120.765062)
		(width 0.1016)
		(layer "F.Cu")
		(net "BMC_NODE1_CLK_24M_R")
	)
	(segment
		(start 55.38216 -119.227346)
		(end 55.38216 -120.358662)
		(width 0.1016)
		(layer "F.Cu")
		(net "BMC_NODE1_CLK_24M_R")
	)
	(via
		(at 55.38216 -120.358662)
		(size 0.508)
		(drill 0.254)
		(layers "F.Cu" "B.Cu")
		(net "BMC_NODE1_CLK_24M_R")
	)
	(segment
		(start 67.57162 -87.518748)
		(end 67.729354 -87.361014)
		(width 0.1016)
		(layer "F.Cu")
		(net "TP_CPU_D53")
	)
	(segment
		(start 67.57162 -87.594186)
		(end 67.57162 -87.518748)
		(width 0.1016)
		(layer "F.Cu")
		(net "TP_CPU_D53")
	)
	(segment
		(start 67.729354 -87.361014)
		(end 67.729354 -86.590886)
		(width 0.1016)
		(layer "F.Cu")
		(net "TP_CPU_D53")
	)
	(segment
		(start 67.729354 -86.590886)
		(end 68.057522 -86.262718)
		(width 0.1016)
		(layer "F.Cu")
		(net "TP_CPU_D53")
	)
	(via
		(at 68.507864 -88.821006)
		(size 0.6604)
		(drill 0.3302)
		(layers "F.Cu" "B.Cu")
		(net "TP_CPU_D53")
	)
	(via
		(at 68.057522 -86.262718)
		(size 0.508)
		(drill 0.254)
		(layers "F.Cu" "B.Cu")
		(net "TP_CPU_D53")
	)
	(segment
		(start 68.057522 -86.367874)
		(end 68.057522 -86.262718)
		(width 0.1016)
		(layer "B.Cu")
		(net "TP_CPU_D53")
	)
	(segment
		(start 68.605908 -88.722962)
		(end 68.605908 -86.91626)
		(width 0.1016)
		(layer "B.Cu")
		(net "TP_CPU_D53")
	)
	(segment
		(start 68.605908 -86.91626)
		(end 68.057522 -86.367874)
		(width 0.1016)
		(layer "B.Cu")
		(net "TP_CPU_D53")
	)
	(segment
		(start 68.507864 -88.821006)
		(end 68.605908 -88.722962)
		(width 0.1016)
		(layer "B.Cu")
		(net "TP_CPU_D53")
	)
	(segment
		(start 71.443342 -41.093898)
		(end 71.443342 -45.927518)
		(width 0.2286)
		(layer "F.Cu")
		(net "M_DDR3_NODE1_MA6")
	)
	(segment
		(start 64.3763 -51.350672)
		(end 60.6044 -55.122572)
		(width 0.2286)
		(layer "F.Cu")
		(net "M_DDR3_NODE1_MA6")
	)
	(segment
		(start 71.285354 -47.815246)
		(end 70.572884 -47.102776)
		(width 0.2286)
		(layer "F.Cu")
		(net "M_DDR3_NODE1_MA6")
	)
	(segment
		(start 72.450198 -29.149802)
		(end 72.450198 -30.393894)
		(width 0.2286)
		(layer "F.Cu")
		(net "M_DDR3_NODE1_MA6")
	)
	(segment
		(start 64.3763 -50.910744)
		(end 64.3763 -51.350672)
		(width 0.2286)
		(layer "F.Cu")
		(net "M_DDR3_NODE1_MA6")
	)
	(segment
		(start 71.590154 -47.815246)
		(end 71.285354 -47.815246)
		(width 0.2286)
		(layer "F.Cu")
		(net "M_DDR3_NODE1_MA6")
	)
	(segment
		(start 72.609202 -30.552898)
		(end 72.609202 -34.13506)
		(width 0.2286)
		(layer "F.Cu")
		(net "M_DDR3_NODE1_MA6")
	)
	(segment
		(start 59.687206 -61.770514)
		(end 59.687206 -62.405514)
		(width 0.1016)
		(layer "F.Cu")
		(net "M_DDR3_NODE1_MA6")
	)
	(segment
		(start 72.713342 -46.674278)
		(end 72.383142 -46.674278)
		(width 0.2286)
		(layer "F.Cu")
		(net "M_DDR3_NODE1_MA6")
	)
	(segment
		(start 72.450198 -30.393894)
		(end 72.609202 -30.552898)
		(width 0.2286)
		(layer "F.Cu")
		(net "M_DDR3_NODE1_MA6")
	)
	(segment
		(start 72.03186 -36.697158)
		(end 72.03186 -39.707058)
		(width 0.2286)
		(layer "F.Cu")
		(net "M_DDR3_NODE1_MA6")
	)
	(segment
		(start 72.032622 -34.71164)
		(end 72.032622 -36.697158)
		(width 0.2286)
		(layer "F.Cu")
		(net "M_DDR3_NODE1_MA6")
	)
	(segment
		(start 60.6044 -55.122572)
		(end 60.6044 -59.353704)
		(width 0.2286)
		(layer "F.Cu")
		(net "M_DDR3_NODE1_MA6")
	)
	(segment
		(start 71.093838 -46.277022)
		(end 71.093838 -46.581822)
		(width 0.2286)
		(layer "F.Cu")
		(net "M_DDR3_NODE1_MA6")
	)
	(segment
		(start 70.268084 -47.102776)
		(end 65.788794 -51.582066)
		(width 0.2286)
		(layer "F.Cu")
		(net "M_DDR3_NODE1_MA6")
	)
	(segment
		(start 66.820034 -49.508918)
		(end 66.820034 -49.22139)
		(width 0.2286)
		(layer "F.Cu")
		(net "M_DDR3_NODE1_MA6")
	)
	(segment
		(start 60.381134 -59.57697)
		(end 60.381134 -61.076586)
		(width 0.1016)
		(layer "F.Cu")
		(net "M_DDR3_NODE1_MA6")
	)
	(segment
		(start 72.916542 -46.471078)
		(end 72.713342 -46.674278)
		(width 0.2286)
		(layer "F.Cu")
		(net "M_DDR3_NODE1_MA6")
	)
	(segment
		(start 72.609202 -34.13506)
		(end 72.032622 -34.71164)
		(width 0.2286)
		(layer "F.Cu")
		(net "M_DDR3_NODE1_MA6")
	)
	(segment
		(start 70.572884 -47.102776)
		(end 70.268084 -47.102776)
		(width 0.2286)
		(layer "F.Cu")
		(net "M_DDR3_NODE1_MA6")
	)
	(segment
		(start 66.29908 -48.987964)
		(end 64.3763 -50.910744)
		(width 0.2286)
		(layer "F.Cu")
		(net "M_DDR3_NODE1_MA6")
	)
	(segment
		(start 66.820034 -49.22139)
		(end 66.586608 -48.987964)
		(width 0.2286)
		(layer "F.Cu")
		(net "M_DDR3_NODE1_MA6")
	)
	(segment
		(start 72.032622 -36.697158)
		(end 72.03186 -36.697158)
		(width 0.2286)
		(layer "F.Cu")
		(net "M_DDR3_NODE1_MA6")
	)
	(segment
		(start 72.383142 -46.674278)
		(end 72.179942 -46.471078)
		(width 0.2286)
		(layer "F.Cu")
		(net "M_DDR3_NODE1_MA6")
	)
	(segment
		(start 72.179942 -41.093898)
		(end 71.976742 -40.890698)
		(width 0.2286)
		(layer "F.Cu")
		(net "M_DDR3_NODE1_MA6")
	)
	(segment
		(start 65.26784 -51.061112)
		(end 66.820034 -49.508918)
		(width 0.2286)
		(layer "F.Cu")
		(net "M_DDR3_NODE1_MA6")
	)
	(segment
		(start 71.443342 -45.927518)
		(end 71.093838 -46.277022)
		(width 0.2286)
		(layer "F.Cu")
		(net "M_DDR3_NODE1_MA6")
	)
	(segment
		(start 72.179942 -46.471078)
		(end 72.179942 -41.093898)
		(width 0.2286)
		(layer "F.Cu")
		(net "M_DDR3_NODE1_MA6")
	)
	(segment
		(start 66.586608 -48.987964)
		(end 66.29908 -48.987964)
		(width 0.2286)
		(layer "F.Cu")
		(net "M_DDR3_NODE1_MA6")
	)
	(segment
		(start 71.093838 -46.581822)
		(end 71.806308 -47.294292)
		(width 0.2286)
		(layer "F.Cu")
		(net "M_DDR3_NODE1_MA6")
	)
	(segment
		(start 65.788794 -51.582066)
		(end 65.483486 -51.582066)
		(width 0.2286)
		(layer "F.Cu")
		(net "M_DDR3_NODE1_MA6")
	)
	(segment
		(start 71.976742 -40.890698)
		(end 71.646542 -40.890698)
		(width 0.2286)
		(layer "F.Cu")
		(net "M_DDR3_NODE1_MA6")
	)
	(segment
		(start 71.646542 -40.890698)
		(end 71.443342 -41.093898)
		(width 0.2286)
		(layer "F.Cu")
		(net "M_DDR3_NODE1_MA6")
	)
	(segment
		(start 71.806308 -47.599092)
		(end 71.590154 -47.815246)
		(width 0.2286)
		(layer "F.Cu")
		(net "M_DDR3_NODE1_MA6")
	)
	(segment
		(start 59.687206 -62.405514)
		(end 59.54268 -62.55004)
		(width 0.1016)
		(layer "F.Cu")
		(net "M_DDR3_NODE1_MA6")
	)
	(segment
		(start 71.806308 -47.294292)
		(end 71.806308 -47.599092)
		(width 0.2286)
		(layer "F.Cu")
		(net "M_DDR3_NODE1_MA6")
	)
	(segment
		(start 72.03186 -39.707058)
		(end 72.916542 -40.59174)
		(width 0.2286)
		(layer "F.Cu")
		(net "M_DDR3_NODE1_MA6")
	)
	(segment
		(start 65.483486 -51.582066)
		(end 65.26784 -51.36642)
		(width 0.2286)
		(layer "F.Cu")
		(net "M_DDR3_NODE1_MA6")
	)
	(segment
		(start 72.916542 -40.59174)
		(end 72.916542 -46.471078)
		(width 0.2286)
		(layer "F.Cu")
		(net "M_DDR3_NODE1_MA6")
	)
	(segment
		(start 60.6044 -59.353704)
		(end 60.381134 -59.57697)
		(width 0.1016)
		(layer "F.Cu")
		(net "M_DDR3_NODE1_MA6")
	)
	(segment
		(start 60.381134 -61.076586)
		(end 59.687206 -61.770514)
		(width 0.1016)
		(layer "F.Cu")
		(net "M_DDR3_NODE1_MA6")
	)
	(segment
		(start 65.26784 -51.36642)
		(end 65.26784 -51.061112)
		(width 0.2286)
		(layer "F.Cu")
		(net "M_DDR3_NODE1_MA6")
	)
	(via
		(at 72.032622 -36.697158)
		(size 0.762)
		(drill 0.381)
		(layers "F.Cu" "B.Cu")
		(net "M_DDR3_NODE1_MA6")
	)
	(segment
		(start 64.18961 -85.000846)
		(end 64.650366 -85.000846)
		(width 0.1016)
		(layer "F.Cu")
		(net "IRQ_CPU_NODE1_SERIAL_R")
	)
	(segment
		(start 64.650366 -85.000846)
		(end 64.801496 -85.151976)
		(width 0.1016)
		(layer "F.Cu")
		(net "IRQ_CPU_NODE1_SERIAL_R")
	)
	(via
		(at 64.801496 -85.151976)
		(size 0.508)
		(drill 0.254)
		(layers "F.Cu" "B.Cu")
		(net "IRQ_CPU_NODE1_SERIAL_R")
	)
	(via
		(at 63.786004 -94.925388)
		(size 0.6604)
		(drill 0.3302)
		(layers "F.Cu" "B.Cu")
		(net "IRQ_CPU_NODE1_SERIAL_R")
	)
	(segment
		(start 64.387222 -90.510614)
		(end 64.387222 -91.046554)
		(width 0.1016)
		(layer "B.Cu")
		(net "IRQ_CPU_NODE1_SERIAL_R")
	)
	(segment
		(start 64.965834 -85.151976)
		(end 65.204594 -85.390736)
		(width 0.1016)
		(layer "B.Cu")
		(net "IRQ_CPU_NODE1_SERIAL_R")
	)
	(segment
		(start 63.960756 -94.750636)
		(end 63.786004 -94.925388)
		(width 0.1016)
		(layer "B.Cu")
		(net "IRQ_CPU_NODE1_SERIAL_R")
	)
	(segment
		(start 64.938148 -86.946486)
		(end 64.38646 -89.089992)
		(width 0.1016)
		(layer "B.Cu")
		(net "IRQ_CPU_NODE1_SERIAL_R")
	)
	(segment
		(start 65.204594 -86.68004)
		(end 64.938148 -86.946486)
		(width 0.1016)
		(layer "B.Cu")
		(net "IRQ_CPU_NODE1_SERIAL_R")
	)
	(segment
		(start 65.204594 -85.390736)
		(end 65.204594 -86.68004)
		(width 0.1016)
		(layer "B.Cu")
		(net "IRQ_CPU_NODE1_SERIAL_R")
	)
	(segment
		(start 64.387222 -91.046554)
		(end 63.960756 -92.541598)
		(width 0.1016)
		(layer "B.Cu")
		(net "IRQ_CPU_NODE1_SERIAL_R")
	)
	(segment
		(start 63.166498 -96.296734)
		(end 63.166498 -95.544894)
		(width 0.1016)
		(layer "B.Cu")
		(net "IRQ_CPU_NODE1_SERIAL_R")
	)
	(segment
		(start 63.166498 -95.544894)
		(end 63.786004 -94.925388)
		(width 0.1016)
		(layer "B.Cu")
		(net "IRQ_CPU_NODE1_SERIAL_R")
	)
	(segment
		(start 64.801496 -85.151976)
		(end 64.965834 -85.151976)
		(width 0.1016)
		(layer "B.Cu")
		(net "IRQ_CPU_NODE1_SERIAL_R")
	)
	(segment
		(start 63.960756 -92.541598)
		(end 63.960756 -94.750636)
		(width 0.1016)
		(layer "B.Cu")
		(net "IRQ_CPU_NODE1_SERIAL_R")
	)
	(segment
		(start 64.38646 -89.089992)
		(end 64.38646 -90.510614)
		(width 0.1016)
		(layer "B.Cu")
		(net "IRQ_CPU_NODE1_SERIAL_R")
	)
	(segment
		(start 64.38646 -90.510614)
		(end 64.387222 -90.510614)
		(width 0.1016)
		(layer "B.Cu")
		(net "IRQ_CPU_NODE1_SERIAL_R")
	)
	(segment
		(start 67.350132 -20.94992)
		(end 67.350132 -23.467568)
		(width 0.1651)
		(layer "F.Cu")
		(net "M_DDR3_NODE1_ECC3")
	)
	(segment
		(start 67.350132 -23.467568)
		(end 66.980562 -23.837138)
		(width 0.1651)
		(layer "F.Cu")
		(net "M_DDR3_NODE1_ECC3")
	)
	(segment
		(start 66.415666 -67.741038)
		(end 66.443098 -67.741038)
		(width 0.1016)
		(layer "F.Cu")
		(net "M_DDR3_NODE1_ECC3")
	)
	(segment
		(start 66.443098 -67.741038)
		(end 66.809366 -68.107306)
		(width 0.1016)
		(layer "F.Cu")
		(net "M_DDR3_NODE1_ECC3")
	)
	(via
		(at 66.980562 -23.837138)
		(size 0.508)
		(drill 0.254)
		(layers "F.Cu" "B.Cu")
		(net "M_DDR3_NODE1_ECC3")
	)
	(via
		(at 66.809366 -68.107306)
		(size 0.508)
		(drill 0.254)
		(layers "F.Cu" "B.Cu")
		(net "M_DDR3_NODE1_ECC3")
	)
	(segment
		(start 63.89624 -61.105288)
		(end 63.89624 -57.208928)
		(width 0.2032)
		(layer "In7.Cu")
		(net "M_DDR3_NODE1_ECC3")
	)
	(segment
		(start 63.31966 -56.632348)
		(end 63.31966 -55.498492)
		(width 0.2032)
		(layer "In7.Cu")
		(net "M_DDR3_NODE1_ECC3")
	)
	(segment
		(start 63.89624 -57.208928)
		(end 63.31966 -56.632348)
		(width 0.2032)
		(layer "In7.Cu")
		(net "M_DDR3_NODE1_ECC3")
	)
	(segment
		(start 66.077084 -63.634874)
		(end 66.022982 -63.634874)
		(width 0.1016)
		(layer "In7.Cu")
		(net "M_DDR3_NODE1_ECC3")
	)
	(segment
		(start 67.345306 -36.850066)
		(end 68.41236 -35.783012)
		(width 0.2032)
		(layer "In7.Cu")
		(net "M_DDR3_NODE1_ECC3")
	)
	(segment
		(start 63.82766 -53.959506)
		(end 63.52286 -53.959506)
		(width 0.2032)
		(layer "In7.Cu")
		(net "M_DDR3_NODE1_ECC3")
	)
	(segment
		(start 64.03086 -51.939698)
		(end 64.03086 -53.756306)
		(width 0.2032)
		(layer "In7.Cu")
		(net "M_DDR3_NODE1_ECC3")
	)
	(segment
		(start 68.41236 -33.31337)
		(end 70.07098 -31.65475)
		(width 0.2032)
		(layer "In7.Cu")
		(net "M_DDR3_NODE1_ECC3")
	)
	(segment
		(start 66.463672 -66.943224)
		(end 66.463672 -66.192146)
		(width 0.1016)
		(layer "In7.Cu")
		(net "M_DDR3_NODE1_ECC3")
	)
	(segment
		(start 66.402204 -63.959994)
		(end 66.077084 -63.634874)
		(width 0.1016)
		(layer "In7.Cu")
		(net "M_DDR3_NODE1_ECC3")
	)
	(segment
		(start 63.52286 -53.959506)
		(end 63.31966 -53.756306)
		(width 0.2032)
		(layer "In7.Cu")
		(net "M_DDR3_NODE1_ECC3")
	)
	(segment
		(start 64.62268 -45.330618)
		(end 64.62268 -38.21811)
		(width 0.2032)
		(layer "In7.Cu")
		(net "M_DDR3_NODE1_ECC3")
	)
	(segment
		(start 63.50508 -55.313072)
		(end 64.51092 -55.313072)
		(width 0.2032)
		(layer "In7.Cu")
		(net "M_DDR3_NODE1_ECC3")
	)
	(segment
		(start 66.068702 -24.497538)
		(end 66.729102 -23.837138)
		(width 0.2032)
		(layer "In7.Cu")
		(net "M_DDR3_NODE1_ECC3")
	)
	(segment
		(start 65.990724 -36.850066)
		(end 67.345306 -36.850066)
		(width 0.2032)
		(layer "In7.Cu")
		(net "M_DDR3_NODE1_ECC3")
	)
	(segment
		(start 68.41236 -35.783012)
		(end 68.41236 -33.31337)
		(width 0.2032)
		(layer "In7.Cu")
		(net "M_DDR3_NODE1_ECC3")
	)
	(segment
		(start 66.729102 -23.837138)
		(end 66.980562 -23.837138)
		(width 0.2032)
		(layer "In7.Cu")
		(net "M_DDR3_NODE1_ECC3")
	)
	(segment
		(start 66.068702 -25.485598)
		(end 66.068702 -24.497538)
		(width 0.2032)
		(layer "In7.Cu")
		(net "M_DDR3_NODE1_ECC3")
	)
	(segment
		(start 64.53378 -51.731418)
		(end 64.23914 -51.731418)
		(width 0.2032)
		(layer "In7.Cu")
		(net "M_DDR3_NODE1_ECC3")
	)
	(segment
		(start 66.463672 -66.192146)
		(end 66.402204 -66.130678)
		(width 0.1016)
		(layer "In7.Cu")
		(net "M_DDR3_NODE1_ECC3")
	)
	(segment
		(start 65.47612 -63.088012)
		(end 65.47612 -62.685168)
		(width 0.2032)
		(layer "In7.Cu")
		(net "M_DDR3_NODE1_ECC3")
	)
	(segment
		(start 70.07098 -30.206188)
		(end 67.585082 -27.72029)
		(width 0.2032)
		(layer "In7.Cu")
		(net "M_DDR3_NODE1_ECC3")
	)
	(segment
		(start 66.402204 -67.700144)
		(end 66.402204 -67.004692)
		(width 0.1016)
		(layer "In7.Cu")
		(net "M_DDR3_NODE1_ECC3")
	)
	(segment
		(start 63.31966 -53.756306)
		(end 63.31966 -46.633638)
		(width 0.2032)
		(layer "In7.Cu")
		(net "M_DDR3_NODE1_ECC3")
	)
	(segment
		(start 66.809366 -68.107306)
		(end 66.402204 -67.700144)
		(width 0.1016)
		(layer "In7.Cu")
		(net "M_DDR3_NODE1_ECC3")
	)
	(segment
		(start 66.022982 -63.634874)
		(end 65.47612 -63.088012)
		(width 0.1016)
		(layer "In7.Cu")
		(net "M_DDR3_NODE1_ECC3")
	)
	(segment
		(start 64.23914 -51.731418)
		(end 64.03086 -51.939698)
		(width 0.2032)
		(layer "In7.Cu")
		(net "M_DDR3_NODE1_ECC3")
	)
	(segment
		(start 64.74206 -55.081932)
		(end 64.74206 -51.939698)
		(width 0.2032)
		(layer "In7.Cu")
		(net "M_DDR3_NODE1_ECC3")
	)
	(segment
		(start 64.62268 -38.21811)
		(end 65.990724 -36.850066)
		(width 0.2032)
		(layer "In7.Cu")
		(net "M_DDR3_NODE1_ECC3")
	)
	(segment
		(start 63.31966 -46.633638)
		(end 64.62268 -45.330618)
		(width 0.2032)
		(layer "In7.Cu")
		(net "M_DDR3_NODE1_ECC3")
	)
	(segment
		(start 64.51092 -55.313072)
		(end 64.74206 -55.081932)
		(width 0.2032)
		(layer "In7.Cu")
		(net "M_DDR3_NODE1_ECC3")
	)
	(segment
		(start 65.47612 -62.685168)
		(end 63.89624 -61.105288)
		(width 0.2032)
		(layer "In7.Cu")
		(net "M_DDR3_NODE1_ECC3")
	)
	(segment
		(start 67.585082 -27.72029)
		(end 67.585082 -27.001978)
		(width 0.2032)
		(layer "In7.Cu")
		(net "M_DDR3_NODE1_ECC3")
	)
	(segment
		(start 70.07098 -31.65475)
		(end 70.07098 -30.206188)
		(width 0.2032)
		(layer "In7.Cu")
		(net "M_DDR3_NODE1_ECC3")
	)
	(segment
		(start 66.402204 -66.130678)
		(end 66.402204 -63.959994)
		(width 0.1016)
		(layer "In7.Cu")
		(net "M_DDR3_NODE1_ECC3")
	)
	(segment
		(start 66.402204 -67.004692)
		(end 66.463672 -66.943224)
		(width 0.1016)
		(layer "In7.Cu")
		(net "M_DDR3_NODE1_ECC3")
	)
	(segment
		(start 64.74206 -51.939698)
		(end 64.53378 -51.731418)
		(width 0.2032)
		(layer "In7.Cu")
		(net "M_DDR3_NODE1_ECC3")
	)
	(segment
		(start 67.585082 -27.001978)
		(end 66.068702 -25.485598)
		(width 0.2032)
		(layer "In7.Cu")
		(net "M_DDR3_NODE1_ECC3")
	)
	(segment
		(start 64.03086 -53.756306)
		(end 63.82766 -53.959506)
		(width 0.2032)
		(layer "In7.Cu")
		(net "M_DDR3_NODE1_ECC3")
	)
	(segment
		(start 63.31966 -55.498492)
		(end 63.50508 -55.313072)
		(width 0.2032)
		(layer "In7.Cu")
		(net "M_DDR3_NODE1_ECC3")
	)
	(segment
		(start 62.79134 -88.688672)
		(end 62.863476 -88.760808)
		(width 0.1016)
		(layer "F.Cu")
		(net "LPC_CPU_NODE1_FRAME_L_R")
	)
	(segment
		(start 62.863476 -88.760808)
		(end 62.863476 -90.056462)
		(width 0.1016)
		(layer "F.Cu")
		(net "LPC_CPU_NODE1_FRAME_L_R")
	)
	(segment
		(start 62.863476 -90.056462)
		(end 62.987428 -90.180414)
		(width 0.1016)
		(layer "F.Cu")
		(net "LPC_CPU_NODE1_FRAME_L_R")
	)
	(segment
		(start 65.335404 -95.419926)
		(end 65.335404 -95.088202)
		(width 0.1016)
		(layer "F.Cu")
		(net "LPC_CPU_NODE1_FRAME_L_R")
	)
	(segment
		(start 62.987428 -90.180414)
		(end 62.987428 -93.423994)
		(width 0.1016)
		(layer "F.Cu")
		(net "LPC_CPU_NODE1_FRAME_L_R")
	)
	(segment
		(start 63.068708 -88.137492)
		(end 62.79134 -88.41486)
		(width 0.1016)
		(layer "F.Cu")
		(net "LPC_CPU_NODE1_FRAME_L_R")
	)
	(segment
		(start 66.225166 -96.309688)
		(end 65.335404 -95.419926)
		(width 0.1016)
		(layer "F.Cu")
		(net "LPC_CPU_NODE1_FRAME_L_R")
	)
	(segment
		(start 63.068708 -87.594186)
		(end 63.068708 -88.137492)
		(width 0.1016)
		(layer "F.Cu")
		(net "LPC_CPU_NODE1_FRAME_L_R")
	)
	(segment
		(start 64.544194 -94.296992)
		(end 65.335404 -95.088202)
		(width 0.1016)
		(layer "F.Cu")
		(net "LPC_CPU_NODE1_FRAME_L_R")
	)
	(segment
		(start 66.225166 -96.309942)
		(end 66.225166 -96.309688)
		(width 0.1016)
		(layer "F.Cu")
		(net "LPC_CPU_NODE1_FRAME_L_R")
	)
	(segment
		(start 62.987428 -93.423994)
		(end 63.860426 -94.296992)
		(width 0.1016)
		(layer "F.Cu")
		(net "LPC_CPU_NODE1_FRAME_L_R")
	)
	(segment
		(start 62.79134 -88.41486)
		(end 62.79134 -88.688672)
		(width 0.1016)
		(layer "F.Cu")
		(net "LPC_CPU_NODE1_FRAME_L_R")
	)
	(segment
		(start 63.860426 -94.296992)
		(end 64.544194 -94.296992)
		(width 0.1016)
		(layer "F.Cu")
		(net "LPC_CPU_NODE1_FRAME_L_R")
	)
	(via
		(at 65.335404 -95.088202)
		(size 0.762)
		(drill 0.381)
		(layers "F.Cu" "B.Cu")
		(net "LPC_CPU_NODE1_FRAME_L_R")
	)
	(segment
		(start 69.469762 -63.575184)
		(end 69.793104 -63.898526)
		(width 0.1016)
		(layer "F.Cu")
		(net "M1_DQ_NODE1_DQ36")
	)
	(segment
		(start 83.10626 -26.638758)
		(end 82.650076 -27.094942)
		(width 0.1651)
		(layer "F.Cu")
		(net "M1_DQ_NODE1_DQ36")
	)
	(segment
		(start 69.223128 -61.302138)
		(end 69.585332 -61.664342)
		(width 0.1016)
		(layer "F.Cu")
		(net "M1_DQ_NODE1_DQ36")
	)
	(segment
		(start 83.10626 -26.369772)
		(end 83.10626 -26.638758)
		(width 0.1651)
		(layer "F.Cu")
		(net "M1_DQ_NODE1_DQ36")
	)
	(segment
		(start 69.586348 -61.880242)
		(end 69.586348 -62.896242)
		(width 0.1016)
		(layer "F.Cu")
		(net "M1_DQ_NODE1_DQ36")
	)
	(segment
		(start 68.950332 -61.302138)
		(end 69.223128 -61.302138)
		(width 0.1016)
		(layer "F.Cu")
		(net "M1_DQ_NODE1_DQ36")
	)
	(segment
		(start 69.585332 -61.664342)
		(end 69.585332 -61.879226)
		(width 0.1016)
		(layer "F.Cu")
		(net "M1_DQ_NODE1_DQ36")
	)
	(segment
		(start 69.585332 -61.879226)
		(end 69.586348 -61.880242)
		(width 0.1016)
		(layer "F.Cu")
		(net "M1_DQ_NODE1_DQ36")
	)
	(segment
		(start 69.469762 -63.012828)
		(end 69.469762 -63.575184)
		(width 0.1016)
		(layer "F.Cu")
		(net "M1_DQ_NODE1_DQ36")
	)
	(segment
		(start 82.650076 -27.094942)
		(end 82.650076 -29.149802)
		(width 0.1651)
		(layer "F.Cu")
		(net "M1_DQ_NODE1_DQ36")
	)
	(segment
		(start 69.586348 -62.896242)
		(end 69.469762 -63.012828)
		(width 0.1016)
		(layer "F.Cu")
		(net "M1_DQ_NODE1_DQ36")
	)
	(via
		(at 83.10626 -26.369772)
		(size 0.508)
		(drill 0.254)
		(layers "F.Cu" "B.Cu")
		(net "M1_DQ_NODE1_DQ36")
	)
	(via
		(at 68.950332 -61.302138)
		(size 0.508)
		(drill 0.254)
		(layers "F.Cu" "B.Cu")
		(net "M1_DQ_NODE1_DQ36")
	)
	(segment
		(start 69.00672 -61.24575)
		(end 69.336666 -61.24575)
		(width 0.2032)
		(layer "In7.Cu")
		(net "M1_DQ_NODE1_DQ36")
	)
	(segment
		(start 70.121272 -44.075096)
		(end 70.329552 -43.866816)
		(width 0.2032)
		(layer "In7.Cu")
		(net "M1_DQ_NODE1_DQ36")
	)
	(segment
		(start 73.346818 -39.548562)
		(end 73.849992 -40.051736)
		(width 0.2032)
		(layer "In7.Cu")
		(net "M1_DQ_NODE1_DQ36")
	)
	(segment
		(start 72.843898 -40.051482)
		(end 72.843898 -39.756842)
		(width 0.2032)
		(layer "In7.Cu")
		(net "M1_DQ_NODE1_DQ36")
	)
	(segment
		(start 79.828644 -36.281868)
		(end 80.04683 -36.063682)
		(width 0.2032)
		(layer "In7.Cu")
		(net "M1_DQ_NODE1_DQ36")
	)
	(segment
		(start 70.329298 -42.566082)
		(end 70.832472 -43.069256)
		(width 0.2032)
		(layer "In7.Cu")
		(net "M1_DQ_NODE1_DQ36")
	)
	(segment
		(start 73.347072 -40.554656)
		(end 72.843898 -40.051482)
		(width 0.2032)
		(layer "In7.Cu")
		(net "M1_DQ_NODE1_DQ36")
	)
	(segment
		(start 70.329552 -43.572176)
		(end 69.826378 -43.069002)
		(width 0.2032)
		(layer "In7.Cu")
		(net "M1_DQ_NODE1_DQ36")
	)
	(segment
		(start 69.73316 -60.849256)
		(end 69.73316 -59.78144)
		(width 0.2032)
		(layer "In7.Cu")
		(net "M1_DQ_NODE1_DQ36")
	)
	(segment
		(start 80.37068 -31.30296)
		(end 80.37068 -28.569412)
		(width 0.2032)
		(layer "In7.Cu")
		(net "M1_DQ_NODE1_DQ36")
	)
	(segment
		(start 70.034658 -42.566082)
		(end 70.329298 -42.566082)
		(width 0.2032)
		(layer "In7.Cu")
		(net "M1_DQ_NODE1_DQ36")
	)
	(segment
		(start 71.335392 -42.860976)
		(end 71.335392 -42.566336)
		(width 0.2032)
		(layer "In7.Cu")
		(net "M1_DQ_NODE1_DQ36")
	)
	(segment
		(start 70.832472 -43.069256)
		(end 71.127112 -43.069256)
		(width 0.2032)
		(layer "In7.Cu")
		(net "M1_DQ_NODE1_DQ36")
	)
	(segment
		(start 73.849738 -39.045642)
		(end 73.849738 -38.751002)
		(width 0.2032)
		(layer "In7.Cu")
		(net "M1_DQ_NODE1_DQ36")
	)
	(segment
		(start 72.132952 -42.063416)
		(end 72.341232 -41.855136)
		(width 0.2032)
		(layer "In7.Cu")
		(net "M1_DQ_NODE1_DQ36")
	)
	(segment
		(start 71.040498 -41.560242)
		(end 71.335138 -41.560242)
		(width 0.2032)
		(layer "In7.Cu")
		(net "M1_DQ_NODE1_DQ36")
	)
	(segment
		(start 74.144632 -40.051736)
		(end 74.352912 -39.843456)
		(width 0.2032)
		(layer "In7.Cu")
		(net "M1_DQ_NODE1_DQ36")
	)
	(segment
		(start 82.57032 -26.369772)
		(end 83.10626 -26.369772)
		(width 0.2032)
		(layer "In7.Cu")
		(net "M1_DQ_NODE1_DQ36")
	)
	(segment
		(start 76.318872 -36.281868)
		(end 79.828644 -36.281868)
		(width 0.2032)
		(layer "In7.Cu")
		(net "M1_DQ_NODE1_DQ36")
	)
	(segment
		(start 73.052178 -39.548562)
		(end 73.346818 -39.548562)
		(width 0.2032)
		(layer "In7.Cu")
		(net "M1_DQ_NODE1_DQ36")
	)
	(segment
		(start 69.323712 -44.578016)
		(end 68.820538 -44.074842)
		(width 0.2032)
		(layer "In7.Cu")
		(net "M1_DQ_NODE1_DQ36")
	)
	(segment
		(start 80.04683 -36.063682)
		(end 80.04683 -31.62681)
		(width 0.2032)
		(layer "In7.Cu")
		(net "M1_DQ_NODE1_DQ36")
	)
	(segment
		(start 71.127112 -43.069256)
		(end 71.335392 -42.860976)
		(width 0.2032)
		(layer "In7.Cu")
		(net "M1_DQ_NODE1_DQ36")
	)
	(segment
		(start 68.950332 -61.302138)
		(end 69.00672 -61.24575)
		(width 0.2032)
		(layer "In7.Cu")
		(net "M1_DQ_NODE1_DQ36")
	)
	(segment
		(start 69.826378 -42.774362)
		(end 70.034658 -42.566082)
		(width 0.2032)
		(layer "In7.Cu")
		(net "M1_DQ_NODE1_DQ36")
	)
	(segment
		(start 71.838058 -41.057322)
		(end 71.838058 -40.762682)
		(width 0.2032)
		(layer "In7.Cu")
		(net "M1_DQ_NODE1_DQ36")
	)
	(segment
		(start 68.67906 -58.035698)
		(end 68.67906 -45.517308)
		(width 0.2032)
		(layer "In7.Cu")
		(net "M1_DQ_NODE1_DQ36")
	)
	(segment
		(start 72.341232 -41.560496)
		(end 71.838058 -41.057322)
		(width 0.2032)
		(layer "In7.Cu")
		(net "M1_DQ_NODE1_DQ36")
	)
	(segment
		(start 70.832218 -42.063162)
		(end 70.832218 -41.768522)
		(width 0.2032)
		(layer "In7.Cu")
		(net "M1_DQ_NODE1_DQ36")
	)
	(segment
		(start 69.323458 -43.571922)
		(end 69.826632 -44.075096)
		(width 0.2032)
		(layer "In7.Cu")
		(net "M1_DQ_NODE1_DQ36")
	)
	(segment
		(start 72.046338 -40.554402)
		(end 72.340978 -40.554402)
		(width 0.2032)
		(layer "In7.Cu")
		(net "M1_DQ_NODE1_DQ36")
	)
	(segment
		(start 69.56806 -59.61634)
		(end 69.56806 -58.924698)
		(width 0.2032)
		(layer "In7.Cu")
		(net "M1_DQ_NODE1_DQ36")
	)
	(segment
		(start 69.826632 -44.075096)
		(end 70.121272 -44.075096)
		(width 0.2032)
		(layer "In7.Cu")
		(net "M1_DQ_NODE1_DQ36")
	)
	(segment
		(start 74.352912 -39.548816)
		(end 73.849738 -39.045642)
		(width 0.2032)
		(layer "In7.Cu")
		(net "M1_DQ_NODE1_DQ36")
	)
	(segment
		(start 71.335392 -42.566336)
		(end 70.832218 -42.063162)
		(width 0.2032)
		(layer "In7.Cu")
		(net "M1_DQ_NODE1_DQ36")
	)
	(segment
		(start 68.820538 -44.074842)
		(end 68.820538 -43.780202)
		(width 0.2032)
		(layer "In7.Cu")
		(net "M1_DQ_NODE1_DQ36")
	)
	(segment
		(start 80.04683 -31.62681)
		(end 80.37068 -31.30296)
		(width 0.2032)
		(layer "In7.Cu")
		(net "M1_DQ_NODE1_DQ36")
	)
	(segment
		(start 72.341232 -41.855136)
		(end 72.341232 -41.560496)
		(width 0.2032)
		(layer "In7.Cu")
		(net "M1_DQ_NODE1_DQ36")
	)
	(segment
		(start 73.849738 -38.751002)
		(end 76.318872 -36.281868)
		(width 0.2032)
		(layer "In7.Cu")
		(net "M1_DQ_NODE1_DQ36")
	)
	(segment
		(start 69.73316 -59.78144)
		(end 69.56806 -59.61634)
		(width 0.2032)
		(layer "In7.Cu")
		(net "M1_DQ_NODE1_DQ36")
	)
	(segment
		(start 69.336666 -61.24575)
		(end 69.73316 -60.849256)
		(width 0.2032)
		(layer "In7.Cu")
		(net "M1_DQ_NODE1_DQ36")
	)
	(segment
		(start 71.838058 -40.762682)
		(end 72.046338 -40.554402)
		(width 0.2032)
		(layer "In7.Cu")
		(net "M1_DQ_NODE1_DQ36")
	)
	(segment
		(start 69.826378 -43.069002)
		(end 69.826378 -42.774362)
		(width 0.2032)
		(layer "In7.Cu")
		(net "M1_DQ_NODE1_DQ36")
	)
	(segment
		(start 69.56806 -58.924698)
		(end 68.67906 -58.035698)
		(width 0.2032)
		(layer "In7.Cu")
		(net "M1_DQ_NODE1_DQ36")
	)
	(segment
		(start 73.849992 -40.051736)
		(end 74.144632 -40.051736)
		(width 0.2032)
		(layer "In7.Cu")
		(net "M1_DQ_NODE1_DQ36")
	)
	(segment
		(start 71.838312 -42.063416)
		(end 72.132952 -42.063416)
		(width 0.2032)
		(layer "In7.Cu")
		(net "M1_DQ_NODE1_DQ36")
	)
	(segment
		(start 74.352912 -39.843456)
		(end 74.352912 -39.548816)
		(width 0.2032)
		(layer "In7.Cu")
		(net "M1_DQ_NODE1_DQ36")
	)
	(segment
		(start 72.843898 -39.756842)
		(end 73.052178 -39.548562)
		(width 0.2032)
		(layer "In7.Cu")
		(net "M1_DQ_NODE1_DQ36")
	)
	(segment
		(start 73.138792 -41.057576)
		(end 73.347072 -40.849296)
		(width 0.2032)
		(layer "In7.Cu")
		(net "M1_DQ_NODE1_DQ36")
	)
	(segment
		(start 68.67906 -45.517308)
		(end 69.323712 -44.872656)
		(width 0.2032)
		(layer "In7.Cu")
		(net "M1_DQ_NODE1_DQ36")
	)
	(segment
		(start 70.329552 -43.866816)
		(end 70.329552 -43.572176)
		(width 0.2032)
		(layer "In7.Cu")
		(net "M1_DQ_NODE1_DQ36")
	)
	(segment
		(start 68.820538 -43.780202)
		(end 69.028818 -43.571922)
		(width 0.2032)
		(layer "In7.Cu")
		(net "M1_DQ_NODE1_DQ36")
	)
	(segment
		(start 73.347072 -40.849296)
		(end 73.347072 -40.554656)
		(width 0.2032)
		(layer "In7.Cu")
		(net "M1_DQ_NODE1_DQ36")
	)
	(segment
		(start 72.844152 -41.057576)
		(end 73.138792 -41.057576)
		(width 0.2032)
		(layer "In7.Cu")
		(net "M1_DQ_NODE1_DQ36")
	)
	(segment
		(start 70.832218 -41.768522)
		(end 71.040498 -41.560242)
		(width 0.2032)
		(layer "In7.Cu")
		(net "M1_DQ_NODE1_DQ36")
	)
	(segment
		(start 69.323712 -44.872656)
		(end 69.323712 -44.578016)
		(width 0.2032)
		(layer "In7.Cu")
		(net "M1_DQ_NODE1_DQ36")
	)
	(segment
		(start 71.335138 -41.560242)
		(end 71.838312 -42.063416)
		(width 0.2032)
		(layer "In7.Cu")
		(net "M1_DQ_NODE1_DQ36")
	)
	(segment
		(start 72.340978 -40.554402)
		(end 72.844152 -41.057576)
		(width 0.2032)
		(layer "In7.Cu")
		(net "M1_DQ_NODE1_DQ36")
	)
	(segment
		(start 69.028818 -43.571922)
		(end 69.323458 -43.571922)
		(width 0.2032)
		(layer "In7.Cu")
		(net "M1_DQ_NODE1_DQ36")
	)
	(segment
		(start 80.37068 -28.569412)
		(end 82.57032 -26.369772)
		(width 0.2032)
		(layer "In7.Cu")
		(net "M1_DQ_NODE1_DQ36")
	)
	(segment
		(start 80.24876 -111.278416)
		(end 80.24876 -114.114072)
		(width 0.1016)
		(layer "F.Cu")
		(net "FM_CPLD_NODE1_CPU_RESET_L")
	)
	(segment
		(start 123.956318 -51.743864)
		(end 124.757434 -50.942748)
		(width 0.1016)
		(layer "F.Cu")
		(net "FM_CPLD_NODE1_CPU_RESET_L")
	)
	(segment
		(start 71.042276 -81.850484)
		(end 71.54926 -82.357468)
		(width 0.1016)
		(layer "F.Cu")
		(net "FM_CPLD_NODE1_CPU_RESET_L")
	)
	(segment
		(start 124.757434 -50.942748)
		(end 124.757434 -50.475896)
		(width 0.1016)
		(layer "F.Cu")
		(net "FM_CPLD_NODE1_CPU_RESET_L")
	)
	(segment
		(start 160.51022 -166.434516)
		(end 160.51022 -165.450774)
		(width 0.1016)
		(layer "F.Cu")
		(net "FM_CPLD_NODE1_CPU_RESET_L")
	)
	(segment
		(start 79.79156 -119.453152)
		(end 80.25892 -119.920512)
		(width 0.1016)
		(layer "F.Cu")
		(net "FM_CPLD_NODE1_CPU_RESET_L")
	)
	(segment
		(start 174.01032 -122.36577)
		(end 173.510448 -122.865642)
		(width 0.1016)
		(layer "F.Cu")
		(net "FM_CPLD_NODE1_CPU_RESET_L")
	)
	(segment
		(start 112.593628 -64.704976)
		(end 111.892334 -65.40627)
		(width 0.1016)
		(layer "F.Cu")
		(net "FM_CPLD_NODE1_CPU_RESET_L")
	)
	(segment
		(start 191.897 -119.253)
		(end 191.215772 -119.934228)
		(width 0.1016)
		(layer "F.Cu")
		(net "FM_CPLD_NODE1_CPU_RESET_L")
	)
	(segment
		(start 115.576604 -64.704976)
		(end 112.593628 -64.704976)
		(width 0.1016)
		(layer "F.Cu")
		(net "FM_CPLD_NODE1_CPU_RESET_L")
	)
	(segment
		(start 71.54926 -82.357468)
		(end 71.670418 -82.357468)
		(width 0.1016)
		(layer "F.Cu")
		(net "FM_CPLD_NODE1_CPU_RESET_L")
	)
	(segment
		(start 70.476364 -81.528158)
		(end 70.79869 -81.850484)
		(width 0.1016)
		(layer "F.Cu")
		(net "FM_CPLD_NODE1_CPU_RESET_L")
	)
	(segment
		(start 52.623212 -149.578822)
		(end 52.623212 -150.26513)
		(width 0.1016)
		(layer "F.Cu")
		(net "FM_CPLD_NODE1_CPU_RESET_L")
	)
	(segment
		(start 79.79156 -114.571272)
		(end 79.79156 -119.453152)
		(width 0.1016)
		(layer "F.Cu")
		(net "FM_CPLD_NODE1_CPU_RESET_L")
	)
	(segment
		(start 156.812742 -163.169346)
		(end 155.257246 -161.61385)
		(width 0.1016)
		(layer "F.Cu")
		(net "FM_CPLD_NODE1_CPU_RESET_L")
	)
	(segment
		(start 70.79869 -81.850484)
		(end 71.042276 -81.850484)
		(width 0.1016)
		(layer "F.Cu")
		(net "FM_CPLD_NODE1_CPU_RESET_L")
	)
	(segment
		(start 186.913774 -119.934228)
		(end 185.76036 -121.087642)
		(width 0.1016)
		(layer "F.Cu")
		(net "FM_CPLD_NODE1_CPU_RESET_L")
	)
	(segment
		(start 111.892334 -65.40627)
		(end 110.460028 -65.40627)
		(width 0.1016)
		(layer "F.Cu")
		(net "FM_CPLD_NODE1_CPU_RESET_L")
	)
	(segment
		(start 158.361634 -163.302188)
		(end 158.13532 -163.302188)
		(width 0.1016)
		(layer "F.Cu")
		(net "FM_CPLD_NODE1_CPU_RESET_L")
	)
	(segment
		(start 158.002478 -163.169346)
		(end 156.812742 -163.169346)
		(width 0.1016)
		(layer "F.Cu")
		(net "FM_CPLD_NODE1_CPU_RESET_L")
	)
	(segment
		(start 160.51022 -165.450774)
		(end 158.361634 -163.302188)
		(width 0.1016)
		(layer "F.Cu")
		(net "FM_CPLD_NODE1_CPU_RESET_L")
	)
	(segment
		(start 80.24876 -114.114072)
		(end 79.79156 -114.571272)
		(width 0.1016)
		(layer "F.Cu")
		(net "FM_CPLD_NODE1_CPU_RESET_L")
	)
	(segment
		(start 115.95862 -65.032636)
		(end 115.904264 -65.032636)
		(width 0.1016)
		(layer "F.Cu")
		(net "FM_CPLD_NODE1_CPU_RESET_L")
	)
	(segment
		(start 191.215772 -119.934228)
		(end 186.913774 -119.934228)
		(width 0.1016)
		(layer "F.Cu")
		(net "FM_CPLD_NODE1_CPU_RESET_L")
	)
	(segment
		(start 192.659 -119.253)
		(end 191.897 -119.253)
		(width 0.1016)
		(layer "F.Cu")
		(net "FM_CPLD_NODE1_CPU_RESET_L")
	)
	(segment
		(start 115.904264 -65.032636)
		(end 115.576604 -64.704976)
		(width 0.1016)
		(layer "F.Cu")
		(net "FM_CPLD_NODE1_CPU_RESET_L")
	)
	(segment
		(start 158.13532 -163.302188)
		(end 158.002478 -163.169346)
		(width 0.1016)
		(layer "F.Cu")
		(net "FM_CPLD_NODE1_CPU_RESET_L")
	)
	(segment
		(start 70.202044 -81.528158)
		(end 70.476364 -81.528158)
		(width 0.1016)
		(layer "F.Cu")
		(net "FM_CPLD_NODE1_CPU_RESET_L")
	)
	(via
		(at 115.95862 -65.032636)
		(size 0.508)
		(drill 0.254)
		(layers "F.Cu" "B.Cu")
		(net "FM_CPLD_NODE1_CPU_RESET_L")
	)
	(via
		(at 71.670418 -82.357468)
		(size 0.508)
		(drill 0.254)
		(layers "F.Cu" "B.Cu")
		(net "FM_CPLD_NODE1_CPU_RESET_L")
	)
	(via
		(at 80.25892 -119.920512)
		(size 0.508)
		(drill 0.254)
		(layers "F.Cu" "B.Cu")
		(net "FM_CPLD_NODE1_CPU_RESET_L")
	)
	(via
		(at 87.34552 -90.675206)
		(size 0.508)
		(drill 0.254)
		(layers "F.Cu" "B.Cu")
		(net "FM_CPLD_NODE1_CPU_RESET_L")
	)
	(via
		(at 192.659 -119.253)
		(size 0.508)
		(drill 0.254)
		(layers "F.Cu" "B.Cu")
		(net "FM_CPLD_NODE1_CPU_RESET_L")
	)
	(via
		(at 160.51022 -166.434516)
		(size 0.508)
		(drill 0.254)
		(layers "F.Cu" "B.Cu")
		(net "FM_CPLD_NODE1_CPU_RESET_L")
	)
	(via
		(at 123.956318 -51.743864)
		(size 0.508)
		(drill 0.254)
		(layers "F.Cu" "B.Cu")
		(net "FM_CPLD_NODE1_CPU_RESET_L")
	)
	(via
		(at 173.510448 -122.865642)
		(size 0.49022)
		(drill 0.254)
		(layers "F.Cu" "B.Cu")
		(net "FM_CPLD_NODE1_CPU_RESET_L")
	)
	(via
		(at 80.24876 -111.278416)
		(size 0.508)
		(drill 0.254)
		(layers "F.Cu" "B.Cu")
		(net "FM_CPLD_NODE1_CPU_RESET_L")
	)
	(via
		(at 52.623212 -150.26513)
		(size 0.508)
		(drill 0.254)
		(layers "F.Cu" "B.Cu")
		(net "FM_CPLD_NODE1_CPU_RESET_L")
	)
	(via
		(at 185.76036 -121.087642)
		(size 0.508)
		(drill 0.254)
		(layers "F.Cu" "B.Cu")
		(net "FM_CPLD_NODE1_CPU_RESET_L")
	)
	(segment
		(start 73.557384 -83.130898)
		(end 73.89114 -82.797142)
		(width 0.1143)
		(layer "In2.Cu")
		(net "FM_CPLD_NODE1_CPU_RESET_L")
	)
	(segment
		(start 77.879702 -85.622384)
		(end 77.89926 -85.622384)
		(width 0.1143)
		(layer "In2.Cu")
		(net "FM_CPLD_NODE1_CPU_RESET_L")
	)
	(segment
		(start 64.635888 -150.234396)
		(end 65.169796 -149.700488)
		(width 0.1143)
		(layer "In2.Cu")
		(net "FM_CPLD_NODE1_CPU_RESET_L")
	)
	(segment
		(start 171.896786 -164.048186)
		(end 182.061358 -164.048186)
		(width 0.1143)
		(layer "In2.Cu")
		(net "FM_CPLD_NODE1_CPU_RESET_L")
	)
	(segment
		(start 84.34324 -97.201228)
		(end 84.34324 -105.36682)
		(width 0.1143)
		(layer "In2.Cu")
		(net "FM_CPLD_NODE1_CPU_RESET_L")
	)
	(segment
		(start 84.34324 -105.36682)
		(end 81.083404 -108.626656)
		(width 0.1143)
		(layer "In2.Cu")
		(net "FM_CPLD_NODE1_CPU_RESET_L")
	)
	(segment
		(start 79.1337 -86.877144)
		(end 79.1337 -90.160348)
		(width 0.1143)
		(layer "In2.Cu")
		(net "FM_CPLD_NODE1_CPU_RESET_L")
	)
	(segment
		(start 71.670418 -82.357468)
		(end 72.443848 -83.130898)
		(width 0.1143)
		(layer "In2.Cu")
		(net "FM_CPLD_NODE1_CPU_RESET_L")
	)
	(segment
		(start 60.908692 -150.234396)
		(end 64.635888 -150.234396)
		(width 0.1143)
		(layer "In2.Cu")
		(net "FM_CPLD_NODE1_CPU_RESET_L")
	)
	(segment
		(start 77.73162 -83.179666)
		(end 77.73162 -85.474302)
		(width 0.1143)
		(layer "In2.Cu")
		(net "FM_CPLD_NODE1_CPU_RESET_L")
	)
	(segment
		(start 82.568034 -91.690952)
		(end 82.570574 -91.688412)
		(width 0.1143)
		(layer "In2.Cu")
		(net "FM_CPLD_NODE1_CPU_RESET_L")
	)
	(segment
		(start 52.68087 -150.207472)
		(end 60.881768 -150.207472)
		(width 0.1143)
		(layer "In2.Cu")
		(net "FM_CPLD_NODE1_CPU_RESET_L")
	)
	(segment
		(start 180.683408 -121.37009)
		(end 173.30547 -121.37009)
		(width 0.1143)
		(layer "In2.Cu")
		(net "FM_CPLD_NODE1_CPU_RESET_L")
	)
	(segment
		(start 77.349096 -82.797142)
		(end 77.73162 -83.179666)
		(width 0.1143)
		(layer "In2.Cu")
		(net "FM_CPLD_NODE1_CPU_RESET_L")
	)
	(segment
		(start 80.510126 -109.082332)
		(end 80.510126 -111.01705)
		(width 0.1143)
		(layer "In2.Cu")
		(net "FM_CPLD_NODE1_CPU_RESET_L")
	)
	(segment
		(start 192.659 -119.634)
		(end 192.659 -119.253)
		(width 0.1143)
		(layer "In2.Cu")
		(net "FM_CPLD_NODE1_CPU_RESET_L")
	)
	(segment
		(start 160.51022 -166.434516)
		(end 163.733226 -166.434516)
		(width 0.1143)
		(layer "In2.Cu")
		(net "FM_CPLD_NODE1_CPU_RESET_L")
	)
	(segment
		(start 79.91602 -120.263412)
		(end 80.25892 -119.920512)
		(width 0.1143)
		(layer "In2.Cu")
		(net "FM_CPLD_NODE1_CPU_RESET_L")
	)
	(segment
		(start 164.698426 -166.751)
		(end 165.613842 -165.835584)
		(width 0.1143)
		(layer "In2.Cu")
		(net "FM_CPLD_NODE1_CPU_RESET_L")
	)
	(segment
		(start 81.083404 -108.626656)
		(end 80.965802 -108.626656)
		(width 0.1143)
		(layer "In2.Cu")
		(net "FM_CPLD_NODE1_CPU_RESET_L")
	)
	(segment
		(start 180.995066 -121.058432)
		(end 180.683408 -121.37009)
		(width 0.1143)
		(layer "In2.Cu")
		(net "FM_CPLD_NODE1_CPU_RESET_L")
	)
	(segment
		(start 86.118192 -90.675206)
		(end 87.34552 -90.675206)
		(width 0.1143)
		(layer "In2.Cu")
		(net "FM_CPLD_NODE1_CPU_RESET_L")
	)
	(segment
		(start 82.570574 -91.688412)
		(end 85.104224 -91.688412)
		(width 0.1143)
		(layer "In2.Cu")
		(net "FM_CPLD_NODE1_CPU_RESET_L")
	)
	(segment
		(start 170.109388 -165.835584)
		(end 171.896786 -164.048186)
		(width 0.1143)
		(layer "In2.Cu")
		(net "FM_CPLD_NODE1_CPU_RESET_L")
	)
	(segment
		(start 52.623212 -150.26513)
		(end 52.68087 -150.207472)
		(width 0.1143)
		(layer "In2.Cu")
		(net "FM_CPLD_NODE1_CPU_RESET_L")
	)
	(segment
		(start 82.433414 -91.688412)
		(end 82.435954 -91.690952)
		(width 0.1143)
		(layer "In2.Cu")
		(net "FM_CPLD_NODE1_CPU_RESET_L")
	)
	(segment
		(start 77.91704 -85.640418)
		(end 77.91704 -85.660484)
		(width 0.1143)
		(layer "In2.Cu")
		(net "FM_CPLD_NODE1_CPU_RESET_L")
	)
	(segment
		(start 85.104224 -91.688412)
		(end 85.104478 -91.688158)
		(width 0.1143)
		(layer "In2.Cu")
		(net "FM_CPLD_NODE1_CPU_RESET_L")
	)
	(segment
		(start 79.91602 -133.845554)
		(end 79.91602 -120.263412)
		(width 0.1143)
		(layer "In2.Cu")
		(net "FM_CPLD_NODE1_CPU_RESET_L")
	)
	(segment
		(start 82.435954 -91.690952)
		(end 82.568034 -91.690952)
		(width 0.1143)
		(layer "In2.Cu")
		(net "FM_CPLD_NODE1_CPU_RESET_L")
	)
	(segment
		(start 192.913 -119.888)
		(end 192.659 -119.634)
		(width 0.1143)
		(layer "In2.Cu")
		(net "FM_CPLD_NODE1_CPU_RESET_L")
	)
	(segment
		(start 77.91704 -85.660484)
		(end 79.1337 -86.877144)
		(width 0.1143)
		(layer "In2.Cu")
		(net "FM_CPLD_NODE1_CPU_RESET_L")
	)
	(segment
		(start 79.0321 -146.322034)
		(end 79.0321 -134.729474)
		(width 0.1143)
		(layer "In2.Cu")
		(net "FM_CPLD_NODE1_CPU_RESET_L")
	)
	(segment
		(start 87.34552 -90.675206)
		(end 87.34552 -94.198948)
		(width 0.1143)
		(layer "In2.Cu")
		(net "FM_CPLD_NODE1_CPU_RESET_L")
	)
	(segment
		(start 73.018142 -148.8694)
		(end 73.5457 -148.341842)
		(width 0.1143)
		(layer "In2.Cu")
		(net "FM_CPLD_NODE1_CPU_RESET_L")
	)
	(segment
		(start 173.30547 -121.37009)
		(end 173.015148 -121.660412)
		(width 0.1143)
		(layer "In2.Cu")
		(net "FM_CPLD_NODE1_CPU_RESET_L")
	)
	(segment
		(start 73.5457 -148.341842)
		(end 77.012292 -148.341842)
		(width 0.1143)
		(layer "In2.Cu")
		(net "FM_CPLD_NODE1_CPU_RESET_L")
	)
	(segment
		(start 80.661764 -91.688412)
		(end 82.433414 -91.688412)
		(width 0.1143)
		(layer "In2.Cu")
		(net "FM_CPLD_NODE1_CPU_RESET_L")
	)
	(segment
		(start 192.659 -153.450544)
		(end 192.659 -138.684)
		(width 0.1143)
		(layer "In2.Cu")
		(net "FM_CPLD_NODE1_CPU_RESET_L")
	)
	(segment
		(start 77.89926 -85.622384)
		(end 77.89926 -85.622638)
		(width 0.1143)
		(layer "In2.Cu")
		(net "FM_CPLD_NODE1_CPU_RESET_L")
	)
	(segment
		(start 68.01612 -148.8694)
		(end 73.018142 -148.8694)
		(width 0.1143)
		(layer "In2.Cu")
		(net "FM_CPLD_NODE1_CPU_RESET_L")
	)
	(segment
		(start 79.1337 -90.160348)
		(end 80.661764 -91.688412)
		(width 0.1143)
		(layer "In2.Cu")
		(net "FM_CPLD_NODE1_CPU_RESET_L")
	)
	(segment
		(start 183.09717 -121.058432)
		(end 180.995066 -121.058432)
		(width 0.1143)
		(layer "In2.Cu")
		(net "FM_CPLD_NODE1_CPU_RESET_L")
	)
	(segment
		(start 173.015148 -121.660412)
		(end 173.015148 -122.436382)
		(width 0.1143)
		(layer "In2.Cu")
		(net "FM_CPLD_NODE1_CPU_RESET_L")
	)
	(segment
		(start 85.104478 -91.688158)
		(end 85.10524 -91.688158)
		(width 0.1143)
		(layer "In2.Cu")
		(net "FM_CPLD_NODE1_CPU_RESET_L")
	)
	(segment
		(start 60.881768 -150.207472)
		(end 60.908692 -150.234396)
		(width 0.1143)
		(layer "In2.Cu")
		(net "FM_CPLD_NODE1_CPU_RESET_L")
	)
	(segment
		(start 87.34552 -94.198948)
		(end 84.34324 -97.201228)
		(width 0.1143)
		(layer "In2.Cu")
		(net "FM_CPLD_NODE1_CPU_RESET_L")
	)
	(segment
		(start 77.012292 -148.341842)
		(end 79.0321 -146.322034)
		(width 0.1143)
		(layer "In2.Cu")
		(net "FM_CPLD_NODE1_CPU_RESET_L")
	)
	(segment
		(start 173.015148 -122.436382)
		(end 173.444408 -122.865642)
		(width 0.1143)
		(layer "In2.Cu")
		(net "FM_CPLD_NODE1_CPU_RESET_L")
	)
	(segment
		(start 67.185032 -149.700488)
		(end 68.01612 -148.8694)
		(width 0.1143)
		(layer "In2.Cu")
		(net "FM_CPLD_NODE1_CPU_RESET_L")
	)
	(segment
		(start 79.0321 -134.729474)
		(end 79.91602 -133.845554)
		(width 0.1143)
		(layer "In2.Cu")
		(net "FM_CPLD_NODE1_CPU_RESET_L")
	)
	(segment
		(start 73.89114 -82.797142)
		(end 77.349096 -82.797142)
		(width 0.1143)
		(layer "In2.Cu")
		(net "FM_CPLD_NODE1_CPU_RESET_L")
	)
	(segment
		(start 185.76036 -121.087642)
		(end 183.12638 -121.087642)
		(width 0.1143)
		(layer "In2.Cu")
		(net "FM_CPLD_NODE1_CPU_RESET_L")
	)
	(segment
		(start 192.659 -138.684)
		(end 192.913 -138.43)
		(width 0.1143)
		(layer "In2.Cu")
		(net "FM_CPLD_NODE1_CPU_RESET_L")
	)
	(segment
		(start 164.04971 -166.751)
		(end 164.698426 -166.751)
		(width 0.1143)
		(layer "In2.Cu")
		(net "FM_CPLD_NODE1_CPU_RESET_L")
	)
	(segment
		(start 65.169796 -149.700488)
		(end 67.185032 -149.700488)
		(width 0.1143)
		(layer "In2.Cu")
		(net "FM_CPLD_NODE1_CPU_RESET_L")
	)
	(segment
		(start 165.613842 -165.835584)
		(end 170.109388 -165.835584)
		(width 0.1143)
		(layer "In2.Cu")
		(net "FM_CPLD_NODE1_CPU_RESET_L")
	)
	(segment
		(start 183.12638 -121.087642)
		(end 183.09717 -121.058432)
		(width 0.1143)
		(layer "In2.Cu")
		(net "FM_CPLD_NODE1_CPU_RESET_L")
	)
	(segment
		(start 182.061358 -164.048186)
		(end 192.659 -153.450544)
		(width 0.1143)
		(layer "In2.Cu")
		(net "FM_CPLD_NODE1_CPU_RESET_L")
	)
	(segment
		(start 192.913 -138.43)
		(end 192.913 -119.888)
		(width 0.1143)
		(layer "In2.Cu")
		(net "FM_CPLD_NODE1_CPU_RESET_L")
	)
	(segment
		(start 85.10524 -91.688158)
		(end 86.118192 -90.675206)
		(width 0.1143)
		(layer "In2.Cu")
		(net "FM_CPLD_NODE1_CPU_RESET_L")
	)
	(segment
		(start 77.73162 -85.474302)
		(end 77.879702 -85.622384)
		(width 0.1143)
		(layer "In2.Cu")
		(net "FM_CPLD_NODE1_CPU_RESET_L")
	)
	(segment
		(start 163.733226 -166.434516)
		(end 164.04971 -166.751)
		(width 0.1143)
		(layer "In2.Cu")
		(net "FM_CPLD_NODE1_CPU_RESET_L")
	)
	(segment
		(start 72.443848 -83.130898)
		(end 73.557384 -83.130898)
		(width 0.1143)
		(layer "In2.Cu")
		(net "FM_CPLD_NODE1_CPU_RESET_L")
	)
	(segment
		(start 80.965802 -108.626656)
		(end 80.510126 -109.082332)
		(width 0.1143)
		(layer "In2.Cu")
		(net "FM_CPLD_NODE1_CPU_RESET_L")
	)
	(segment
		(start 77.89926 -85.622638)
		(end 77.91704 -85.640418)
		(width 0.1143)
		(layer "In2.Cu")
		(net "FM_CPLD_NODE1_CPU_RESET_L")
	)
	(segment
		(start 80.510126 -111.01705)
		(end 80.24876 -111.278416)
		(width 0.1143)
		(layer "In2.Cu")
		(net "FM_CPLD_NODE1_CPU_RESET_L")
	)
	(segment
		(start 173.444408 -122.865642)
		(end 173.510448 -122.865642)
		(width 0.1143)
		(layer "In2.Cu")
		(net "FM_CPLD_NODE1_CPU_RESET_L")
	)
	(segment
		(start 151.40686 -106.054652)
		(end 156.246322 -110.894114)
		(width 0.1143)
		(layer "In6.Cu")
		(net "FM_CPLD_NODE1_CPU_RESET_L")
	)
	(segment
		(start 156.246322 -110.894114)
		(end 165.866826 -110.894114)
		(width 0.1143)
		(layer "In6.Cu")
		(net "FM_CPLD_NODE1_CPU_RESET_L")
	)
	(segment
		(start 167.82796 -112.855248)
		(end 167.82796 -116.827554)
		(width 0.1143)
		(layer "In6.Cu")
		(net "FM_CPLD_NODE1_CPU_RESET_L")
	)
	(segment
		(start 151.40686 -103.876348)
		(end 151.40686 -106.054652)
		(width 0.1143)
		(layer "In6.Cu")
		(net "FM_CPLD_NODE1_CPU_RESET_L")
	)
	(segment
		(start 167.10406 -117.551454)
		(end 167.10406 -120.684798)
		(width 0.1143)
		(layer "In6.Cu")
		(net "FM_CPLD_NODE1_CPU_RESET_L")
	)
	(segment
		(start 167.82796 -116.827554)
		(end 167.10406 -117.551454)
		(width 0.1143)
		(layer "In6.Cu")
		(net "FM_CPLD_NODE1_CPU_RESET_L")
	)
	(segment
		(start 171.43984 -122.059192)
		(end 172.24629 -122.865642)
		(width 0.1143)
		(layer "In6.Cu")
		(net "FM_CPLD_NODE1_CPU_RESET_L")
	)
	(segment
		(start 167.10406 -120.684798)
		(end 168.478454 -122.059192)
		(width 0.1143)
		(layer "In6.Cu")
		(net "FM_CPLD_NODE1_CPU_RESET_L")
	)
	(segment
		(start 168.478454 -122.059192)
		(end 171.43984 -122.059192)
		(width 0.1143)
		(layer "In6.Cu")
		(net "FM_CPLD_NODE1_CPU_RESET_L")
	)
	(segment
		(start 91.64574 -91.625674)
		(end 95.180658 -88.090756)
		(width 0.1143)
		(layer "In6.Cu")
		(net "FM_CPLD_NODE1_CPU_RESET_L")
	)
	(segment
		(start 172.24629 -122.865642)
		(end 173.510448 -122.865642)
		(width 0.1143)
		(layer "In6.Cu")
		(net "FM_CPLD_NODE1_CPU_RESET_L")
	)
	(segment
		(start 88.295988 -91.625674)
		(end 91.64574 -91.625674)
		(width 0.1143)
		(layer "In6.Cu")
		(net "FM_CPLD_NODE1_CPU_RESET_L")
	)
	(segment
		(start 87.34552 -90.675206)
		(end 88.295988 -91.625674)
		(width 0.1143)
		(layer "In6.Cu")
		(net "FM_CPLD_NODE1_CPU_RESET_L")
	)
	(segment
		(start 135.621268 -88.090756)
		(end 151.40686 -103.876348)
		(width 0.1143)
		(layer "In6.Cu")
		(net "FM_CPLD_NODE1_CPU_RESET_L")
	)
	(segment
		(start 165.866826 -110.894114)
		(end 167.82796 -112.855248)
		(width 0.1143)
		(layer "In6.Cu")
		(net "FM_CPLD_NODE1_CPU_RESET_L")
	)
	(segment
		(start 95.180658 -88.090756)
		(end 135.621268 -88.090756)
		(width 0.1143)
		(layer "In6.Cu")
		(net "FM_CPLD_NODE1_CPU_RESET_L")
	)
	(segment
		(start 122.139964 -53.560218)
		(end 123.956318 -51.743864)
		(width 0.1143)
		(layer "In7.Cu")
		(net "FM_CPLD_NODE1_CPU_RESET_L")
	)
	(segment
		(start 162.818572 -122.022616)
		(end 162.61842 -121.822464)
		(width 0.1143)
		(layer "In7.Cu")
		(net "FM_CPLD_NODE1_CPU_RESET_L")
	)
	(segment
		(start 118.057676 -65.032636)
		(end 120.05818 -63.032132)
		(width 0.1143)
		(layer "In7.Cu")
		(net "FM_CPLD_NODE1_CPU_RESET_L")
	)
	(segment
		(start 113.93297 -71.475092)
		(end 115.43792 -69.970142)
		(width 0.1143)
		(layer "In7.Cu")
		(net "FM_CPLD_NODE1_CPU_RESET_L")
	)
	(segment
		(start 115.24996 -76.027534)
		(end 114.82197 -75.599544)
		(width 0.1143)
		(layer "In7.Cu")
		(net "FM_CPLD_NODE1_CPU_RESET_L")
	)
	(segment
		(start 166.46906 -121.73077)
		(end 164.65423 -121.73077)
		(width 0.1143)
		(layer "In7.Cu")
		(net "FM_CPLD_NODE1_CPU_RESET_L")
	)
	(segment
		(start 115.43792 -65.553336)
		(end 115.95862 -65.032636)
		(width 0.1143)
		(layer "In7.Cu")
		(net "FM_CPLD_NODE1_CPU_RESET_L")
	)
	(segment
		(start 156.3497 -112.345724)
		(end 141.458696 -97.45472)
		(width 0.1143)
		(layer "In7.Cu")
		(net "FM_CPLD_NODE1_CPU_RESET_L")
	)
	(segment
		(start 114.71021 -75.599544)
		(end 113.93297 -74.822304)
		(width 0.1143)
		(layer "In7.Cu")
		(net "FM_CPLD_NODE1_CPU_RESET_L")
	)
	(segment
		(start 122.139964 -54.263036)
		(end 122.139964 -53.560218)
		(width 0.1143)
		(layer "In7.Cu")
		(net "FM_CPLD_NODE1_CPU_RESET_L")
	)
	(segment
		(start 160.116012 -121.822464)
		(end 156.3497 -118.056152)
		(width 0.1143)
		(layer "In7.Cu")
		(net "FM_CPLD_NODE1_CPU_RESET_L")
	)
	(segment
		(start 164.362384 -122.022616)
		(end 162.818572 -122.022616)
		(width 0.1143)
		(layer "In7.Cu")
		(net "FM_CPLD_NODE1_CPU_RESET_L")
	)
	(segment
		(start 130.166618 -97.45472)
		(end 115.24996 -82.538062)
		(width 0.1143)
		(layer "In7.Cu")
		(net "FM_CPLD_NODE1_CPU_RESET_L")
	)
	(segment
		(start 170.45178 -122.865642)
		(end 169.915332 -122.329194)
		(width 0.1143)
		(layer "In7.Cu")
		(net "FM_CPLD_NODE1_CPU_RESET_L")
	)
	(segment
		(start 115.24996 -82.538062)
		(end 115.24996 -76.027534)
		(width 0.1143)
		(layer "In7.Cu")
		(net "FM_CPLD_NODE1_CPU_RESET_L")
	)
	(segment
		(start 115.95862 -65.032636)
		(end 118.057676 -65.032636)
		(width 0.1143)
		(layer "In7.Cu")
		(net "FM_CPLD_NODE1_CPU_RESET_L")
	)
	(segment
		(start 169.915332 -122.329194)
		(end 167.067484 -122.329194)
		(width 0.1143)
		(layer "In7.Cu")
		(net "FM_CPLD_NODE1_CPU_RESET_L")
	)
	(segment
		(start 115.43792 -69.970142)
		(end 115.43792 -65.553336)
		(width 0.1143)
		(layer "In7.Cu")
		(net "FM_CPLD_NODE1_CPU_RESET_L")
	)
	(segment
		(start 164.65423 -121.73077)
		(end 164.362384 -122.022616)
		(width 0.1143)
		(layer "In7.Cu")
		(net "FM_CPLD_NODE1_CPU_RESET_L")
	)
	(segment
		(start 114.82197 -75.599544)
		(end 114.71021 -75.599544)
		(width 0.1143)
		(layer "In7.Cu")
		(net "FM_CPLD_NODE1_CPU_RESET_L")
	)
	(segment
		(start 120.05818 -63.032132)
		(end 120.05818 -56.34482)
		(width 0.1143)
		(layer "In7.Cu")
		(net "FM_CPLD_NODE1_CPU_RESET_L")
	)
	(segment
		(start 173.510448 -122.865642)
		(end 170.45178 -122.865642)
		(width 0.1143)
		(layer "In7.Cu")
		(net "FM_CPLD_NODE1_CPU_RESET_L")
	)
	(segment
		(start 120.05818 -56.34482)
		(end 122.139964 -54.263036)
		(width 0.1143)
		(layer "In7.Cu")
		(net "FM_CPLD_NODE1_CPU_RESET_L")
	)
	(segment
		(start 167.067484 -122.329194)
		(end 166.46906 -121.73077)
		(width 0.1143)
		(layer "In7.Cu")
		(net "FM_CPLD_NODE1_CPU_RESET_L")
	)
	(segment
		(start 162.61842 -121.822464)
		(end 160.116012 -121.822464)
		(width 0.1143)
		(layer "In7.Cu")
		(net "FM_CPLD_NODE1_CPU_RESET_L")
	)
	(segment
		(start 113.93297 -74.822304)
		(end 113.93297 -71.475092)
		(width 0.1143)
		(layer "In7.Cu")
		(net "FM_CPLD_NODE1_CPU_RESET_L")
	)
	(segment
		(start 156.3497 -118.056152)
		(end 156.3497 -112.345724)
		(width 0.1143)
		(layer "In7.Cu")
		(net "FM_CPLD_NODE1_CPU_RESET_L")
	)
	(segment
		(start 141.458696 -97.45472)
		(end 130.166618 -97.45472)
		(width 0.1143)
		(layer "In7.Cu")
		(net "FM_CPLD_NODE1_CPU_RESET_L")
	)
	(segment
		(start 71.706486 -67.98564)
		(end 71.706486 -68.69049)
		(width 0.1016)
		(layer "F.Cu")
		(net "M1_DQ_NODE1_DQ43")
	)
	(segment
		(start 71.345044 -67.624198)
		(end 71.706486 -67.98564)
		(width 0.1016)
		(layer "F.Cu")
		(net "M1_DQ_NODE1_DQ43")
	)
	(segment
		(start 90.750136 -22.831806)
		(end 91.019122 -23.100792)
		(width 0.1651)
		(layer "F.Cu")
		(net "M1_DQ_NODE1_DQ43")
	)
	(segment
		(start 90.750136 -20.94992)
		(end 90.750136 -22.831806)
		(width 0.1651)
		(layer "F.Cu")
		(net "M1_DQ_NODE1_DQ43")
	)
	(via
		(at 91.019122 -23.100792)
		(size 0.508)
		(drill 0.254)
		(layers "F.Cu" "B.Cu")
		(net "M1_DQ_NODE1_DQ43")
	)
	(via
		(at 71.706486 -68.69049)
		(size 0.508)
		(drill 0.254)
		(layers "F.Cu" "B.Cu")
		(net "M1_DQ_NODE1_DQ43")
	)
	(segment
		(start 91.343988 -23.974044)
		(end 91.647772 -23.974044)
		(width 0.2032)
		(layer "In2.Cu")
		(net "M1_DQ_NODE1_DQ43")
	)
	(segment
		(start 93.75648 -28.222956)
		(end 94.86138 -29.327856)
		(width 0.2032)
		(layer "In2.Cu")
		(net "M1_DQ_NODE1_DQ43")
	)
	(segment
		(start 91.019122 -23.100792)
		(end 91.019122 -23.649178)
		(width 0.2032)
		(layer "In2.Cu")
		(net "M1_DQ_NODE1_DQ43")
	)
	(segment
		(start 77.195172 -66.128392)
		(end 74.877676 -66.128392)
		(width 0.1016)
		(layer "In2.Cu")
		(net "M1_DQ_NODE1_DQ43")
	)
	(segment
		(start 91.019122 -23.649178)
		(end 91.343988 -23.974044)
		(width 0.2032)
		(layer "In2.Cu")
		(net "M1_DQ_NODE1_DQ43")
	)
	(segment
		(start 95.3643 -49.415954)
		(end 82.503518 -62.276736)
		(width 0.2032)
		(layer "In2.Cu")
		(net "M1_DQ_NODE1_DQ43")
	)
	(segment
		(start 91.647772 -23.974044)
		(end 92.9513 -25.277572)
		(width 0.2032)
		(layer "In2.Cu")
		(net "M1_DQ_NODE1_DQ43")
	)
	(segment
		(start 78.482444 -64.23533)
		(end 78.48092 -64.236854)
		(width 0.2032)
		(layer "In2.Cu")
		(net "M1_DQ_NODE1_DQ43")
	)
	(segment
		(start 94.86138 -29.327856)
		(end 94.86138 -33.156906)
		(width 0.2032)
		(layer "In2.Cu")
		(net "M1_DQ_NODE1_DQ43")
	)
	(segment
		(start 74.877676 -66.128392)
		(end 73.275952 -67.730116)
		(width 0.1016)
		(layer "In2.Cu")
		(net "M1_DQ_NODE1_DQ43")
	)
	(segment
		(start 78.482444 -62.605158)
		(end 78.482444 -64.23533)
		(width 0.2032)
		(layer "In2.Cu")
		(net "M1_DQ_NODE1_DQ43")
	)
	(segment
		(start 93.75648 -27.06116)
		(end 93.75648 -28.222956)
		(width 0.2032)
		(layer "In2.Cu")
		(net "M1_DQ_NODE1_DQ43")
	)
	(segment
		(start 92.9513 -25.277572)
		(end 92.9513 -26.25598)
		(width 0.2032)
		(layer "In2.Cu")
		(net "M1_DQ_NODE1_DQ43")
	)
	(segment
		(start 92.9513 -26.25598)
		(end 93.75648 -27.06116)
		(width 0.2032)
		(layer "In2.Cu")
		(net "M1_DQ_NODE1_DQ43")
	)
	(segment
		(start 77.42174 -65.901824)
		(end 77.195172 -66.128392)
		(width 0.1016)
		(layer "In2.Cu")
		(net "M1_DQ_NODE1_DQ43")
	)
	(segment
		(start 94.86138 -33.156906)
		(end 95.3643 -33.659826)
		(width 0.2032)
		(layer "In2.Cu")
		(net "M1_DQ_NODE1_DQ43")
	)
	(segment
		(start 72.66686 -67.730116)
		(end 71.706486 -68.69049)
		(width 0.1016)
		(layer "In2.Cu")
		(net "M1_DQ_NODE1_DQ43")
	)
	(segment
		(start 78.48092 -64.236854)
		(end 78.48092 -64.842644)
		(width 0.2032)
		(layer "In2.Cu")
		(net "M1_DQ_NODE1_DQ43")
	)
	(segment
		(start 78.48092 -64.842644)
		(end 77.42174 -65.901824)
		(width 0.2032)
		(layer "In2.Cu")
		(net "M1_DQ_NODE1_DQ43")
	)
	(segment
		(start 95.3643 -33.659826)
		(end 95.3643 -49.415954)
		(width 0.2032)
		(layer "In2.Cu")
		(net "M1_DQ_NODE1_DQ43")
	)
	(segment
		(start 78.810866 -62.276736)
		(end 78.482444 -62.605158)
		(width 0.2032)
		(layer "In2.Cu")
		(net "M1_DQ_NODE1_DQ43")
	)
	(segment
		(start 73.275952 -67.730116)
		(end 72.66686 -67.730116)
		(width 0.1016)
		(layer "In2.Cu")
		(net "M1_DQ_NODE1_DQ43")
	)
	(segment
		(start 82.503518 -62.276736)
		(end 78.810866 -62.276736)
		(width 0.2032)
		(layer "In2.Cu")
		(net "M1_DQ_NODE1_DQ43")
	)
	(segment
		(start 22.737572 -99.33305)
		(end 26.201878 -99.33305)
		(width 0.1016)
		(layer "F.Cu")
		(net "SMB_MUX_CPU_ICS_NODE1_DAT")
	)
	(segment
		(start 48.387 -99.579684)
		(end 48.027082 -99.579684)
		(width 0.1016)
		(layer "F.Cu")
		(net "SMB_MUX_CPU_ICS_NODE1_DAT")
	)
	(segment
		(start 132.267452 -111.218726)
		(end 132.267452 -112.781842)
		(width 0.1016)
		(layer "F.Cu")
		(net "SMB_MUX_CPU_ICS_NODE1_DAT")
	)
	(segment
		(start 36.329874 -98.230944)
		(end 36.715446 -98.616516)
		(width 0.1016)
		(layer "F.Cu")
		(net "SMB_MUX_CPU_ICS_NODE1_DAT")
	)
	(segment
		(start 47.595028 -99.14763)
		(end 47.02683 -99.14763)
		(width 0.1016)
		(layer "F.Cu")
		(net "SMB_MUX_CPU_ICS_NODE1_DAT")
	)
	(segment
		(start 21.831554 -97.426272)
		(end 21.831554 -98.427032)
		(width 0.1016)
		(layer "F.Cu")
		(net "SMB_MUX_CPU_ICS_NODE1_DAT")
	)
	(segment
		(start 132.684266 -110.801912)
		(end 132.267452 -111.218726)
		(width 0.1016)
		(layer "F.Cu")
		(net "SMB_MUX_CPU_ICS_NODE1_DAT")
	)
	(segment
		(start 131.953762 -113.095532)
		(end 131.953762 -113.96472)
		(width 0.1016)
		(layer "F.Cu")
		(net "SMB_MUX_CPU_ICS_NODE1_DAT")
	)
	(segment
		(start 47.02683 -99.14763)
		(end 44.583858 -96.704658)
		(width 0.1016)
		(layer "F.Cu")
		(net "SMB_MUX_CPU_ICS_NODE1_DAT")
	)
	(segment
		(start 9.701784 -4.535678)
		(end 10.534396 -4.535678)
		(width 0.1016)
		(layer "F.Cu")
		(net "SMB_MUX_CPU_ICS_NODE1_DAT")
	)
	(segment
		(start 9.3726 -4.864862)
		(end 9.701784 -4.535678)
		(width 0.1016)
		(layer "F.Cu")
		(net "SMB_MUX_CPU_ICS_NODE1_DAT")
	)
	(segment
		(start 44.583858 -96.704658)
		(end 44.48937 -96.704658)
		(width 0.1016)
		(layer "F.Cu")
		(net "SMB_MUX_CPU_ICS_NODE1_DAT")
	)
	(segment
		(start 26.37536 -99.33178)
		(end 27.985212 -97.721928)
		(width 0.1016)
		(layer "F.Cu")
		(net "SMB_MUX_CPU_ICS_NODE1_DAT")
	)
	(segment
		(start 31.01848 -98.22942)
		(end 31.01848 -98.230944)
		(width 0.1016)
		(layer "F.Cu")
		(net "SMB_MUX_CPU_ICS_NODE1_DAT")
	)
	(segment
		(start 10.534396 -4.535678)
		(end 10.72007 -4.721352)
		(width 0.1016)
		(layer "F.Cu")
		(net "SMB_MUX_CPU_ICS_NODE1_DAT")
	)
	(segment
		(start 42.103548 -98.616516)
		(end 42.50182 -98.218244)
		(width 0.1016)
		(layer "F.Cu")
		(net "SMB_MUX_CPU_ICS_NODE1_DAT")
	)
	(segment
		(start 132.267452 -112.781842)
		(end 131.953762 -113.095532)
		(width 0.1016)
		(layer "F.Cu")
		(net "SMB_MUX_CPU_ICS_NODE1_DAT")
	)
	(segment
		(start 26.203148 -99.33178)
		(end 26.37536 -99.33178)
		(width 0.1016)
		(layer "F.Cu")
		(net "SMB_MUX_CPU_ICS_NODE1_DAT")
	)
	(segment
		(start 26.201878 -99.33305)
		(end 26.203148 -99.33178)
		(width 0.1016)
		(layer "F.Cu")
		(net "SMB_MUX_CPU_ICS_NODE1_DAT")
	)
	(segment
		(start 48.027082 -99.579684)
		(end 47.595028 -99.14763)
		(width 0.1016)
		(layer "F.Cu")
		(net "SMB_MUX_CPU_ICS_NODE1_DAT")
	)
	(segment
		(start 31.01848 -98.230944)
		(end 36.329874 -98.230944)
		(width 0.1016)
		(layer "F.Cu")
		(net "SMB_MUX_CPU_ICS_NODE1_DAT")
	)
	(segment
		(start 9.3726 -5.272278)
		(end 9.3726 -4.864862)
		(width 0.1016)
		(layer "F.Cu")
		(net "SMB_MUX_CPU_ICS_NODE1_DAT")
	)
	(segment
		(start 132.684266 -109.721396)
		(end 132.684266 -110.801912)
		(width 0.1016)
		(layer "F.Cu")
		(net "SMB_MUX_CPU_ICS_NODE1_DAT")
	)
	(segment
		(start 10.72007 -5.465572)
		(end 10.72007 -4.721352)
		(width 0.1016)
		(layer "F.Cu")
		(net "SMB_MUX_CPU_ICS_NODE1_DAT")
	)
	(segment
		(start 21.831554 -98.427032)
		(end 22.737572 -99.33305)
		(width 0.1016)
		(layer "F.Cu")
		(net "SMB_MUX_CPU_ICS_NODE1_DAT")
	)
	(segment
		(start 42.50182 -98.218244)
		(end 42.50182 -97.672144)
		(width 0.1016)
		(layer "F.Cu")
		(net "SMB_MUX_CPU_ICS_NODE1_DAT")
	)
	(segment
		(start 43.469306 -96.704658)
		(end 44.48937 -96.704658)
		(width 0.1016)
		(layer "F.Cu")
		(net "SMB_MUX_CPU_ICS_NODE1_DAT")
	)
	(segment
		(start 36.715446 -98.616516)
		(end 42.103548 -98.616516)
		(width 0.1016)
		(layer "F.Cu")
		(net "SMB_MUX_CPU_ICS_NODE1_DAT")
	)
	(segment
		(start 30.510988 -97.721928)
		(end 31.01848 -98.22942)
		(width 0.1016)
		(layer "F.Cu")
		(net "SMB_MUX_CPU_ICS_NODE1_DAT")
	)
	(segment
		(start 42.50182 -97.672144)
		(end 43.469306 -96.704658)
		(width 0.1016)
		(layer "F.Cu")
		(net "SMB_MUX_CPU_ICS_NODE1_DAT")
	)
	(segment
		(start 27.985212 -97.721928)
		(end 30.510988 -97.721928)
		(width 0.1016)
		(layer "F.Cu")
		(net "SMB_MUX_CPU_ICS_NODE1_DAT")
	)
	(via
		(at 44.48937 -96.704658)
		(size 0.508)
		(drill 0.254)
		(layers "F.Cu" "B.Cu")
		(net "SMB_MUX_CPU_ICS_NODE1_DAT")
	)
	(via
		(at 132.684266 -109.721396)
		(size 0.508)
		(drill 0.254)
		(layers "F.Cu" "B.Cu")
		(net "SMB_MUX_CPU_ICS_NODE1_DAT")
	)
	(via
		(at 10.72007 -5.465572)
		(size 0.508)
		(drill 0.254)
		(layers "F.Cu" "B.Cu")
		(net "SMB_MUX_CPU_ICS_NODE1_DAT")
	)
	(via
		(at 31.01848 -98.230944)
		(size 0.508)
		(drill 0.254)
		(layers "F.Cu" "B.Cu")
		(net "SMB_MUX_CPU_ICS_NODE1_DAT")
	)
	(via
		(at 118.334282 -101.557836)
		(size 0.508)
		(drill 0.254)
		(layers "F.Cu" "B.Cu")
		(net "SMB_MUX_CPU_ICS_NODE1_DAT")
	)
	(segment
		(start 43.702732 -94.80042)
		(end 43.671236 -94.831916)
		(width 0.1016)
		(layer "B.Cu")
		(net "SMB_MUX_CPU_ICS_NODE1_DAT")
	)
	(segment
		(start 43.671236 -96.704658)
		(end 44.48937 -96.704658)
		(width 0.1016)
		(layer "B.Cu")
		(net "SMB_MUX_CPU_ICS_NODE1_DAT")
	)
	(segment
		(start 43.671236 -94.831916)
		(end 43.671236 -96.704658)
		(width 0.1016)
		(layer "B.Cu")
		(net "SMB_MUX_CPU_ICS_NODE1_DAT")
	)
	(segment
		(start 118.334282 -101.557582)
		(end 118.468902 -101.422962)
		(width 0.1143)
		(layer "In2.Cu")
		(net "SMB_MUX_CPU_ICS_NODE1_DAT")
	)
	(segment
		(start 132.50672 -106.324908)
		(end 132.50672 -109.54385)
		(width 0.1143)
		(layer "In2.Cu")
		(net "SMB_MUX_CPU_ICS_NODE1_DAT")
	)
	(segment
		(start 118.334282 -101.557836)
		(end 118.334282 -101.557582)
		(width 0.1143)
		(layer "In2.Cu")
		(net "SMB_MUX_CPU_ICS_NODE1_DAT")
	)
	(segment
		(start 132.50672 -109.54385)
		(end 132.684266 -109.721396)
		(width 0.1143)
		(layer "In2.Cu")
		(net "SMB_MUX_CPU_ICS_NODE1_DAT")
	)
	(segment
		(start 127.604774 -101.422962)
		(end 132.50672 -106.324908)
		(width 0.1143)
		(layer "In2.Cu")
		(net "SMB_MUX_CPU_ICS_NODE1_DAT")
	)
	(segment
		(start 118.468902 -101.422962)
		(end 127.604774 -101.422962)
		(width 0.1143)
		(layer "In2.Cu")
		(net "SMB_MUX_CPU_ICS_NODE1_DAT")
	)
	(segment
		(start 31.10484 -69.630544)
		(end 31.10484 -41.289986)
		(width 0.1143)
		(layer "In6.Cu")
		(net "SMB_MUX_CPU_ICS_NODE1_DAT")
	)
	(segment
		(start 30.34792 -82.050128)
		(end 30.34792 -70.386194)
		(width 0.1143)
		(layer "In6.Cu")
		(net "SMB_MUX_CPU_ICS_NODE1_DAT")
	)
	(segment
		(start 31.01848 -82.720688)
		(end 30.34792 -82.050128)
		(width 0.1143)
		(layer "In6.Cu")
		(net "SMB_MUX_CPU_ICS_NODE1_DAT")
	)
	(segment
		(start 31.01848 -98.230944)
		(end 31.01848 -82.720688)
		(width 0.1143)
		(layer "In6.Cu")
		(net "SMB_MUX_CPU_ICS_NODE1_DAT")
	)
	(segment
		(start 30.34792 -70.386194)
		(end 30.34919 -70.386194)
		(width 0.1143)
		(layer "In6.Cu")
		(net "SMB_MUX_CPU_ICS_NODE1_DAT")
	)
	(segment
		(start 17.80286 -27.988006)
		(end 17.80286 -14.679168)
		(width 0.1143)
		(layer "In6.Cu")
		(net "SMB_MUX_CPU_ICS_NODE1_DAT")
	)
	(segment
		(start 17.80286 -14.679168)
		(end 11.74496 -8.621268)
		(width 0.1143)
		(layer "In6.Cu")
		(net "SMB_MUX_CPU_ICS_NODE1_DAT")
	)
	(segment
		(start 11.74496 -6.489192)
		(end 10.72134 -5.465572)
		(width 0.1143)
		(layer "In6.Cu")
		(net "SMB_MUX_CPU_ICS_NODE1_DAT")
	)
	(segment
		(start 31.10484 -41.289986)
		(end 17.80286 -27.988006)
		(width 0.1143)
		(layer "In6.Cu")
		(net "SMB_MUX_CPU_ICS_NODE1_DAT")
	)
	(segment
		(start 10.72134 -5.465572)
		(end 10.72007 -5.465572)
		(width 0.1143)
		(layer "In6.Cu")
		(net "SMB_MUX_CPU_ICS_NODE1_DAT")
	)
	(segment
		(start 30.34919 -70.386194)
		(end 31.10484 -69.630544)
		(width 0.1143)
		(layer "In6.Cu")
		(net "SMB_MUX_CPU_ICS_NODE1_DAT")
	)
	(segment
		(start 11.74496 -8.621268)
		(end 11.74496 -6.489192)
		(width 0.1143)
		(layer "In6.Cu")
		(net "SMB_MUX_CPU_ICS_NODE1_DAT")
	)
	(segment
		(start 117.81155 -101.035104)
		(end 105.032048 -101.035104)
		(width 0.1143)
		(layer "In7.Cu")
		(net "SMB_MUX_CPU_ICS_NODE1_DAT")
	)
	(segment
		(start 105.032048 -101.035104)
		(end 100.066602 -106.00055)
		(width 0.1143)
		(layer "In7.Cu")
		(net "SMB_MUX_CPU_ICS_NODE1_DAT")
	)
	(segment
		(start 48.815244 -103.954072)
		(end 47.06874 -102.207568)
		(width 0.1143)
		(layer "In7.Cu")
		(net "SMB_MUX_CPU_ICS_NODE1_DAT")
	)
	(segment
		(start 100.066602 -106.00055)
		(end 88.73744 -106.00055)
		(width 0.1143)
		(layer "In7.Cu")
		(net "SMB_MUX_CPU_ICS_NODE1_DAT")
	)
	(segment
		(start 72.058022 -104.177084)
		(end 65.21704 -104.177084)
		(width 0.1143)
		(layer "In7.Cu")
		(net "SMB_MUX_CPU_ICS_NODE1_DAT")
	)
	(segment
		(start 75.4888 -107.607862)
		(end 72.058022 -104.177084)
		(width 0.1143)
		(layer "In7.Cu")
		(net "SMB_MUX_CPU_ICS_NODE1_DAT")
	)
	(segment
		(start 47.06874 -99.284028)
		(end 44.48937 -96.704658)
		(width 0.1143)
		(layer "In7.Cu")
		(net "SMB_MUX_CPU_ICS_NODE1_DAT")
	)
	(segment
		(start 88.73744 -106.00055)
		(end 87.55761 -107.18038)
		(width 0.1143)
		(layer "In7.Cu")
		(net "SMB_MUX_CPU_ICS_NODE1_DAT")
	)
	(segment
		(start 80.139794 -108.35005)
		(end 79.397606 -107.607862)
		(width 0.1143)
		(layer "In7.Cu")
		(net "SMB_MUX_CPU_ICS_NODE1_DAT")
	)
	(segment
		(start 47.06874 -102.207568)
		(end 47.06874 -99.284028)
		(width 0.1143)
		(layer "In7.Cu")
		(net "SMB_MUX_CPU_ICS_NODE1_DAT")
	)
	(segment
		(start 64.994028 -103.954072)
		(end 48.815244 -103.954072)
		(width 0.1143)
		(layer "In7.Cu")
		(net "SMB_MUX_CPU_ICS_NODE1_DAT")
	)
	(segment
		(start 87.55761 -107.18038)
		(end 85.38337 -107.18038)
		(width 0.1143)
		(layer "In7.Cu")
		(net "SMB_MUX_CPU_ICS_NODE1_DAT")
	)
	(segment
		(start 85.38337 -107.18038)
		(end 84.2137 -108.35005)
		(width 0.1143)
		(layer "In7.Cu")
		(net "SMB_MUX_CPU_ICS_NODE1_DAT")
	)
	(segment
		(start 84.2137 -108.35005)
		(end 80.139794 -108.35005)
		(width 0.1143)
		(layer "In7.Cu")
		(net "SMB_MUX_CPU_ICS_NODE1_DAT")
	)
	(segment
		(start 65.21704 -104.177084)
		(end 64.994028 -103.954072)
		(width 0.1143)
		(layer "In7.Cu")
		(net "SMB_MUX_CPU_ICS_NODE1_DAT")
	)
	(segment
		(start 79.397606 -107.607862)
		(end 75.4888 -107.607862)
		(width 0.1143)
		(layer "In7.Cu")
		(net "SMB_MUX_CPU_ICS_NODE1_DAT")
	)
	(segment
		(start 118.334282 -101.557836)
		(end 117.81155 -101.035104)
		(width 0.1143)
		(layer "In7.Cu")
		(net "SMB_MUX_CPU_ICS_NODE1_DAT")
	)
	(segment
		(start 166.554912 -124.318268)
		(end 167.10787 -123.76531)
		(width 0.1016)
		(layer "F.Cu")
		(net "LED_PWR_NODE1_L")
	)
	(segment
		(start 180.765704 -11.93673)
		(end 180.765704 -12.958826)
		(width 0.1016)
		(layer "F.Cu")
		(net "LED_PWR_NODE1_L")
	)
	(segment
		(start 165.716712 -124.318268)
		(end 166.554912 -124.318268)
		(width 0.1016)
		(layer "F.Cu")
		(net "LED_PWR_NODE1_L")
	)
	(segment
		(start 168.14927 -124.392182)
		(end 167.522398 -123.76531)
		(width 0.1016)
		(layer "F.Cu")
		(net "LED_PWR_NODE1_L")
	)
	(segment
		(start 171.239942 -123.365768)
		(end 170.213528 -124.392182)
		(width 0.1016)
		(layer "F.Cu")
		(net "LED_PWR_NODE1_L")
	)
	(segment
		(start 170.213528 -124.392182)
		(end 168.14927 -124.392182)
		(width 0.1016)
		(layer "F.Cu")
		(net "LED_PWR_NODE1_L")
	)
	(segment
		(start 165.1381 -124.89688)
		(end 165.716712 -124.318268)
		(width 0.1016)
		(layer "F.Cu")
		(net "LED_PWR_NODE1_L")
	)
	(segment
		(start 167.522398 -123.76531)
		(end 167.10787 -123.76531)
		(width 0.1016)
		(layer "F.Cu")
		(net "LED_PWR_NODE1_L")
	)
	(segment
		(start 165.1381 -125.561598)
		(end 165.1381 -124.89688)
		(width 0.1016)
		(layer "F.Cu")
		(net "LED_PWR_NODE1_L")
	)
	(segment
		(start 172.010324 -123.365768)
		(end 171.239942 -123.365768)
		(width 0.1016)
		(layer "F.Cu")
		(net "LED_PWR_NODE1_L")
	)
	(via
		(at 175.90008 -128.752092)
		(size 0.508)
		(drill 0.254)
		(layers "F.Cu" "B.Cu")
		(net "LED_PWR_NODE1_L")
	)
	(via
		(at 187.48502 -127.697992)
		(size 0.508)
		(drill 0.254)
		(layers "F.Cu" "B.Cu")
		(net "LED_PWR_NODE1_L")
	)
	(via
		(at 180.765704 -12.958826)
		(size 0.508)
		(drill 0.254)
		(layers "F.Cu" "B.Cu")
		(net "LED_PWR_NODE1_L")
	)
	(via
		(at 165.1381 -125.561598)
		(size 0.508)
		(drill 0.254)
		(layers "F.Cu" "B.Cu")
		(net "LED_PWR_NODE1_L")
	)
	(segment
		(start 177.063908 -127.588264)
		(end 175.90008 -128.752092)
		(width 0.1143)
		(layer "In2.Cu")
		(net "LED_PWR_NODE1_L")
	)
	(segment
		(start 187.375292 -127.588264)
		(end 177.063908 -127.588264)
		(width 0.1143)
		(layer "In2.Cu")
		(net "LED_PWR_NODE1_L")
	)
	(segment
		(start 187.48502 -127.697992)
		(end 187.375292 -127.588264)
		(width 0.1143)
		(layer "In2.Cu")
		(net "LED_PWR_NODE1_L")
	)
	(segment
		(start 180.83657 -29.686758)
		(end 180.83657 -13.029692)
		(width 0.1143)
		(layer "In6.Cu")
		(net "LED_PWR_NODE1_L")
	)
	(segment
		(start 187.897008 -127.697992)
		(end 195.07835 -120.51665)
		(width 0.1143)
		(layer "In6.Cu")
		(net "LED_PWR_NODE1_L")
	)
	(segment
		(start 195.07835 -120.51665)
		(end 195.07835 -83.693)
		(width 0.1143)
		(layer "In6.Cu")
		(net "LED_PWR_NODE1_L")
	)
	(segment
		(start 177.602388 -69.274182)
		(end 177.602388 -52.929028)
		(width 0.1143)
		(layer "In6.Cu")
		(net "LED_PWR_NODE1_L")
	)
	(segment
		(start 180.83657 -13.029692)
		(end 180.765704 -12.958826)
		(width 0.1143)
		(layer "In6.Cu")
		(net "LED_PWR_NODE1_L")
	)
	(segment
		(start 195.07835 -83.693)
		(end 192.183004 -80.797654)
		(width 0.1143)
		(layer "In6.Cu")
		(net "LED_PWR_NODE1_L")
	)
	(segment
		(start 177.94605 -52.585366)
		(end 177.94605 -45.873416)
		(width 0.1143)
		(layer "In6.Cu")
		(net "LED_PWR_NODE1_L")
	)
	(segment
		(start 176.89195 -44.819316)
		(end 176.89195 -33.631378)
		(width 0.1143)
		(layer "In6.Cu")
		(net "LED_PWR_NODE1_L")
	)
	(segment
		(start 189.12586 -80.797654)
		(end 177.602388 -69.274182)
		(width 0.1143)
		(layer "In6.Cu")
		(net "LED_PWR_NODE1_L")
	)
	(segment
		(start 177.94605 -45.873416)
		(end 176.89195 -44.819316)
		(width 0.1143)
		(layer "In6.Cu")
		(net "LED_PWR_NODE1_L")
	)
	(segment
		(start 187.48502 -127.697992)
		(end 187.897008 -127.697992)
		(width 0.1143)
		(layer "In6.Cu")
		(net "LED_PWR_NODE1_L")
	)
	(segment
		(start 176.89195 -33.631378)
		(end 180.83657 -29.686758)
		(width 0.1143)
		(layer "In6.Cu")
		(net "LED_PWR_NODE1_L")
	)
	(segment
		(start 192.183004 -80.797654)
		(end 189.12586 -80.797654)
		(width 0.1143)
		(layer "In6.Cu")
		(net "LED_PWR_NODE1_L")
	)
	(segment
		(start 177.602388 -52.929028)
		(end 177.94605 -52.585366)
		(width 0.1143)
		(layer "In6.Cu")
		(net "LED_PWR_NODE1_L")
	)
	(segment
		(start 173.921928 -126.77394)
		(end 173.77664 -126.77394)
		(width 0.1143)
		(layer "In7.Cu")
		(net "LED_PWR_NODE1_L")
	)
	(segment
		(start 166.91102 -126.76886)
		(end 165.703758 -125.561598)
		(width 0.1143)
		(layer "In7.Cu")
		(net "LED_PWR_NODE1_L")
	)
	(segment
		(start 175.90008 -128.752092)
		(end 173.921928 -126.77394)
		(width 0.1143)
		(layer "In7.Cu")
		(net "LED_PWR_NODE1_L")
	)
	(segment
		(start 173.77156 -126.76886)
		(end 166.91102 -126.76886)
		(width 0.1143)
		(layer "In7.Cu")
		(net "LED_PWR_NODE1_L")
	)
	(segment
		(start 165.703758 -125.561598)
		(end 165.1381 -125.561598)
		(width 0.1143)
		(layer "In7.Cu")
		(net "LED_PWR_NODE1_L")
	)
	(segment
		(start 173.77664 -126.77394)
		(end 173.77156 -126.76886)
		(width 0.1143)
		(layer "In7.Cu")
		(net "LED_PWR_NODE1_L")
	)
	(segment
		(start 70.141846 -127.259588)
		(end 70.561454 -126.563882)
		(width 0.127)
		(layer "F.Cu")
		(net "P2E_CPU_BMC_NODE1_TX_DP")
	)
	(segment
		(start 71.130414 -125.446536)
		(end 71.130414 -122.460004)
		(width 0.127)
		(layer "F.Cu")
		(net "P2E_CPU_BMC_NODE1_TX_DP")
	)
	(segment
		(start 70.561454 -126.015496)
		(end 71.130414 -125.446536)
		(width 0.127)
		(layer "F.Cu")
		(net "P2E_CPU_BMC_NODE1_TX_DP")
	)
	(segment
		(start 71.130414 -122.460004)
		(end 71.36638 -122.224038)
		(width 0.127)
		(layer "F.Cu")
		(net "P2E_CPU_BMC_NODE1_TX_DP")
	)
	(segment
		(start 70.561454 -126.563882)
		(end 70.561454 -126.015496)
		(width 0.127)
		(layer "F.Cu")
		(net "P2E_CPU_BMC_NODE1_TX_DP")
	)
	(via
		(at 119.838216 -141.24559)
		(size 0.508)
		(drill 0.254)
		(layers "F.Cu" "B.Cu")
		(net "P2E_CPU_BMC_NODE1_TX_DP")
	)
	(via
		(at 71.36638 -122.224038)
		(size 0.508)
		(drill 0.254)
		(layers "F.Cu" "B.Cu")
		(net "P2E_CPU_BMC_NODE1_TX_DP")
	)
	(segment
		(start 120.641872 -141.74851)
		(end 120.341136 -141.74851)
		(width 0.127)
		(layer "B.Cu")
		(net "P2E_CPU_BMC_NODE1_TX_DP")
	)
	(segment
		(start 121.00179 -141.388592)
		(end 120.641872 -141.74851)
		(width 0.127)
		(layer "B.Cu")
		(net "P2E_CPU_BMC_NODE1_TX_DP")
	)
	(segment
		(start 120.341136 -141.74851)
		(end 119.838216 -141.24559)
		(width 0.127)
		(layer "B.Cu")
		(net "P2E_CPU_BMC_NODE1_TX_DP")
	)
	(segment
		(start 102.753668 -144.527016)
		(end 110.00232 -145.541238)
		(width 0.127)
		(layer "In7.Cu")
		(net "P2E_CPU_BMC_NODE1_TX_DP")
	)
	(segment
		(start 72.130666 -123.75515)
		(end 75.546712 -122.816366)
		(width 0.127)
		(layer "In7.Cu")
		(net "P2E_CPU_BMC_NODE1_TX_DP")
	)
	(segment
		(start 110.946692 -145.295366)
		(end 111.1123 -145.432018)
		(width 0.127)
		(layer "In7.Cu")
		(net "P2E_CPU_BMC_NODE1_TX_DP")
	)
	(segment
		(start 71.184262 -123.34494)
		(end 71.259446 -123.430792)
		(width 0.127)
		(layer "In7.Cu")
		(net "P2E_CPU_BMC_NODE1_TX_DP")
	)
	(segment
		(start 71.06793 -122.522488)
		(end 71.06793 -123.091194)
		(width 0.127)
		(layer "In7.Cu")
		(net "P2E_CPU_BMC_NODE1_TX_DP")
	)
	(segment
		(start 99.834954 -142.798038)
		(end 101.019864 -142.920212)
		(width 0.127)
		(layer "In7.Cu")
		(net "P2E_CPU_BMC_NODE1_TX_DP")
	)
	(segment
		(start 71.710296 -123.70054)
		(end 71.798688 -123.72848)
		(width 0.127)
		(layer "In7.Cu")
		(net "P2E_CPU_BMC_NODE1_TX_DP")
	)
	(segment
		(start 94.941898 -142.576042)
		(end 99.543108 -142.784576)
		(width 0.127)
		(layer "In7.Cu")
		(net "P2E_CPU_BMC_NODE1_TX_DP")
	)
	(segment
		(start 110.567216 -145.332704)
		(end 110.946692 -145.295366)
		(width 0.127)
		(layer "In7.Cu")
		(net "P2E_CPU_BMC_NODE1_TX_DP")
	)
	(segment
		(start 91.183968 -139.679172)
		(end 91.935554 -141.043914)
		(width 0.127)
		(layer "In7.Cu")
		(net "P2E_CPU_BMC_NODE1_TX_DP")
	)
	(segment
		(start 87.549228 -133.905752)
		(end 90.144854 -138.49096)
		(width 0.127)
		(layer "In7.Cu")
		(net "P2E_CPU_BMC_NODE1_TX_DP")
	)
	(segment
		(start 71.798688 -123.72848)
		(end 72.130666 -123.75515)
		(width 0.127)
		(layer "In7.Cu")
		(net "P2E_CPU_BMC_NODE1_TX_DP")
	)
	(segment
		(start 113.0681 -145.087086)
		(end 113.233708 -145.223738)
		(width 0.127)
		(layer "In7.Cu")
		(net "P2E_CPU_BMC_NODE1_TX_DP")
	)
	(segment
		(start 92.604336 -141.836648)
		(end 94.941898 -142.576042)
		(width 0.127)
		(layer "In7.Cu")
		(net "P2E_CPU_BMC_NODE1_TX_DP")
	)
	(segment
		(start 77.789532 -123.440698)
		(end 79.984854 -125.172216)
		(width 0.127)
		(layer "In7.Cu")
		(net "P2E_CPU_BMC_NODE1_TX_DP")
	)
	(segment
		(start 110.431072 -145.49882)
		(end 110.567216 -145.332704)
		(width 0.127)
		(layer "In7.Cu")
		(net "P2E_CPU_BMC_NODE1_TX_DP")
	)
	(segment
		(start 111.1123 -145.432018)
		(end 111.491776 -145.39468)
		(width 0.127)
		(layer "In7.Cu")
		(net "P2E_CPU_BMC_NODE1_TX_DP")
	)
	(segment
		(start 119.349266 -141.73454)
		(end 119.838216 -141.24559)
		(width 0.127)
		(layer "In7.Cu")
		(net "P2E_CPU_BMC_NODE1_TX_DP")
	)
	(segment
		(start 71.259446 -123.430792)
		(end 71.710296 -123.70054)
		(width 0.127)
		(layer "In7.Cu")
		(net "P2E_CPU_BMC_NODE1_TX_DP")
	)
	(segment
		(start 90.144854 -138.49096)
		(end 91.183968 -139.679172)
		(width 0.127)
		(layer "In7.Cu")
		(net "P2E_CPU_BMC_NODE1_TX_DP")
	)
	(segment
		(start 112.007396 -145.191226)
		(end 112.173004 -145.327878)
		(width 0.127)
		(layer "In7.Cu")
		(net "P2E_CPU_BMC_NODE1_TX_DP")
	)
	(segment
		(start 99.543108 -142.784576)
		(end 99.834954 -142.798038)
		(width 0.127)
		(layer "In7.Cu")
		(net "P2E_CPU_BMC_NODE1_TX_DP")
	)
	(segment
		(start 111.62792 -145.228564)
		(end 112.007396 -145.191226)
		(width 0.127)
		(layer "In7.Cu")
		(net "P2E_CPU_BMC_NODE1_TX_DP")
	)
	(segment
		(start 114.110516 -145.13814)
		(end 117.271038 -143.19504)
		(width 0.127)
		(layer "In7.Cu")
		(net "P2E_CPU_BMC_NODE1_TX_DP")
	)
	(segment
		(start 91.952318 -141.06779)
		(end 92.604336 -141.836648)
		(width 0.127)
		(layer "In7.Cu")
		(net "P2E_CPU_BMC_NODE1_TX_DP")
	)
	(segment
		(start 79.984854 -125.172216)
		(end 84.752434 -131.82854)
		(width 0.127)
		(layer "In7.Cu")
		(net "P2E_CPU_BMC_NODE1_TX_DP")
	)
	(segment
		(start 110.00232 -145.541238)
		(end 110.431072 -145.49882)
		(width 0.127)
		(layer "In7.Cu")
		(net "P2E_CPU_BMC_NODE1_TX_DP")
	)
	(segment
		(start 91.935554 -141.043914)
		(end 91.952318 -141.06779)
		(width 0.127)
		(layer "In7.Cu")
		(net "P2E_CPU_BMC_NODE1_TX_DP")
	)
	(segment
		(start 117.271038 -143.19504)
		(end 118.7323 -141.73454)
		(width 0.127)
		(layer "In7.Cu")
		(net "P2E_CPU_BMC_NODE1_TX_DP")
	)
	(segment
		(start 112.55248 -145.29054)
		(end 112.688624 -145.124424)
		(width 0.127)
		(layer "In7.Cu")
		(net "P2E_CPU_BMC_NODE1_TX_DP")
	)
	(segment
		(start 75.546712 -122.816366)
		(end 77.683868 -123.387612)
		(width 0.127)
		(layer "In7.Cu")
		(net "P2E_CPU_BMC_NODE1_TX_DP")
	)
	(segment
		(start 101.019864 -142.920212)
		(end 102.753668 -144.527016)
		(width 0.127)
		(layer "In7.Cu")
		(net "P2E_CPU_BMC_NODE1_TX_DP")
	)
	(segment
		(start 71.36638 -122.224038)
		(end 71.06793 -122.522488)
		(width 0.127)
		(layer "In7.Cu")
		(net "P2E_CPU_BMC_NODE1_TX_DP")
	)
	(segment
		(start 77.683868 -123.387612)
		(end 77.789532 -123.440698)
		(width 0.127)
		(layer "In7.Cu")
		(net "P2E_CPU_BMC_NODE1_TX_DP")
	)
	(segment
		(start 113.233708 -145.223738)
		(end 114.110516 -145.13814)
		(width 0.127)
		(layer "In7.Cu")
		(net "P2E_CPU_BMC_NODE1_TX_DP")
	)
	(segment
		(start 112.173004 -145.327878)
		(end 112.55248 -145.29054)
		(width 0.127)
		(layer "In7.Cu")
		(net "P2E_CPU_BMC_NODE1_TX_DP")
	)
	(segment
		(start 84.752434 -131.82854)
		(end 87.549228 -133.905752)
		(width 0.127)
		(layer "In7.Cu")
		(net "P2E_CPU_BMC_NODE1_TX_DP")
	)
	(segment
		(start 112.688624 -145.124424)
		(end 113.0681 -145.087086)
		(width 0.127)
		(layer "In7.Cu")
		(net "P2E_CPU_BMC_NODE1_TX_DP")
	)
	(segment
		(start 118.7323 -141.73454)
		(end 119.349266 -141.73454)
		(width 0.127)
		(layer "In7.Cu")
		(net "P2E_CPU_BMC_NODE1_TX_DP")
	)
	(segment
		(start 71.06793 -123.091194)
		(end 71.184262 -123.34494)
		(width 0.127)
		(layer "In7.Cu")
		(net "P2E_CPU_BMC_NODE1_TX_DP")
	)
	(segment
		(start 111.491776 -145.39468)
		(end 111.62792 -145.228564)
		(width 0.127)
		(layer "In7.Cu")
		(net "P2E_CPU_BMC_NODE1_TX_DP")
	)
	(segment
		(start 61.268102 -85.444584)
		(end 60.66028 -85.444584)
		(width 0.1016)
		(layer "F.Cu")
		(net "LPC_CPU_NODE1_LAD3_R")
	)
	(segment
		(start 61.33084 -85.381846)
		(end 61.268102 -85.444584)
		(width 0.1016)
		(layer "F.Cu")
		(net "LPC_CPU_NODE1_LAD3_R")
	)
	(segment
		(start 61.503306 -85.381846)
		(end 61.33084 -85.381846)
		(width 0.1016)
		(layer "F.Cu")
		(net "LPC_CPU_NODE1_LAD3_R")
	)
	(segment
		(start 60.66028 -85.444584)
		(end 60.59424 -85.378544)
		(width 0.1016)
		(layer "F.Cu")
		(net "LPC_CPU_NODE1_LAD3_R")
	)
	(via
		(at 61.021214 -89.651332)
		(size 0.6604)
		(drill 0.3302)
		(layers "F.Cu" "B.Cu")
		(net "LPC_CPU_NODE1_LAD3_R")
	)
	(via
		(at 60.59424 -85.378544)
		(size 0.508)
		(drill 0.254)
		(layers "F.Cu" "B.Cu")
		(net "LPC_CPU_NODE1_LAD3_R")
	)
	(segment
		(start 61.021214 -89.651332)
		(end 60.289186 -87.648796)
		(width 0.1016)
		(layer "B.Cu")
		(net "LPC_CPU_NODE1_LAD3_R")
	)
	(segment
		(start 59.493912 -95.458534)
		(end 60.649866 -94.336362)
		(width 0.1016)
		(layer "B.Cu")
		(net "LPC_CPU_NODE1_LAD3_R")
	)
	(segment
		(start 60.859162 -93.363796)
		(end 61.083444 -92.651326)
		(width 0.1016)
		(layer "B.Cu")
		(net "LPC_CPU_NODE1_LAD3_R")
	)
	(segment
		(start 60.59424 -85.623654)
		(end 60.59424 -85.378544)
		(width 0.1016)
		(layer "B.Cu")
		(net "LPC_CPU_NODE1_LAD3_R")
	)
	(segment
		(start 61.083444 -92.651326)
		(end 61.235336 -91.315032)
		(width 0.1016)
		(layer "B.Cu")
		(net "LPC_CPU_NODE1_LAD3_R")
	)
	(segment
		(start 60.289186 -85.928708)
		(end 60.59424 -85.623654)
		(width 0.1016)
		(layer "B.Cu")
		(net "LPC_CPU_NODE1_LAD3_R")
	)
	(segment
		(start 60.859162 -94.127066)
		(end 60.859162 -93.363796)
		(width 0.1016)
		(layer "B.Cu")
		(net "LPC_CPU_NODE1_LAD3_R")
	)
	(segment
		(start 61.235336 -90.205052)
		(end 61.021214 -89.651332)
		(width 0.1016)
		(layer "B.Cu")
		(net "LPC_CPU_NODE1_LAD3_R")
	)
	(segment
		(start 60.289186 -87.648796)
		(end 60.289186 -85.928708)
		(width 0.1016)
		(layer "B.Cu")
		(net "LPC_CPU_NODE1_LAD3_R")
	)
	(segment
		(start 61.235336 -91.315032)
		(end 61.235336 -90.205052)
		(width 0.1016)
		(layer "B.Cu")
		(net "LPC_CPU_NODE1_LAD3_R")
	)
	(segment
		(start 59.102498 -95.915734)
		(end 59.493912 -95.458534)
		(width 0.1016)
		(layer "B.Cu")
		(net "LPC_CPU_NODE1_LAD3_R")
	)
	(segment
		(start 60.649866 -94.336362)
		(end 60.859162 -94.127066)
		(width 0.1016)
		(layer "B.Cu")
		(net "LPC_CPU_NODE1_LAD3_R")
	)
	(segment
		(start 73.950068 -23.646638)
		(end 73.950068 -20.94992)
		(width 0.2286)
		(layer "F.Cu")
		(net "M_DDR3_NODE1_MA1")
	)
	(segment
		(start 60.78728 -63.854584)
		(end 60.364116 -63.43142)
		(width 0.1016)
		(layer "F.Cu")
		(net "M_DDR3_NODE1_MA1")
	)
	(segment
		(start 60.364116 -63.43142)
		(end 60.364116 -63.428626)
		(width 0.1016)
		(layer "F.Cu")
		(net "M_DDR3_NODE1_MA1")
	)
	(segment
		(start 60.78728 -63.898526)
		(end 60.78728 -63.854584)
		(width 0.1016)
		(layer "F.Cu")
		(net "M_DDR3_NODE1_MA1")
	)
	(segment
		(start 73.58888 -24.007826)
		(end 73.950068 -23.646638)
		(width 0.2286)
		(layer "F.Cu")
		(net "M_DDR3_NODE1_MA1")
	)
	(segment
		(start 73.58888 -24.407876)
		(end 73.58888 -24.007826)
		(width 0.2286)
		(layer "F.Cu")
		(net "M_DDR3_NODE1_MA1")
	)
	(via
		(at 60.364116 -63.428626)
		(size 0.508)
		(drill 0.254)
		(layers "F.Cu" "B.Cu")
		(net "M_DDR3_NODE1_MA1")
	)
	(via
		(at 73.58888 -24.407876)
		(size 0.508)
		(drill 0.254)
		(layers "F.Cu" "B.Cu")
		(net "M_DDR3_NODE1_MA1")
	)
	(segment
		(start 60.6679 -54.076346)
		(end 60.6679 -60.469526)
		(width 0.2286)
		(layer "In2.Cu")
		(net "M_DDR3_NODE1_MA1")
	)
	(segment
		(start 65.4558 -43.154092)
		(end 65.4558 -49.288446)
		(width 0.2286)
		(layer "In2.Cu")
		(net "M_DDR3_NODE1_MA1")
	)
	(segment
		(start 68.215764 -41.023794)
		(end 68.480432 -41.288462)
		(width 0.2286)
		(layer "In2.Cu")
		(net "M_DDR3_NODE1_MA1")
	)
	(segment
		(start 65.4558 -49.288446)
		(end 60.6679 -54.076346)
		(width 0.2286)
		(layer "In2.Cu")
		(net "M_DDR3_NODE1_MA1")
	)
	(segment
		(start 68.415662 -40.519096)
		(end 68.215764 -40.718994)
		(width 0.2286)
		(layer "In2.Cu")
		(net "M_DDR3_NODE1_MA1")
	)
	(segment
		(start 68.480432 -41.593262)
		(end 68.264278 -41.809416)
		(width 0.2286)
		(layer "In2.Cu")
		(net "M_DDR3_NODE1_MA1")
	)
	(segment
		(start 61.4045 -62.666118)
		(end 60.641992 -63.428626)
		(width 0.2286)
		(layer "In2.Cu")
		(net "M_DDR3_NODE1_MA1")
	)
	(segment
		(start 68.215764 -40.718994)
		(end 68.215764 -41.023794)
		(width 0.2286)
		(layer "In2.Cu")
		(net "M_DDR3_NODE1_MA1")
	)
	(segment
		(start 66.408046 -47.956724)
		(end 66.1924 -47.741078)
		(width 0.2286)
		(layer "In2.Cu")
		(net "M_DDR3_NODE1_MA1")
	)
	(segment
		(start 72.289162 -28.543504)
		(end 71.94296 -28.889706)
		(width 0.2286)
		(layer "In2.Cu")
		(net "M_DDR3_NODE1_MA1")
	)
	(segment
		(start 65.976754 -42.938446)
		(end 65.671446 -42.938446)
		(width 0.2286)
		(layer "In2.Cu")
		(net "M_DDR3_NODE1_MA1")
	)
	(segment
		(start 72.73798 -25.725882)
		(end 72.289162 -26.1747)
		(width 0.2286)
		(layer "In2.Cu")
		(net "M_DDR3_NODE1_MA1")
	)
	(segment
		(start 66.929 -42.005758)
		(end 66.929 -47.741078)
		(width 0.2286)
		(layer "In2.Cu")
		(net "M_DDR3_NODE1_MA1")
	)
	(segment
		(start 66.929 -47.741078)
		(end 66.713354 -47.956724)
		(width 0.2286)
		(layer "In2.Cu")
		(net "M_DDR3_NODE1_MA1")
	)
	(segment
		(start 65.671446 -42.938446)
		(end 65.4558 -43.154092)
		(width 0.2286)
		(layer "In2.Cu")
		(net "M_DDR3_NODE1_MA1")
	)
	(segment
		(start 73.58888 -24.407876)
		(end 72.73798 -25.258776)
		(width 0.2286)
		(layer "In2.Cu")
		(net "M_DDR3_NODE1_MA1")
	)
	(segment
		(start 68.480432 -41.288462)
		(end 68.480432 -41.593262)
		(width 0.2286)
		(layer "In2.Cu")
		(net "M_DDR3_NODE1_MA1")
	)
	(segment
		(start 68.264278 -41.809416)
		(end 67.959478 -41.809416)
		(width 0.2286)
		(layer "In2.Cu")
		(net "M_DDR3_NODE1_MA1")
	)
	(segment
		(start 71.94296 -28.889706)
		(end 71.94296 -30.152594)
		(width 0.2286)
		(layer "In2.Cu")
		(net "M_DDR3_NODE1_MA1")
	)
	(segment
		(start 66.713354 -47.956724)
		(end 66.408046 -47.956724)
		(width 0.2286)
		(layer "In2.Cu")
		(net "M_DDR3_NODE1_MA1")
	)
	(segment
		(start 67.39001 -41.544748)
		(end 66.929 -42.005758)
		(width 0.2286)
		(layer "In2.Cu")
		(net "M_DDR3_NODE1_MA1")
	)
	(segment
		(start 60.641992 -63.428626)
		(end 60.364116 -63.428626)
		(width 0.2286)
		(layer "In2.Cu")
		(net "M_DDR3_NODE1_MA1")
	)
	(segment
		(start 72.73798 -25.258776)
		(end 72.73798 -25.725882)
		(width 0.2286)
		(layer "In2.Cu")
		(net "M_DDR3_NODE1_MA1")
	)
	(segment
		(start 70.95236 -31.143194)
		(end 70.95236 -39.856664)
		(width 0.2286)
		(layer "In2.Cu")
		(net "M_DDR3_NODE1_MA1")
	)
	(segment
		(start 67.959478 -41.809416)
		(end 67.69481 -41.544748)
		(width 0.2286)
		(layer "In2.Cu")
		(net "M_DDR3_NODE1_MA1")
	)
	(segment
		(start 66.1924 -43.154092)
		(end 65.976754 -42.938446)
		(width 0.2286)
		(layer "In2.Cu")
		(net "M_DDR3_NODE1_MA1")
	)
	(segment
		(start 71.94296 -30.152594)
		(end 70.95236 -31.143194)
		(width 0.2286)
		(layer "In2.Cu")
		(net "M_DDR3_NODE1_MA1")
	)
	(segment
		(start 66.1924 -47.741078)
		(end 66.1924 -43.154092)
		(width 0.2286)
		(layer "In2.Cu")
		(net "M_DDR3_NODE1_MA1")
	)
	(segment
		(start 67.69481 -41.544748)
		(end 67.39001 -41.544748)
		(width 0.2286)
		(layer "In2.Cu")
		(net "M_DDR3_NODE1_MA1")
	)
	(segment
		(start 72.289162 -26.1747)
		(end 72.289162 -28.543504)
		(width 0.2286)
		(layer "In2.Cu")
		(net "M_DDR3_NODE1_MA1")
	)
	(segment
		(start 70.289928 -40.519096)
		(end 68.415662 -40.519096)
		(width 0.2286)
		(layer "In2.Cu")
		(net "M_DDR3_NODE1_MA1")
	)
	(segment
		(start 60.6679 -60.469526)
		(end 61.4045 -61.206126)
		(width 0.2286)
		(layer "In2.Cu")
		(net "M_DDR3_NODE1_MA1")
	)
	(segment
		(start 61.4045 -61.206126)
		(end 61.4045 -62.666118)
		(width 0.2286)
		(layer "In2.Cu")
		(net "M_DDR3_NODE1_MA1")
	)
	(segment
		(start 70.95236 -39.856664)
		(end 70.289928 -40.519096)
		(width 0.2286)
		(layer "In2.Cu")
		(net "M_DDR3_NODE1_MA1")
	)
	(segment
		(start 139.98956 -114.783108)
		(end 141.00556 -114.783108)
		(width 0.1016)
		(layer "F.Cu")
		(net "CLKREQC_NODE1_N")
	)
	(segment
		(start 137.234168 -115.714526)
		(end 136.503664 -115.714526)
		(width 0.1016)
		(layer "F.Cu")
		(net "CLKREQC_NODE1_N")
	)
	(segment
		(start 139.181586 -114.783108)
		(end 139.061952 -114.902742)
		(width 0.1016)
		(layer "F.Cu")
		(net "CLKREQC_NODE1_N")
	)
	(segment
		(start 137.652252 -115.296442)
		(end 137.234168 -115.714526)
		(width 0.1016)
		(layer "F.Cu")
		(net "CLKREQC_NODE1_N")
	)
	(segment
		(start 141.00556 -114.783108)
		(end 142.02156 -114.783108)
		(width 0.1016)
		(layer "F.Cu")
		(net "CLKREQC_NODE1_N")
	)
	(segment
		(start 139.061952 -114.902742)
		(end 138.668252 -115.296442)
		(width 0.1016)
		(layer "F.Cu")
		(net "CLKREQC_NODE1_N")
	)
	(segment
		(start 138.668252 -115.296442)
		(end 137.652252 -115.296442)
		(width 0.1016)
		(layer "F.Cu")
		(net "CLKREQC_NODE1_N")
	)
	(segment
		(start 139.98956 -114.783108)
		(end 139.181586 -114.783108)
		(width 0.1016)
		(layer "F.Cu")
		(net "CLKREQC_NODE1_N")
	)
	(via
		(at 139.061952 -114.902742)
		(size 0.508)
		(drill 0.254)
		(layers "F.Cu" "B.Cu")
		(net "CLKREQC_NODE1_N")
	)
	(segment
		(start 171.551092 -138.367008)
		(end 172.213524 -138.367008)
		(width 0.1016)
		(layer "F.Cu")
		(net "PWR_BTN_NODE1_C_L")
	)
	(segment
		(start 177.376582 -138.152632)
		(end 178.58867 -138.152632)
		(width 0.1016)
		(layer "F.Cu")
		(net "PWR_BTN_NODE1_C_L")
	)
	(segment
		(start 171.551092 -139.383008)
		(end 171.551092 -138.367008)
		(width 0.1016)
		(layer "F.Cu")
		(net "PWR_BTN_NODE1_C_L")
	)
	(segment
		(start 174.43958 -138.00455)
		(end 175.901604 -138.00455)
		(width 0.1016)
		(layer "F.Cu")
		(net "PWR_BTN_NODE1_C_L")
	)
	(segment
		(start 175.901604 -138.00455)
		(end 177.2285 -138.00455)
		(width 0.1016)
		(layer "F.Cu")
		(net "PWR_BTN_NODE1_C_L")
	)
	(segment
		(start 177.2285 -138.00455)
		(end 177.376582 -138.152632)
		(width 0.1016)
		(layer "F.Cu")
		(net "PWR_BTN_NODE1_C_L")
	)
	(segment
		(start 172.575982 -138.00455)
		(end 174.43958 -138.00455)
		(width 0.1016)
		(layer "F.Cu")
		(net "PWR_BTN_NODE1_C_L")
	)
	(segment
		(start 172.213524 -138.367008)
		(end 172.575982 -138.00455)
		(width 0.1016)
		(layer "F.Cu")
		(net "PWR_BTN_NODE1_C_L")
	)
	(via
		(at 174.43958 -138.00455)
		(size 0.508)
		(drill 0.254)
		(layers "F.Cu" "B.Cu")
		(net "PWR_BTN_NODE1_C_L")
	)
	(segment
		(start 79.563468 -85.93328)
		(end 79.468726 -86.028022)
		(width 0.1016)
		(layer "F.Cu")
		(net "A_CPU_NODE1_RTC_EXTPAD")
	)
	(segment
		(start 76.05014 -84.170266)
		(end 76.05014 -84.125054)
		(width 0.1016)
		(layer "F.Cu")
		(net "A_CPU_NODE1_RTC_EXTPAD")
	)
	(segment
		(start 78.355698 -86.028022)
		(end 77.338936 -85.01126)
		(width 0.1016)
		(layer "F.Cu")
		(net "A_CPU_NODE1_RTC_EXTPAD")
	)
	(segment
		(start 76.891134 -85.01126)
		(end 76.05014 -84.170266)
		(width 0.1016)
		(layer "F.Cu")
		(net "A_CPU_NODE1_RTC_EXTPAD")
	)
	(segment
		(start 73.752964 -84.187538)
		(end 73.854564 -84.085938)
		(width 0.1016)
		(layer "F.Cu")
		(net "A_CPU_NODE1_RTC_EXTPAD")
	)
	(segment
		(start 76.011024 -84.085938)
		(end 76.05014 -84.125054)
		(width 0.1016)
		(layer "F.Cu")
		(net "A_CPU_NODE1_RTC_EXTPAD")
	)
	(segment
		(start 79.468726 -86.028022)
		(end 78.355698 -86.028022)
		(width 0.1016)
		(layer "F.Cu")
		(net "A_CPU_NODE1_RTC_EXTPAD")
	)
	(segment
		(start 73.854564 -84.085938)
		(end 76.011024 -84.085938)
		(width 0.1016)
		(layer "F.Cu")
		(net "A_CPU_NODE1_RTC_EXTPAD")
	)
	(segment
		(start 77.338936 -85.01126)
		(end 76.891134 -85.01126)
		(width 0.1016)
		(layer "F.Cu")
		(net "A_CPU_NODE1_RTC_EXTPAD")
	)
	(via
		(at 76.05014 -84.125054)
		(size 0.508)
		(drill 0.254)
		(layers "F.Cu" "B.Cu")
		(net "A_CPU_NODE1_RTC_EXTPAD")
	)
	(segment
		(start 55.501032 -65.552828)
		(end 55.501032 -65.192656)
		(width 0.1016)
		(layer "F.Cu")
		(net "M1_DQ_NODE1_DQ23")
	)
	(segment
		(start 55.050182 -27.005026)
		(end 55.050182 -29.149802)
		(width 0.1651)
		(layer "F.Cu")
		(net "M1_DQ_NODE1_DQ23")
	)
	(segment
		(start 55.75554 -26.299668)
		(end 55.050182 -27.005026)
		(width 0.1651)
		(layer "F.Cu")
		(net "M1_DQ_NODE1_DQ23")
	)
	(segment
		(start 55.784242 -65.836038)
		(end 55.501032 -65.552828)
		(width 0.1016)
		(layer "F.Cu")
		(net "M1_DQ_NODE1_DQ23")
	)
	(segment
		(start 55.75554 -25.739852)
		(end 55.75554 -26.299668)
		(width 0.1651)
		(layer "F.Cu")
		(net "M1_DQ_NODE1_DQ23")
	)
	(via
		(at 55.75554 -25.739852)
		(size 0.508)
		(drill 0.254)
		(layers "F.Cu" "B.Cu")
		(net "M1_DQ_NODE1_DQ23")
	)
	(via
		(at 55.501032 -65.192656)
		(size 0.508)
		(drill 0.254)
		(layers "F.Cu" "B.Cu")
		(net "M1_DQ_NODE1_DQ23")
	)
	(segment
		(start 56.265064 -63.857886)
		(end 56.265064 -64.428624)
		(width 0.1016)
		(layer "In7.Cu")
		(net "M1_DQ_NODE1_DQ23")
	)
	(segment
		(start 49.15916 -46.322234)
		(end 48.95088 -46.530514)
		(width 0.2032)
		(layer "In7.Cu")
		(net "M1_DQ_NODE1_DQ23")
	)
	(segment
		(start 47.93996 -41.434766)
		(end 47.73676 -41.637966)
		(width 0.2032)
		(layer "In7.Cu")
		(net "M1_DQ_NODE1_DQ23")
	)
	(segment
		(start 47.94504 -47.241714)
		(end 48.95088 -47.241714)
		(width 0.2032)
		(layer "In7.Cu")
		(net "M1_DQ_NODE1_DQ23")
	)
	(segment
		(start 55.75554 -26.30424)
		(end 54.99608 -27.0637)
		(width 0.2032)
		(layer "In7.Cu")
		(net "M1_DQ_NODE1_DQ23")
	)
	(segment
		(start 56.265064 -64.428624)
		(end 55.501032 -65.192656)
		(width 0.1016)
		(layer "In7.Cu")
		(net "M1_DQ_NODE1_DQ23")
	)
	(segment
		(start 55.24246 -28.1813)
		(end 55.24246 -31.47314)
		(width 0.2032)
		(layer "In7.Cu")
		(net "M1_DQ_NODE1_DQ23")
	)
	(segment
		(start 50.653188 -51.647598)
		(end 50.653188 -52.876704)
		(width 0.2032)
		(layer "In7.Cu")
		(net "M1_DQ_NODE1_DQ23")
	)
	(segment
		(start 49.15916 -40.307006)
		(end 49.15916 -46.322234)
		(width 0.2032)
		(layer "In7.Cu")
		(net "M1_DQ_NODE1_DQ23")
	)
	(segment
		(start 55.24246 -31.47314)
		(end 54.13248 -32.58312)
		(width 0.2032)
		(layer "In7.Cu")
		(net "M1_DQ_NODE1_DQ23")
	)
	(segment
		(start 54.13248 -32.58312)
		(end 54.13248 -35.333686)
		(width 0.2032)
		(layer "In7.Cu")
		(net "M1_DQ_NODE1_DQ23")
	)
	(segment
		(start 54.65318 -62.246002)
		(end 56.265064 -63.857886)
		(width 0.1016)
		(layer "In7.Cu")
		(net "M1_DQ_NODE1_DQ23")
	)
	(segment
		(start 47.73676 -41.637966)
		(end 47.73676 -47.033434)
		(width 0.2032)
		(layer "In7.Cu")
		(net "M1_DQ_NODE1_DQ23")
	)
	(segment
		(start 54.65318 -56.876696)
		(end 54.65318 -58.349134)
		(width 0.2032)
		(layer "In7.Cu")
		(net "M1_DQ_NODE1_DQ23")
	)
	(segment
		(start 48.95088 -47.241714)
		(end 49.15916 -47.449994)
		(width 0.2032)
		(layer "In7.Cu")
		(net "M1_DQ_NODE1_DQ23")
	)
	(segment
		(start 48.95088 -46.530514)
		(end 48.65624 -46.530514)
		(width 0.2032)
		(layer "In7.Cu")
		(net "M1_DQ_NODE1_DQ23")
	)
	(segment
		(start 49.15916 -50.15357)
		(end 50.653188 -51.647598)
		(width 0.2032)
		(layer "In7.Cu")
		(net "M1_DQ_NODE1_DQ23")
	)
	(segment
		(start 54.99608 -27.93492)
		(end 55.24246 -28.1813)
		(width 0.2032)
		(layer "In7.Cu")
		(net "M1_DQ_NODE1_DQ23")
	)
	(segment
		(start 48.65624 -46.530514)
		(end 48.44796 -46.322234)
		(width 0.2032)
		(layer "In7.Cu")
		(net "M1_DQ_NODE1_DQ23")
	)
	(segment
		(start 54.99608 -27.0637)
		(end 54.99608 -27.93492)
		(width 0.2032)
		(layer "In7.Cu")
		(net "M1_DQ_NODE1_DQ23")
	)
	(segment
		(start 49.15916 -47.449994)
		(end 49.15916 -50.15357)
		(width 0.2032)
		(layer "In7.Cu")
		(net "M1_DQ_NODE1_DQ23")
	)
	(segment
		(start 48.44796 -41.637966)
		(end 48.24476 -41.434766)
		(width 0.2032)
		(layer "In7.Cu")
		(net "M1_DQ_NODE1_DQ23")
	)
	(segment
		(start 48.24476 -41.434766)
		(end 47.93996 -41.434766)
		(width 0.2032)
		(layer "In7.Cu")
		(net "M1_DQ_NODE1_DQ23")
	)
	(segment
		(start 54.65318 -58.349134)
		(end 54.65318 -62.246002)
		(width 0.1016)
		(layer "In7.Cu")
		(net "M1_DQ_NODE1_DQ23")
	)
	(segment
		(start 48.44796 -46.322234)
		(end 48.44796 -41.637966)
		(width 0.2032)
		(layer "In7.Cu")
		(net "M1_DQ_NODE1_DQ23")
	)
	(segment
		(start 47.73676 -47.033434)
		(end 47.94504 -47.241714)
		(width 0.2032)
		(layer "In7.Cu")
		(net "M1_DQ_NODE1_DQ23")
	)
	(segment
		(start 55.75554 -25.739852)
		(end 55.75554 -26.30424)
		(width 0.2032)
		(layer "In7.Cu")
		(net "M1_DQ_NODE1_DQ23")
	)
	(segment
		(start 50.653188 -52.876704)
		(end 54.65318 -56.876696)
		(width 0.2032)
		(layer "In7.Cu")
		(net "M1_DQ_NODE1_DQ23")
	)
	(segment
		(start 54.13248 -35.333686)
		(end 49.15916 -40.307006)
		(width 0.2032)
		(layer "In7.Cu")
		(net "M1_DQ_NODE1_DQ23")
	)
	(segment
		(start 36.688522 -96.35617)
		(end 38.237922 -96.35617)
		(width 0.1016)
		(layer "F.Cu")
		(net "SMB_MUX_CPU_ICS_NODE1_CLK")
	)
	(segment
		(start 31.7627 -97.673668)
		(end 31.7627 -97.674684)
		(width 0.1016)
		(layer "F.Cu")
		(net "SMB_MUX_CPU_ICS_NODE1_CLK")
	)
	(segment
		(start 31.32836 -97.239328)
		(end 31.7627 -97.673668)
		(width 0.1016)
		(layer "F.Cu")
		(net "SMB_MUX_CPU_ICS_NODE1_CLK")
	)
	(segment
		(start 38.613588 -96.162876)
		(end 38.329108 -96.447356)
		(width 0.1016)
		(layer "F.Cu")
		(net "SMB_MUX_CPU_ICS_NODE1_CLK")
	)
	(segment
		(start 33.187894 -97.674684)
		(end 34.52876 -96.333818)
		(width 0.1016)
		(layer "F.Cu")
		(net "SMB_MUX_CPU_ICS_NODE1_CLK")
	)
	(segment
		(start 10.72007 -3.705352)
		(end 10.72007 -3.704844)
		(width 0.1016)
		(layer "F.Cu")
		(net "SMB_MUX_CPU_ICS_NODE1_CLK")
	)
	(segment
		(start 10.72007 -3.704844)
		(end 11.151362 -3.273552)
		(width 0.1016)
		(layer "F.Cu")
		(net "SMB_MUX_CPU_ICS_NODE1_CLK")
	)
	(segment
		(start 13.10132 -4.466844)
		(end 13.10132 -4.46913)
		(width 0.1016)
		(layer "F.Cu")
		(net "SMB_MUX_CPU_ICS_NODE1_CLK")
	)
	(segment
		(start 44.72559 -96.162876)
		(end 38.613588 -96.162876)
		(width 0.1016)
		(layer "F.Cu")
		(net "SMB_MUX_CPU_ICS_NODE1_CLK")
	)
	(segment
		(start 10.521188 -3.904234)
		(end 10.72007 -3.705352)
		(width 0.1016)
		(layer "F.Cu")
		(net "SMB_MUX_CPU_ICS_NODE1_CLK")
	)
	(segment
		(start 47.771812 -98.629216)
		(end 47.19193 -98.629216)
		(width 0.1016)
		(layer "F.Cu")
		(net "SMB_MUX_CPU_ICS_NODE1_CLK")
	)
	(segment
		(start 23.50008 -98.84918)
		(end 26.175208 -98.84918)
		(width 0.1016)
		(layer "F.Cu")
		(net "SMB_MUX_CPU_ICS_NODE1_CLK")
	)
	(segment
		(start 48.072294 -98.929698)
		(end 47.771812 -98.629216)
		(width 0.1016)
		(layer "F.Cu")
		(net "SMB_MUX_CPU_ICS_NODE1_CLK")
	)
	(segment
		(start 27.78506 -97.239328)
		(end 31.32836 -97.239328)
		(width 0.1016)
		(layer "F.Cu")
		(net "SMB_MUX_CPU_ICS_NODE1_CLK")
	)
	(segment
		(start 31.7627 -97.674684)
		(end 33.187894 -97.674684)
		(width 0.1016)
		(layer "F.Cu")
		(net "SMB_MUX_CPU_ICS_NODE1_CLK")
	)
	(segment
		(start 34.52876 -96.333818)
		(end 36.66617 -96.333818)
		(width 0.1016)
		(layer "F.Cu")
		(net "SMB_MUX_CPU_ICS_NODE1_CLK")
	)
	(segment
		(start 9.629648 -3.904234)
		(end 10.521188 -3.904234)
		(width 0.1016)
		(layer "F.Cu")
		(net "SMB_MUX_CPU_ICS_NODE1_CLK")
	)
	(segment
		(start 48.387 -98.929698)
		(end 48.072294 -98.929698)
		(width 0.1016)
		(layer "F.Cu")
		(net "SMB_MUX_CPU_ICS_NODE1_CLK")
	)
	(segment
		(start 132.353812 -113.127282)
		(end 132.546852 -112.934242)
		(width 0.1016)
		(layer "F.Cu")
		(net "SMB_MUX_CPU_ICS_NODE1_CLK")
	)
	(segment
		(start 132.546852 -111.831374)
		(end 133.011418 -111.366808)
		(width 0.1016)
		(layer "F.Cu")
		(net "SMB_MUX_CPU_ICS_NODE1_CLK")
	)
	(segment
		(start 11.151362 -3.273552)
		(end 11.908028 -3.273552)
		(width 0.1016)
		(layer "F.Cu")
		(net "SMB_MUX_CPU_ICS_NODE1_CLK")
	)
	(segment
		(start 36.66617 -96.333818)
		(end 36.688522 -96.35617)
		(width 0.1016)
		(layer "F.Cu")
		(net "SMB_MUX_CPU_ICS_NODE1_CLK")
	)
	(segment
		(start 11.908028 -3.273552)
		(end 13.10132 -4.466844)
		(width 0.1016)
		(layer "F.Cu")
		(net "SMB_MUX_CPU_ICS_NODE1_CLK")
	)
	(segment
		(start 9.3726 -3.272282)
		(end 9.3726 -3.647186)
		(width 0.1016)
		(layer "F.Cu")
		(net "SMB_MUX_CPU_ICS_NODE1_CLK")
	)
	(segment
		(start 26.175208 -98.84918)
		(end 27.78506 -97.239328)
		(width 0.1016)
		(layer "F.Cu")
		(net "SMB_MUX_CPU_ICS_NODE1_CLK")
	)
	(segment
		(start 23.101554 -98.450654)
		(end 23.50008 -98.84918)
		(width 0.1016)
		(layer "F.Cu")
		(net "SMB_MUX_CPU_ICS_NODE1_CLK")
	)
	(segment
		(start 23.101554 -97.426272)
		(end 23.101554 -98.450654)
		(width 0.1016)
		(layer "F.Cu")
		(net "SMB_MUX_CPU_ICS_NODE1_CLK")
	)
	(segment
		(start 9.3726 -3.647186)
		(end 9.629648 -3.904234)
		(width 0.1016)
		(layer "F.Cu")
		(net "SMB_MUX_CPU_ICS_NODE1_CLK")
	)
	(segment
		(start 47.19193 -98.629216)
		(end 44.72559 -96.162876)
		(width 0.1016)
		(layer "F.Cu")
		(net "SMB_MUX_CPU_ICS_NODE1_CLK")
	)
	(segment
		(start 132.546852 -112.934242)
		(end 132.546852 -111.831374)
		(width 0.1016)
		(layer "F.Cu")
		(net "SMB_MUX_CPU_ICS_NODE1_CLK")
	)
	(segment
		(start 132.353812 -113.96472)
		(end 132.353812 -113.127282)
		(width 0.1016)
		(layer "F.Cu")
		(net "SMB_MUX_CPU_ICS_NODE1_CLK")
	)
	(segment
		(start 38.237922 -96.35617)
		(end 38.329108 -96.447356)
		(width 0.1016)
		(layer "F.Cu")
		(net "SMB_MUX_CPU_ICS_NODE1_CLK")
	)
	(via
		(at 38.329108 -96.447356)
		(size 0.508)
		(drill 0.254)
		(layers "F.Cu" "B.Cu")
		(net "SMB_MUX_CPU_ICS_NODE1_CLK")
	)
	(via
		(at 133.011418 -111.366808)
		(size 0.508)
		(drill 0.254)
		(layers "F.Cu" "B.Cu")
		(net "SMB_MUX_CPU_ICS_NODE1_CLK")
	)
	(via
		(at 13.10132 -4.46913)
		(size 0.508)
		(drill 0.254)
		(layers "F.Cu" "B.Cu")
		(net "SMB_MUX_CPU_ICS_NODE1_CLK")
	)
	(via
		(at 118.341902 -102.275386)
		(size 0.508)
		(drill 0.254)
		(layers "F.Cu" "B.Cu")
		(net "SMB_MUX_CPU_ICS_NODE1_CLK")
	)
	(via
		(at 31.7627 -97.674684)
		(size 0.508)
		(drill 0.254)
		(layers "F.Cu" "B.Cu")
		(net "SMB_MUX_CPU_ICS_NODE1_CLK")
	)
	(segment
		(start 37.86886 -95.574866)
		(end 37.591746 -95.85198)
		(width 0.1016)
		(layer "B.Cu")
		(net "SMB_MUX_CPU_ICS_NODE1_CLK")
	)
	(segment
		(start 38.108636 -96.667828)
		(end 37.591746 -96.667828)
		(width 0.1016)
		(layer "B.Cu")
		(net "SMB_MUX_CPU_ICS_NODE1_CLK")
	)
	(segment
		(start 37.591746 -95.85198)
		(end 37.591746 -96.667828)
		(width 0.1016)
		(layer "B.Cu")
		(net "SMB_MUX_CPU_ICS_NODE1_CLK")
	)
	(segment
		(start 38.329108 -96.447356)
		(end 38.108636 -96.667828)
		(width 0.1016)
		(layer "B.Cu")
		(net "SMB_MUX_CPU_ICS_NODE1_CLK")
	)
	(segment
		(start 37.86886 -95.062548)
		(end 37.86886 -95.574866)
		(width 0.1016)
		(layer "B.Cu")
		(net "SMB_MUX_CPU_ICS_NODE1_CLK")
	)
	(segment
		(start 37.606732 -94.80042)
		(end 37.86886 -95.062548)
		(width 0.1016)
		(layer "B.Cu")
		(net "SMB_MUX_CPU_ICS_NODE1_CLK")
	)
	(segment
		(start 118.341902 -102.275386)
		(end 118.341902 -102.27691)
		(width 0.1143)
		(layer "In2.Cu")
		(net "SMB_MUX_CPU_ICS_NODE1_CLK")
	)
	(segment
		(start 132.01142 -110.36681)
		(end 133.011418 -111.366808)
		(width 0.1143)
		(layer "In2.Cu")
		(net "SMB_MUX_CPU_ICS_NODE1_CLK")
	)
	(segment
		(start 118.341902 -102.27691)
		(end 118.527322 -102.46233)
		(width 0.1143)
		(layer "In2.Cu")
		(net "SMB_MUX_CPU_ICS_NODE1_CLK")
	)
	(segment
		(start 127.94361 -102.46233)
		(end 132.01142 -106.53014)
		(width 0.1143)
		(layer "In2.Cu")
		(net "SMB_MUX_CPU_ICS_NODE1_CLK")
	)
	(segment
		(start 132.01142 -106.53014)
		(end 132.01142 -110.36681)
		(width 0.1143)
		(layer "In2.Cu")
		(net "SMB_MUX_CPU_ICS_NODE1_CLK")
	)
	(segment
		(start 118.527322 -102.46233)
		(end 127.94361 -102.46233)
		(width 0.1143)
		(layer "In2.Cu")
		(net "SMB_MUX_CPU_ICS_NODE1_CLK")
	)
	(segment
		(start 12.23391 -5.33654)
		(end 13.10132 -4.46913)
		(width 0.1143)
		(layer "In6.Cu")
		(net "SMB_MUX_CPU_ICS_NODE1_CLK")
	)
	(segment
		(start 18.35404 -27.761692)
		(end 18.35404 -14.453362)
		(width 0.1143)
		(layer "In6.Cu")
		(net "SMB_MUX_CPU_ICS_NODE1_CLK")
	)
	(segment
		(start 18.35404 -14.453362)
		(end 12.23391 -8.333232)
		(width 0.1143)
		(layer "In6.Cu")
		(net "SMB_MUX_CPU_ICS_NODE1_CLK")
	)
	(segment
		(start 31.37154 -40.779192)
		(end 18.35404 -27.761692)
		(width 0.1143)
		(layer "In6.Cu")
		(net "SMB_MUX_CPU_ICS_NODE1_CLK")
	)
	(segment
		(start 30.84449 -81.844896)
		(end 30.84449 -70.591426)
		(width 0.1143)
		(layer "In6.Cu")
		(net "SMB_MUX_CPU_ICS_NODE1_CLK")
	)
	(segment
		(start 30.84449 -70.591426)
		(end 31.37154 -70.064376)
		(width 0.1143)
		(layer "In6.Cu")
		(net "SMB_MUX_CPU_ICS_NODE1_CLK")
	)
	(segment
		(start 31.37154 -70.064376)
		(end 31.37154 -40.779192)
		(width 0.1143)
		(layer "In6.Cu")
		(net "SMB_MUX_CPU_ICS_NODE1_CLK")
	)
	(segment
		(start 31.7627 -82.763106)
		(end 30.84449 -81.844896)
		(width 0.1143)
		(layer "In6.Cu")
		(net "SMB_MUX_CPU_ICS_NODE1_CLK")
	)
	(segment
		(start 12.23391 -8.333232)
		(end 12.23391 -5.33654)
		(width 0.1143)
		(layer "In6.Cu")
		(net "SMB_MUX_CPU_ICS_NODE1_CLK")
	)
	(segment
		(start 31.7627 -97.674684)
		(end 31.7627 -82.763106)
		(width 0.1143)
		(layer "In6.Cu")
		(net "SMB_MUX_CPU_ICS_NODE1_CLK")
	)
	(segment
		(start 84.32546 -108.61675)
		(end 84.572094 -108.370116)
		(width 0.1143)
		(layer "In7.Cu")
		(net "SMB_MUX_CPU_ICS_NODE1_CLK")
	)
	(segment
		(start 86.746334 -108.370116)
		(end 88.825324 -106.291126)
		(width 0.1143)
		(layer "In7.Cu")
		(net "SMB_MUX_CPU_ICS_NODE1_CLK")
	)
	(segment
		(start 64.78778 -104.449372)
		(end 65.010792 -104.672384)
		(width 0.1143)
		(layer "In7.Cu")
		(net "SMB_MUX_CPU_ICS_NODE1_CLK")
	)
	(segment
		(start 39.77386 -97.102676)
		(end 39.77386 -97.858834)
		(width 0.1143)
		(layer "In7.Cu")
		(net "SMB_MUX_CPU_ICS_NODE1_CLK")
	)
	(segment
		(start 116.692172 -101.301804)
		(end 117.665754 -102.275386)
		(width 0.1143)
		(layer "In7.Cu")
		(net "SMB_MUX_CPU_ICS_NODE1_CLK")
	)
	(segment
		(start 38.329108 -96.447356)
		(end 39.11854 -96.447356)
		(width 0.1143)
		(layer "In7.Cu")
		(net "SMB_MUX_CPU_ICS_NODE1_CLK")
	)
	(segment
		(start 100.153216 -106.291126)
		(end 105.142538 -101.301804)
		(width 0.1143)
		(layer "In7.Cu")
		(net "SMB_MUX_CPU_ICS_NODE1_CLK")
	)
	(segment
		(start 71.849742 -104.672384)
		(end 75.922124 -108.744766)
		(width 0.1143)
		(layer "In7.Cu")
		(net "SMB_MUX_CPU_ICS_NODE1_CLK")
	)
	(segment
		(start 65.010792 -104.672384)
		(end 71.849742 -104.672384)
		(width 0.1143)
		(layer "In7.Cu")
		(net "SMB_MUX_CPU_ICS_NODE1_CLK")
	)
	(segment
		(start 40.69842 -98.783394)
		(end 42.352976 -98.783394)
		(width 0.1143)
		(layer "In7.Cu")
		(net "SMB_MUX_CPU_ICS_NODE1_CLK")
	)
	(segment
		(start 80.974946 -108.61675)
		(end 84.32546 -108.61675)
		(width 0.1143)
		(layer "In7.Cu")
		(net "SMB_MUX_CPU_ICS_NODE1_CLK")
	)
	(segment
		(start 75.922124 -108.744766)
		(end 80.84693 -108.744766)
		(width 0.1143)
		(layer "In7.Cu")
		(net "SMB_MUX_CPU_ICS_NODE1_CLK")
	)
	(segment
		(start 80.84693 -108.744766)
		(end 80.974946 -108.61675)
		(width 0.1143)
		(layer "In7.Cu")
		(net "SMB_MUX_CPU_ICS_NODE1_CLK")
	)
	(segment
		(start 48.018954 -104.449372)
		(end 64.78778 -104.449372)
		(width 0.1143)
		(layer "In7.Cu")
		(net "SMB_MUX_CPU_ICS_NODE1_CLK")
	)
	(segment
		(start 42.352976 -98.783394)
		(end 48.018954 -104.449372)
		(width 0.1143)
		(layer "In7.Cu")
		(net "SMB_MUX_CPU_ICS_NODE1_CLK")
	)
	(segment
		(start 39.11854 -96.447356)
		(end 39.77386 -97.102676)
		(width 0.1143)
		(layer "In7.Cu")
		(net "SMB_MUX_CPU_ICS_NODE1_CLK")
	)
	(segment
		(start 105.142538 -101.301804)
		(end 116.692172 -101.301804)
		(width 0.1143)
		(layer "In7.Cu")
		(net "SMB_MUX_CPU_ICS_NODE1_CLK")
	)
	(segment
		(start 84.572094 -108.370116)
		(end 86.746334 -108.370116)
		(width 0.1143)
		(layer "In7.Cu")
		(net "SMB_MUX_CPU_ICS_NODE1_CLK")
	)
	(segment
		(start 88.825324 -106.291126)
		(end 100.153216 -106.291126)
		(width 0.1143)
		(layer "In7.Cu")
		(net "SMB_MUX_CPU_ICS_NODE1_CLK")
	)
	(segment
		(start 117.665754 -102.275386)
		(end 118.341902 -102.275386)
		(width 0.1143)
		(layer "In7.Cu")
		(net "SMB_MUX_CPU_ICS_NODE1_CLK")
	)
	(segment
		(start 39.77386 -97.858834)
		(end 40.69842 -98.783394)
		(width 0.1143)
		(layer "In7.Cu")
		(net "SMB_MUX_CPU_ICS_NODE1_CLK")
	)
	(segment
		(start 56.335676 -121.744232)
		(end 56.494426 -121.902982)
		(width 0.1016)
		(layer "F.Cu")
		(net "BMC_NODE1_CLK_24M")
	)
	(segment
		(start 56.529732 -121.938288)
		(end 56.494426 -121.902982)
		(width 0.1016)
		(layer "F.Cu")
		(net "BMC_NODE1_CLK_24M")
	)
	(segment
		(start 57.34177 -125.89383)
		(end 57.380886 -125.854714)
		(width 0.1016)
		(layer "F.Cu")
		(net "BMC_NODE1_CLK_24M")
	)
	(segment
		(start 57.380886 -125.854714)
		(end 57.380886 -123.796298)
		(width 0.1016)
		(layer "F.Cu")
		(net "BMC_NODE1_CLK_24M")
	)
	(segment
		(start 57.34177 -126.459488)
		(end 57.34177 -125.89383)
		(width 0.1016)
		(layer "F.Cu")
		(net "BMC_NODE1_CLK_24M")
	)
	(segment
		(start 57.380886 -123.796298)
		(end 56.529732 -122.945144)
		(width 0.1016)
		(layer "F.Cu")
		(net "BMC_NODE1_CLK_24M")
	)
	(segment
		(start 55.78856 -121.744232)
		(end 56.335676 -121.744232)
		(width 0.1016)
		(layer "F.Cu")
		(net "BMC_NODE1_CLK_24M")
	)
	(segment
		(start 56.529732 -122.945144)
		(end 56.529732 -121.938288)
		(width 0.1016)
		(layer "F.Cu")
		(net "BMC_NODE1_CLK_24M")
	)
	(via
		(at 56.494426 -121.902982)
		(size 0.508)
		(drill 0.254)
		(layers "F.Cu" "B.Cu")
		(net "BMC_NODE1_CLK_24M")
	)
	(segment
		(start 60.508896 -87.00389)
		(end 60.508896 -87.0585)
		(width 0.1016)
		(layer "F.Cu")
		(net "TP_SPI_CPU_NODE1_CS1_L")
	)
	(segment
		(start 60.252102 -87.315294)
		(end 60.252102 -88.895936)
		(width 0.1016)
		(layer "F.Cu")
		(net "TP_SPI_CPU_NODE1_CS1_L")
	)
	(segment
		(start 59.326018 -92.546424)
		(end 59.73953 -92.959936)
		(width 0.1016)
		(layer "F.Cu")
		(net "TP_SPI_CPU_NODE1_CS1_L")
	)
	(segment
		(start 59.782456 -91.543378)
		(end 59.326018 -91.999816)
		(width 0.1016)
		(layer "F.Cu")
		(net "TP_SPI_CPU_NODE1_CS1_L")
	)
	(segment
		(start 59.326018 -91.999816)
		(end 59.326018 -92.546424)
		(width 0.1016)
		(layer "F.Cu")
		(net "TP_SPI_CPU_NODE1_CS1_L")
	)
	(segment
		(start 60.508896 -87.0585)
		(end 60.252102 -87.315294)
		(width 0.1016)
		(layer "F.Cu")
		(net "TP_SPI_CPU_NODE1_CS1_L")
	)
	(segment
		(start 59.782456 -89.365582)
		(end 59.782456 -91.543378)
		(width 0.1016)
		(layer "F.Cu")
		(net "TP_SPI_CPU_NODE1_CS1_L")
	)
	(segment
		(start 59.73953 -93.269054)
		(end 60.344812 -93.874336)
		(width 0.1016)
		(layer "F.Cu")
		(net "TP_SPI_CPU_NODE1_CS1_L")
	)
	(segment
		(start 59.73953 -92.959936)
		(end 59.73953 -93.269054)
		(width 0.1016)
		(layer "F.Cu")
		(net "TP_SPI_CPU_NODE1_CS1_L")
	)
	(segment
		(start 60.252102 -88.895936)
		(end 59.782456 -89.365582)
		(width 0.1016)
		(layer "F.Cu")
		(net "TP_SPI_CPU_NODE1_CS1_L")
	)
	(via
		(at 60.344812 -93.874336)
		(size 0.508)
		(drill 0.254)
		(layers "F.Cu" "B.Cu")
		(net "TP_SPI_CPU_NODE1_CS1_L")
	)
	(segment
		(start 98.748342 -23.484586)
		(end 97.950274 -22.686518)
		(width 0.1651)
		(layer "F.Cu")
		(net "M1_DQ_NODE1_DQ57")
	)
	(segment
		(start 73.305162 -71.349362)
		(end 73.739756 -71.349362)
		(width 0.1016)
		(layer "F.Cu")
		(net "M1_DQ_NODE1_DQ57")
	)
	(segment
		(start 73.739756 -71.349362)
		(end 74.13244 -71.742046)
		(width 0.1016)
		(layer "F.Cu")
		(net "M1_DQ_NODE1_DQ57")
	)
	(segment
		(start 97.950274 -22.686518)
		(end 97.950274 -20.94992)
		(width 0.1651)
		(layer "F.Cu")
		(net "M1_DQ_NODE1_DQ57")
	)
	(segment
		(start 74.13244 -71.742046)
		(end 75.20178 -71.742046)
		(width 0.1016)
		(layer "F.Cu")
		(net "M1_DQ_NODE1_DQ57")
	)
	(segment
		(start 98.748342 -23.625302)
		(end 98.748342 -23.484586)
		(width 0.1651)
		(layer "F.Cu")
		(net "M1_DQ_NODE1_DQ57")
	)
	(segment
		(start 99.373182 -24.407622)
		(end 99.373182 -24.250142)
		(width 0.1651)
		(layer "F.Cu")
		(net "M1_DQ_NODE1_DQ57")
	)
	(segment
		(start 75.20178 -71.742046)
		(end 75.64374 -71.300086)
		(width 0.1016)
		(layer "F.Cu")
		(net "M1_DQ_NODE1_DQ57")
	)
	(segment
		(start 99.373182 -24.250142)
		(end 98.748342 -23.625302)
		(width 0.1651)
		(layer "F.Cu")
		(net "M1_DQ_NODE1_DQ57")
	)
	(via
		(at 99.373182 -24.407622)
		(size 0.508)
		(drill 0.254)
		(layers "F.Cu" "B.Cu")
		(net "M1_DQ_NODE1_DQ57")
	)
	(via
		(at 75.64374 -71.300086)
		(size 0.508)
		(drill 0.254)
		(layers "F.Cu" "B.Cu")
		(net "M1_DQ_NODE1_DQ57")
	)
	(segment
		(start 102.28326 -33.843214)
		(end 102.685342 -34.245296)
		(width 0.2032)
		(layer "In7.Cu")
		(net "M1_DQ_NODE1_DQ57")
	)
	(segment
		(start 103.4669 -32.82315)
		(end 102.49154 -32.82315)
		(width 0.2032)
		(layer "In7.Cu")
		(net "M1_DQ_NODE1_DQ57")
	)
	(segment
		(start 95.32112 -62.873382)
		(end 89.514934 -68.679568)
		(width 0.2032)
		(layer "In7.Cu")
		(net "M1_DQ_NODE1_DQ57")
	)
	(segment
		(start 102.49154 -32.82315)
		(end 102.28326 -33.03143)
		(width 0.2032)
		(layer "In7.Cu")
		(net "M1_DQ_NODE1_DQ57")
	)
	(segment
		(start 102.28326 -33.03143)
		(end 102.28326 -33.843214)
		(width 0.2032)
		(layer "In7.Cu")
		(net "M1_DQ_NODE1_DQ57")
	)
	(segment
		(start 103.52024 -33.704276)
		(end 103.814372 -33.704276)
		(width 0.2032)
		(layer "In7.Cu")
		(net "M1_DQ_NODE1_DQ57")
	)
	(segment
		(start 103.482394 -35.042348)
		(end 103.85806 -35.418014)
		(width 0.2032)
		(layer "In7.Cu")
		(net "M1_DQ_NODE1_DQ57")
	)
	(segment
		(start 77.97038 -72.499474)
		(end 77.97038 -72.976994)
		(width 0.1016)
		(layer "In7.Cu")
		(net "M1_DQ_NODE1_DQ57")
	)
	(segment
		(start 103.814372 -33.704276)
		(end 104.02316 -33.913064)
		(width 0.2032)
		(layer "In7.Cu")
		(net "M1_DQ_NODE1_DQ57")
	)
	(segment
		(start 78.84287 -72.11314)
		(end 78.84287 -72.11441)
		(width 0.2032)
		(layer "In7.Cu")
		(net "M1_DQ_NODE1_DQ57")
	)
	(segment
		(start 104.02316 -34.207196)
		(end 103.482394 -34.748216)
		(width 0.2032)
		(layer "In7.Cu")
		(net "M1_DQ_NODE1_DQ57")
	)
	(segment
		(start 103.85806 -35.418014)
		(end 103.85806 -37.737288)
		(width 0.2032)
		(layer "In7.Cu")
		(net "M1_DQ_NODE1_DQ57")
	)
	(segment
		(start 99.972622 -28.381452)
		(end 101.140768 -29.549598)
		(width 0.2032)
		(layer "In7.Cu")
		(net "M1_DQ_NODE1_DQ57")
	)
	(segment
		(start 102.28326 -30.247336)
		(end 102.28326 -31.90367)
		(width 0.2032)
		(layer "In7.Cu")
		(net "M1_DQ_NODE1_DQ57")
	)
	(segment
		(start 103.67518 -32.32023)
		(end 103.67518 -32.61487)
		(width 0.2032)
		(layer "In7.Cu")
		(net "M1_DQ_NODE1_DQ57")
	)
	(segment
		(start 95.32112 -56.63311)
		(end 95.32112 -62.873382)
		(width 0.2032)
		(layer "In7.Cu")
		(net "M1_DQ_NODE1_DQ57")
	)
	(segment
		(start 101.585522 -29.549598)
		(end 102.28326 -30.247336)
		(width 0.2032)
		(layer "In7.Cu")
		(net "M1_DQ_NODE1_DQ57")
	)
	(segment
		(start 103.482394 -34.748216)
		(end 103.482394 -35.042348)
		(width 0.2032)
		(layer "In7.Cu")
		(net "M1_DQ_NODE1_DQ57")
	)
	(segment
		(start 99.972622 -25.007062)
		(end 99.972622 -28.381452)
		(width 0.2032)
		(layer "In7.Cu")
		(net "M1_DQ_NODE1_DQ57")
	)
	(segment
		(start 104.02316 -33.913064)
		(end 104.02316 -34.207196)
		(width 0.2032)
		(layer "In7.Cu")
		(net "M1_DQ_NODE1_DQ57")
	)
	(segment
		(start 89.514934 -68.679568)
		(end 86.162896 -68.679568)
		(width 0.2032)
		(layer "In7.Cu")
		(net "M1_DQ_NODE1_DQ57")
	)
	(segment
		(start 101.2825 -40.312848)
		(end 101.2825 -50.67173)
		(width 0.2032)
		(layer "In7.Cu")
		(net "M1_DQ_NODE1_DQ57")
	)
	(segment
		(start 82.729324 -72.11314)
		(end 78.84287 -72.11314)
		(width 0.2032)
		(layer "In7.Cu")
		(net "M1_DQ_NODE1_DQ57")
	)
	(segment
		(start 78.355444 -72.11441)
		(end 77.97038 -72.499474)
		(width 0.1016)
		(layer "In7.Cu")
		(net "M1_DQ_NODE1_DQ57")
	)
	(segment
		(start 103.85806 -37.737288)
		(end 101.2825 -40.312848)
		(width 0.2032)
		(layer "In7.Cu")
		(net "M1_DQ_NODE1_DQ57")
	)
	(segment
		(start 102.49154 -32.11195)
		(end 103.4669 -32.11195)
		(width 0.2032)
		(layer "In7.Cu")
		(net "M1_DQ_NODE1_DQ57")
	)
	(segment
		(start 77.97038 -72.976994)
		(end 77.671676 -73.275698)
		(width 0.1016)
		(layer "In7.Cu")
		(net "M1_DQ_NODE1_DQ57")
	)
	(segment
		(start 102.28326 -31.90367)
		(end 102.49154 -32.11195)
		(width 0.2032)
		(layer "In7.Cu")
		(net "M1_DQ_NODE1_DQ57")
	)
	(segment
		(start 101.2825 -50.67173)
		(end 95.32112 -56.63311)
		(width 0.2032)
		(layer "In7.Cu")
		(net "M1_DQ_NODE1_DQ57")
	)
	(segment
		(start 86.162896 -68.679568)
		(end 82.729324 -72.11314)
		(width 0.2032)
		(layer "In7.Cu")
		(net "M1_DQ_NODE1_DQ57")
	)
	(segment
		(start 75.64374 -72.129142)
		(end 75.64374 -71.300086)
		(width 0.1016)
		(layer "In7.Cu")
		(net "M1_DQ_NODE1_DQ57")
	)
	(segment
		(start 103.67518 -32.61487)
		(end 103.4669 -32.82315)
		(width 0.2032)
		(layer "In7.Cu")
		(net "M1_DQ_NODE1_DQ57")
	)
	(segment
		(start 76.458064 -73.275698)
		(end 76.204064 -73.021698)
		(width 0.1016)
		(layer "In7.Cu")
		(net "M1_DQ_NODE1_DQ57")
	)
	(segment
		(start 76.204064 -73.021698)
		(end 76.204064 -72.689466)
		(width 0.1016)
		(layer "In7.Cu")
		(net "M1_DQ_NODE1_DQ57")
	)
	(segment
		(start 103.4669 -32.11195)
		(end 103.67518 -32.32023)
		(width 0.2032)
		(layer "In7.Cu")
		(net "M1_DQ_NODE1_DQ57")
	)
	(segment
		(start 101.140768 -29.549598)
		(end 101.585522 -29.549598)
		(width 0.2032)
		(layer "In7.Cu")
		(net "M1_DQ_NODE1_DQ57")
	)
	(segment
		(start 76.204064 -72.689466)
		(end 75.64374 -72.129142)
		(width 0.1016)
		(layer "In7.Cu")
		(net "M1_DQ_NODE1_DQ57")
	)
	(segment
		(start 102.979474 -34.245296)
		(end 103.52024 -33.704276)
		(width 0.2032)
		(layer "In7.Cu")
		(net "M1_DQ_NODE1_DQ57")
	)
	(segment
		(start 77.671676 -73.275698)
		(end 76.458064 -73.275698)
		(width 0.1016)
		(layer "In7.Cu")
		(net "M1_DQ_NODE1_DQ57")
	)
	(segment
		(start 102.685342 -34.245296)
		(end 102.979474 -34.245296)
		(width 0.2032)
		(layer "In7.Cu")
		(net "M1_DQ_NODE1_DQ57")
	)
	(segment
		(start 99.373182 -24.407622)
		(end 99.972622 -25.007062)
		(width 0.2032)
		(layer "In7.Cu")
		(net "M1_DQ_NODE1_DQ57")
	)
	(segment
		(start 78.84287 -72.11441)
		(end 78.355444 -72.11441)
		(width 0.1016)
		(layer "In7.Cu")
		(net "M1_DQ_NODE1_DQ57")
	)
	(segment
		(start 103.048562 -24.566118)
		(end 103.048562 -29.149802)
		(width 0.1016)
		(layer "F.Cu")
		(net "SMB_DIMM_NODE1_CLK")
	)
	(segment
		(start 103.048562 -29.149802)
		(end 103.050086 -29.149802)
		(width 0.1016)
		(layer "F.Cu")
		(net "SMB_DIMM_NODE1_CLK")
	)
	(segment
		(start 103.454962 -24.159718)
		(end 103.048562 -24.566118)
		(width 0.1016)
		(layer "F.Cu")
		(net "SMB_DIMM_NODE1_CLK")
	)
	(segment
		(start 14.238224 -5.220462)
		(end 14.37894 -5.220462)
		(width 0.1016)
		(layer "F.Cu")
		(net "SMB_DIMM_NODE1_CLK")
	)
	(segment
		(start 11.52017 -3.705352)
		(end 13.06322 -5.248402)
		(width 0.1016)
		(layer "F.Cu")
		(net "SMB_DIMM_NODE1_CLK")
	)
	(segment
		(start 14.210284 -5.248402)
		(end 14.238224 -5.220462)
		(width 0.1016)
		(layer "F.Cu")
		(net "SMB_DIMM_NODE1_CLK")
	)
	(segment
		(start 13.06322 -5.248402)
		(end 14.210284 -5.248402)
		(width 0.1016)
		(layer "F.Cu")
		(net "SMB_DIMM_NODE1_CLK")
	)
	(via
		(at 102.69474 -16.564102)
		(size 0.508)
		(drill 0.254)
		(layers "F.Cu" "B.Cu")
		(net "SMB_DIMM_NODE1_CLK")
	)
	(via
		(at 14.37894 -5.220462)
		(size 0.508)
		(drill 0.254)
		(layers "F.Cu" "B.Cu")
		(net "SMB_DIMM_NODE1_CLK")
	)
	(via
		(at 103.454962 -24.159718)
		(size 0.508)
		(drill 0.254)
		(layers "F.Cu" "B.Cu")
		(net "SMB_DIMM_NODE1_CLK")
	)
	(segment
		(start 102.69474 -16.944086)
		(end 103.454962 -17.704308)
		(width 0.1016)
		(layer "B.Cu")
		(net "SMB_DIMM_NODE1_CLK")
	)
	(segment
		(start 103.454962 -17.704308)
		(end 103.454962 -24.159718)
		(width 0.1016)
		(layer "B.Cu")
		(net "SMB_DIMM_NODE1_CLK")
	)
	(segment
		(start 102.69474 -16.564102)
		(end 102.69474 -16.944086)
		(width 0.1016)
		(layer "B.Cu")
		(net "SMB_DIMM_NODE1_CLK")
	)
	(segment
		(start 24.472646 -15.225522)
		(end 27.524964 -15.225522)
		(width 0.1143)
		(layer "In6.Cu")
		(net "SMB_DIMM_NODE1_CLK")
	)
	(segment
		(start 30.155642 -17.8562)
		(end 64.463422 -17.8562)
		(width 0.1143)
		(layer "In6.Cu")
		(net "SMB_DIMM_NODE1_CLK")
	)
	(segment
		(start 14.467586 -5.220462)
		(end 24.472646 -15.225522)
		(width 0.1143)
		(layer "In6.Cu")
		(net "SMB_DIMM_NODE1_CLK")
	)
	(segment
		(start 98.74504 -16.909796)
		(end 99.213162 -16.441674)
		(width 0.1143)
		(layer "In6.Cu")
		(net "SMB_DIMM_NODE1_CLK")
	)
	(segment
		(start 101.122734 -16.441674)
		(end 101.453188 -16.11122)
		(width 0.1143)
		(layer "In6.Cu")
		(net "SMB_DIMM_NODE1_CLK")
	)
	(segment
		(start 27.524964 -15.225522)
		(end 30.155642 -17.8562)
		(width 0.1143)
		(layer "In6.Cu")
		(net "SMB_DIMM_NODE1_CLK")
	)
	(segment
		(start 14.37894 -5.220462)
		(end 14.467586 -5.220462)
		(width 0.1143)
		(layer "In6.Cu")
		(net "SMB_DIMM_NODE1_CLK")
	)
	(segment
		(start 99.213162 -16.441674)
		(end 101.122734 -16.441674)
		(width 0.1143)
		(layer "In6.Cu")
		(net "SMB_DIMM_NODE1_CLK")
	)
	(segment
		(start 101.453188 -16.11122)
		(end 102.241858 -16.11122)
		(width 0.1143)
		(layer "In6.Cu")
		(net "SMB_DIMM_NODE1_CLK")
	)
	(segment
		(start 64.463422 -17.8562)
		(end 66.98488 -16.909796)
		(width 0.1143)
		(layer "In6.Cu")
		(net "SMB_DIMM_NODE1_CLK")
	)
	(segment
		(start 102.241858 -16.11122)
		(end 102.69474 -16.564102)
		(width 0.1143)
		(layer "In6.Cu")
		(net "SMB_DIMM_NODE1_CLK")
	)
	(segment
		(start 66.98488 -16.909796)
		(end 98.74504 -16.909796)
		(width 0.1143)
		(layer "In6.Cu")
		(net "SMB_DIMM_NODE1_CLK")
	)
	(segment
		(start 67.462146 -83.476846)
		(end 67.554348 -83.476846)
		(width 0.1016)
		(layer "F.Cu")
		(net "TP_CPU_NODE1_M52")
	)
	(segment
		(start 68.71335 -83.005676)
		(end 68.71335 -82.741516)
		(width 0.1016)
		(layer "F.Cu")
		(net "TP_CPU_NODE1_M52")
	)
	(segment
		(start 67.554348 -83.476846)
		(end 67.861688 -83.169506)
		(width 0.1016)
		(layer "F.Cu")
		(net "TP_CPU_NODE1_M52")
	)
	(segment
		(start 68.54952 -83.169506)
		(end 68.71335 -83.005676)
		(width 0.1016)
		(layer "F.Cu")
		(net "TP_CPU_NODE1_M52")
	)
	(segment
		(start 67.861688 -83.169506)
		(end 68.54952 -83.169506)
		(width 0.1016)
		(layer "F.Cu")
		(net "TP_CPU_NODE1_M52")
	)
	(via
		(at 68.71335 -82.741516)
		(size 0.508)
		(drill 0.254)
		(layers "F.Cu" "B.Cu")
		(net "TP_CPU_NODE1_M52")
	)
	(via
		(at 70.061328 -83.642962)
		(size 0.6604)
		(drill 0.3302)
		(layers "F.Cu" "B.Cu")
		(net "TP_CPU_NODE1_M52")
	)
	(segment
		(start 68.71335 -82.823304)
		(end 68.71335 -82.741516)
		(width 0.1016)
		(layer "B.Cu")
		(net "TP_CPU_NODE1_M52")
	)
	(segment
		(start 69.879464 -83.369912)
		(end 69.259958 -83.369912)
		(width 0.1016)
		(layer "B.Cu")
		(net "TP_CPU_NODE1_M52")
	)
	(segment
		(start 70.061328 -83.642962)
		(end 70.061328 -83.551776)
		(width 0.1016)
		(layer "B.Cu")
		(net "TP_CPU_NODE1_M52")
	)
	(segment
		(start 70.061328 -83.551776)
		(end 69.879464 -83.369912)
		(width 0.1016)
		(layer "B.Cu")
		(net "TP_CPU_NODE1_M52")
	)
	(segment
		(start 69.259958 -83.369912)
		(end 68.71335 -82.823304)
		(width 0.1016)
		(layer "B.Cu")
		(net "TP_CPU_NODE1_M52")
	)
	(segment
		(start 70.93331 -64.047878)
		(end 70.93331 -63.393828)
		(width 0.1016)
		(layer "F.Cu")
		(net "M1_DQ_NODE1_DQ37")
	)
	(segment
		(start 71.229474 -63.097664)
		(end 71.229474 -60.728098)
		(width 0.1016)
		(layer "F.Cu")
		(net "M1_DQ_NODE1_DQ37")
	)
	(segment
		(start 71.229474 -60.728098)
		(end 70.906894 -60.405518)
		(width 0.1016)
		(layer "F.Cu")
		(net "M1_DQ_NODE1_DQ37")
	)
	(segment
		(start 83.250278 -27.56789)
		(end 83.250278 -29.149802)
		(width 0.1651)
		(layer "F.Cu")
		(net "M1_DQ_NODE1_DQ37")
	)
	(segment
		(start 83.16722 -27.484832)
		(end 83.250278 -27.56789)
		(width 0.1651)
		(layer "F.Cu")
		(net "M1_DQ_NODE1_DQ37")
	)
	(segment
		(start 70.93331 -63.393828)
		(end 71.229474 -63.097664)
		(width 0.1016)
		(layer "F.Cu")
		(net "M1_DQ_NODE1_DQ37")
	)
	(via
		(at 70.906894 -60.405518)
		(size 0.508)
		(drill 0.254)
		(layers "F.Cu" "B.Cu")
		(net "M1_DQ_NODE1_DQ37")
	)
	(via
		(at 83.16722 -27.484832)
		(size 0.508)
		(drill 0.254)
		(layers "F.Cu" "B.Cu")
		(net "M1_DQ_NODE1_DQ37")
	)
	(segment
		(start 75.38466 -40.047926)
		(end 74.31786 -41.114726)
		(width 0.2032)
		(layer "In7.Cu")
		(net "M1_DQ_NODE1_DQ37")
	)
	(segment
		(start 70.812152 -44.996354)
		(end 71.106792 -44.996354)
		(width 0.2032)
		(layer "In7.Cu")
		(net "M1_DQ_NODE1_DQ37")
	)
	(segment
		(start 69.5706 -51.753262)
		(end 69.31406 -52.009802)
		(width 0.2032)
		(layer "In7.Cu")
		(net "M1_DQ_NODE1_DQ37")
	)
	(segment
		(start 69.31406 -57.589928)
		(end 70.08368 -58.359548)
		(width 0.2032)
		(layer "In7.Cu")
		(net "M1_DQ_NODE1_DQ37")
	)
	(segment
		(start 74.31786 -41.114726)
		(end 73.98258 -41.114726)
		(width 0.2032)
		(layer "In7.Cu")
		(net "M1_DQ_NODE1_DQ37")
	)
	(segment
		(start 69.5706 -49.876202)
		(end 69.5706 -50.330862)
		(width 0.2032)
		(layer "In7.Cu")
		(net "M1_DQ_NODE1_DQ37")
	)
	(segment
		(start 75.38466 -38.59784)
		(end 75.38466 -40.047926)
		(width 0.2032)
		(layer "In7.Cu")
		(net "M1_DQ_NODE1_DQ37")
	)
	(segment
		(start 69.52234 -46.750478)
		(end 69.75602 -46.750478)
		(width 0.2032)
		(layer "In7.Cu")
		(net "M1_DQ_NODE1_DQ37")
	)
	(segment
		(start 81.191862 -31.472378)
		(end 80.810862 -31.853378)
		(width 0.2032)
		(layer "In7.Cu")
		(net "M1_DQ_NODE1_DQ37")
	)
	(segment
		(start 69.31406 -52.009802)
		(end 69.31406 -52.464462)
		(width 0.2032)
		(layer "In7.Cu")
		(net "M1_DQ_NODE1_DQ37")
	)
	(segment
		(start 70.812152 -46.002194)
		(end 70.100952 -45.290994)
		(width 0.2032)
		(layer "In7.Cu")
		(net "M1_DQ_NODE1_DQ37")
	)
	(segment
		(start 69.9643 -47.253398)
		(end 69.75602 -47.461678)
		(width 0.2032)
		(layer "In7.Cu")
		(net "M1_DQ_NODE1_DQ37")
	)
	(segment
		(start 70.603872 -44.493434)
		(end 70.603872 -44.788074)
		(width 0.2032)
		(layer "In7.Cu")
		(net "M1_DQ_NODE1_DQ37")
	)
	(segment
		(start 70.08368 -58.359548)
		(end 70.08368 -59.520074)
		(width 0.2032)
		(layer "In7.Cu")
		(net "M1_DQ_NODE1_DQ37")
	)
	(segment
		(start 69.75602 -46.750478)
		(end 69.9643 -46.958758)
		(width 0.2032)
		(layer "In7.Cu")
		(net "M1_DQ_NODE1_DQ37")
	)
	(segment
		(start 80.810862 -31.853378)
		(end 80.810862 -36.493704)
		(width 0.2032)
		(layer "In7.Cu")
		(net "M1_DQ_NODE1_DQ37")
	)
	(segment
		(start 69.31406 -48.197262)
		(end 69.5706 -48.453802)
		(width 0.2032)
		(layer "In7.Cu")
		(net "M1_DQ_NODE1_DQ37")
	)
	(segment
		(start 80.810862 -36.493704)
		(end 79.890112 -37.414454)
		(width 0.2032)
		(layer "In7.Cu")
		(net "M1_DQ_NODE1_DQ37")
	)
	(segment
		(start 69.31406 -53.432202)
		(end 69.31406 -57.589928)
		(width 0.2032)
		(layer "In7.Cu")
		(net "M1_DQ_NODE1_DQ37")
	)
	(segment
		(start 69.31406 -47.669958)
		(end 69.31406 -48.197262)
		(width 0.2032)
		(layer "In7.Cu")
		(net "M1_DQ_NODE1_DQ37")
	)
	(segment
		(start 82.570066 -27.484832)
		(end 81.191862 -28.863036)
		(width 0.2032)
		(layer "In7.Cu")
		(net "M1_DQ_NODE1_DQ37")
	)
	(segment
		(start 69.9643 -46.958758)
		(end 69.9643 -47.253398)
		(width 0.2032)
		(layer "In7.Cu")
		(net "M1_DQ_NODE1_DQ37")
	)
	(segment
		(start 69.5706 -51.298602)
		(end 69.5706 -51.753262)
		(width 0.2032)
		(layer "In7.Cu")
		(net "M1_DQ_NODE1_DQ37")
	)
	(segment
		(start 69.52234 -47.461678)
		(end 69.31406 -47.669958)
		(width 0.2032)
		(layer "In7.Cu")
		(net "M1_DQ_NODE1_DQ37")
	)
	(segment
		(start 69.31406 -45.783246)
		(end 69.31406 -46.542198)
		(width 0.2032)
		(layer "In7.Cu")
		(net "M1_DQ_NODE1_DQ37")
	)
	(segment
		(start 83.16722 -27.484832)
		(end 82.570066 -27.484832)
		(width 0.2032)
		(layer "In7.Cu")
		(net "M1_DQ_NODE1_DQ37")
	)
	(segment
		(start 69.31406 -52.464462)
		(end 69.5706 -52.721002)
		(width 0.2032)
		(layer "In7.Cu")
		(net "M1_DQ_NODE1_DQ37")
	)
	(segment
		(start 74.25817 -42.850816)
		(end 71.106792 -46.002194)
		(width 0.2032)
		(layer "In7.Cu")
		(net "M1_DQ_NODE1_DQ37")
	)
	(segment
		(start 71.106792 -44.996354)
		(end 73.75525 -42.347896)
		(width 0.2032)
		(layer "In7.Cu")
		(net "M1_DQ_NODE1_DQ37")
	)
	(segment
		(start 74.04989 -42.347896)
		(end 74.25817 -42.556176)
		(width 0.2032)
		(layer "In7.Cu")
		(net "M1_DQ_NODE1_DQ37")
	)
	(segment
		(start 70.100952 -45.290994)
		(end 69.806312 -45.290994)
		(width 0.2032)
		(layer "In7.Cu")
		(net "M1_DQ_NODE1_DQ37")
	)
	(segment
		(start 69.31406 -50.587402)
		(end 69.31406 -51.042062)
		(width 0.2032)
		(layer "In7.Cu")
		(net "M1_DQ_NODE1_DQ37")
	)
	(segment
		(start 69.5706 -53.175662)
		(end 69.31406 -53.432202)
		(width 0.2032)
		(layer "In7.Cu")
		(net "M1_DQ_NODE1_DQ37")
	)
	(segment
		(start 70.08368 -59.520074)
		(end 70.906894 -60.343288)
		(width 0.2032)
		(layer "In7.Cu")
		(net "M1_DQ_NODE1_DQ37")
	)
	(segment
		(start 69.5706 -48.453802)
		(end 69.5706 -48.908462)
		(width 0.2032)
		(layer "In7.Cu")
		(net "M1_DQ_NODE1_DQ37")
	)
	(segment
		(start 70.603872 -44.788074)
		(end 70.812152 -44.996354)
		(width 0.2032)
		(layer "In7.Cu")
		(net "M1_DQ_NODE1_DQ37")
	)
	(segment
		(start 74.25817 -42.556176)
		(end 74.25817 -42.850816)
		(width 0.2032)
		(layer "In7.Cu")
		(net "M1_DQ_NODE1_DQ37")
	)
	(segment
		(start 73.98258 -41.114726)
		(end 70.603872 -44.493434)
		(width 0.2032)
		(layer "In7.Cu")
		(net "M1_DQ_NODE1_DQ37")
	)
	(segment
		(start 76.568046 -37.414454)
		(end 75.38466 -38.59784)
		(width 0.2032)
		(layer "In7.Cu")
		(net "M1_DQ_NODE1_DQ37")
	)
	(segment
		(start 69.5706 -48.908462)
		(end 69.31406 -49.165002)
		(width 0.2032)
		(layer "In7.Cu")
		(net "M1_DQ_NODE1_DQ37")
	)
	(segment
		(start 70.906894 -60.343288)
		(end 70.906894 -60.405518)
		(width 0.2032)
		(layer "In7.Cu")
		(net "M1_DQ_NODE1_DQ37")
	)
	(segment
		(start 69.806312 -45.290994)
		(end 69.31406 -45.783246)
		(width 0.2032)
		(layer "In7.Cu")
		(net "M1_DQ_NODE1_DQ37")
	)
	(segment
		(start 79.890112 -37.414454)
		(end 76.568046 -37.414454)
		(width 0.2032)
		(layer "In7.Cu")
		(net "M1_DQ_NODE1_DQ37")
	)
	(segment
		(start 71.106792 -46.002194)
		(end 70.812152 -46.002194)
		(width 0.2032)
		(layer "In7.Cu")
		(net "M1_DQ_NODE1_DQ37")
	)
	(segment
		(start 69.75602 -47.461678)
		(end 69.52234 -47.461678)
		(width 0.2032)
		(layer "In7.Cu")
		(net "M1_DQ_NODE1_DQ37")
	)
	(segment
		(start 69.31406 -49.619662)
		(end 69.5706 -49.876202)
		(width 0.2032)
		(layer "In7.Cu")
		(net "M1_DQ_NODE1_DQ37")
	)
	(segment
		(start 69.5706 -50.330862)
		(end 69.31406 -50.587402)
		(width 0.2032)
		(layer "In7.Cu")
		(net "M1_DQ_NODE1_DQ37")
	)
	(segment
		(start 69.31406 -49.165002)
		(end 69.31406 -49.619662)
		(width 0.2032)
		(layer "In7.Cu")
		(net "M1_DQ_NODE1_DQ37")
	)
	(segment
		(start 81.191862 -28.863036)
		(end 81.191862 -31.472378)
		(width 0.2032)
		(layer "In7.Cu")
		(net "M1_DQ_NODE1_DQ37")
	)
	(segment
		(start 69.5706 -52.721002)
		(end 69.5706 -53.175662)
		(width 0.2032)
		(layer "In7.Cu")
		(net "M1_DQ_NODE1_DQ37")
	)
	(segment
		(start 69.31406 -46.542198)
		(end 69.52234 -46.750478)
		(width 0.2032)
		(layer "In7.Cu")
		(net "M1_DQ_NODE1_DQ37")
	)
	(segment
		(start 73.75525 -42.347896)
		(end 74.04989 -42.347896)
		(width 0.2032)
		(layer "In7.Cu")
		(net "M1_DQ_NODE1_DQ37")
	)
	(segment
		(start 69.31406 -51.042062)
		(end 69.5706 -51.298602)
		(width 0.2032)
		(layer "In7.Cu")
		(net "M1_DQ_NODE1_DQ37")
	)
	(segment
		(start 29.1211 -60.004706)
		(end 29.1211 -65.024508)
		(width 0.1016)
		(layer "F.Cu")
		(net "BMC_NODE1_GFX_VSYNC")
	)
	(segment
		(start 25.755346 -51.858418)
		(end 25.755346 -53.006498)
		(width 0.1016)
		(layer "F.Cu")
		(net "BMC_NODE1_GFX_VSYNC")
	)
	(segment
		(start 25.755346 -53.006498)
		(end 27.563318 -54.81447)
		(width 0.1016)
		(layer "F.Cu")
		(net "BMC_NODE1_GFX_VSYNC")
	)
	(segment
		(start 27.563318 -54.81447)
		(end 27.563318 -58.446924)
		(width 0.1016)
		(layer "F.Cu")
		(net "BMC_NODE1_GFX_VSYNC")
	)
	(segment
		(start 29.1211 -65.024508)
		(end 26.66746 -67.478148)
		(width 0.1016)
		(layer "F.Cu")
		(net "BMC_NODE1_GFX_VSYNC")
	)
	(segment
		(start 27.563318 -58.446924)
		(end 29.1211 -60.004706)
		(width 0.1016)
		(layer "F.Cu")
		(net "BMC_NODE1_GFX_VSYNC")
	)
	(segment
		(start 26.66746 -67.478148)
		(end 26.48458 -67.478148)
		(width 0.1016)
		(layer "F.Cu")
		(net "BMC_NODE1_GFX_VSYNC")
	)
	(via
		(at 26.48458 -67.478148)
		(size 0.508)
		(drill 0.254)
		(layers "F.Cu" "B.Cu")
		(net "BMC_NODE1_GFX_VSYNC")
	)
	(via
		(at 53.54066 -143.999204)
		(size 0.508)
		(drill 0.254)
		(layers "F.Cu" "B.Cu")
		(net "BMC_NODE1_GFX_VSYNC")
	)
	(segment
		(start 53.54066 -144.336008)
		(end 53.54066 -143.999204)
		(width 0.1016)
		(layer "B.Cu")
		(net "BMC_NODE1_GFX_VSYNC")
	)
	(segment
		(start 55.059326 -145.854674)
		(end 53.54066 -144.336008)
		(width 0.1016)
		(layer "B.Cu")
		(net "BMC_NODE1_GFX_VSYNC")
	)
	(segment
		(start 55.79999 -145.854674)
		(end 55.059326 -145.854674)
		(width 0.1016)
		(layer "B.Cu")
		(net "BMC_NODE1_GFX_VSYNC")
	)
	(segment
		(start 12.365736 -133.116828)
		(end 10.7188 -131.469892)
		(width 0.1143)
		(layer "In6.Cu")
		(net "BMC_NODE1_GFX_VSYNC")
	)
	(segment
		(start 25.0317 -77.474826)
		(end 25.0317 -68.356988)
		(width 0.1143)
		(layer "In6.Cu")
		(net "BMC_NODE1_GFX_VSYNC")
	)
	(segment
		(start 44.251372 -143.424148)
		(end 39.27221 -143.424148)
		(width 0.1143)
		(layer "In6.Cu")
		(net "BMC_NODE1_GFX_VSYNC")
	)
	(segment
		(start 45.12564 -144.822418)
		(end 45.12564 -144.298416)
		(width 0.1143)
		(layer "In6.Cu")
		(net "BMC_NODE1_GFX_VSYNC")
	)
	(segment
		(start 51.21402 -143.109696)
		(end 48.718978 -143.109696)
		(width 0.1143)
		(layer "In6.Cu")
		(net "BMC_NODE1_GFX_VSYNC")
	)
	(segment
		(start 25.91054 -67.478148)
		(end 26.48458 -67.478148)
		(width 0.1143)
		(layer "In6.Cu")
		(net "BMC_NODE1_GFX_VSYNC")
	)
	(segment
		(start 45.43552 -145.132298)
		(end 45.12564 -144.822418)
		(width 0.1143)
		(layer "In6.Cu")
		(net "BMC_NODE1_GFX_VSYNC")
	)
	(segment
		(start 10.7188 -131.469892)
		(end 10.7188 -98.820986)
		(width 0.1143)
		(layer "In6.Cu")
		(net "BMC_NODE1_GFX_VSYNC")
	)
	(segment
		(start 10.7188 -98.820986)
		(end 21.717 -87.822786)
		(width 0.1143)
		(layer "In6.Cu")
		(net "BMC_NODE1_GFX_VSYNC")
	)
	(segment
		(start 21.717 -80.789526)
		(end 25.0317 -77.474826)
		(width 0.1143)
		(layer "In6.Cu")
		(net "BMC_NODE1_GFX_VSYNC")
	)
	(segment
		(start 21.2598 -133.660388)
		(end 20.463764 -134.456424)
		(width 0.1143)
		(layer "In6.Cu")
		(net "BMC_NODE1_GFX_VSYNC")
	)
	(segment
		(start 39.27221 -143.424148)
		(end 29.50845 -133.660388)
		(width 0.1143)
		(layer "In6.Cu")
		(net "BMC_NODE1_GFX_VSYNC")
	)
	(segment
		(start 20.463764 -134.456424)
		(end 15.310104 -134.456424)
		(width 0.1143)
		(layer "In6.Cu")
		(net "BMC_NODE1_GFX_VSYNC")
	)
	(segment
		(start 48.718978 -143.109696)
		(end 46.696376 -145.132298)
		(width 0.1143)
		(layer "In6.Cu")
		(net "BMC_NODE1_GFX_VSYNC")
	)
	(segment
		(start 13.970508 -133.116828)
		(end 12.365736 -133.116828)
		(width 0.1143)
		(layer "In6.Cu")
		(net "BMC_NODE1_GFX_VSYNC")
	)
	(segment
		(start 52.103528 -143.999204)
		(end 51.21402 -143.109696)
		(width 0.1143)
		(layer "In6.Cu")
		(net "BMC_NODE1_GFX_VSYNC")
	)
	(segment
		(start 53.54066 -143.999204)
		(end 52.103528 -143.999204)
		(width 0.1143)
		(layer "In6.Cu")
		(net "BMC_NODE1_GFX_VSYNC")
	)
	(segment
		(start 45.12564 -144.298416)
		(end 44.251372 -143.424148)
		(width 0.1143)
		(layer "In6.Cu")
		(net "BMC_NODE1_GFX_VSYNC")
	)
	(segment
		(start 21.717 -87.822786)
		(end 21.717 -80.789526)
		(width 0.1143)
		(layer "In6.Cu")
		(net "BMC_NODE1_GFX_VSYNC")
	)
	(segment
		(start 15.310104 -134.456424)
		(end 13.970508 -133.116828)
		(width 0.1143)
		(layer "In6.Cu")
		(net "BMC_NODE1_GFX_VSYNC")
	)
	(segment
		(start 46.696376 -145.132298)
		(end 45.43552 -145.132298)
		(width 0.1143)
		(layer "In6.Cu")
		(net "BMC_NODE1_GFX_VSYNC")
	)
	(segment
		(start 29.50845 -133.660388)
		(end 21.2598 -133.660388)
		(width 0.1143)
		(layer "In6.Cu")
		(net "BMC_NODE1_GFX_VSYNC")
	)
	(segment
		(start 25.0317 -68.356988)
		(end 25.91054 -67.478148)
		(width 0.1143)
		(layer "In6.Cu")
		(net "BMC_NODE1_GFX_VSYNC")
	)
	(segment
		(start 53.396134 -22.30501)
		(end 53.396134 -23.24227)
		(width 0.1651)
		(layer "F.Cu")
		(net "M_DDR3_NODE1_DQS2P")
	)
	(segment
		(start 54.50205 -66.979038)
		(end 54.891686 -66.589402)
		(width 0.09906)
		(layer "F.Cu")
		(net "M_DDR3_NODE1_DQS2P")
	)
	(segment
		(start 54.497986 -66.979038)
		(end 54.50205 -66.979038)
		(width 0.09906)
		(layer "F.Cu")
		(net "M_DDR3_NODE1_DQS2P")
	)
	(segment
		(start 53.843682 -23.689818)
		(end 53.843682 -24.1427)
		(width 0.1651)
		(layer "F.Cu")
		(net "M_DDR3_NODE1_DQS2P")
	)
	(segment
		(start 53.843682 -24.1427)
		(end 54.332632 -24.63165)
		(width 0.1651)
		(layer "F.Cu")
		(net "M_DDR3_NODE1_DQS2P")
	)
	(segment
		(start 53.396134 -23.24227)
		(end 53.843682 -23.689818)
		(width 0.1651)
		(layer "F.Cu")
		(net "M_DDR3_NODE1_DQS2P")
	)
	(segment
		(start 54.891686 -66.589402)
		(end 54.891686 -66.583306)
		(width 0.09906)
		(layer "F.Cu")
		(net "M_DDR3_NODE1_DQS2P")
	)
	(segment
		(start 53.550058 -20.94992)
		(end 53.550058 -22.151086)
		(width 0.1651)
		(layer "F.Cu")
		(net "M_DDR3_NODE1_DQS2P")
	)
	(segment
		(start 53.550058 -22.151086)
		(end 53.396134 -22.30501)
		(width 0.1651)
		(layer "F.Cu")
		(net "M_DDR3_NODE1_DQS2P")
	)
	(via
		(at 54.332632 -24.63165)
		(size 0.508)
		(drill 0.254)
		(layers "F.Cu" "B.Cu")
		(net "M_DDR3_NODE1_DQS2P")
	)
	(via
		(at 54.891686 -66.583306)
		(size 0.508)
		(drill 0.254)
		(layers "F.Cu" "B.Cu")
		(net "M_DDR3_NODE1_DQS2P")
	)
	(segment
		(start 52.46878 -26.944066)
		(end 52.46878 -34.492692)
		(width 0.2032)
		(layer "In7.Cu")
		(net "M_DDR3_NODE1_DQS2P")
	)
	(segment
		(start 54.456076 -66.924682)
		(end 54.80812 -66.924682)
		(width 0.09906)
		(layer "In7.Cu")
		(net "M_DDR3_NODE1_DQS2P")
	)
	(segment
		(start 43.9293 -48.494442)
		(end 44.137834 -48.702976)
		(width 0.2032)
		(layer "In7.Cu")
		(net "M_DDR3_NODE1_DQS2P")
	)
	(segment
		(start 44.137834 -48.702976)
		(end 44.431966 -48.702976)
		(width 0.2032)
		(layer "In7.Cu")
		(net "M_DDR3_NODE1_DQS2P")
	)
	(segment
		(start 44.6405 -46.119288)
		(end 45.042328 -45.71746)
		(width 0.2032)
		(layer "In7.Cu")
		(net "M_DDR3_NODE1_DQS2P")
	)
	(segment
		(start 54.891686 -66.841116)
		(end 54.891686 -66.583306)
		(width 0.09906)
		(layer "In7.Cu")
		(net "M_DDR3_NODE1_DQS2P")
	)
	(segment
		(start 54.080664 -64.079628)
		(end 54.59984 -64.598804)
		(width 0.09906)
		(layer "In7.Cu")
		(net "M_DDR3_NODE1_DQS2P")
	)
	(segment
		(start 46.820582 -51.453796)
		(end 46.820836 -51.453796)
		(width 0.2032)
		(layer "In7.Cu")
		(net "M_DDR3_NODE1_DQS2P")
	)
	(segment
		(start 54.283864 -65.703704)
		(end 54.283864 -66.75247)
		(width 0.09906)
		(layer "In7.Cu")
		(net "M_DDR3_NODE1_DQS2P")
	)
	(segment
		(start 54.283864 -66.75247)
		(end 54.456076 -66.924682)
		(width 0.09906)
		(layer "In7.Cu")
		(net "M_DDR3_NODE1_DQS2P")
	)
	(segment
		(start 53.3146 -58.037984)
		(end 53.3146 -59.224164)
		(width 0.09906)
		(layer "In7.Cu")
		(net "M_DDR3_NODE1_DQS2P")
	)
	(segment
		(start 52.46878 -34.492692)
		(end 45.21708 -41.744392)
		(width 0.2032)
		(layer "In7.Cu")
		(net "M_DDR3_NODE1_DQS2P")
	)
	(segment
		(start 43.9293 -43.032172)
		(end 43.9293 -48.494442)
		(width 0.2032)
		(layer "In7.Cu")
		(net "M_DDR3_NODE1_DQS2P")
	)
	(segment
		(start 53.17236 -59.366404)
		(end 53.17236 -62.605666)
		(width 0.09906)
		(layer "In7.Cu")
		(net "M_DDR3_NODE1_DQS2P")
	)
	(segment
		(start 44.6405 -48.494442)
		(end 44.6405 -46.119288)
		(width 0.2032)
		(layer "In7.Cu")
		(net "M_DDR3_NODE1_DQS2P")
	)
	(segment
		(start 45.21708 -41.902126)
		(end 45.19676 -41.922446)
		(width 0.2032)
		(layer "In7.Cu")
		(net "M_DDR3_NODE1_DQS2P")
	)
	(segment
		(start 52.5272 -57.16016)
		(end 52.527962 -57.16016)
		(width 0.2032)
		(layer "In7.Cu")
		(net "M_DDR3_NODE1_DQS2P")
	)
	(segment
		(start 54.59984 -65.387728)
		(end 54.283864 -65.703704)
		(width 0.09906)
		(layer "In7.Cu")
		(net "M_DDR3_NODE1_DQS2P")
	)
	(segment
		(start 53.795422 -25.617424)
		(end 52.46878 -26.944066)
		(width 0.2032)
		(layer "In7.Cu")
		(net "M_DDR3_NODE1_DQS2P")
	)
	(segment
		(start 45.19676 -41.922446)
		(end 45.194474 -41.922446)
		(width 0.2032)
		(layer "In7.Cu")
		(net "M_DDR3_NODE1_DQS2P")
	)
	(segment
		(start 45.194474 -41.922446)
		(end 44.763436 -42.353484)
		(width 0.2032)
		(layer "In7.Cu")
		(net "M_DDR3_NODE1_DQS2P")
	)
	(segment
		(start 54.80812 -66.924682)
		(end 54.891686 -66.841116)
		(width 0.09906)
		(layer "In7.Cu")
		(net "M_DDR3_NODE1_DQS2P")
	)
	(segment
		(start 46.820836 -51.453796)
		(end 52.5272 -57.16016)
		(width 0.2032)
		(layer "In7.Cu")
		(net "M_DDR3_NODE1_DQS2P")
	)
	(segment
		(start 46.0121 -50.645314)
		(end 46.820582 -51.453796)
		(width 0.2032)
		(layer "In7.Cu")
		(net "M_DDR3_NODE1_DQS2P")
	)
	(segment
		(start 45.610272 -45.71746)
		(end 46.0121 -46.119288)
		(width 0.2032)
		(layer "In7.Cu")
		(net "M_DDR3_NODE1_DQS2P")
	)
	(segment
		(start 54.332632 -24.63165)
		(end 53.795422 -25.16886)
		(width 0.2032)
		(layer "In7.Cu")
		(net "M_DDR3_NODE1_DQS2P")
	)
	(segment
		(start 52.527962 -57.16016)
		(end 52.54625 -57.178448)
		(width 0.09906)
		(layer "In7.Cu")
		(net "M_DDR3_NODE1_DQS2P")
	)
	(segment
		(start 44.431966 -48.702976)
		(end 44.6405 -48.494442)
		(width 0.2032)
		(layer "In7.Cu")
		(net "M_DDR3_NODE1_DQS2P")
	)
	(segment
		(start 44.763436 -42.353484)
		(end 44.607988 -42.353484)
		(width 0.2032)
		(layer "In7.Cu")
		(net "M_DDR3_NODE1_DQS2P")
	)
	(segment
		(start 45.042328 -45.71746)
		(end 45.610272 -45.71746)
		(width 0.2032)
		(layer "In7.Cu")
		(net "M_DDR3_NODE1_DQS2P")
	)
	(segment
		(start 54.59984 -64.598804)
		(end 54.59984 -65.387728)
		(width 0.09906)
		(layer "In7.Cu")
		(net "M_DDR3_NODE1_DQS2P")
	)
	(segment
		(start 53.795422 -25.16886)
		(end 53.795422 -25.617424)
		(width 0.2032)
		(layer "In7.Cu")
		(net "M_DDR3_NODE1_DQS2P")
	)
	(segment
		(start 54.080664 -63.51397)
		(end 54.080664 -64.079628)
		(width 0.09906)
		(layer "In7.Cu")
		(net "M_DDR3_NODE1_DQS2P")
	)
	(segment
		(start 53.17236 -62.605666)
		(end 54.080664 -63.51397)
		(width 0.09906)
		(layer "In7.Cu")
		(net "M_DDR3_NODE1_DQS2P")
	)
	(segment
		(start 52.54625 -57.268364)
		(end 52.54498 -57.268364)
		(width 0.09906)
		(layer "In7.Cu")
		(net "M_DDR3_NODE1_DQS2P")
	)
	(segment
		(start 46.0121 -46.119288)
		(end 46.0121 -50.645314)
		(width 0.2032)
		(layer "In7.Cu")
		(net "M_DDR3_NODE1_DQS2P")
	)
	(segment
		(start 44.607988 -42.353484)
		(end 43.9293 -43.032172)
		(width 0.2032)
		(layer "In7.Cu")
		(net "M_DDR3_NODE1_DQS2P")
	)
	(segment
		(start 52.54498 -57.268364)
		(end 53.3146 -58.037984)
		(width 0.09906)
		(layer "In7.Cu")
		(net "M_DDR3_NODE1_DQS2P")
	)
	(segment
		(start 45.21708 -41.744392)
		(end 45.21708 -41.902126)
		(width 0.2032)
		(layer "In7.Cu")
		(net "M_DDR3_NODE1_DQS2P")
	)
	(segment
		(start 53.3146 -59.224164)
		(end 53.17236 -59.366404)
		(width 0.09906)
		(layer "In7.Cu")
		(net "M_DDR3_NODE1_DQS2P")
	)
	(segment
		(start 52.54625 -57.178448)
		(end 52.54625 -57.268364)
		(width 0.09906)
		(layer "In7.Cu")
		(net "M_DDR3_NODE1_DQS2P")
	)
	(segment
		(start 149.57171 -62.758066)
		(end 150.585932 -62.758066)
		(width 0.1778)
		(layer "F.Cu")
		(net "P1V8_SATA_VAA2_1_NODE1")
	)
	(via
		(at 156.838396 -62.60973)
		(size 0.6604)
		(drill 0.3302)
		(layers "F.Cu" "B.Cu")
		(net "P1V8_SATA_VAA2_1_NODE1")
	)
	(via
		(at 150.585932 -62.758066)
		(size 0.508)
		(drill 0.254)
		(layers "F.Cu" "B.Cu")
		(net "P1V8_SATA_VAA2_1_NODE1")
	)
	(segment
		(start 67.425316 -84.275676)
		(end 66.845942 -84.275676)
		(width 0.1016)
		(layer "F.Cu")
		(net "NODE1_BIOS_MB_REV_ID1")
	)
	(segment
		(start 67.462146 -84.238846)
		(end 67.425316 -84.275676)
		(width 0.1016)
		(layer "F.Cu")
		(net "NODE1_BIOS_MB_REV_ID1")
	)
	(via
		(at 66.845942 -84.275676)
		(size 0.508)
		(drill 0.254)
		(layers "F.Cu" "B.Cu")
		(net "NODE1_BIOS_MB_REV_ID1")
	)
	(segment
		(start 67.97802 -90.753946)
		(end 67.946778 -90.453718)
		(width 0.1016)
		(layer "B.Cu")
		(net "NODE1_BIOS_MB_REV_ID1")
	)
	(segment
		(start 70.850252 -98.296476)
		(end 70.850252 -97.29597)
		(width 0.1016)
		(layer "B.Cu")
		(net "NODE1_BIOS_MB_REV_ID1")
	)
	(segment
		(start 69.262498 -96.296734)
		(end 69.04101 -96.075246)
		(width 0.1016)
		(layer "B.Cu")
		(net "NODE1_BIOS_MB_REV_ID1")
	)
	(segment
		(start 70.678802 -98.467926)
		(end 70.850252 -98.296476)
		(width 0.1016)
		(layer "B.Cu")
		(net "NODE1_BIOS_MB_REV_ID1")
	)
	(segment
		(start 67.97802 -93.443806)
		(end 67.97802 -90.753946)
		(width 0.1016)
		(layer "B.Cu")
		(net "NODE1_BIOS_MB_REV_ID1")
	)
	(segment
		(start 67.609974 -87.69477)
		(end 67.609974 -85.039708)
		(width 0.1016)
		(layer "B.Cu")
		(net "NODE1_BIOS_MB_REV_ID1")
	)
	(segment
		(start 69.996558 -97.031556)
		(end 69.262498 -96.297496)
		(width 0.1016)
		(layer "B.Cu")
		(net "NODE1_BIOS_MB_REV_ID1")
	)
	(segment
		(start 69.04101 -96.075246)
		(end 69.04101 -94.506796)
		(width 0.1016)
		(layer "B.Cu")
		(net "NODE1_BIOS_MB_REV_ID1")
	)
	(segment
		(start 67.946778 -90.453718)
		(end 67.946778 -88.031574)
		(width 0.1016)
		(layer "B.Cu")
		(net "NODE1_BIOS_MB_REV_ID1")
	)
	(segment
		(start 67.609974 -85.039708)
		(end 66.845942 -84.275676)
		(width 0.1016)
		(layer "B.Cu")
		(net "NODE1_BIOS_MB_REV_ID1")
	)
	(segment
		(start 70.585838 -97.031556)
		(end 69.996558 -97.031556)
		(width 0.1016)
		(layer "B.Cu")
		(net "NODE1_BIOS_MB_REV_ID1")
	)
	(segment
		(start 69.262498 -96.297496)
		(end 69.262498 -96.296734)
		(width 0.1016)
		(layer "B.Cu")
		(net "NODE1_BIOS_MB_REV_ID1")
	)
	(segment
		(start 67.946778 -88.031574)
		(end 67.609974 -87.69477)
		(width 0.1016)
		(layer "B.Cu")
		(net "NODE1_BIOS_MB_REV_ID1")
	)
	(segment
		(start 70.850252 -97.29597)
		(end 70.585838 -97.031556)
		(width 0.1016)
		(layer "B.Cu")
		(net "NODE1_BIOS_MB_REV_ID1")
	)
	(segment
		(start 69.04101 -94.506796)
		(end 67.97802 -93.443806)
		(width 0.1016)
		(layer "B.Cu")
		(net "NODE1_BIOS_MB_REV_ID1")
	)
	(segment
		(start 64.572134 -58.676286)
		(end 63.942976 -59.305444)
		(width 0.1016)
		(layer "F.Cu")
		(net "M_DDR3_NODE1_BS0")
	)
	(segment
		(start 78.150212 -20.94992)
		(end 78.150212 -23.66391)
		(width 0.2286)
		(layer "F.Cu")
		(net "M_DDR3_NODE1_BS0")
	)
	(segment
		(start 62.905386 -64.116712)
		(end 62.765178 -64.25692)
		(width 0.1016)
		(layer "F.Cu")
		(net "M_DDR3_NODE1_BS0")
	)
	(segment
		(start 63.942976 -60.680346)
		(end 62.96914 -61.654182)
		(width 0.1016)
		(layer "F.Cu")
		(net "M_DDR3_NODE1_BS0")
	)
	(segment
		(start 62.96914 -61.654182)
		(end 62.96914 -62.652148)
		(width 0.1016)
		(layer "F.Cu")
		(net "M_DDR3_NODE1_BS0")
	)
	(segment
		(start 62.765178 -64.25692)
		(end 62.606936 -64.25692)
		(width 0.1016)
		(layer "F.Cu")
		(net "M_DDR3_NODE1_BS0")
	)
	(segment
		(start 62.792102 -62.829186)
		(end 62.792102 -63.25108)
		(width 0.1016)
		(layer "F.Cu")
		(net "M_DDR3_NODE1_BS0")
	)
	(segment
		(start 78.97368 -24.487378)
		(end 79.304642 -24.487378)
		(width 0.2286)
		(layer "F.Cu")
		(net "M_DDR3_NODE1_BS0")
	)
	(segment
		(start 62.792102 -63.25108)
		(end 62.905386 -63.364364)
		(width 0.1016)
		(layer "F.Cu")
		(net "M_DDR3_NODE1_BS0")
	)
	(segment
		(start 78.150212 -23.66391)
		(end 78.97368 -24.487378)
		(width 0.2286)
		(layer "F.Cu")
		(net "M_DDR3_NODE1_BS0")
	)
	(segment
		(start 63.942976 -59.305444)
		(end 63.942976 -60.680346)
		(width 0.1016)
		(layer "F.Cu")
		(net "M_DDR3_NODE1_BS0")
	)
	(segment
		(start 62.905386 -63.364364)
		(end 62.905386 -64.116712)
		(width 0.1016)
		(layer "F.Cu")
		(net "M_DDR3_NODE1_BS0")
	)
	(segment
		(start 64.572134 -58.567828)
		(end 64.572134 -58.676286)
		(width 0.1016)
		(layer "F.Cu")
		(net "M_DDR3_NODE1_BS0")
	)
	(segment
		(start 62.96914 -62.652148)
		(end 62.792102 -62.829186)
		(width 0.1016)
		(layer "F.Cu")
		(net "M_DDR3_NODE1_BS0")
	)
	(via
		(at 79.304642 -24.487378)
		(size 0.508)
		(drill 0.254)
		(layers "F.Cu" "B.Cu")
		(net "M_DDR3_NODE1_BS0")
	)
	(via
		(at 64.572134 -58.567828)
		(size 0.508)
		(drill 0.254)
		(layers "F.Cu" "B.Cu")
		(net "M_DDR3_NODE1_BS0")
	)
	(segment
		(start 78.61808 -46.43374)
		(end 75.356974 -49.694846)
		(width 0.2286)
		(layer "In2.Cu")
		(net "M_DDR3_NODE1_BS0")
	)
	(segment
		(start 79.35468 -45.603414)
		(end 79.35468 -42.872152)
		(width 0.2286)
		(layer "In2.Cu")
		(net "M_DDR3_NODE1_BS0")
	)
	(segment
		(start 78.98892 -26.027888)
		(end 78.98892 -31.874206)
		(width 0.2286)
		(layer "In2.Cu")
		(net "M_DDR3_NODE1_BS0")
	)
	(segment
		(start 79.40802 -32.293306)
		(end 79.40802 -41.152572)
		(width 0.2286)
		(layer "In2.Cu")
		(net "M_DDR3_NODE1_BS0")
	)
	(segment
		(start 71.515478 -52.831492)
		(end 70.010274 -52.831492)
		(width 0.2286)
		(layer "In2.Cu")
		(net "M_DDR3_NODE1_BS0")
	)
	(segment
		(start 79.88808 -45.806614)
		(end 79.55788 -45.806614)
		(width 0.2286)
		(layer "In2.Cu")
		(net "M_DDR3_NODE1_BS0")
	)
	(segment
		(start 79.40802 -41.152572)
		(end 80.09128 -41.835832)
		(width 0.2286)
		(layer "In2.Cu")
		(net "M_DDR3_NODE1_BS0")
	)
	(segment
		(start 79.35468 -42.872152)
		(end 79.15148 -42.668952)
		(width 0.2286)
		(layer "In2.Cu")
		(net "M_DDR3_NODE1_BS0")
	)
	(segment
		(start 80.09128 -45.603414)
		(end 79.88808 -45.806614)
		(width 0.2286)
		(layer "In2.Cu")
		(net "M_DDR3_NODE1_BS0")
	)
	(segment
		(start 65.427606 -58.36412)
		(end 64.775334 -58.36412)
		(width 0.2286)
		(layer "In2.Cu")
		(net "M_DDR3_NODE1_BS0")
	)
	(segment
		(start 66.60642 -57.185306)
		(end 65.427606 -58.36412)
		(width 0.2286)
		(layer "In2.Cu")
		(net "M_DDR3_NODE1_BS0")
	)
	(segment
		(start 78.61808 -42.872152)
		(end 78.61808 -46.43374)
		(width 0.2286)
		(layer "In2.Cu")
		(net "M_DDR3_NODE1_BS0")
	)
	(segment
		(start 64.775334 -58.36412)
		(end 64.572134 -58.56732)
		(width 0.2286)
		(layer "In2.Cu")
		(net "M_DDR3_NODE1_BS0")
	)
	(segment
		(start 75.356974 -49.694846)
		(end 74.652124 -49.694846)
		(width 0.2286)
		(layer "In2.Cu")
		(net "M_DDR3_NODE1_BS0")
	)
	(segment
		(start 78.98892 -31.874206)
		(end 79.40802 -32.293306)
		(width 0.2286)
		(layer "In2.Cu")
		(net "M_DDR3_NODE1_BS0")
	)
	(segment
		(start 79.304642 -24.487378)
		(end 79.4258 -24.608536)
		(width 0.2286)
		(layer "In2.Cu")
		(net "M_DDR3_NODE1_BS0")
	)
	(segment
		(start 79.55788 -45.806614)
		(end 79.35468 -45.603414)
		(width 0.2286)
		(layer "In2.Cu")
		(net "M_DDR3_NODE1_BS0")
	)
	(segment
		(start 79.4258 -25.591008)
		(end 78.98892 -26.027888)
		(width 0.2286)
		(layer "In2.Cu")
		(net "M_DDR3_NODE1_BS0")
	)
	(segment
		(start 74.652124 -49.694846)
		(end 71.515478 -52.831492)
		(width 0.2286)
		(layer "In2.Cu")
		(net "M_DDR3_NODE1_BS0")
	)
	(segment
		(start 79.4258 -24.608536)
		(end 79.4258 -25.591008)
		(width 0.2286)
		(layer "In2.Cu")
		(net "M_DDR3_NODE1_BS0")
	)
	(segment
		(start 80.09128 -41.835832)
		(end 80.09128 -45.603414)
		(width 0.2286)
		(layer "In2.Cu")
		(net "M_DDR3_NODE1_BS0")
	)
	(segment
		(start 70.010274 -52.831492)
		(end 66.60642 -56.235346)
		(width 0.2286)
		(layer "In2.Cu")
		(net "M_DDR3_NODE1_BS0")
	)
	(segment
		(start 64.572134 -58.56732)
		(end 64.572134 -58.567828)
		(width 0.2286)
		(layer "In2.Cu")
		(net "M_DDR3_NODE1_BS0")
	)
	(segment
		(start 79.15148 -42.668952)
		(end 78.82128 -42.668952)
		(width 0.2286)
		(layer "In2.Cu")
		(net "M_DDR3_NODE1_BS0")
	)
	(segment
		(start 66.60642 -56.235346)
		(end 66.60642 -57.185306)
		(width 0.2286)
		(layer "In2.Cu")
		(net "M_DDR3_NODE1_BS0")
	)
	(segment
		(start 78.82128 -42.668952)
		(end 78.61808 -42.872152)
		(width 0.2286)
		(layer "In2.Cu")
		(net "M_DDR3_NODE1_BS0")
	)
	(segment
		(start 149.57171 -66.358008)
		(end 150.26894 -66.358008)
		(width 0.1778)
		(layer "F.Cu")
		(net "P1V8_SATA_VAA1_NODE1")
	)
	(segment
		(start 150.559262 -66.64833)
		(end 150.843996 -66.64833)
		(width 0.1778)
		(layer "F.Cu")
		(net "P1V8_SATA_VAA1_NODE1")
	)
	(segment
		(start 150.26894 -66.358008)
		(end 150.559262 -66.64833)
		(width 0.1778)
		(layer "F.Cu")
		(net "P1V8_SATA_VAA1_NODE1")
	)
	(via
		(at 150.843996 -66.64833)
		(size 0.508)
		(drill 0.254)
		(layers "F.Cu" "B.Cu")
		(net "P1V8_SATA_VAA1_NODE1")
	)
	(via
		(at 156.812996 -66.72453)
		(size 0.6604)
		(drill 0.3302)
		(layers "F.Cu" "B.Cu")
		(net "P1V8_SATA_VAA1_NODE1")
	)
	(segment
		(start 16.62176 -42.594022)
		(end 16.62176 -41.795192)
		(width 0.1016)
		(layer "F.Cu")
		(net "BMC_NODE1_GFX_RED")
	)
	(segment
		(start 16.686784 -43.198034)
		(end 16.686784 -42.659046)
		(width 0.1016)
		(layer "F.Cu")
		(net "BMC_NODE1_GFX_RED")
	)
	(segment
		(start 62.941708 -142.459456)
		(end 62.939676 -142.459456)
		(width 0.1016)
		(layer "F.Cu")
		(net "BMC_NODE1_GFX_RED")
	)
	(segment
		(start 16.62176 -41.795192)
		(end 18.16354 -41.795192)
		(width 0.1016)
		(layer "F.Cu")
		(net "BMC_NODE1_GFX_RED")
	)
	(segment
		(start 16.686784 -42.659046)
		(end 16.62176 -42.594022)
		(width 0.1016)
		(layer "F.Cu")
		(net "BMC_NODE1_GFX_RED")
	)
	(segment
		(start 62.939676 -142.459456)
		(end 62.540896 -142.858236)
		(width 0.1016)
		(layer "F.Cu")
		(net "BMC_NODE1_GFX_RED")
	)
	(via
		(at 61.449712 -144.846802)
		(size 0.6604)
		(drill 0.3302)
		(layers "F.Cu" "B.Cu")
		(net "BMC_NODE1_GFX_RED")
	)
	(via
		(at 62.540896 -142.858236)
		(size 0.49022)
		(drill 0.254)
		(layers "F.Cu" "B.Cu")
		(net "BMC_NODE1_GFX_RED")
	)
	(via
		(at 18.16354 -41.795192)
		(size 0.508)
		(drill 0.254)
		(layers "F.Cu" "B.Cu")
		(net "BMC_NODE1_GFX_RED")
	)
	(segment
		(start 61.089286 -146.019012)
		(end 61.089286 -145.509742)
		(width 0.1016)
		(layer "B.Cu")
		(net "BMC_NODE1_GFX_RED")
	)
	(segment
		(start 61.089286 -145.509742)
		(end 61.449712 -145.149316)
		(width 0.1016)
		(layer "B.Cu")
		(net "BMC_NODE1_GFX_RED")
	)
	(segment
		(start 61.449712 -145.149316)
		(end 61.449712 -144.846802)
		(width 0.1016)
		(layer "B.Cu")
		(net "BMC_NODE1_GFX_RED")
	)
	(segment
		(start 61.449712 -144.233138)
		(end 62.540896 -143.141954)
		(width 0.1016)
		(layer "B.Cu")
		(net "BMC_NODE1_GFX_RED")
	)
	(segment
		(start 62.540896 -143.141954)
		(end 62.540896 -142.858236)
		(width 0.1016)
		(layer "B.Cu")
		(net "BMC_NODE1_GFX_RED")
	)
	(segment
		(start 61.449712 -144.846802)
		(end 61.449712 -144.233138)
		(width 0.1016)
		(layer "B.Cu")
		(net "BMC_NODE1_GFX_RED")
	)
	(segment
		(start 43.965876 -147.058888)
		(end 44.547028 -147.64004)
		(width 0.1143)
		(layer "In6.Cu")
		(net "BMC_NODE1_GFX_RED")
	)
	(segment
		(start 21.94814 -61.586872)
		(end 21.94814 -62.423802)
		(width 0.1143)
		(layer "In6.Cu")
		(net "BMC_NODE1_GFX_RED")
	)
	(segment
		(start 18.56994 -53.509672)
		(end 18.56994 -55.760366)
		(width 0.1143)
		(layer "In6.Cu")
		(net "BMC_NODE1_GFX_RED")
	)
	(segment
		(start 22.43582 -61.099192)
		(end 21.94814 -61.586872)
		(width 0.1143)
		(layer "In6.Cu")
		(net "BMC_NODE1_GFX_RED")
	)
	(segment
		(start 56.056784 -145.632932)
		(end 59.45886 -145.632932)
		(width 0.1143)
		(layer "In6.Cu")
		(net "BMC_NODE1_GFX_RED")
	)
	(segment
		(start 37.828728 -145.43913)
		(end 37.93744 -145.547588)
		(width 0.1143)
		(layer "In6.Cu")
		(net "BMC_NODE1_GFX_RED")
	)
	(segment
		(start 54.596538 -147.093178)
		(end 56.056784 -145.632932)
		(width 0.1143)
		(layer "In6.Cu")
		(net "BMC_NODE1_GFX_RED")
	)
	(segment
		(start 17.61998 -82.803746)
		(end 19.07032 -84.254086)
		(width 0.1143)
		(layer "In6.Cu")
		(net "BMC_NODE1_GFX_RED")
	)
	(segment
		(start 22.56028 -75.661266)
		(end 17.61998 -80.601566)
		(width 0.1143)
		(layer "In6.Cu")
		(net "BMC_NODE1_GFX_RED")
	)
	(segment
		(start 19.042126 -139.973304)
		(end 32.36087 -139.973304)
		(width 0.1143)
		(layer "In6.Cu")
		(net "BMC_NODE1_GFX_RED")
	)
	(segment
		(start 18.16354 -41.795192)
		(end 18.47342 -42.105072)
		(width 0.1143)
		(layer "In6.Cu")
		(net "BMC_NODE1_GFX_RED")
	)
	(segment
		(start 43.9547 -147.058888)
		(end 43.965876 -147.058888)
		(width 0.1143)
		(layer "In6.Cu")
		(net "BMC_NODE1_GFX_RED")
	)
	(segment
		(start 8.45058 -97.390204)
		(end 8.45058 -132.829808)
		(width 0.1143)
		(layer "In6.Cu")
		(net "BMC_NODE1_GFX_RED")
	)
	(segment
		(start 18.934176 -56.124602)
		(end 19.812254 -56.124602)
		(width 0.1143)
		(layer "In6.Cu")
		(net "BMC_NODE1_GFX_RED")
	)
	(segment
		(start 44.547028 -147.64004)
		(end 45.417486 -147.64004)
		(width 0.1143)
		(layer "In6.Cu")
		(net "BMC_NODE1_GFX_RED")
	)
	(segment
		(start 18.47342 -42.105072)
		(end 18.47342 -50.769774)
		(width 0.1143)
		(layer "In6.Cu")
		(net "BMC_NODE1_GFX_RED")
	)
	(segment
		(start 45.872146 -148.0947)
		(end 49.25441 -148.0947)
		(width 0.1143)
		(layer "In6.Cu")
		(net "BMC_NODE1_GFX_RED")
	)
	(segment
		(start 16.679926 -137.611358)
		(end 18.938748 -139.87018)
		(width 0.1143)
		(layer "In6.Cu")
		(net "BMC_NODE1_GFX_RED")
	)
	(segment
		(start 18.938748 -139.87018)
		(end 19.042126 -139.973304)
		(width 0.1143)
		(layer "In6.Cu")
		(net "BMC_NODE1_GFX_RED")
	)
	(segment
		(start 19.812254 -56.124602)
		(end 22.43582 -58.748168)
		(width 0.1143)
		(layer "In6.Cu")
		(net "BMC_NODE1_GFX_RED")
	)
	(segment
		(start 13.23213 -137.611358)
		(end 16.679926 -137.611358)
		(width 0.1143)
		(layer "In6.Cu")
		(net "BMC_NODE1_GFX_RED")
	)
	(segment
		(start 17.61998 -80.601566)
		(end 17.61998 -82.803746)
		(width 0.1143)
		(layer "In6.Cu")
		(net "BMC_NODE1_GFX_RED")
	)
	(segment
		(start 19.07032 -84.254086)
		(end 19.07032 -86.770464)
		(width 0.1143)
		(layer "In6.Cu")
		(net "BMC_NODE1_GFX_RED")
	)
	(segment
		(start 22.56028 -63.035942)
		(end 22.56028 -75.661266)
		(width 0.1143)
		(layer "In6.Cu")
		(net "BMC_NODE1_GFX_RED")
	)
	(segment
		(start 32.435038 -140.04671)
		(end 37.828728 -145.43913)
		(width 0.1143)
		(layer "In6.Cu")
		(net "BMC_NODE1_GFX_RED")
	)
	(segment
		(start 21.94814 -62.423802)
		(end 22.56028 -63.035942)
		(width 0.1143)
		(layer "In6.Cu")
		(net "BMC_NODE1_GFX_RED")
	)
	(segment
		(start 37.93744 -145.547588)
		(end 39.746936 -145.547588)
		(width 0.1143)
		(layer "In6.Cu")
		(net "BMC_NODE1_GFX_RED")
	)
	(segment
		(start 40.60698 -146.408648)
		(end 43.303444 -146.408648)
		(width 0.1143)
		(layer "In6.Cu")
		(net "BMC_NODE1_GFX_RED")
	)
	(segment
		(start 59.45886 -145.632932)
		(end 62.233556 -142.858236)
		(width 0.1143)
		(layer "In6.Cu")
		(net "BMC_NODE1_GFX_RED")
	)
	(segment
		(start 18.47342 -50.769774)
		(end 18.16862 -51.074574)
		(width 0.1143)
		(layer "In6.Cu")
		(net "BMC_NODE1_GFX_RED")
	)
	(segment
		(start 50.255932 -147.093178)
		(end 54.596538 -147.093178)
		(width 0.1143)
		(layer "In6.Cu")
		(net "BMC_NODE1_GFX_RED")
	)
	(segment
		(start 32.36087 -139.973304)
		(end 32.435038 -140.04671)
		(width 0.1143)
		(layer "In6.Cu")
		(net "BMC_NODE1_GFX_RED")
	)
	(segment
		(start 43.303444 -146.408648)
		(end 43.9547 -147.058888)
		(width 0.1143)
		(layer "In6.Cu")
		(net "BMC_NODE1_GFX_RED")
	)
	(segment
		(start 22.43582 -58.748168)
		(end 22.43582 -61.099192)
		(width 0.1143)
		(layer "In6.Cu")
		(net "BMC_NODE1_GFX_RED")
	)
	(segment
		(start 8.45058 -132.829808)
		(end 13.23213 -137.611358)
		(width 0.1143)
		(layer "In6.Cu")
		(net "BMC_NODE1_GFX_RED")
	)
	(segment
		(start 62.233556 -142.858236)
		(end 62.540896 -142.858236)
		(width 0.1143)
		(layer "In6.Cu")
		(net "BMC_NODE1_GFX_RED")
	)
	(segment
		(start 45.417486 -147.64004)
		(end 45.872146 -148.0947)
		(width 0.1143)
		(layer "In6.Cu")
		(net "BMC_NODE1_GFX_RED")
	)
	(segment
		(start 18.16862 -53.108352)
		(end 18.56994 -53.509672)
		(width 0.1143)
		(layer "In6.Cu")
		(net "BMC_NODE1_GFX_RED")
	)
	(segment
		(start 18.16862 -51.074574)
		(end 18.16862 -53.108352)
		(width 0.1143)
		(layer "In6.Cu")
		(net "BMC_NODE1_GFX_RED")
	)
	(segment
		(start 18.56994 -55.760366)
		(end 18.934176 -56.124602)
		(width 0.1143)
		(layer "In6.Cu")
		(net "BMC_NODE1_GFX_RED")
	)
	(segment
		(start 49.25441 -148.0947)
		(end 50.255932 -147.093178)
		(width 0.1143)
		(layer "In6.Cu")
		(net "BMC_NODE1_GFX_RED")
	)
	(segment
		(start 19.07032 -86.770464)
		(end 8.45058 -97.390204)
		(width 0.1143)
		(layer "In6.Cu")
		(net "BMC_NODE1_GFX_RED")
	)
	(segment
		(start 39.746936 -145.547588)
		(end 40.60698 -146.408648)
		(width 0.1143)
		(layer "In6.Cu")
		(net "BMC_NODE1_GFX_RED")
	)
	(segment
		(start 52.299362 -25.775158)
		(end 52.299362 -25.774904)
		(width 0.1016)
		(layer "F.Cu")
		(net "M_NODE1_DIMM_RST_L")
	)
	(segment
		(start 49.050194 -26.43886)
		(end 49.050194 -29.149802)
		(width 0.1016)
		(layer "F.Cu")
		(net "M_NODE1_DIMM_RST_L")
	)
	(segment
		(start 60.456826 -68.122038)
		(end 60.456826 -68.120006)
		(width 0.1016)
		(layer "F.Cu")
		(net "M_NODE1_DIMM_RST_L")
	)
	(segment
		(start 52.299362 -25.774904)
		(end 52.047902 -25.523444)
		(width 0.1016)
		(layer "F.Cu")
		(net "M_NODE1_DIMM_RST_L")
	)
	(segment
		(start 60.456826 -68.120006)
		(end 60.850526 -67.726306)
		(width 0.1016)
		(layer "F.Cu")
		(net "M_NODE1_DIMM_RST_L")
	)
	(segment
		(start 49.96561 -25.523444)
		(end 49.050194 -26.43886)
		(width 0.1016)
		(layer "F.Cu")
		(net "M_NODE1_DIMM_RST_L")
	)
	(segment
		(start 52.047902 -25.523444)
		(end 49.96561 -25.523444)
		(width 0.1016)
		(layer "F.Cu")
		(net "M_NODE1_DIMM_RST_L")
	)
	(via
		(at 60.850526 -67.726306)
		(size 0.508)
		(drill 0.254)
		(layers "F.Cu" "B.Cu")
		(net "M_NODE1_DIMM_RST_L")
	)
	(via
		(at 52.299362 -25.775158)
		(size 0.508)
		(drill 0.254)
		(layers "F.Cu" "B.Cu")
		(net "M_NODE1_DIMM_RST_L")
	)
	(segment
		(start 52.97678 -33.181544)
		(end 46.4312 -39.727124)
		(width 0.1143)
		(layer "In2.Cu")
		(net "M_NODE1_DIMM_RST_L")
	)
	(segment
		(start 51.130708 -60.236862)
		(end 51.130708 -61.4299)
		(width 0.1143)
		(layer "In2.Cu")
		(net "M_NODE1_DIMM_RST_L")
	)
	(segment
		(start 52.605432 -25.775158)
		(end 52.97678 -26.146506)
		(width 0.1143)
		(layer "In2.Cu")
		(net "M_NODE1_DIMM_RST_L")
	)
	(segment
		(start 52.299362 -25.775158)
		(end 52.605432 -25.775158)
		(width 0.1143)
		(layer "In2.Cu")
		(net "M_NODE1_DIMM_RST_L")
	)
	(segment
		(start 44.41698 -39.727124)
		(end 42.343832 -41.800272)
		(width 0.1143)
		(layer "In2.Cu")
		(net "M_NODE1_DIMM_RST_L")
	)
	(segment
		(start 41.007792 -41.800272)
		(end 40.3352 -42.472864)
		(width 0.1143)
		(layer "In2.Cu")
		(net "M_NODE1_DIMM_RST_L")
	)
	(segment
		(start 40.3352 -47.691294)
		(end 49.34712 -56.703214)
		(width 0.1143)
		(layer "In2.Cu")
		(net "M_NODE1_DIMM_RST_L")
	)
	(segment
		(start 50.957734 -60.063888)
		(end 51.130708 -60.236862)
		(width 0.1143)
		(layer "In2.Cu")
		(net "M_NODE1_DIMM_RST_L")
	)
	(segment
		(start 40.3352 -42.472864)
		(end 40.3352 -47.691294)
		(width 0.1143)
		(layer "In2.Cu")
		(net "M_NODE1_DIMM_RST_L")
	)
	(segment
		(start 50.957734 -59.076336)
		(end 50.957734 -60.063888)
		(width 0.1143)
		(layer "In2.Cu")
		(net "M_NODE1_DIMM_RST_L")
	)
	(segment
		(start 46.4312 -39.727124)
		(end 44.41698 -39.727124)
		(width 0.1143)
		(layer "In2.Cu")
		(net "M_NODE1_DIMM_RST_L")
	)
	(segment
		(start 51.655726 -61.954918)
		(end 51.655726 -62.246256)
		(width 0.1143)
		(layer "In2.Cu")
		(net "M_NODE1_DIMM_RST_L")
	)
	(segment
		(start 49.34712 -56.703214)
		(end 49.34712 -57.465722)
		(width 0.1143)
		(layer "In2.Cu")
		(net "M_NODE1_DIMM_RST_L")
	)
	(segment
		(start 51.655726 -62.246256)
		(end 54.152546 -64.743076)
		(width 0.1143)
		(layer "In2.Cu")
		(net "M_NODE1_DIMM_RST_L")
	)
	(segment
		(start 60.22086 -67.09664)
		(end 60.850526 -67.726306)
		(width 0.1143)
		(layer "In2.Cu")
		(net "M_NODE1_DIMM_RST_L")
	)
	(segment
		(start 49.34712 -57.465722)
		(end 50.957734 -59.076336)
		(width 0.1143)
		(layer "In2.Cu")
		(net "M_NODE1_DIMM_RST_L")
	)
	(segment
		(start 42.343832 -41.800272)
		(end 41.007792 -41.800272)
		(width 0.1143)
		(layer "In2.Cu")
		(net "M_NODE1_DIMM_RST_L")
	)
	(segment
		(start 60.22086 -65.485518)
		(end 60.22086 -67.09664)
		(width 0.1143)
		(layer "In2.Cu")
		(net "M_NODE1_DIMM_RST_L")
	)
	(segment
		(start 59.478418 -64.743076)
		(end 60.22086 -65.485518)
		(width 0.1143)
		(layer "In2.Cu")
		(net "M_NODE1_DIMM_RST_L")
	)
	(segment
		(start 52.97678 -26.146506)
		(end 52.97678 -33.181544)
		(width 0.1143)
		(layer "In2.Cu")
		(net "M_NODE1_DIMM_RST_L")
	)
	(segment
		(start 51.130708 -61.4299)
		(end 51.655726 -61.954918)
		(width 0.1143)
		(layer "In2.Cu")
		(net "M_NODE1_DIMM_RST_L")
	)
	(segment
		(start 54.152546 -64.743076)
		(end 59.478418 -64.743076)
		(width 0.1143)
		(layer "In2.Cu")
		(net "M_NODE1_DIMM_RST_L")
	)
	(segment
		(start 152.782016 -138.822938)
		(end 154.748484 -138.822938)
		(width 0.1016)
		(layer "F.Cu")
		(net "RST_BTN_NODE1_L")
	)
	(segment
		(start 157.212284 -135.768842)
		(end 158.700724 -135.768842)
		(width 0.1016)
		(layer "F.Cu")
		(net "RST_BTN_NODE1_L")
	)
	(segment
		(start 152.355804 -138.396726)
		(end 152.782016 -138.822938)
		(width 0.1016)
		(layer "F.Cu")
		(net "RST_BTN_NODE1_L")
	)
	(segment
		(start 152.355804 -138.203432)
		(end 152.355804 -138.396726)
		(width 0.1016)
		(layer "F.Cu")
		(net "RST_BTN_NODE1_L")
	)
	(segment
		(start 158.700724 -135.768842)
		(end 158.78302 -135.686546)
		(width 0.1016)
		(layer "F.Cu")
		(net "RST_BTN_NODE1_L")
	)
	(segment
		(start 158.78302 -135.686546)
		(end 158.78302 -133.645148)
		(width 0.1016)
		(layer "F.Cu")
		(net "RST_BTN_NODE1_L")
	)
	(segment
		(start 166.783766 -128.646428)
		(end 173.105318 -128.646428)
		(width 0.1016)
		(layer "F.Cu")
		(net "RST_BTN_NODE1_L")
	)
	(segment
		(start 160.492948 -131.93522)
		(end 163.494974 -131.93522)
		(width 0.1016)
		(layer "F.Cu")
		(net "RST_BTN_NODE1_L")
	)
	(segment
		(start 174.49292 -127.258826)
		(end 174.49292 -124.883164)
		(width 0.1016)
		(layer "F.Cu")
		(net "RST_BTN_NODE1_L")
	)
	(segment
		(start 173.105318 -128.646428)
		(end 174.49292 -127.258826)
		(width 0.1016)
		(layer "F.Cu")
		(net "RST_BTN_NODE1_L")
	)
	(segment
		(start 158.78302 -133.645148)
		(end 160.492948 -131.93522)
		(width 0.1016)
		(layer "F.Cu")
		(net "RST_BTN_NODE1_L")
	)
	(segment
		(start 157.212284 -136.359138)
		(end 157.212284 -135.768842)
		(width 0.1016)
		(layer "F.Cu")
		(net "RST_BTN_NODE1_L")
	)
	(segment
		(start 163.494974 -131.93522)
		(end 166.783766 -128.646428)
		(width 0.1016)
		(layer "F.Cu")
		(net "RST_BTN_NODE1_L")
	)
	(segment
		(start 154.748484 -138.822938)
		(end 157.212284 -136.359138)
		(width 0.1016)
		(layer "F.Cu")
		(net "RST_BTN_NODE1_L")
	)
	(segment
		(start 174.49292 -124.883164)
		(end 175.010318 -124.365766)
		(width 0.1016)
		(layer "F.Cu")
		(net "RST_BTN_NODE1_L")
	)
	(via
		(at 158.78302 -135.686546)
		(size 0.508)
		(drill 0.254)
		(layers "F.Cu" "B.Cu")
		(net "RST_BTN_NODE1_L")
	)
	(segment
		(start 147.530566 -69.6341)
		(end 147.694396 -69.79793)
		(width 0.1778)
		(layer "F.Cu")
		(net "P1V8_SATA_AVDD_NODE1")
	)
	(segment
		(start 147.530566 -68.799202)
		(end 147.530566 -69.6341)
		(width 0.1778)
		(layer "F.Cu")
		(net "P1V8_SATA_AVDD_NODE1")
	)
	(segment
		(start 147.930616 -69.56171)
		(end 147.694396 -69.79793)
		(width 0.1778)
		(layer "F.Cu")
		(net "P1V8_SATA_AVDD_NODE1")
	)
	(segment
		(start 147.930616 -68.799202)
		(end 147.930616 -69.56171)
		(width 0.1778)
		(layer "F.Cu")
		(net "P1V8_SATA_AVDD_NODE1")
	)
	(via
		(at 148.811996 -71.62673)
		(size 0.6604)
		(drill 0.3302)
		(layers "F.Cu" "B.Cu")
		(net "P1V8_SATA_AVDD_NODE1")
	)
	(via
		(at 147.694396 -69.79793)
		(size 0.508)
		(drill 0.254)
		(layers "F.Cu" "B.Cu")
		(net "P1V8_SATA_AVDD_NODE1")
	)
	(segment
		(start 47.996094 -22.30501)
		(end 48.150272 -22.150832)
		(width 0.1651)
		(layer "F.Cu")
		(net "M_DDR3_NODE1_DQS1P")
	)
	(segment
		(start 47.752762 -23.205186)
		(end 47.752762 -22.874732)
		(width 0.1651)
		(layer "F.Cu")
		(net "M_DDR3_NODE1_DQS1P")
	)
	(segment
		(start 48.241712 -23.329138)
		(end 47.876714 -23.329138)
		(width 0.1651)
		(layer "F.Cu")
		(net "M_DDR3_NODE1_DQS1P")
	)
	(segment
		(start 48.746664 -62.660276)
		(end 48.746664 -60.617862)
		(width 0.09906)
		(layer "F.Cu")
		(net "M_DDR3_NODE1_DQS1P")
	)
	(segment
		(start 49.489614 -62.993778)
		(end 49.340008 -63.143384)
		(width 0.09906)
		(layer "F.Cu")
		(net "M_DDR3_NODE1_DQS1P")
	)
	(segment
		(start 48.57242 -60.443618)
		(end 48.274732 -60.443618)
		(width 0.09906)
		(layer "F.Cu")
		(net "M_DDR3_NODE1_DQS1P")
	)
	(segment
		(start 49.340008 -63.143384)
		(end 49.229772 -63.143384)
		(width 0.09906)
		(layer "F.Cu")
		(net "M_DDR3_NODE1_DQS1P")
	)
	(segment
		(start 48.274732 -60.443618)
		(end 47.980346 -60.149232)
		(width 0.09906)
		(layer "F.Cu")
		(net "M_DDR3_NODE1_DQS1P")
	)
	(segment
		(start 48.150272 -22.150832)
		(end 48.150272 -20.94992)
		(width 0.1651)
		(layer "F.Cu")
		(net "M_DDR3_NODE1_DQS1P")
	)
	(segment
		(start 47.876714 -23.329138)
		(end 47.752762 -23.205186)
		(width 0.1651)
		(layer "F.Cu")
		(net "M_DDR3_NODE1_DQS1P")
	)
	(segment
		(start 48.746664 -60.617862)
		(end 48.57242 -60.443618)
		(width 0.09906)
		(layer "F.Cu")
		(net "M_DDR3_NODE1_DQS1P")
	)
	(segment
		(start 47.996094 -22.6314)
		(end 47.996094 -22.30501)
		(width 0.1651)
		(layer "F.Cu")
		(net "M_DDR3_NODE1_DQS1P")
	)
	(segment
		(start 49.85766 -62.993778)
		(end 49.489614 -62.993778)
		(width 0.09906)
		(layer "F.Cu")
		(net "M_DDR3_NODE1_DQS1P")
	)
	(segment
		(start 47.752762 -22.874732)
		(end 47.996094 -22.6314)
		(width 0.1651)
		(layer "F.Cu")
		(net "M_DDR3_NODE1_DQS1P")
	)
	(segment
		(start 49.229772 -63.143384)
		(end 48.746664 -62.660276)
		(width 0.09906)
		(layer "F.Cu")
		(net "M_DDR3_NODE1_DQS1P")
	)
	(via
		(at 47.980346 -60.149232)
		(size 0.508)
		(drill 0.254)
		(layers "F.Cu" "B.Cu")
		(net "M_DDR3_NODE1_DQS1P")
	)
	(via
		(at 48.241712 -23.329138)
		(size 0.508)
		(drill 0.254)
		(layers "F.Cu" "B.Cu")
		(net "M_DDR3_NODE1_DQS1P")
	)
	(segment
		(start 44.595542 -57.171336)
		(end 44.62145 -57.171336)
		(width 0.09906)
		(layer "In2.Cu")
		(net "M_DDR3_NODE1_DQS1P")
	)
	(segment
		(start 47.43958 -60.367926)
		(end 47.551086 -60.479432)
		(width 0.09906)
		(layer "In2.Cu")
		(net "M_DDR3_NODE1_DQS1P")
	)
	(segment
		(start 36.51758 -51.559206)
		(end 36.3093 -51.767486)
		(width 0.2032)
		(layer "In2.Cu")
		(net "M_DDR3_NODE1_DQS1P")
	)
	(segment
		(start 36.51758 -48.104806)
		(end 36.786566 -48.104806)
		(width 0.2032)
		(layer "In2.Cu")
		(net "M_DDR3_NODE1_DQS1P")
	)
	(segment
		(start 36.786566 -45.310806)
		(end 36.51758 -45.310806)
		(width 0.2032)
		(layer "In2.Cu")
		(net "M_DDR3_NODE1_DQS1P")
	)
	(segment
		(start 45.869352 -57.715404)
		(end 46.98746 -57.715404)
		(width 0.09906)
		(layer "In2.Cu")
		(net "M_DDR3_NODE1_DQS1P")
	)
	(segment
		(start 47.551086 -60.479432)
		(end 47.650146 -60.479432)
		(width 0.09906)
		(layer "In2.Cu")
		(net "M_DDR3_NODE1_DQS1P")
	)
	(segment
		(start 37.18814 -40.743632)
		(end 36.786566 -41.145206)
		(width 0.2032)
		(layer "In2.Cu")
		(net "M_DDR3_NODE1_DQS1P")
	)
	(segment
		(start 37.18814 -42.826432)
		(end 36.786566 -43.228006)
		(width 0.2032)
		(layer "In2.Cu")
		(net "M_DDR3_NODE1_DQS1P")
	)
	(segment
		(start 36.786566 -50.187606)
		(end 37.18814 -50.58918)
		(width 0.2032)
		(layer "In2.Cu")
		(net "M_DDR3_NODE1_DQS1P")
	)
	(segment
		(start 37.18814 -39.210742)
		(end 37.18814 -40.743632)
		(width 0.2032)
		(layer "In2.Cu")
		(net "M_DDR3_NODE1_DQS1P")
	)
	(segment
		(start 48.819816 -24.240236)
		(end 49.42586 -24.84628)
		(width 0.2032)
		(layer "In2.Cu")
		(net "M_DDR3_NODE1_DQS1P")
	)
	(segment
		(start 36.3093 -51.767486)
		(end 36.3093 -52.062126)
		(width 0.2032)
		(layer "In2.Cu")
		(net "M_DDR3_NODE1_DQS1P")
	)
	(segment
		(start 47.43958 -58.167524)
		(end 47.43958 -60.367926)
		(width 0.09906)
		(layer "In2.Cu")
		(net "M_DDR3_NODE1_DQS1P")
	)
	(segment
		(start 36.51758 -50.187606)
		(end 36.786566 -50.187606)
		(width 0.2032)
		(layer "In2.Cu")
		(net "M_DDR3_NODE1_DQS1P")
	)
	(segment
		(start 37.18814 -51.157632)
		(end 36.786566 -51.559206)
		(width 0.2032)
		(layer "In2.Cu")
		(net "M_DDR3_NODE1_DQS1P")
	)
	(segment
		(start 37.18814 -46.992032)
		(end 36.786566 -47.393606)
		(width 0.2032)
		(layer "In2.Cu")
		(net "M_DDR3_NODE1_DQS1P")
	)
	(segment
		(start 37.18814 -49.074832)
		(end 36.786566 -49.476406)
		(width 0.2032)
		(layer "In2.Cu")
		(net "M_DDR3_NODE1_DQS1P")
	)
	(segment
		(start 37.18814 -42.25798)
		(end 37.18814 -42.826432)
		(width 0.2032)
		(layer "In2.Cu")
		(net "M_DDR3_NODE1_DQS1P")
	)
	(segment
		(start 36.3093 -45.519086)
		(end 36.3093 -45.813726)
		(width 0.2032)
		(layer "In2.Cu")
		(net "M_DDR3_NODE1_DQS1P")
	)
	(segment
		(start 47.941484 -24.240236)
		(end 48.819816 -24.240236)
		(width 0.2032)
		(layer "In2.Cu")
		(net "M_DDR3_NODE1_DQS1P")
	)
	(segment
		(start 37.18814 -44.34078)
		(end 37.18814 -44.909232)
		(width 0.2032)
		(layer "In2.Cu")
		(net "M_DDR3_NODE1_DQS1P")
	)
	(segment
		(start 44.62145 -57.171336)
		(end 44.68495 -57.234836)
		(width 0.09906)
		(layer "In2.Cu")
		(net "M_DDR3_NODE1_DQS1P")
	)
	(segment
		(start 36.786566 -49.476406)
		(end 36.51758 -49.476406)
		(width 0.2032)
		(layer "In2.Cu")
		(net "M_DDR3_NODE1_DQS1P")
	)
	(segment
		(start 36.3093 -49.979326)
		(end 36.51758 -50.187606)
		(width 0.2032)
		(layer "In2.Cu")
		(net "M_DDR3_NODE1_DQS1P")
	)
	(segment
		(start 36.51758 -41.856406)
		(end 36.786566 -41.856406)
		(width 0.2032)
		(layer "In2.Cu")
		(net "M_DDR3_NODE1_DQS1P")
	)
	(segment
		(start 43.221148 -57.171336)
		(end 44.595542 -57.171336)
		(width 0.2032)
		(layer "In2.Cu")
		(net "M_DDR3_NODE1_DQS1P")
	)
	(segment
		(start 36.3093 -41.648126)
		(end 36.51758 -41.856406)
		(width 0.2032)
		(layer "In2.Cu")
		(net "M_DDR3_NODE1_DQS1P")
	)
	(segment
		(start 36.51758 -43.228006)
		(end 36.3093 -43.436286)
		(width 0.2032)
		(layer "In2.Cu")
		(net "M_DDR3_NODE1_DQS1P")
	)
	(segment
		(start 37.18814 -48.50638)
		(end 37.18814 -49.074832)
		(width 0.2032)
		(layer "In2.Cu")
		(net "M_DDR3_NODE1_DQS1P")
	)
	(segment
		(start 36.51758 -49.476406)
		(end 36.3093 -49.684686)
		(width 0.2032)
		(layer "In2.Cu")
		(net "M_DDR3_NODE1_DQS1P")
	)
	(segment
		(start 36.3093 -45.813726)
		(end 36.51758 -46.022006)
		(width 0.2032)
		(layer "In2.Cu")
		(net "M_DDR3_NODE1_DQS1P")
	)
	(segment
		(start 42.120312 -56.0705)
		(end 43.221148 -57.171336)
		(width 0.2032)
		(layer "In2.Cu")
		(net "M_DDR3_NODE1_DQS1P")
	)
	(segment
		(start 36.51758 -43.939206)
		(end 36.786566 -43.939206)
		(width 0.2032)
		(layer "In2.Cu")
		(net "M_DDR3_NODE1_DQS1P")
	)
	(segment
		(start 48.241712 -23.329138)
		(end 47.757842 -23.813008)
		(width 0.2032)
		(layer "In2.Cu")
		(net "M_DDR3_NODE1_DQS1P")
	)
	(segment
		(start 36.786566 -47.393606)
		(end 36.51758 -47.393606)
		(width 0.2032)
		(layer "In2.Cu")
		(net "M_DDR3_NODE1_DQS1P")
	)
	(segment
		(start 48.47336 -31.479744)
		(end 48.97628 -31.982664)
		(width 0.2032)
		(layer "In2.Cu")
		(net "M_DDR3_NODE1_DQS1P")
	)
	(segment
		(start 47.650146 -60.479432)
		(end 47.980346 -60.149232)
		(width 0.09906)
		(layer "In2.Cu")
		(net "M_DDR3_NODE1_DQS1P")
	)
	(segment
		(start 36.3093 -52.062126)
		(end 36.51758 -52.270406)
		(width 0.2032)
		(layer "In2.Cu")
		(net "M_DDR3_NODE1_DQS1P")
	)
	(segment
		(start 36.786566 -43.939206)
		(end 37.18814 -44.34078)
		(width 0.2032)
		(layer "In2.Cu")
		(net "M_DDR3_NODE1_DQS1P")
	)
	(segment
		(start 36.51758 -45.310806)
		(end 36.3093 -45.519086)
		(width 0.2032)
		(layer "In2.Cu")
		(net "M_DDR3_NODE1_DQS1P")
	)
	(segment
		(start 48.97628 -31.982664)
		(end 48.97628 -32.730948)
		(width 0.2032)
		(layer "In2.Cu")
		(net "M_DDR3_NODE1_DQS1P")
	)
	(segment
		(start 36.51758 -46.022006)
		(end 36.786566 -46.022006)
		(width 0.2032)
		(layer "In2.Cu")
		(net "M_DDR3_NODE1_DQS1P")
	)
	(segment
		(start 48.97628 -32.730948)
		(end 45.901356 -35.805872)
		(width 0.2032)
		(layer "In2.Cu")
		(net "M_DDR3_NODE1_DQS1P")
	)
	(segment
		(start 37.18814 -44.909232)
		(end 36.786566 -45.310806)
		(width 0.2032)
		(layer "In2.Cu")
		(net "M_DDR3_NODE1_DQS1P")
	)
	(segment
		(start 37.18814 -53.545232)
		(end 39.713408 -56.0705)
		(width 0.2032)
		(layer "In2.Cu")
		(net "M_DDR3_NODE1_DQS1P")
	)
	(segment
		(start 37.18814 -52.67198)
		(end 37.18814 -53.545232)
		(width 0.2032)
		(layer "In2.Cu")
		(net "M_DDR3_NODE1_DQS1P")
	)
	(segment
		(start 37.18814 -46.42358)
		(end 37.18814 -46.992032)
		(width 0.2032)
		(layer "In2.Cu")
		(net "M_DDR3_NODE1_DQS1P")
	)
	(segment
		(start 36.3093 -47.896526)
		(end 36.51758 -48.104806)
		(width 0.2032)
		(layer "In2.Cu")
		(net "M_DDR3_NODE1_DQS1P")
	)
	(segment
		(start 39.713408 -56.0705)
		(end 42.120312 -56.0705)
		(width 0.2032)
		(layer "In2.Cu")
		(net "M_DDR3_NODE1_DQS1P")
	)
	(segment
		(start 36.786566 -52.270406)
		(end 37.18814 -52.67198)
		(width 0.2032)
		(layer "In2.Cu")
		(net "M_DDR3_NODE1_DQS1P")
	)
	(segment
		(start 36.786566 -41.856406)
		(end 37.18814 -42.25798)
		(width 0.2032)
		(layer "In2.Cu")
		(net "M_DDR3_NODE1_DQS1P")
	)
	(segment
		(start 48.47336 -29.41193)
		(end 48.47336 -31.479744)
		(width 0.2032)
		(layer "In2.Cu")
		(net "M_DDR3_NODE1_DQS1P")
	)
	(segment
		(start 36.786566 -41.145206)
		(end 36.51758 -41.145206)
		(width 0.2032)
		(layer "In2.Cu")
		(net "M_DDR3_NODE1_DQS1P")
	)
	(segment
		(start 49.42586 -25.977342)
		(end 48.880522 -26.52268)
		(width 0.2032)
		(layer "In2.Cu")
		(net "M_DDR3_NODE1_DQS1P")
	)
	(segment
		(start 44.68495 -57.234836)
		(end 45.388784 -57.234836)
		(width 0.09906)
		(layer "In2.Cu")
		(net "M_DDR3_NODE1_DQS1P")
	)
	(segment
		(start 45.388784 -57.234836)
		(end 45.869352 -57.715404)
		(width 0.09906)
		(layer "In2.Cu")
		(net "M_DDR3_NODE1_DQS1P")
	)
	(segment
		(start 36.51758 -52.270406)
		(end 36.786566 -52.270406)
		(width 0.2032)
		(layer "In2.Cu")
		(net "M_DDR3_NODE1_DQS1P")
	)
	(segment
		(start 36.51758 -47.393606)
		(end 36.3093 -47.601886)
		(width 0.2032)
		(layer "In2.Cu")
		(net "M_DDR3_NODE1_DQS1P")
	)
	(segment
		(start 36.3093 -47.601886)
		(end 36.3093 -47.896526)
		(width 0.2032)
		(layer "In2.Cu")
		(net "M_DDR3_NODE1_DQS1P")
	)
	(segment
		(start 45.901356 -35.805872)
		(end 40.59301 -35.805872)
		(width 0.2032)
		(layer "In2.Cu")
		(net "M_DDR3_NODE1_DQS1P")
	)
	(segment
		(start 36.786566 -48.104806)
		(end 37.18814 -48.50638)
		(width 0.2032)
		(layer "In2.Cu")
		(net "M_DDR3_NODE1_DQS1P")
	)
	(segment
		(start 49.42586 -24.84628)
		(end 49.42586 -25.977342)
		(width 0.2032)
		(layer "In2.Cu")
		(net "M_DDR3_NODE1_DQS1P")
	)
	(segment
		(start 47.757842 -24.056594)
		(end 47.941484 -24.240236)
		(width 0.2032)
		(layer "In2.Cu")
		(net "M_DDR3_NODE1_DQS1P")
	)
	(segment
		(start 36.3093 -41.353486)
		(end 36.3093 -41.648126)
		(width 0.2032)
		(layer "In2.Cu")
		(net "M_DDR3_NODE1_DQS1P")
	)
	(segment
		(start 46.98746 -57.715404)
		(end 47.43958 -58.167524)
		(width 0.09906)
		(layer "In2.Cu")
		(net "M_DDR3_NODE1_DQS1P")
	)
	(segment
		(start 36.786566 -46.022006)
		(end 37.18814 -46.42358)
		(width 0.2032)
		(layer "In2.Cu")
		(net "M_DDR3_NODE1_DQS1P")
	)
	(segment
		(start 37.18814 -50.58918)
		(end 37.18814 -51.157632)
		(width 0.2032)
		(layer "In2.Cu")
		(net "M_DDR3_NODE1_DQS1P")
	)
	(segment
		(start 48.880522 -26.52268)
		(end 48.880522 -29.004768)
		(width 0.2032)
		(layer "In2.Cu")
		(net "M_DDR3_NODE1_DQS1P")
	)
	(segment
		(start 36.3093 -43.730926)
		(end 36.51758 -43.939206)
		(width 0.2032)
		(layer "In2.Cu")
		(net "M_DDR3_NODE1_DQS1P")
	)
	(segment
		(start 48.880522 -29.004768)
		(end 48.47336 -29.41193)
		(width 0.2032)
		(layer "In2.Cu")
		(net "M_DDR3_NODE1_DQS1P")
	)
	(segment
		(start 36.3093 -43.436286)
		(end 36.3093 -43.730926)
		(width 0.2032)
		(layer "In2.Cu")
		(net "M_DDR3_NODE1_DQS1P")
	)
	(segment
		(start 36.51758 -41.145206)
		(end 36.3093 -41.353486)
		(width 0.2032)
		(layer "In2.Cu")
		(net "M_DDR3_NODE1_DQS1P")
	)
	(segment
		(start 36.786566 -51.559206)
		(end 36.51758 -51.559206)
		(width 0.2032)
		(layer "In2.Cu")
		(net "M_DDR3_NODE1_DQS1P")
	)
	(segment
		(start 36.786566 -43.228006)
		(end 36.51758 -43.228006)
		(width 0.2032)
		(layer "In2.Cu")
		(net "M_DDR3_NODE1_DQS1P")
	)
	(segment
		(start 36.3093 -49.684686)
		(end 36.3093 -49.979326)
		(width 0.2032)
		(layer "In2.Cu")
		(net "M_DDR3_NODE1_DQS1P")
	)
	(segment
		(start 47.757842 -23.813008)
		(end 47.757842 -24.056594)
		(width 0.2032)
		(layer "In2.Cu")
		(net "M_DDR3_NODE1_DQS1P")
	)
	(segment
		(start 40.59301 -35.805872)
		(end 37.18814 -39.210742)
		(width 0.2032)
		(layer "In2.Cu")
		(net "M_DDR3_NODE1_DQS1P")
	)
	(segment
		(start 170.750992 -136.335008)
		(end 169.793412 -136.335008)
		(width 0.1016)
		(layer "F.Cu")
		(net "PWR_BTN_NODE1_L")
	)
	(segment
		(start 170.750992 -138.367008)
		(end 170.750992 -137.351008)
		(width 0.1016)
		(layer "F.Cu")
		(net "PWR_BTN_NODE1_L")
	)
	(segment
		(start 170.750992 -137.351008)
		(end 170.750992 -136.335008)
		(width 0.1016)
		(layer "F.Cu")
		(net "PWR_BTN_NODE1_L")
	)
	(segment
		(start 160.723326 -134.064502)
		(end 167.523414 -134.064502)
		(width 0.1016)
		(layer "F.Cu")
		(net "PWR_BTN_NODE1_L")
	)
	(segment
		(start 168.823894 -135.36549)
		(end 169.4307 -135.972296)
		(width 0.1016)
		(layer "F.Cu")
		(net "PWR_BTN_NODE1_L")
	)
	(segment
		(start 168.569894 -134.064502)
		(end 168.823894 -134.318502)
		(width 0.1016)
		(layer "F.Cu")
		(net "PWR_BTN_NODE1_L")
	)
	(segment
		(start 167.523414 -134.064502)
		(end 168.569894 -134.064502)
		(width 0.1016)
		(layer "F.Cu")
		(net "PWR_BTN_NODE1_L")
	)
	(segment
		(start 169.793412 -136.335008)
		(end 169.4307 -135.972296)
		(width 0.1016)
		(layer "F.Cu")
		(net "PWR_BTN_NODE1_L")
	)
	(segment
		(start 168.823894 -134.318502)
		(end 168.823894 -135.36549)
		(width 0.1016)
		(layer "F.Cu")
		(net "PWR_BTN_NODE1_L")
	)
	(via
		(at 169.4307 -135.972296)
		(size 0.508)
		(drill 0.254)
		(layers "F.Cu" "B.Cu")
		(net "PWR_BTN_NODE1_L")
	)
	(segment
		(start 150.877778 -65.158112)
		(end 150.920196 -65.20053)
		(width 0.1778)
		(layer "F.Cu")
		(net "P1V8_SATA_VAA2_0_NODE1")
	)
	(segment
		(start 149.57171 -65.158112)
		(end 150.877778 -65.158112)
		(width 0.1778)
		(layer "F.Cu")
		(net "P1V8_SATA_VAA2_0_NODE1")
	)
	(via
		(at 150.920196 -65.20053)
		(size 0.508)
		(drill 0.254)
		(layers "F.Cu" "B.Cu")
		(net "P1V8_SATA_VAA2_0_NODE1")
	)
	(via
		(at 156.787596 -65.42913)
		(size 0.6604)
		(drill 0.3302)
		(layers "F.Cu" "B.Cu")
		(net "P1V8_SATA_VAA2_0_NODE1")
	)
	(segment
		(start 47.889922 -63.556642)
		(end 47.889922 -63.129414)
		(width 0.1016)
		(layer "F.Cu")
		(net "M1_DQ_NODE1_DQ8")
	)
	(segment
		(start 45.750226 -20.94992)
		(end 45.750226 -22.659594)
		(width 0.1651)
		(layer "F.Cu")
		(net "M1_DQ_NODE1_DQ8")
	)
	(segment
		(start 45.750226 -22.659594)
		(end 45.144182 -23.265638)
		(width 0.1651)
		(layer "F.Cu")
		(net "M1_DQ_NODE1_DQ8")
	)
	(segment
		(start 47.512732 -62.899544)
		(end 46.811184 -62.197996)
		(width 0.1016)
		(layer "F.Cu")
		(net "M1_DQ_NODE1_DQ8")
	)
	(segment
		(start 47.660052 -62.899544)
		(end 47.512732 -62.899544)
		(width 0.1016)
		(layer "F.Cu")
		(net "M1_DQ_NODE1_DQ8")
	)
	(segment
		(start 46.811184 -62.197996)
		(end 46.811184 -61.238892)
		(width 0.1016)
		(layer "F.Cu")
		(net "M1_DQ_NODE1_DQ8")
	)
	(segment
		(start 45.144182 -23.265638)
		(end 45.144182 -23.359618)
		(width 0.1651)
		(layer "F.Cu")
		(net "M1_DQ_NODE1_DQ8")
	)
	(segment
		(start 47.889922 -63.129414)
		(end 47.660052 -62.899544)
		(width 0.1016)
		(layer "F.Cu")
		(net "M1_DQ_NODE1_DQ8")
	)
	(via
		(at 45.144182 -23.359618)
		(size 0.508)
		(drill 0.254)
		(layers "F.Cu" "B.Cu")
		(net "M1_DQ_NODE1_DQ8")
	)
	(via
		(at 46.811184 -61.238892)
		(size 0.508)
		(drill 0.254)
		(layers "F.Cu" "B.Cu")
		(net "M1_DQ_NODE1_DQ8")
	)
	(segment
		(start 35.106356 -59.794902)
		(end 34.068258 -58.756804)
		(width 0.2032)
		(layer "In2.Cu")
		(net "M1_DQ_NODE1_DQ8")
	)
	(segment
		(start 43.004994 -28.113482)
		(end 43.213274 -28.321762)
		(width 0.2032)
		(layer "In2.Cu")
		(net "M1_DQ_NODE1_DQ8")
	)
	(segment
		(start 32.28594 -56.974486)
		(end 32.28594 -39.190422)
		(width 0.2032)
		(layer "In2.Cu")
		(net "M1_DQ_NODE1_DQ8")
	)
	(segment
		(start 45.08754 -27.52598)
		(end 45.7581 -26.85542)
		(width 0.2032)
		(layer "In2.Cu")
		(net "M1_DQ_NODE1_DQ8")
	)
	(segment
		(start 42.293794 -29.412438)
		(end 42.502074 -29.204158)
		(width 0.2032)
		(layer "In2.Cu")
		(net "M1_DQ_NODE1_DQ8")
	)
	(segment
		(start 38.04031 -59.794902)
		(end 35.106356 -59.794902)
		(width 0.2032)
		(layer "In2.Cu")
		(net "M1_DQ_NODE1_DQ8")
	)
	(segment
		(start 42.502074 -28.321762)
		(end 42.710354 -28.113482)
		(width 0.2032)
		(layer "In2.Cu")
		(net "M1_DQ_NODE1_DQ8")
	)
	(segment
		(start 38.95979 -60.234576)
		(end 38.75151 -60.442856)
		(width 0.2032)
		(layer "In2.Cu")
		(net "M1_DQ_NODE1_DQ8")
	)
	(segment
		(start 43.77563 -60.426854)
		(end 40.18915 -60.426854)
		(width 0.2032)
		(layer "In2.Cu")
		(net "M1_DQ_NODE1_DQ8")
	)
	(segment
		(start 38.4937 -32.982662)
		(end 38.4937 -31.757874)
		(width 0.2032)
		(layer "In2.Cu")
		(net "M1_DQ_NODE1_DQ8")
	)
	(segment
		(start 42.502074 -29.204158)
		(end 42.502074 -28.321762)
		(width 0.2032)
		(layer "In2.Cu")
		(net "M1_DQ_NODE1_DQ8")
	)
	(segment
		(start 43.421554 -29.412438)
		(end 44.666154 -29.412438)
		(width 0.2032)
		(layer "In2.Cu")
		(net "M1_DQ_NODE1_DQ8")
	)
	(segment
		(start 45.144182 -23.51278)
		(end 45.144182 -23.359618)
		(width 0.2032)
		(layer "In2.Cu")
		(net "M1_DQ_NODE1_DQ8")
	)
	(segment
		(start 34.079942 -57.73928)
		(end 33.785302 -57.73928)
		(width 0.2032)
		(layer "In2.Cu")
		(net "M1_DQ_NODE1_DQ8")
	)
	(segment
		(start 38.75151 -60.442856)
		(end 38.45687 -60.442856)
		(width 0.2032)
		(layer "In2.Cu")
		(net "M1_DQ_NODE1_DQ8")
	)
	(segment
		(start 34.288222 -58.2422)
		(end 34.288222 -57.94756)
		(width 0.2032)
		(layer "In2.Cu")
		(net "M1_DQ_NODE1_DQ8")
	)
	(segment
		(start 32.28594 -39.190422)
		(end 38.4937 -32.982662)
		(width 0.2032)
		(layer "In2.Cu")
		(net "M1_DQ_NODE1_DQ8")
	)
	(segment
		(start 45.675042 -24.04364)
		(end 45.144182 -23.51278)
		(width 0.2032)
		(layer "In2.Cu")
		(net "M1_DQ_NODE1_DQ8")
	)
	(segment
		(start 33.270698 -57.959244)
		(end 32.28594 -56.974486)
		(width 0.2032)
		(layer "In2.Cu")
		(net "M1_DQ_NODE1_DQ8")
	)
	(segment
		(start 45.7581 -25.377902)
		(end 45.675042 -25.294844)
		(width 0.2032)
		(layer "In2.Cu")
		(net "M1_DQ_NODE1_DQ8")
	)
	(segment
		(start 38.95979 -60.003182)
		(end 38.95979 -60.234576)
		(width 0.2032)
		(layer "In2.Cu")
		(net "M1_DQ_NODE1_DQ8")
	)
	(segment
		(start 45.08754 -28.991052)
		(end 45.08754 -27.52598)
		(width 0.2032)
		(layer "In2.Cu")
		(net "M1_DQ_NODE1_DQ8")
	)
	(segment
		(start 38.24859 -60.234576)
		(end 38.24859 -60.003182)
		(width 0.2032)
		(layer "In2.Cu")
		(net "M1_DQ_NODE1_DQ8")
	)
	(segment
		(start 45.7581 -26.85542)
		(end 45.7581 -25.377902)
		(width 0.2032)
		(layer "In2.Cu")
		(net "M1_DQ_NODE1_DQ8")
	)
	(segment
		(start 38.4937 -31.757874)
		(end 40.839136 -29.412438)
		(width 0.2032)
		(layer "In2.Cu")
		(net "M1_DQ_NODE1_DQ8")
	)
	(segment
		(start 34.068258 -58.462164)
		(end 34.288222 -58.2422)
		(width 0.2032)
		(layer "In2.Cu")
		(net "M1_DQ_NODE1_DQ8")
	)
	(segment
		(start 39.16807 -59.794902)
		(end 38.95979 -60.003182)
		(width 0.2032)
		(layer "In2.Cu")
		(net "M1_DQ_NODE1_DQ8")
	)
	(segment
		(start 40.18915 -60.426854)
		(end 39.557198 -59.794902)
		(width 0.2032)
		(layer "In2.Cu")
		(net "M1_DQ_NODE1_DQ8")
	)
	(segment
		(start 39.557198 -59.794902)
		(end 39.16807 -59.794902)
		(width 0.2032)
		(layer "In2.Cu")
		(net "M1_DQ_NODE1_DQ8")
	)
	(segment
		(start 38.24859 -60.003182)
		(end 38.04031 -59.794902)
		(width 0.2032)
		(layer "In2.Cu")
		(net "M1_DQ_NODE1_DQ8")
	)
	(segment
		(start 34.068258 -58.756804)
		(end 34.068258 -58.462164)
		(width 0.2032)
		(layer "In2.Cu")
		(net "M1_DQ_NODE1_DQ8")
	)
	(segment
		(start 42.710354 -28.113482)
		(end 43.004994 -28.113482)
		(width 0.2032)
		(layer "In2.Cu")
		(net "M1_DQ_NODE1_DQ8")
	)
	(segment
		(start 38.45687 -60.442856)
		(end 38.24859 -60.234576)
		(width 0.2032)
		(layer "In2.Cu")
		(net "M1_DQ_NODE1_DQ8")
	)
	(segment
		(start 46.811184 -61.238892)
		(end 44.587668 -61.238892)
		(width 0.2032)
		(layer "In2.Cu")
		(net "M1_DQ_NODE1_DQ8")
	)
	(segment
		(start 33.785302 -57.73928)
		(end 33.565338 -57.959244)
		(width 0.2032)
		(layer "In2.Cu")
		(net "M1_DQ_NODE1_DQ8")
	)
	(segment
		(start 45.675042 -25.294844)
		(end 45.675042 -24.04364)
		(width 0.2032)
		(layer "In2.Cu")
		(net "M1_DQ_NODE1_DQ8")
	)
	(segment
		(start 43.213274 -29.204158)
		(end 43.421554 -29.412438)
		(width 0.2032)
		(layer "In2.Cu")
		(net "M1_DQ_NODE1_DQ8")
	)
	(segment
		(start 33.565338 -57.959244)
		(end 33.270698 -57.959244)
		(width 0.2032)
		(layer "In2.Cu")
		(net "M1_DQ_NODE1_DQ8")
	)
	(segment
		(start 44.666154 -29.412438)
		(end 45.08754 -28.991052)
		(width 0.2032)
		(layer "In2.Cu")
		(net "M1_DQ_NODE1_DQ8")
	)
	(segment
		(start 40.839136 -29.412438)
		(end 42.293794 -29.412438)
		(width 0.2032)
		(layer "In2.Cu")
		(net "M1_DQ_NODE1_DQ8")
	)
	(segment
		(start 34.288222 -57.94756)
		(end 34.079942 -57.73928)
		(width 0.2032)
		(layer "In2.Cu")
		(net "M1_DQ_NODE1_DQ8")
	)
	(segment
		(start 43.213274 -28.321762)
		(end 43.213274 -29.204158)
		(width 0.2032)
		(layer "In2.Cu")
		(net "M1_DQ_NODE1_DQ8")
	)
	(segment
		(start 44.587668 -61.238892)
		(end 43.77563 -60.426854)
		(width 0.2032)
		(layer "In2.Cu")
		(net "M1_DQ_NODE1_DQ8")
	)
	(segment
		(start 139.03833 -74.301096)
		(end 136.470644 -74.301096)
		(width 0.1016)
		(layer "F.Cu")
		(net "SATA_SPI_CLK_NODE1")
	)
	(segment
		(start 137.55497 -70.338188)
		(end 137.703814 -70.189344)
		(width 0.1016)
		(layer "F.Cu")
		(net "SATA_SPI_CLK_NODE1")
	)
	(segment
		(start 137.703814 -72.221344)
		(end 137.703814 -72.011032)
		(width 0.1016)
		(layer "F.Cu")
		(net "SATA_SPI_CLK_NODE1")
	)
	(segment
		(start 137.703814 -69.979032)
		(end 137.55497 -69.830188)
		(width 0.1016)
		(layer "F.Cu")
		(net "SATA_SPI_CLK_NODE1")
	)
	(segment
		(start 135.43153 -69.830188)
		(end 133.916928 -68.315586)
		(width 0.1016)
		(layer "F.Cu")
		(net "SATA_SPI_CLK_NODE1")
	)
	(segment
		(start 136.110726 -71.713344)
		(end 136.110726 -71.503032)
		(width 0.1016)
		(layer "F.Cu")
		(net "SATA_SPI_CLK_NODE1")
	)
	(segment
		(start 137.55497 -71.862188)
		(end 136.25957 -71.862188)
		(width 0.1016)
		(layer "F.Cu")
		(net "SATA_SPI_CLK_NODE1")
	)
	(segment
		(start 125.464316 -66.188336)
		(end 129.16281 -66.188336)
		(width 0.1016)
		(layer "F.Cu")
		(net "SATA_SPI_CLK_NODE1")
	)
	(segment
		(start 136.25957 -71.354188)
		(end 137.55497 -71.354188)
		(width 0.1016)
		(layer "F.Cu")
		(net "SATA_SPI_CLK_NODE1")
	)
	(segment
		(start 138.393424 -72.878188)
		(end 136.25957 -72.878188)
		(width 0.1016)
		(layer "F.Cu")
		(net "SATA_SPI_CLK_NODE1")
	)
	(segment
		(start 131.29006 -68.315586)
		(end 133.47192 -68.315586)
		(width 0.1016)
		(layer "F.Cu")
		(net "SATA_SPI_CLK_NODE1")
	)
	(segment
		(start 136.25957 -72.370188)
		(end 137.55497 -72.370188)
		(width 0.1016)
		(layer "F.Cu")
		(net "SATA_SPI_CLK_NODE1")
	)
	(segment
		(start 136.110726 -73.535032)
		(end 136.25957 -73.386188)
		(width 0.1016)
		(layer "F.Cu")
		(net "SATA_SPI_CLK_NODE1")
	)
	(segment
		(start 136.110726 -70.487032)
		(end 136.25957 -70.338188)
		(width 0.1016)
		(layer "F.Cu")
		(net "SATA_SPI_CLK_NODE1")
	)
	(segment
		(start 136.110726 -72.519032)
		(end 136.25957 -72.370188)
		(width 0.1016)
		(layer "F.Cu")
		(net "SATA_SPI_CLK_NODE1")
	)
	(segment
		(start 136.25957 -73.386188)
		(end 138.402568 -73.386188)
		(width 0.1016)
		(layer "F.Cu")
		(net "SATA_SPI_CLK_NODE1")
	)
	(segment
		(start 136.25957 -70.846188)
		(end 136.110726 -70.697344)
		(width 0.1016)
		(layer "F.Cu")
		(net "SATA_SPI_CLK_NODE1")
	)
	(segment
		(start 136.25957 -72.878188)
		(end 136.110726 -72.729344)
		(width 0.1016)
		(layer "F.Cu")
		(net "SATA_SPI_CLK_NODE1")
	)
	(segment
		(start 138.54684 -73.241916)
		(end 138.54684 -73.031604)
		(width 0.1016)
		(layer "F.Cu")
		(net "SATA_SPI_CLK_NODE1")
	)
	(segment
		(start 137.703814 -72.011032)
		(end 137.55497 -71.862188)
		(width 0.1016)
		(layer "F.Cu")
		(net "SATA_SPI_CLK_NODE1")
	)
	(segment
		(start 136.110726 -72.729344)
		(end 136.110726 -72.519032)
		(width 0.1016)
		(layer "F.Cu")
		(net "SATA_SPI_CLK_NODE1")
	)
	(segment
		(start 133.916928 -68.315586)
		(end 133.47192 -68.315586)
		(width 0.1016)
		(layer "F.Cu")
		(net "SATA_SPI_CLK_NODE1")
	)
	(segment
		(start 136.110726 -71.503032)
		(end 136.25957 -71.354188)
		(width 0.1016)
		(layer "F.Cu")
		(net "SATA_SPI_CLK_NODE1")
	)
	(segment
		(start 136.110726 -73.941178)
		(end 136.110726 -73.535032)
		(width 0.1016)
		(layer "F.Cu")
		(net "SATA_SPI_CLK_NODE1")
	)
	(segment
		(start 138.402568 -73.386188)
		(end 138.54684 -73.241916)
		(width 0.1016)
		(layer "F.Cu")
		(net "SATA_SPI_CLK_NODE1")
	)
	(segment
		(start 138.54684 -73.031604)
		(end 138.393424 -72.878188)
		(width 0.1016)
		(layer "F.Cu")
		(net "SATA_SPI_CLK_NODE1")
	)
	(segment
		(start 137.55497 -70.846188)
		(end 136.25957 -70.846188)
		(width 0.1016)
		(layer "F.Cu")
		(net "SATA_SPI_CLK_NODE1")
	)
	(segment
		(start 136.110726 -70.697344)
		(end 136.110726 -70.487032)
		(width 0.1016)
		(layer "F.Cu")
		(net "SATA_SPI_CLK_NODE1")
	)
	(segment
		(start 137.55497 -71.354188)
		(end 137.703814 -71.205344)
		(width 0.1016)
		(layer "F.Cu")
		(net "SATA_SPI_CLK_NODE1")
	)
	(segment
		(start 137.703814 -71.205344)
		(end 137.703814 -70.995032)
		(width 0.1016)
		(layer "F.Cu")
		(net "SATA_SPI_CLK_NODE1")
	)
	(segment
		(start 129.16281 -66.188336)
		(end 131.29006 -68.315586)
		(width 0.1016)
		(layer "F.Cu")
		(net "SATA_SPI_CLK_NODE1")
	)
	(segment
		(start 136.25957 -70.338188)
		(end 137.55497 -70.338188)
		(width 0.1016)
		(layer "F.Cu")
		(net "SATA_SPI_CLK_NODE1")
	)
	(segment
		(start 136.25957 -71.862188)
		(end 136.110726 -71.713344)
		(width 0.1016)
		(layer "F.Cu")
		(net "SATA_SPI_CLK_NODE1")
	)
	(segment
		(start 137.55497 -69.830188)
		(end 135.43153 -69.830188)
		(width 0.1016)
		(layer "F.Cu")
		(net "SATA_SPI_CLK_NODE1")
	)
	(segment
		(start 136.470644 -74.301096)
		(end 136.110726 -73.941178)
		(width 0.1016)
		(layer "F.Cu")
		(net "SATA_SPI_CLK_NODE1")
	)
	(segment
		(start 137.703814 -70.189344)
		(end 137.703814 -69.979032)
		(width 0.1016)
		(layer "F.Cu")
		(net "SATA_SPI_CLK_NODE1")
	)
	(segment
		(start 137.703814 -70.995032)
		(end 137.55497 -70.846188)
		(width 0.1016)
		(layer "F.Cu")
		(net "SATA_SPI_CLK_NODE1")
	)
	(segment
		(start 137.55497 -72.370188)
		(end 137.703814 -72.221344)
		(width 0.1016)
		(layer "F.Cu")
		(net "SATA_SPI_CLK_NODE1")
	)
	(via
		(at 133.47192 -68.315586)
		(size 0.508)
		(drill 0.254)
		(layers "F.Cu" "B.Cu")
		(net "SATA_SPI_CLK_NODE1")
	)
	(segment
		(start 16.77797 -57.294272)
		(end 16.77797 -56.881776)
		(width 0.1016)
		(layer "F.Cu")
		(net "BMC_NODE1_GFX_BLUE")
	)
	(segment
		(start 19.19224 -55.502302)
		(end 19.19224 -57.19445)
		(width 0.1016)
		(layer "F.Cu")
		(net "BMC_NODE1_GFX_BLUE")
	)
	(segment
		(start 19.19224 -57.19445)
		(end 18.750788 -57.635902)
		(width 0.1016)
		(layer "F.Cu")
		(net "BMC_NODE1_GFX_BLUE")
	)
	(segment
		(start 62.939422 -140.85951)
		(end 62.540896 -141.258036)
		(width 0.1016)
		(layer "F.Cu")
		(net "BMC_NODE1_GFX_BLUE")
	)
	(segment
		(start 16.825468 -56.269382)
		(end 16.825468 -55.509922)
		(width 0.1016)
		(layer "F.Cu")
		(net "BMC_NODE1_GFX_BLUE")
	)
	(segment
		(start 18.750788 -57.635902)
		(end 17.1196 -57.635902)
		(width 0.1016)
		(layer "F.Cu")
		(net "BMC_NODE1_GFX_BLUE")
	)
	(segment
		(start 17.1196 -57.635902)
		(end 16.77797 -57.294272)
		(width 0.1016)
		(layer "F.Cu")
		(net "BMC_NODE1_GFX_BLUE")
	)
	(segment
		(start 16.77797 -56.881776)
		(end 16.77797 -56.31688)
		(width 0.1016)
		(layer "F.Cu")
		(net "BMC_NODE1_GFX_BLUE")
	)
	(segment
		(start 62.941708 -140.85951)
		(end 62.939422 -140.85951)
		(width 0.1016)
		(layer "F.Cu")
		(net "BMC_NODE1_GFX_BLUE")
	)
	(segment
		(start 16.77797 -56.31688)
		(end 16.825468 -56.269382)
		(width 0.1016)
		(layer "F.Cu")
		(net "BMC_NODE1_GFX_BLUE")
	)
	(via
		(at 19.19224 -55.502302)
		(size 0.508)
		(drill 0.254)
		(layers "F.Cu" "B.Cu")
		(net "BMC_NODE1_GFX_BLUE")
	)
	(via
		(at 62.540896 -141.258036)
		(size 0.49022)
		(drill 0.254)
		(layers "F.Cu" "B.Cu")
		(net "BMC_NODE1_GFX_BLUE")
	)
	(via
		(at 58.950352 -144.907762)
		(size 0.6604)
		(drill 0.3302)
		(layers "F.Cu" "B.Cu")
		(net "BMC_NODE1_GFX_BLUE")
	)
	(segment
		(start 59.399932 -144.907762)
		(end 58.950352 -144.907762)
		(width 0.1016)
		(layer "B.Cu")
		(net "BMC_NODE1_GFX_BLUE")
	)
	(segment
		(start 61.673994 -142.6337)
		(end 59.399932 -144.907762)
		(width 0.1016)
		(layer "B.Cu")
		(net "BMC_NODE1_GFX_BLUE")
	)
	(segment
		(start 58.879486 -146.019012)
		(end 58.879486 -144.978628)
		(width 0.1016)
		(layer "B.Cu")
		(net "BMC_NODE1_GFX_BLUE")
	)
	(segment
		(start 61.727842 -142.6337)
		(end 61.673994 -142.6337)
		(width 0.1016)
		(layer "B.Cu")
		(net "BMC_NODE1_GFX_BLUE")
	)
	(segment
		(start 62.140084 -141.658848)
		(end 62.140084 -142.221458)
		(width 0.1016)
		(layer "B.Cu")
		(net "BMC_NODE1_GFX_BLUE")
	)
	(segment
		(start 62.140084 -142.221458)
		(end 61.727842 -142.6337)
		(width 0.1016)
		(layer "B.Cu")
		(net "BMC_NODE1_GFX_BLUE")
	)
	(segment
		(start 58.879486 -144.978628)
		(end 58.950352 -144.907762)
		(width 0.1016)
		(layer "B.Cu")
		(net "BMC_NODE1_GFX_BLUE")
	)
	(segment
		(start 62.540896 -141.258036)
		(end 62.140084 -141.658848)
		(width 0.1016)
		(layer "B.Cu")
		(net "BMC_NODE1_GFX_BLUE")
	)
	(segment
		(start 19.14906 -82.47253)
		(end 18.92046 -82.70113)
		(width 0.1143)
		(layer "In6.Cu")
		(net "BMC_NODE1_GFX_BLUE")
	)
	(segment
		(start 43.56354 -145.786348)
		(end 40.86606 -145.786348)
		(width 0.1143)
		(layer "In6.Cu")
		(net "BMC_NODE1_GFX_BLUE")
	)
	(segment
		(start 19.71802 -84.473288)
		(end 19.89836 -84.292948)
		(width 0.1143)
		(layer "In6.Cu")
		(net "BMC_NODE1_GFX_BLUE")
	)
	(segment
		(start 18.92046 -82.70113)
		(end 18.62836 -82.70113)
		(width 0.1143)
		(layer "In6.Cu")
		(net "BMC_NODE1_GFX_BLUE")
	)
	(segment
		(start 20.528788 -52.122324)
		(end 20.325588 -51.919124)
		(width 0.1143)
		(layer "In6.Cu")
		(net "BMC_NODE1_GFX_BLUE")
	)
	(segment
		(start 61.217302 -142.010638)
		(end 61.217302 -142.9766)
		(width 0.1143)
		(layer "In6.Cu")
		(net "BMC_NODE1_GFX_BLUE")
	)
	(segment
		(start 49.256188 -146.803872)
		(end 45.181774 -146.803872)
		(width 0.1143)
		(layer "In6.Cu")
		(net "BMC_NODE1_GFX_BLUE")
	)
	(segment
		(start 19.89836 -84.292948)
		(end 19.89836 -81.018888)
		(width 0.1143)
		(layer "In6.Cu")
		(net "BMC_NODE1_GFX_BLUE")
	)
	(segment
		(start 61.217302 -142.9766)
		(end 59.18327 -145.010632)
		(width 0.1143)
		(layer "In6.Cu")
		(net "BMC_NODE1_GFX_BLUE")
	)
	(segment
		(start 19.19224 -54.496208)
		(end 19.19224 -55.502302)
		(width 0.1143)
		(layer "In6.Cu")
		(net "BMC_NODE1_GFX_BLUE")
	)
	(segment
		(start 55.776622 -145.010632)
		(end 54.784498 -146.002756)
		(width 0.1143)
		(layer "In6.Cu")
		(net "BMC_NODE1_GFX_BLUE")
	)
	(segment
		(start 19.368516 -80.799432)
		(end 19.14906 -81.018888)
		(width 0.1143)
		(layer "In6.Cu")
		(net "BMC_NODE1_GFX_BLUE")
	)
	(segment
		(start 23.18258 -75.919076)
		(end 23.18258 -58.537602)
		(width 0.1143)
		(layer "In6.Cu")
		(net "BMC_NODE1_GFX_BLUE")
	)
	(segment
		(start 50.057304 -146.002756)
		(end 49.256188 -146.803872)
		(width 0.1143)
		(layer "In6.Cu")
		(net "BMC_NODE1_GFX_BLUE")
	)
	(segment
		(start 19.71802 -87.002874)
		(end 19.71802 -84.473288)
		(width 0.1143)
		(layer "In6.Cu")
		(net "BMC_NODE1_GFX_BLUE")
	)
	(segment
		(start 62.345316 -141.453616)
		(end 61.774324 -141.453616)
		(width 0.1143)
		(layer "In6.Cu")
		(net "BMC_NODE1_GFX_BLUE")
	)
	(segment
		(start 20.528788 -55.88381)
		(end 20.528788 -52.122324)
		(width 0.1143)
		(layer "In6.Cu")
		(net "BMC_NODE1_GFX_BLUE")
	)
	(segment
		(start 19.4564 -52.122324)
		(end 19.4564 -54.232048)
		(width 0.1143)
		(layer "In6.Cu")
		(net "BMC_NODE1_GFX_BLUE")
	)
	(segment
		(start 44.21378 -146.436588)
		(end 43.56354 -145.786348)
		(width 0.1143)
		(layer "In6.Cu")
		(net "BMC_NODE1_GFX_BLUE")
	)
	(segment
		(start 32.580834 -139.311126)
		(end 19.273774 -139.311126)
		(width 0.1143)
		(layer "In6.Cu")
		(net "BMC_NODE1_GFX_BLUE")
	)
	(segment
		(start 16.788384 -136.825736)
		(end 13.405612 -136.825736)
		(width 0.1143)
		(layer "In6.Cu")
		(net "BMC_NODE1_GFX_BLUE")
	)
	(segment
		(start 19.273774 -139.311126)
		(end 16.788384 -136.825736)
		(width 0.1143)
		(layer "In6.Cu")
		(net "BMC_NODE1_GFX_BLUE")
	)
	(segment
		(start 18.39976 -82.47253)
		(end 18.39976 -80.701896)
		(width 0.1143)
		(layer "In6.Cu")
		(net "BMC_NODE1_GFX_BLUE")
	)
	(segment
		(start 19.89836 -81.018888)
		(end 19.678904 -80.799432)
		(width 0.1143)
		(layer "In6.Cu")
		(net "BMC_NODE1_GFX_BLUE")
	)
	(segment
		(start 40.006524 -144.925288)
		(end 38.196012 -144.925288)
		(width 0.1143)
		(layer "In6.Cu")
		(net "BMC_NODE1_GFX_BLUE")
	)
	(segment
		(start 59.18327 -145.010632)
		(end 55.776622 -145.010632)
		(width 0.1143)
		(layer "In6.Cu")
		(net "BMC_NODE1_GFX_BLUE")
	)
	(segment
		(start 44.81449 -146.436588)
		(end 44.21378 -146.436588)
		(width 0.1143)
		(layer "In6.Cu")
		(net "BMC_NODE1_GFX_BLUE")
	)
	(segment
		(start 9.07288 -97.648014)
		(end 19.71802 -87.002874)
		(width 0.1143)
		(layer "In6.Cu")
		(net "BMC_NODE1_GFX_BLUE")
	)
	(segment
		(start 19.6596 -51.919124)
		(end 19.4564 -52.122324)
		(width 0.1143)
		(layer "In6.Cu")
		(net "BMC_NODE1_GFX_BLUE")
	)
	(segment
		(start 38.196012 -144.925288)
		(end 32.580834 -139.311126)
		(width 0.1143)
		(layer "In6.Cu")
		(net "BMC_NODE1_GFX_BLUE")
	)
	(segment
		(start 45.181774 -146.803872)
		(end 44.81449 -146.436588)
		(width 0.1143)
		(layer "In6.Cu")
		(net "BMC_NODE1_GFX_BLUE")
	)
	(segment
		(start 19.678904 -80.799432)
		(end 19.368516 -80.799432)
		(width 0.1143)
		(layer "In6.Cu")
		(net "BMC_NODE1_GFX_BLUE")
	)
	(segment
		(start 18.62836 -82.70113)
		(end 18.39976 -82.47253)
		(width 0.1143)
		(layer "In6.Cu")
		(net "BMC_NODE1_GFX_BLUE")
	)
	(segment
		(start 9.07288 -132.493004)
		(end 9.07288 -97.648014)
		(width 0.1143)
		(layer "In6.Cu")
		(net "BMC_NODE1_GFX_BLUE")
	)
	(segment
		(start 19.14906 -81.018888)
		(end 19.14906 -82.47253)
		(width 0.1143)
		(layer "In6.Cu")
		(net "BMC_NODE1_GFX_BLUE")
	)
	(segment
		(start 40.86606 -145.786348)
		(end 40.006524 -144.925288)
		(width 0.1143)
		(layer "In6.Cu")
		(net "BMC_NODE1_GFX_BLUE")
	)
	(segment
		(start 13.405612 -136.825736)
		(end 9.07288 -132.493004)
		(width 0.1143)
		(layer "In6.Cu")
		(net "BMC_NODE1_GFX_BLUE")
	)
	(segment
		(start 23.18258 -58.537602)
		(end 20.528788 -55.88381)
		(width 0.1143)
		(layer "In6.Cu")
		(net "BMC_NODE1_GFX_BLUE")
	)
	(segment
		(start 62.540896 -141.258036)
		(end 62.345316 -141.453616)
		(width 0.1143)
		(layer "In6.Cu")
		(net "BMC_NODE1_GFX_BLUE")
	)
	(segment
		(start 20.325588 -51.919124)
		(end 19.6596 -51.919124)
		(width 0.1143)
		(layer "In6.Cu")
		(net "BMC_NODE1_GFX_BLUE")
	)
	(segment
		(start 54.784498 -146.002756)
		(end 50.057304 -146.002756)
		(width 0.1143)
		(layer "In6.Cu")
		(net "BMC_NODE1_GFX_BLUE")
	)
	(segment
		(start 18.39976 -80.701896)
		(end 23.18258 -75.919076)
		(width 0.1143)
		(layer "In6.Cu")
		(net "BMC_NODE1_GFX_BLUE")
	)
	(segment
		(start 19.4564 -54.232048)
		(end 19.19224 -54.496208)
		(width 0.1143)
		(layer "In6.Cu")
		(net "BMC_NODE1_GFX_BLUE")
	)
	(segment
		(start 61.774324 -141.453616)
		(end 61.217302 -142.010638)
		(width 0.1143)
		(layer "In6.Cu")
		(net "BMC_NODE1_GFX_BLUE")
	)
	(segment
		(start 125.050804 -140.575538)
		(end 125.003306 -140.623036)
		(width 0.127)
		(layer "F.Cu")
		(net "P2E_CPU_BMC_NODE1_RX_DN")
	)
	(segment
		(start 123.987052 -139.35075)
		(end 123.606052 -138.96975)
		(width 0.127)
		(layer "F.Cu")
		(net "P2E_CPU_BMC_NODE1_RX_DN")
	)
	(segment
		(start 76.893674 -120.575578)
		(end 77.122274 -120.804178)
		(width 0.127)
		(layer "F.Cu")
		(net "P2E_CPU_BMC_NODE1_RX_DN")
	)
	(segment
		(start 125.003306 -140.623036)
		(end 124.751338 -140.623036)
		(width 0.127)
		(layer "F.Cu")
		(net "P2E_CPU_BMC_NODE1_RX_DN")
	)
	(segment
		(start 75.574906 -120.964706)
		(end 75.964034 -120.575578)
		(width 0.127)
		(layer "F.Cu")
		(net "P2E_CPU_BMC_NODE1_RX_DN")
	)
	(segment
		(start 125.787912 -140.575538)
		(end 125.050804 -140.575538)
		(width 0.127)
		(layer "F.Cu")
		(net "P2E_CPU_BMC_NODE1_RX_DN")
	)
	(segment
		(start 123.987052 -139.85875)
		(end 123.987052 -139.35075)
		(width 0.127)
		(layer "F.Cu")
		(net "P2E_CPU_BMC_NODE1_RX_DN")
	)
	(segment
		(start 75.964034 -120.575578)
		(end 76.893674 -120.575578)
		(width 0.127)
		(layer "F.Cu")
		(net "P2E_CPU_BMC_NODE1_RX_DN")
	)
	(segment
		(start 124.751338 -140.623036)
		(end 123.987052 -139.85875)
		(width 0.127)
		(layer "F.Cu")
		(net "P2E_CPU_BMC_NODE1_RX_DN")
	)
	(segment
		(start 123.606052 -138.96975)
		(end 123.211336 -138.96975)
		(width 0.127)
		(layer "F.Cu")
		(net "P2E_CPU_BMC_NODE1_RX_DN")
	)
	(segment
		(start 123.211336 -138.96975)
		(end 122.735086 -138.4935)
		(width 0.127)
		(layer "F.Cu")
		(net "P2E_CPU_BMC_NODE1_RX_DN")
	)
	(via
		(at 77.122274 -120.804178)
		(size 0.508)
		(drill 0.254)
		(layers "F.Cu" "B.Cu")
		(net "P2E_CPU_BMC_NODE1_RX_DN")
	)
	(via
		(at 122.735086 -138.4935)
		(size 0.508)
		(drill 0.254)
		(layers "F.Cu" "B.Cu")
		(net "P2E_CPU_BMC_NODE1_RX_DN")
	)
	(segment
		(start 101.83876 -142.030196)
		(end 99.8855 -141.664944)
		(width 0.127)
		(layer "In7.Cu")
		(net "P2E_CPU_BMC_NODE1_RX_DN")
	)
	(segment
		(start 93.265498 -140.780516)
		(end 92.50172 -139.881102)
		(width 0.127)
		(layer "In7.Cu")
		(net "P2E_CPU_BMC_NODE1_RX_DN")
	)
	(segment
		(start 110.927388 -143.930624)
		(end 110.547912 -143.969232)
		(width 0.127)
		(layer "In7.Cu")
		(net "P2E_CPU_BMC_NODE1_RX_DN")
	)
	(segment
		(start 109.577886 -144.180052)
		(end 109.176312 -144.144746)
		(width 0.127)
		(layer "In7.Cu")
		(net "P2E_CPU_BMC_NODE1_RX_DN")
	)
	(segment
		(start 105.54843 -143.686276)
		(end 105.396792 -143.814292)
		(width 0.127)
		(layer "In7.Cu")
		(net "P2E_CPU_BMC_NODE1_RX_DN")
	)
	(segment
		(start 104.356916 -143.723614)
		(end 103.220012 -143.624554)
		(width 0.127)
		(layer "In7.Cu")
		(net "P2E_CPU_BMC_NODE1_RX_DN")
	)
	(segment
		(start 114.072416 -143.749014)
		(end 113.124234 -143.843756)
		(width 0.127)
		(layer "In7.Cu")
		(net "P2E_CPU_BMC_NODE1_RX_DN")
	)
	(segment
		(start 111.952532 -143.826992)
		(end 111.573056 -143.8656)
		(width 0.127)
		(layer "In7.Cu")
		(net "P2E_CPU_BMC_NODE1_RX_DN")
	)
	(segment
		(start 77.390244 -121.82729)
		(end 77.286612 -121.799858)
		(width 0.127)
		(layer "In7.Cu")
		(net "P2E_CPU_BMC_NODE1_RX_DN")
	)
	(segment
		(start 108.51642 -144.087088)
		(end 108.136436 -144.053814)
		(width 0.127)
		(layer "In7.Cu")
		(net "P2E_CPU_BMC_NODE1_RX_DN")
	)
	(segment
		(start 88.111838 -132.568188)
		(end 85.154516 -129.41935)
		(width 0.127)
		(layer "In7.Cu")
		(net "P2E_CPU_BMC_NODE1_RX_DN")
	)
	(segment
		(start 109.048296 -143.992346)
		(end 108.668058 -143.959072)
		(width 0.127)
		(layer "In7.Cu")
		(net "P2E_CPU_BMC_NODE1_RX_DN")
	)
	(segment
		(start 106.056684 -143.87195)
		(end 105.928668 -143.71955)
		(width 0.127)
		(layer "In7.Cu")
		(net "P2E_CPU_BMC_NODE1_RX_DN")
	)
	(segment
		(start 76.197968 -120.569228)
		(end 76.887324 -120.569228)
		(width 0.127)
		(layer "In7.Cu")
		(net "P2E_CPU_BMC_NODE1_RX_DN")
	)
	(segment
		(start 110.428024 -144.116044)
		(end 109.794802 -144.180052)
		(width 0.127)
		(layer "In7.Cu")
		(net "P2E_CPU_BMC_NODE1_RX_DN")
	)
	(segment
		(start 76.887324 -120.569228)
		(end 77.122274 -120.804178)
		(width 0.127)
		(layer "In7.Cu")
		(net "P2E_CPU_BMC_NODE1_RX_DN")
	)
	(segment
		(start 111.573056 -143.8656)
		(end 111.453168 -144.012412)
		(width 0.127)
		(layer "In7.Cu")
		(net "P2E_CPU_BMC_NODE1_RX_DN")
	)
	(segment
		(start 92.50172 -139.881102)
		(end 92.180156 -139.111482)
		(width 0.127)
		(layer "In7.Cu")
		(net "P2E_CPU_BMC_NODE1_RX_DN")
	)
	(segment
		(start 76.859892 -121.7676)
		(end 76.155296 -121.339356)
		(width 0.127)
		(layer "In7.Cu")
		(net "P2E_CPU_BMC_NODE1_RX_DN")
	)
	(segment
		(start 92.180156 -139.111482)
		(end 90.620088 -137.063226)
		(width 0.127)
		(layer "In7.Cu")
		(net "P2E_CPU_BMC_NODE1_RX_DN")
	)
	(segment
		(start 77.286612 -121.799858)
		(end 76.859892 -121.7676)
		(width 0.127)
		(layer "In7.Cu")
		(net "P2E_CPU_BMC_NODE1_RX_DN")
	)
	(segment
		(start 96.16059 -141.552422)
		(end 93.265498 -140.780516)
		(width 0.127)
		(layer "In7.Cu")
		(net "P2E_CPU_BMC_NODE1_RX_DN")
	)
	(segment
		(start 112.098836 -143.947388)
		(end 111.952532 -143.826992)
		(width 0.127)
		(layer "In7.Cu")
		(net "P2E_CPU_BMC_NODE1_RX_DN")
	)
	(segment
		(start 112.5982 -143.761968)
		(end 112.478312 -143.90878)
		(width 0.127)
		(layer "In7.Cu")
		(net "P2E_CPU_BMC_NODE1_RX_DN")
	)
	(segment
		(start 76.049632 -120.715786)
		(end 76.197968 -120.569228)
		(width 0.127)
		(layer "In7.Cu")
		(net "P2E_CPU_BMC_NODE1_RX_DN")
	)
	(segment
		(start 122.735086 -138.4935)
		(end 122.246136 -138.98245)
		(width 0.127)
		(layer "In7.Cu")
		(net "P2E_CPU_BMC_NODE1_RX_DN")
	)
	(segment
		(start 122.246136 -138.98245)
		(end 120.139968 -138.98245)
		(width 0.127)
		(layer "In7.Cu")
		(net "P2E_CPU_BMC_NODE1_RX_DN")
	)
	(segment
		(start 110.547912 -143.969232)
		(end 110.428024 -144.116044)
		(width 0.127)
		(layer "In7.Cu")
		(net "P2E_CPU_BMC_NODE1_RX_DN")
	)
	(segment
		(start 109.794802 -144.180052)
		(end 109.577886 -144.180052)
		(width 0.127)
		(layer "In7.Cu")
		(net "P2E_CPU_BMC_NODE1_RX_DN")
	)
	(segment
		(start 99.8855 -141.664944)
		(end 96.16059 -141.552422)
		(width 0.127)
		(layer "In7.Cu")
		(net "P2E_CPU_BMC_NODE1_RX_DN")
	)
	(segment
		(start 105.396792 -143.814292)
		(end 105.016808 -143.781018)
		(width 0.127)
		(layer "In7.Cu")
		(net "P2E_CPU_BMC_NODE1_RX_DN")
	)
	(segment
		(start 82.74304 -127.145796)
		(end 79.404718 -122.785632)
		(width 0.127)
		(layer "In7.Cu")
		(net "P2E_CPU_BMC_NODE1_RX_DN")
	)
	(segment
		(start 107.628182 -143.86814)
		(end 107.476544 -143.996156)
		(width 0.127)
		(layer "In7.Cu")
		(net "P2E_CPU_BMC_NODE1_RX_DN")
	)
	(segment
		(start 104.508554 -143.595344)
		(end 104.356916 -143.723614)
		(width 0.127)
		(layer "In7.Cu")
		(net "P2E_CPU_BMC_NODE1_RX_DN")
	)
	(segment
		(start 107.09656 -143.962882)
		(end 106.968544 -143.810482)
		(width 0.127)
		(layer "In7.Cu")
		(net "P2E_CPU_BMC_NODE1_RX_DN")
	)
	(segment
		(start 76.012294 -120.980708)
		(end 76.049632 -120.715786)
		(width 0.127)
		(layer "In7.Cu")
		(net "P2E_CPU_BMC_NODE1_RX_DN")
	)
	(segment
		(start 83.65617 -128.54813)
		(end 82.74304 -127.145796)
		(width 0.127)
		(layer "In7.Cu")
		(net "P2E_CPU_BMC_NODE1_RX_DN")
	)
	(segment
		(start 108.668058 -143.959072)
		(end 108.51642 -144.087088)
		(width 0.127)
		(layer "In7.Cu")
		(net "P2E_CPU_BMC_NODE1_RX_DN")
	)
	(segment
		(start 107.476544 -143.996156)
		(end 107.09656 -143.962882)
		(width 0.127)
		(layer "In7.Cu")
		(net "P2E_CPU_BMC_NODE1_RX_DN")
	)
	(segment
		(start 109.176312 -144.144746)
		(end 109.048296 -143.992346)
		(width 0.127)
		(layer "In7.Cu")
		(net "P2E_CPU_BMC_NODE1_RX_DN")
	)
	(segment
		(start 103.220012 -143.624554)
		(end 101.83876 -142.030196)
		(width 0.127)
		(layer "In7.Cu")
		(net "P2E_CPU_BMC_NODE1_RX_DN")
	)
	(segment
		(start 114.625628 -143.365982)
		(end 114.072416 -143.749014)
		(width 0.127)
		(layer "In7.Cu")
		(net "P2E_CPU_BMC_NODE1_RX_DN")
	)
	(segment
		(start 85.154516 -129.41935)
		(end 83.65617 -128.54813)
		(width 0.127)
		(layer "In7.Cu")
		(net "P2E_CPU_BMC_NODE1_RX_DN")
	)
	(segment
		(start 111.073692 -144.05102)
		(end 110.927388 -143.930624)
		(width 0.127)
		(layer "In7.Cu")
		(net "P2E_CPU_BMC_NODE1_RX_DN")
	)
	(segment
		(start 108.136436 -144.053814)
		(end 108.00842 -143.901414)
		(width 0.127)
		(layer "In7.Cu")
		(net "P2E_CPU_BMC_NODE1_RX_DN")
	)
	(segment
		(start 106.588306 -143.777208)
		(end 106.436668 -143.905224)
		(width 0.127)
		(layer "In7.Cu")
		(net "P2E_CPU_BMC_NODE1_RX_DN")
	)
	(segment
		(start 90.227912 -135.77951)
		(end 90.167206 -134.941818)
		(width 0.127)
		(layer "In7.Cu")
		(net "P2E_CPU_BMC_NODE1_RX_DN")
	)
	(segment
		(start 112.977676 -143.72336)
		(end 112.5982 -143.761968)
		(width 0.127)
		(layer "In7.Cu")
		(net "P2E_CPU_BMC_NODE1_RX_DN")
	)
	(segment
		(start 105.016808 -143.781018)
		(end 104.888792 -143.628618)
		(width 0.127)
		(layer "In7.Cu")
		(net "P2E_CPU_BMC_NODE1_RX_DN")
	)
	(segment
		(start 79.404718 -122.785632)
		(end 77.390244 -121.82729)
		(width 0.127)
		(layer "In7.Cu")
		(net "P2E_CPU_BMC_NODE1_RX_DN")
	)
	(segment
		(start 104.888792 -143.628618)
		(end 104.508554 -143.595344)
		(width 0.127)
		(layer "In7.Cu")
		(net "P2E_CPU_BMC_NODE1_RX_DN")
	)
	(segment
		(start 108.00842 -143.901414)
		(end 107.628182 -143.86814)
		(width 0.127)
		(layer "In7.Cu")
		(net "P2E_CPU_BMC_NODE1_RX_DN")
	)
	(segment
		(start 76.155296 -121.339356)
		(end 76.012294 -120.980708)
		(width 0.127)
		(layer "In7.Cu")
		(net "P2E_CPU_BMC_NODE1_RX_DN")
	)
	(segment
		(start 113.124234 -143.843756)
		(end 112.977676 -143.72336)
		(width 0.127)
		(layer "In7.Cu")
		(net "P2E_CPU_BMC_NODE1_RX_DN")
	)
	(segment
		(start 112.478312 -143.90878)
		(end 112.098836 -143.947388)
		(width 0.127)
		(layer "In7.Cu")
		(net "P2E_CPU_BMC_NODE1_RX_DN")
	)
	(segment
		(start 111.453168 -144.012412)
		(end 111.073692 -144.05102)
		(width 0.127)
		(layer "In7.Cu")
		(net "P2E_CPU_BMC_NODE1_RX_DN")
	)
	(segment
		(start 120.139968 -138.98245)
		(end 114.625628 -143.365982)
		(width 0.127)
		(layer "In7.Cu")
		(net "P2E_CPU_BMC_NODE1_RX_DN")
	)
	(segment
		(start 89.75725 -134.214108)
		(end 88.111838 -132.568188)
		(width 0.127)
		(layer "In7.Cu")
		(net "P2E_CPU_BMC_NODE1_RX_DN")
	)
	(segment
		(start 106.436668 -143.905224)
		(end 106.056684 -143.87195)
		(width 0.127)
		(layer "In7.Cu")
		(net "P2E_CPU_BMC_NODE1_RX_DN")
	)
	(segment
		(start 105.928668 -143.71955)
		(end 105.54843 -143.686276)
		(width 0.127)
		(layer "In7.Cu")
		(net "P2E_CPU_BMC_NODE1_RX_DN")
	)
	(segment
		(start 90.167206 -134.941818)
		(end 89.75725 -134.214108)
		(width 0.127)
		(layer "In7.Cu")
		(net "P2E_CPU_BMC_NODE1_RX_DN")
	)
	(segment
		(start 90.620088 -137.063226)
		(end 90.227912 -135.77951)
		(width 0.127)
		(layer "In7.Cu")
		(net "P2E_CPU_BMC_NODE1_RX_DN")
	)
	(segment
		(start 106.968544 -143.810482)
		(end 106.588306 -143.777208)
		(width 0.127)
		(layer "In7.Cu")
		(net "P2E_CPU_BMC_NODE1_RX_DN")
	)
	(segment
		(start 99.116134 -17.689322)
		(end 99.116134 -19.212814)
		(width 0.1016)
		(layer "F.Cu")
		(net "PD_NODE1_DM7")
	)
	(segment
		(start 99.116134 -19.212814)
		(end 99.15017 -19.24685)
		(width 0.1016)
		(layer "F.Cu")
		(net "PD_NODE1_DM7")
	)
	(segment
		(start 99.15017 -20.94992)
		(end 99.15017 -19.24685)
		(width 0.1016)
		(layer "F.Cu")
		(net "PD_NODE1_DM7")
	)
	(via
		(at 99.15017 -19.24685)
		(size 0.508)
		(drill 0.254)
		(layers "F.Cu" "B.Cu")
		(net "PD_NODE1_DM7")
	)
	(segment
		(start 56.684164 -86.813136)
		(end 56.51119 -86.813136)
		(width 0.1143)
		(layer "F.Cu")
		(net "PU_CPU_NODE1_DFX_GPIO_GRP1_5")
	)
	(segment
		(start 56.51119 -86.813136)
		(end 56.20512 -86.507066)
		(width 0.1143)
		(layer "F.Cu")
		(net "PU_CPU_NODE1_DFX_GPIO_GRP1_5")
	)
	(via
		(at 56.20512 -88.96477)
		(size 0.6604)
		(drill 0.3302)
		(layers "F.Cu" "B.Cu")
		(net "PU_CPU_NODE1_DFX_GPIO_GRP1_5")
	)
	(via
		(at 56.20512 -86.507066)
		(size 0.508)
		(drill 0.254)
		(layers "F.Cu" "B.Cu")
		(net "PU_CPU_NODE1_DFX_GPIO_GRP1_5")
	)
	(segment
		(start 56.20512 -89.106756)
		(end 56.20512 -88.96477)
		(width 0.1016)
		(layer "B.Cu")
		(net "PU_CPU_NODE1_DFX_GPIO_GRP1_5")
	)
	(segment
		(start 55.737252 -91.46921)
		(end 55.737252 -89.574624)
		(width 0.1016)
		(layer "B.Cu")
		(net "PU_CPU_NODE1_DFX_GPIO_GRP1_5")
	)
	(segment
		(start 53.006498 -94.199964)
		(end 55.737252 -91.46921)
		(width 0.1016)
		(layer "B.Cu")
		(net "PU_CPU_NODE1_DFX_GPIO_GRP1_5")
	)
	(segment
		(start 56.20512 -88.96477)
		(end 56.20512 -86.507066)
		(width 0.1016)
		(layer "B.Cu")
		(net "PU_CPU_NODE1_DFX_GPIO_GRP1_5")
	)
	(segment
		(start 53.006498 -96.296734)
		(end 53.006498 -94.199964)
		(width 0.1016)
		(layer "B.Cu")
		(net "PU_CPU_NODE1_DFX_GPIO_GRP1_5")
	)
	(segment
		(start 55.737252 -89.574624)
		(end 56.20512 -89.106756)
		(width 0.1016)
		(layer "B.Cu")
		(net "PU_CPU_NODE1_DFX_GPIO_GRP1_5")
	)
	(segment
		(start 140.502132 -116.446046)
		(end 139.91971 -115.863624)
		(width 0.1016)
		(layer "F.Cu")
		(net "CLKREQB_NODE1_N")
	)
	(segment
		(start 137.346436 -116.514626)
		(end 137.65022 -116.210842)
		(width 0.1016)
		(layer "F.Cu")
		(net "CLKREQB_NODE1_N")
	)
	(segment
		(start 137.65022 -116.210842)
		(end 138.693652 -116.210842)
		(width 0.1016)
		(layer "F.Cu")
		(net "CLKREQB_NODE1_N")
	)
	(segment
		(start 136.503664 -116.514626)
		(end 137.346436 -116.514626)
		(width 0.1016)
		(layer "F.Cu")
		(net "CLKREQB_NODE1_N")
	)
	(segment
		(start 141.750288 -116.446046)
		(end 140.502132 -116.446046)
		(width 0.1016)
		(layer "F.Cu")
		(net "CLKREQB_NODE1_N")
	)
	(segment
		(start 139.26947 -115.863624)
		(end 138.922252 -116.210842)
		(width 0.1016)
		(layer "F.Cu")
		(net "CLKREQB_NODE1_N")
	)
	(segment
		(start 139.91971 -115.863624)
		(end 139.26947 -115.863624)
		(width 0.1016)
		(layer "F.Cu")
		(net "CLKREQB_NODE1_N")
	)
	(segment
		(start 138.922252 -116.210842)
		(end 138.693652 -116.210842)
		(width 0.1016)
		(layer "F.Cu")
		(net "CLKREQB_NODE1_N")
	)
	(segment
		(start 142.33271 -115.863624)
		(end 141.750288 -116.446046)
		(width 0.1016)
		(layer "F.Cu")
		(net "CLKREQB_NODE1_N")
	)
	(via
		(at 138.693652 -116.210842)
		(size 0.508)
		(drill 0.254)
		(layers "F.Cu" "B.Cu")
		(net "CLKREQB_NODE1_N")
	)
	(segment
		(start 143.427196 -70.86473)
		(end 143.325596 -70.96633)
		(width 0.1016)
		(layer "F.Cu")
		(net "IRQ_LVC3_SATA_NODE1_WAKE_L")
	)
	(segment
		(start 143.345916 -71.914258)
		(end 143.345916 -71.78548)
		(width 0.1016)
		(layer "F.Cu")
		(net "IRQ_LVC3_SATA_NODE1_WAKE_L")
	)
	(segment
		(start 143.427196 -69.72173)
		(end 143.427196 -70.86473)
		(width 0.1016)
		(layer "F.Cu")
		(net "IRQ_LVC3_SATA_NODE1_WAKE_L")
	)
	(segment
		(start 143.325596 -71.76516)
		(end 143.325596 -70.96633)
		(width 0.1016)
		(layer "F.Cu")
		(net "IRQ_LVC3_SATA_NODE1_WAKE_L")
	)
	(segment
		(start 143.530574 -69.618352)
		(end 143.427196 -69.72173)
		(width 0.1016)
		(layer "F.Cu")
		(net "IRQ_LVC3_SATA_NODE1_WAKE_L")
	)
	(segment
		(start 143.530574 -68.799202)
		(end 143.530574 -69.618352)
		(width 0.1016)
		(layer "F.Cu")
		(net "IRQ_LVC3_SATA_NODE1_WAKE_L")
	)
	(segment
		(start 143.345916 -71.78548)
		(end 143.325596 -71.76516)
		(width 0.1016)
		(layer "F.Cu")
		(net "IRQ_LVC3_SATA_NODE1_WAKE_L")
	)
	(via
		(at 143.325596 -70.96633)
		(size 0.508)
		(drill 0.254)
		(layers "F.Cu" "B.Cu")
		(net "IRQ_LVC3_SATA_NODE1_WAKE_L")
	)
	(segment
		(start 58.47588 -86.143846)
		(end 58.710576 -85.90915)
		(width 0.1016)
		(layer "F.Cu")
		(net "PD_CPU_NODE1_DFX_GPIO_GRP1_2")
	)
	(segment
		(start 58.23077 -86.143846)
		(end 58.47588 -86.143846)
		(width 0.1016)
		(layer "F.Cu")
		(net "PD_CPU_NODE1_DFX_GPIO_GRP1_2")
	)
	(via
		(at 56.054498 -94.197678)
		(size 0.6604)
		(drill 0.3302)
		(layers "F.Cu" "B.Cu")
		(net "PD_CPU_NODE1_DFX_GPIO_GRP1_2")
	)
	(via
		(at 58.710576 -85.90915)
		(size 0.508)
		(drill 0.254)
		(layers "F.Cu" "B.Cu")
		(net "PD_CPU_NODE1_DFX_GPIO_GRP1_2")
	)
	(segment
		(start 57.792112 -92.460064)
		(end 56.054498 -94.197678)
		(width 0.1016)
		(layer "B.Cu")
		(net "PD_CPU_NODE1_DFX_GPIO_GRP1_2")
	)
	(segment
		(start 58.710576 -85.90915)
		(end 58.641742 -85.977984)
		(width 0.1016)
		(layer "B.Cu")
		(net "PD_CPU_NODE1_DFX_GPIO_GRP1_2")
	)
	(segment
		(start 56.054498 -94.197678)
		(end 56.054498 -96.296734)
		(width 0.1016)
		(layer "B.Cu")
		(net "PD_CPU_NODE1_DFX_GPIO_GRP1_2")
	)
	(segment
		(start 58.641742 -85.977984)
		(end 58.641742 -90.18651)
		(width 0.1016)
		(layer "B.Cu")
		(net "PD_CPU_NODE1_DFX_GPIO_GRP1_2")
	)
	(segment
		(start 58.780426 -90.938858)
		(end 57.792112 -91.927172)
		(width 0.1016)
		(layer "B.Cu")
		(net "PD_CPU_NODE1_DFX_GPIO_GRP1_2")
	)
	(segment
		(start 58.641742 -90.18651)
		(end 58.780426 -90.325194)
		(width 0.1016)
		(layer "B.Cu")
		(net "PD_CPU_NODE1_DFX_GPIO_GRP1_2")
	)
	(segment
		(start 58.780426 -90.325194)
		(end 58.780426 -90.938858)
		(width 0.1016)
		(layer "B.Cu")
		(net "PD_CPU_NODE1_DFX_GPIO_GRP1_2")
	)
	(segment
		(start 57.792112 -91.927172)
		(end 57.792112 -92.460064)
		(width 0.1016)
		(layer "B.Cu")
		(net "PD_CPU_NODE1_DFX_GPIO_GRP1_2")
	)
	(segment
		(start 73.71588 -68.375784)
		(end 73.83018 -68.375784)
		(width 0.09906)
		(layer "F.Cu")
		(net "M_DDR3_NODE1_DQS6N")
	)
	(segment
		(start 73.83018 -68.375784)
		(end 74.139806 -68.68541)
		(width 0.09906)
		(layer "F.Cu")
		(net "M_DDR3_NODE1_DQS6N")
	)
	(segment
		(start 76.27874 -64.781684)
		(end 76.27874 -64.475868)
		(width 0.09906)
		(layer "F.Cu")
		(net "M_DDR3_NODE1_DQS6N")
	)
	(segment
		(start 75.923902 -66.082672)
		(end 75.61961 -65.77838)
		(width 0.09906)
		(layer "F.Cu")
		(net "M_DDR3_NODE1_DQS6N")
	)
	(segment
		(start 93.904054 -22.814534)
		(end 93.415104 -23.303484)
		(width 0.1651)
		(layer "F.Cu")
		(net "M_DDR3_NODE1_DQS6N")
	)
	(segment
		(start 74.139806 -68.68541)
		(end 74.943716 -68.68541)
		(width 0.09906)
		(layer "F.Cu")
		(net "M_DDR3_NODE1_DQS6N")
	)
	(segment
		(start 93.75013 -22.151086)
		(end 93.904054 -22.30501)
		(width 0.1651)
		(layer "F.Cu")
		(net "M_DDR3_NODE1_DQS6N")
	)
	(segment
		(start 75.61961 -68.009516)
		(end 75.61961 -67.022726)
		(width 0.09906)
		(layer "F.Cu")
		(net "M_DDR3_NODE1_DQS6N")
	)
	(segment
		(start 93.904054 -22.30501)
		(end 93.904054 -22.814534)
		(width 0.1651)
		(layer "F.Cu")
		(net "M_DDR3_NODE1_DQS6N")
	)
	(segment
		(start 76.16952 -64.890904)
		(end 76.27874 -64.781684)
		(width 0.09906)
		(layer "F.Cu")
		(net "M_DDR3_NODE1_DQS6N")
	)
	(segment
		(start 73.641458 -68.450206)
		(end 73.71588 -68.375784)
		(width 0.09906)
		(layer "F.Cu")
		(net "M_DDR3_NODE1_DQS6N")
	)
	(segment
		(start 75.82408 -64.890904)
		(end 76.16952 -64.890904)
		(width 0.09906)
		(layer "F.Cu")
		(net "M_DDR3_NODE1_DQS6N")
	)
	(segment
		(start 75.61961 -65.095374)
		(end 75.82408 -64.890904)
		(width 0.09906)
		(layer "F.Cu")
		(net "M_DDR3_NODE1_DQS6N")
	)
	(segment
		(start 74.943716 -68.68541)
		(end 75.61961 -68.009516)
		(width 0.09906)
		(layer "F.Cu")
		(net "M_DDR3_NODE1_DQS6N")
	)
	(segment
		(start 75.61961 -67.022726)
		(end 75.923902 -66.718434)
		(width 0.09906)
		(layer "F.Cu")
		(net "M_DDR3_NODE1_DQS6N")
	)
	(segment
		(start 93.75013 -20.94992)
		(end 93.75013 -22.151086)
		(width 0.1651)
		(layer "F.Cu")
		(net "M_DDR3_NODE1_DQS6N")
	)
	(segment
		(start 73.641458 -68.68541)
		(end 73.641458 -68.450206)
		(width 0.09906)
		(layer "F.Cu")
		(net "M_DDR3_NODE1_DQS6N")
	)
	(segment
		(start 75.61961 -65.77838)
		(end 75.61961 -65.095374)
		(width 0.09906)
		(layer "F.Cu")
		(net "M_DDR3_NODE1_DQS6N")
	)
	(segment
		(start 75.923902 -66.718434)
		(end 75.923902 -66.082672)
		(width 0.09906)
		(layer "F.Cu")
		(net "M_DDR3_NODE1_DQS6N")
	)
	(via
		(at 93.415104 -23.303484)
		(size 0.508)
		(drill 0.254)
		(layers "F.Cu" "B.Cu")
		(net "M_DDR3_NODE1_DQS6N")
	)
	(via
		(at 76.27874 -64.475868)
		(size 0.508)
		(drill 0.254)
		(layers "F.Cu" "B.Cu")
		(net "M_DDR3_NODE1_DQS6N")
	)
	(segment
		(start 89.836498 -41.979088)
		(end 91.626182 -41.979088)
		(width 0.2032)
		(layer "In7.Cu")
		(net "M_DDR3_NODE1_DQS6N")
	)
	(segment
		(start 91.626182 -41.979088)
		(end 91.834462 -41.770808)
		(width 0.2032)
		(layer "In7.Cu")
		(net "M_DDR3_NODE1_DQS6N")
	)
	(segment
		(start 88.440768 -43.374818)
		(end 89.836498 -41.979088)
		(width 0.2032)
		(layer "In7.Cu")
		(net "M_DDR3_NODE1_DQS6N")
	)
	(segment
		(start 81.647284 -50.395124)
		(end 82.078576 -49.963832)
		(width 0.2032)
		(layer "In7.Cu")
		(net "M_DDR3_NODE1_DQS6N")
	)
	(segment
		(start 91.834462 -41.770808)
		(end 91.834462 -41.476168)
		(width 0.2032)
		(layer "In7.Cu")
		(net "M_DDR3_NODE1_DQS6N")
	)
	(segment
		(start 93.861382 -23.613618)
		(end 93.551248 -23.303484)
		(width 0.2032)
		(layer "In7.Cu")
		(net "M_DDR3_NODE1_DQS6N")
	)
	(segment
		(start 79.590392 -52.452016)
		(end 79.76108 -52.452016)
		(width 0.2032)
		(layer "In7.Cu")
		(net "M_DDR3_NODE1_DQS6N")
	)
	(segment
		(start 88.203024 -44.843192)
		(end 88.440768 -44.605448)
		(width 0.2032)
		(layer "In7.Cu")
		(net "M_DDR3_NODE1_DQS6N")
	)
	(segment
		(start 84.737448 -47.475648)
		(end 85.89645 -46.316646)
		(width 0.2032)
		(layer "In7.Cu")
		(net "M_DDR3_NODE1_DQS6N")
	)
	(segment
		(start 79.76108 -52.452016)
		(end 80.40116 -51.811936)
		(width 0.2032)
		(layer "In7.Cu")
		(net "M_DDR3_NODE1_DQS6N")
	)
	(segment
		(start 82.249264 -49.963832)
		(end 82.89036 -49.322736)
		(width 0.2032)
		(layer "In7.Cu")
		(net "M_DDR3_NODE1_DQS6N")
	)
	(segment
		(start 76.38669 -64.92494)
		(end 76.557632 -64.92494)
		(width 0.09906)
		(layer "In7.Cu")
		(net "M_DDR3_NODE1_DQS6N")
	)
	(segment
		(start 90.714322 -29.190188)
		(end 90.714322 -27.261566)
		(width 0.2032)
		(layer "In7.Cu")
		(net "M_DDR3_NODE1_DQS6N")
	)
	(segment
		(start 91.834462 -41.476168)
		(end 91.626182 -41.267888)
		(width 0.2032)
		(layer "In7.Cu")
		(net "M_DDR3_NODE1_DQS6N")
	)
	(segment
		(start 79.1591 -52.883308)
		(end 79.590392 -52.452016)
		(width 0.2032)
		(layer "In7.Cu")
		(net "M_DDR3_NODE1_DQS6N")
	)
	(segment
		(start 81.005172 -51.207924)
		(end 81.64576 -50.567336)
		(width 0.2032)
		(layer "In7.Cu")
		(net "M_DDR3_NODE1_DQS6N")
	)
	(segment
		(start 93.681296 -24.050498)
		(end 93.861382 -23.870412)
		(width 0.2032)
		(layer "In7.Cu")
		(net "M_DDR3_NODE1_DQS6N")
	)
	(segment
		(start 90.353134 -41.267888)
		(end 89.95664 -40.871394)
		(width 0.2032)
		(layer "In7.Cu")
		(net "M_DDR3_NODE1_DQS6N")
	)
	(segment
		(start 92.66428 -25.898856)
		(end 92.66428 -24.579072)
		(width 0.2032)
		(layer "In7.Cu")
		(net "M_DDR3_NODE1_DQS6N")
	)
	(segment
		(start 90.922602 -29.398468)
		(end 90.714322 -29.190188)
		(width 0.2032)
		(layer "In7.Cu")
		(net "M_DDR3_NODE1_DQS6N")
	)
	(segment
		(start 89.95664 -39.743126)
		(end 90.444828 -39.254938)
		(width 0.2032)
		(layer "In7.Cu")
		(net "M_DDR3_NODE1_DQS6N")
	)
	(segment
		(start 82.89036 -49.151032)
		(end 82.891376 -49.151032)
		(width 0.2032)
		(layer "In7.Cu")
		(net "M_DDR3_NODE1_DQS6N")
	)
	(segment
		(start 93.861382 -23.870412)
		(end 93.861382 -23.613618)
		(width 0.2032)
		(layer "In7.Cu")
		(net "M_DDR3_NODE1_DQS6N")
	)
	(segment
		(start 90.444828 -39.254938)
		(end 90.760296 -39.254938)
		(width 0.2032)
		(layer "In7.Cu")
		(net "M_DDR3_NODE1_DQS6N")
	)
	(segment
		(start 76.686664 -63.20282)
		(end 76.686664 -63.189612)
		(width 0.09906)
		(layer "In7.Cu")
		(net "M_DDR3_NODE1_DQS6N")
	)
	(segment
		(start 81.64576 -50.567336)
		(end 81.64576 -50.395124)
		(width 0.2032)
		(layer "In7.Cu")
		(net "M_DDR3_NODE1_DQS6N")
	)
	(segment
		(start 90.922602 -39.092632)
		(end 90.922602 -29.398468)
		(width 0.2032)
		(layer "In7.Cu")
		(net "M_DDR3_NODE1_DQS6N")
	)
	(segment
		(start 92.66428 -24.579072)
		(end 93.192854 -24.050498)
		(width 0.2032)
		(layer "In7.Cu")
		(net "M_DDR3_NODE1_DQS6N")
	)
	(segment
		(start 80.40116 -51.811936)
		(end 80.40116 -51.639216)
		(width 0.2032)
		(layer "In7.Cu")
		(net "M_DDR3_NODE1_DQS6N")
	)
	(segment
		(start 86.967314 -45.245782)
		(end 87.369904 -44.843192)
		(width 0.2032)
		(layer "In7.Cu")
		(net "M_DDR3_NODE1_DQS6N")
	)
	(segment
		(start 84.56676 -47.475648)
		(end 84.737448 -47.475648)
		(width 0.2032)
		(layer "In7.Cu")
		(net "M_DDR3_NODE1_DQS6N")
	)
	(segment
		(start 76.750164 -64.732408)
		(end 76.750164 -63.26632)
		(width 0.09906)
		(layer "In7.Cu")
		(net "M_DDR3_NODE1_DQS6N")
	)
	(segment
		(start 90.714322 -27.261566)
		(end 91.422474 -26.553414)
		(width 0.2032)
		(layer "In7.Cu")
		(net "M_DDR3_NODE1_DQS6N")
	)
	(segment
		(start 81.64576 -50.395124)
		(end 81.647284 -50.395124)
		(width 0.2032)
		(layer "In7.Cu")
		(net "M_DDR3_NODE1_DQS6N")
	)
	(segment
		(start 92.009722 -26.553414)
		(end 92.66428 -25.898856)
		(width 0.2032)
		(layer "In7.Cu")
		(net "M_DDR3_NODE1_DQS6N")
	)
	(segment
		(start 77.17282 -55.040276)
		(end 79.1591 -53.053996)
		(width 0.2032)
		(layer "In7.Cu")
		(net "M_DDR3_NODE1_DQS6N")
	)
	(segment
		(start 93.192854 -24.050498)
		(end 93.681296 -24.050498)
		(width 0.2032)
		(layer "In7.Cu")
		(net "M_DDR3_NODE1_DQS6N")
	)
	(segment
		(start 93.551248 -23.303484)
		(end 93.415104 -23.303484)
		(width 0.2032)
		(layer "In7.Cu")
		(net "M_DDR3_NODE1_DQS6N")
	)
	(segment
		(start 76.557632 -64.92494)
		(end 76.750164 -64.732408)
		(width 0.09906)
		(layer "In7.Cu")
		(net "M_DDR3_NODE1_DQS6N")
	)
	(segment
		(start 84.135468 -47.90694)
		(end 84.56676 -47.475648)
		(width 0.2032)
		(layer "In7.Cu")
		(net "M_DDR3_NODE1_DQS6N")
	)
	(segment
		(start 84.13496 -47.90694)
		(end 84.135468 -47.90694)
		(width 0.2032)
		(layer "In7.Cu")
		(net "M_DDR3_NODE1_DQS6N")
	)
	(segment
		(start 76.686664 -59.018678)
		(end 77.17282 -58.532522)
		(width 0.2032)
		(layer "In7.Cu")
		(net "M_DDR3_NODE1_DQS6N")
	)
	(segment
		(start 86.967314 -46.096174)
		(end 86.967314 -45.245782)
		(width 0.2032)
		(layer "In7.Cu")
		(net "M_DDR3_NODE1_DQS6N")
	)
	(segment
		(start 83.322668 -48.71974)
		(end 83.493356 -48.71974)
		(width 0.2032)
		(layer "In7.Cu")
		(net "M_DDR3_NODE1_DQS6N")
	)
	(segment
		(start 86.746842 -46.316646)
		(end 86.967314 -46.096174)
		(width 0.2032)
		(layer "In7.Cu")
		(net "M_DDR3_NODE1_DQS6N")
	)
	(segment
		(start 89.95664 -40.871394)
		(end 89.95664 -39.743126)
		(width 0.2032)
		(layer "In7.Cu")
		(net "M_DDR3_NODE1_DQS6N")
	)
	(segment
		(start 88.440768 -44.605448)
		(end 88.440768 -43.374818)
		(width 0.2032)
		(layer "In7.Cu")
		(net "M_DDR3_NODE1_DQS6N")
	)
	(segment
		(start 76.27874 -64.81699)
		(end 76.38669 -64.92494)
		(width 0.09906)
		(layer "In7.Cu")
		(net "M_DDR3_NODE1_DQS6N")
	)
	(segment
		(start 85.89645 -46.316646)
		(end 86.746842 -46.316646)
		(width 0.2032)
		(layer "In7.Cu")
		(net "M_DDR3_NODE1_DQS6N")
	)
	(segment
		(start 76.686664 -63.189612)
		(end 76.686664 -59.018678)
		(width 0.2032)
		(layer "In7.Cu")
		(net "M_DDR3_NODE1_DQS6N")
	)
	(segment
		(start 82.078576 -49.963832)
		(end 82.249264 -49.963832)
		(width 0.2032)
		(layer "In7.Cu")
		(net "M_DDR3_NODE1_DQS6N")
	)
	(segment
		(start 80.40116 -51.639216)
		(end 80.403192 -51.639216)
		(width 0.2032)
		(layer "In7.Cu")
		(net "M_DDR3_NODE1_DQS6N")
	)
	(segment
		(start 91.422474 -26.553414)
		(end 92.009722 -26.553414)
		(width 0.2032)
		(layer "In7.Cu")
		(net "M_DDR3_NODE1_DQS6N")
	)
	(segment
		(start 84.13496 -48.078136)
		(end 84.13496 -47.90694)
		(width 0.2032)
		(layer "In7.Cu")
		(net "M_DDR3_NODE1_DQS6N")
	)
	(segment
		(start 80.403192 -51.639216)
		(end 80.834484 -51.207924)
		(width 0.2032)
		(layer "In7.Cu")
		(net "M_DDR3_NODE1_DQS6N")
	)
	(segment
		(start 80.834484 -51.207924)
		(end 81.005172 -51.207924)
		(width 0.2032)
		(layer "In7.Cu")
		(net "M_DDR3_NODE1_DQS6N")
	)
	(segment
		(start 76.27874 -64.475868)
		(end 76.27874 -64.81699)
		(width 0.09906)
		(layer "In7.Cu")
		(net "M_DDR3_NODE1_DQS6N")
	)
	(segment
		(start 77.17282 -58.532522)
		(end 77.17282 -55.040276)
		(width 0.2032)
		(layer "In7.Cu")
		(net "M_DDR3_NODE1_DQS6N")
	)
	(segment
		(start 91.626182 -41.267888)
		(end 90.353134 -41.267888)
		(width 0.2032)
		(layer "In7.Cu")
		(net "M_DDR3_NODE1_DQS6N")
	)
	(segment
		(start 87.369904 -44.843192)
		(end 88.203024 -44.843192)
		(width 0.2032)
		(layer "In7.Cu")
		(net "M_DDR3_NODE1_DQS6N")
	)
	(segment
		(start 82.89036 -49.322736)
		(end 82.89036 -49.151032)
		(width 0.2032)
		(layer "In7.Cu")
		(net "M_DDR3_NODE1_DQS6N")
	)
	(segment
		(start 82.891376 -49.151032)
		(end 83.322668 -48.71974)
		(width 0.2032)
		(layer "In7.Cu")
		(net "M_DDR3_NODE1_DQS6N")
	)
	(segment
		(start 90.760296 -39.254938)
		(end 90.922602 -39.092632)
		(width 0.2032)
		(layer "In7.Cu")
		(net "M_DDR3_NODE1_DQS6N")
	)
	(segment
		(start 76.750164 -63.26632)
		(end 76.686664 -63.20282)
		(width 0.09906)
		(layer "In7.Cu")
		(net "M_DDR3_NODE1_DQS6N")
	)
	(segment
		(start 83.493356 -48.71974)
		(end 84.13496 -48.078136)
		(width 0.2032)
		(layer "In7.Cu")
		(net "M_DDR3_NODE1_DQS6N")
	)
	(segment
		(start 79.1591 -53.053996)
		(end 79.1591 -52.883308)
		(width 0.2032)
		(layer "In7.Cu")
		(net "M_DDR3_NODE1_DQS6N")
	)
	(segment
		(start 27.055318 -58.735214)
		(end 28.57246 -60.252356)
		(width 0.1016)
		(layer "F.Cu")
		(net "BMC_NODE1_GFX_HSYNC")
	)
	(segment
		(start 28.57246 -64.680084)
		(end 26.613358 -66.639186)
		(width 0.1016)
		(layer "F.Cu")
		(net "BMC_NODE1_GFX_HSYNC")
	)
	(segment
		(start 26.613358 -66.639186)
		(end 26.5557 -66.639186)
		(width 0.1016)
		(layer "F.Cu")
		(net "BMC_NODE1_GFX_HSYNC")
	)
	(segment
		(start 28.57246 -60.252356)
		(end 28.57246 -64.680084)
		(width 0.1016)
		(layer "F.Cu")
		(net "BMC_NODE1_GFX_HSYNC")
	)
	(segment
		(start 27.055318 -55.558436)
		(end 27.055318 -58.735214)
		(width 0.1016)
		(layer "F.Cu")
		(net "BMC_NODE1_GFX_HSYNC")
	)
	(via
		(at 55.6133 -143.659606)
		(size 0.508)
		(drill 0.254)
		(layers "F.Cu" "B.Cu")
		(net "BMC_NODE1_GFX_HSYNC")
	)
	(via
		(at 26.5557 -66.639186)
		(size 0.508)
		(drill 0.254)
		(layers "F.Cu" "B.Cu")
		(net "BMC_NODE1_GFX_HSYNC")
	)
	(segment
		(start 55.802276 -144.809464)
		(end 55.802276 -143.848582)
		(width 0.1016)
		(layer "B.Cu")
		(net "BMC_NODE1_GFX_HSYNC")
	)
	(segment
		(start 55.802276 -143.848582)
		(end 55.6133 -143.659606)
		(width 0.1016)
		(layer "B.Cu")
		(net "BMC_NODE1_GFX_HSYNC")
	)
	(segment
		(start 12.143486 -133.653276)
		(end 13.748258 -133.653276)
		(width 0.1143)
		(layer "In6.Cu")
		(net "BMC_NODE1_GFX_HSYNC")
	)
	(segment
		(start 49.097184 -143.646144)
		(end 50.859182 -143.646144)
		(width 0.1143)
		(layer "In6.Cu")
		(net "BMC_NODE1_GFX_HSYNC")
	)
	(segment
		(start 10.182352 -131.692142)
		(end 12.143486 -133.653276)
		(width 0.1143)
		(layer "In6.Cu")
		(net "BMC_NODE1_GFX_HSYNC")
	)
	(segment
		(start 29.390086 -134.279894)
		(end 39.05504 -143.944848)
		(width 0.1143)
		(layer "In6.Cu")
		(net "BMC_NODE1_GFX_HSYNC")
	)
	(segment
		(start 15.072106 -134.977124)
		(end 21.60397 -134.977124)
		(width 0.1143)
		(layer "In6.Cu")
		(net "BMC_NODE1_GFX_HSYNC")
	)
	(segment
		(start 50.859182 -143.646144)
		(end 51.770534 -144.557496)
		(width 0.1143)
		(layer "In6.Cu")
		(net "BMC_NODE1_GFX_HSYNC")
	)
	(segment
		(start 44.10964 -144.02054)
		(end 44.10964 -144.857216)
		(width 0.1143)
		(layer "In6.Cu")
		(net "BMC_NODE1_GFX_HSYNC")
	)
	(segment
		(start 39.05504 -143.944848)
		(end 44.033948 -143.944848)
		(width 0.1143)
		(layer "In6.Cu")
		(net "BMC_NODE1_GFX_HSYNC")
	)
	(segment
		(start 44.033948 -143.944848)
		(end 44.10964 -144.02054)
		(width 0.1143)
		(layer "In6.Cu")
		(net "BMC_NODE1_GFX_HSYNC")
	)
	(segment
		(start 13.748258 -133.653276)
		(end 15.072106 -134.977124)
		(width 0.1143)
		(layer "In6.Cu")
		(net "BMC_NODE1_GFX_HSYNC")
	)
	(segment
		(start 44.36618 -145.113756)
		(end 44.680378 -145.113756)
		(width 0.1143)
		(layer "In6.Cu")
		(net "BMC_NODE1_GFX_HSYNC")
	)
	(segment
		(start 10.182352 -98.598736)
		(end 10.182352 -131.692142)
		(width 0.1143)
		(layer "In6.Cu")
		(net "BMC_NODE1_GFX_HSYNC")
	)
	(segment
		(start 24.49322 -68.158868)
		(end 24.49322 -77.254608)
		(width 0.1143)
		(layer "In6.Cu")
		(net "BMC_NODE1_GFX_HSYNC")
	)
	(segment
		(start 51.770534 -144.557496)
		(end 54.71541 -144.557496)
		(width 0.1143)
		(layer "In6.Cu")
		(net "BMC_NODE1_GFX_HSYNC")
	)
	(segment
		(start 26.012902 -66.639186)
		(end 24.49322 -68.158868)
		(width 0.1143)
		(layer "In6.Cu")
		(net "BMC_NODE1_GFX_HSYNC")
	)
	(segment
		(start 21.17852 -80.569308)
		(end 21.17852 -87.602568)
		(width 0.1143)
		(layer "In6.Cu")
		(net "BMC_NODE1_GFX_HSYNC")
	)
	(segment
		(start 54.71541 -144.557496)
		(end 55.6133 -143.659606)
		(width 0.1143)
		(layer "In6.Cu")
		(net "BMC_NODE1_GFX_HSYNC")
	)
	(segment
		(start 21.60397 -134.977124)
		(end 22.3012 -134.279894)
		(width 0.1143)
		(layer "In6.Cu")
		(net "BMC_NODE1_GFX_HSYNC")
	)
	(segment
		(start 45.21962 -145.652998)
		(end 47.09033 -145.652998)
		(width 0.1143)
		(layer "In6.Cu")
		(net "BMC_NODE1_GFX_HSYNC")
	)
	(segment
		(start 21.17852 -87.602568)
		(end 10.182352 -98.598736)
		(width 0.1143)
		(layer "In6.Cu")
		(net "BMC_NODE1_GFX_HSYNC")
	)
	(segment
		(start 44.10964 -144.857216)
		(end 44.36618 -145.113756)
		(width 0.1143)
		(layer "In6.Cu")
		(net "BMC_NODE1_GFX_HSYNC")
	)
	(segment
		(start 44.680378 -145.113756)
		(end 45.21962 -145.652998)
		(width 0.1143)
		(layer "In6.Cu")
		(net "BMC_NODE1_GFX_HSYNC")
	)
	(segment
		(start 22.3012 -134.279894)
		(end 29.390086 -134.279894)
		(width 0.1143)
		(layer "In6.Cu")
		(net "BMC_NODE1_GFX_HSYNC")
	)
	(segment
		(start 26.5557 -66.639186)
		(end 26.012902 -66.639186)
		(width 0.1143)
		(layer "In6.Cu")
		(net "BMC_NODE1_GFX_HSYNC")
	)
	(segment
		(start 47.09033 -145.652998)
		(end 49.097184 -143.646144)
		(width 0.1143)
		(layer "In6.Cu")
		(net "BMC_NODE1_GFX_HSYNC")
	)
	(segment
		(start 24.49322 -77.254608)
		(end 21.17852 -80.569308)
		(width 0.1143)
		(layer "In6.Cu")
		(net "BMC_NODE1_GFX_HSYNC")
	)
	(segment
		(start 59.472576 -95.099124)
		(end 57.84723 -93.473778)
		(width 0.1016)
		(layer "F.Cu")
		(net "PD_CPU_NODE1_DFX_GPIO_GRP1_0")
	)
	(segment
		(start 57.948068 -88.535764)
		(end 57.496202 -88.98763)
		(width 0.1016)
		(layer "F.Cu")
		(net "PD_CPU_NODE1_DFX_GPIO_GRP1_0")
	)
	(segment
		(start 59.472576 -95.167196)
		(end 59.472576 -95.099124)
		(width 0.1016)
		(layer "F.Cu")
		(net "PD_CPU_NODE1_DFX_GPIO_GRP1_0")
	)
	(segment
		(start 57.496202 -93.12275)
		(end 57.84723 -93.473778)
		(width 0.1016)
		(layer "F.Cu")
		(net "PD_CPU_NODE1_DFX_GPIO_GRP1_0")
	)
	(segment
		(start 60.129166 -96.309942)
		(end 60.129166 -95.823786)
		(width 0.1016)
		(layer "F.Cu")
		(net "PD_CPU_NODE1_DFX_GPIO_GRP1_0")
	)
	(segment
		(start 57.948068 -88.103964)
		(end 57.948068 -88.535764)
		(width 0.1016)
		(layer "F.Cu")
		(net "PD_CPU_NODE1_DFX_GPIO_GRP1_0")
	)
	(segment
		(start 57.496202 -88.98763)
		(end 57.496202 -93.12275)
		(width 0.1016)
		(layer "F.Cu")
		(net "PD_CPU_NODE1_DFX_GPIO_GRP1_0")
	)
	(segment
		(start 60.129166 -95.823786)
		(end 59.472576 -95.167196)
		(width 0.1016)
		(layer "F.Cu")
		(net "PD_CPU_NODE1_DFX_GPIO_GRP1_0")
	)
	(via
		(at 57.84723 -93.473778)
		(size 0.508)
		(drill 0.254)
		(layers "F.Cu" "B.Cu")
		(net "PD_CPU_NODE1_DFX_GPIO_GRP1_0")
	)
	(segment
		(start 48.002698 -62.405768)
		(end 48.002698 -62.672976)
		(width 0.1016)
		(layer "F.Cu")
		(net "M1_DQ_NODE1_DQ10")
	)
	(segment
		(start 47.55896 -60.125356)
		(end 47.55896 -61.96203)
		(width 0.1016)
		(layer "F.Cu")
		(net "M1_DQ_NODE1_DQ10")
	)
	(segment
		(start 47.041562 -59.051698)
		(end 47.375572 -59.385708)
		(width 0.1016)
		(layer "F.Cu")
		(net "M1_DQ_NODE1_DQ10")
	)
	(segment
		(start 48.002698 -62.672976)
		(end 48.37684 -63.047118)
		(width 0.1016)
		(layer "F.Cu")
		(net "M1_DQ_NODE1_DQ10")
	)
	(segment
		(start 48.2854 -25.324054)
		(end 49.129442 -24.480012)
		(width 0.1651)
		(layer "F.Cu")
		(net "M1_DQ_NODE1_DQ10")
	)
	(segment
		(start 49.129442 -24.480012)
		(end 49.129442 -22.986238)
		(width 0.1651)
		(layer "F.Cu")
		(net "M1_DQ_NODE1_DQ10")
	)
	(segment
		(start 45.423836 -58.160412)
		(end 46.315122 -59.051698)
		(width 0.1016)
		(layer "F.Cu")
		(net "M1_DQ_NODE1_DQ10")
	)
	(segment
		(start 45.22216 -58.160412)
		(end 45.423836 -58.160412)
		(width 0.1016)
		(layer "F.Cu")
		(net "M1_DQ_NODE1_DQ10")
	)
	(segment
		(start 46.315122 -59.051698)
		(end 47.041562 -59.051698)
		(width 0.1016)
		(layer "F.Cu")
		(net "M1_DQ_NODE1_DQ10")
	)
	(segment
		(start 47.375572 -59.941968)
		(end 47.55896 -60.125356)
		(width 0.1016)
		(layer "F.Cu")
		(net "M1_DQ_NODE1_DQ10")
	)
	(segment
		(start 49.350168 -22.765512)
		(end 49.350168 -20.94992)
		(width 0.1651)
		(layer "F.Cu")
		(net "M1_DQ_NODE1_DQ10")
	)
	(segment
		(start 47.55896 -61.96203)
		(end 48.002698 -62.405768)
		(width 0.1016)
		(layer "F.Cu")
		(net "M1_DQ_NODE1_DQ10")
	)
	(segment
		(start 47.375572 -59.385708)
		(end 47.375572 -59.941968)
		(width 0.1016)
		(layer "F.Cu")
		(net "M1_DQ_NODE1_DQ10")
	)
	(segment
		(start 49.129442 -22.986238)
		(end 49.350168 -22.765512)
		(width 0.1651)
		(layer "F.Cu")
		(net "M1_DQ_NODE1_DQ10")
	)
	(via
		(at 45.22216 -58.160412)
		(size 0.508)
		(drill 0.254)
		(layers "F.Cu" "B.Cu")
		(net "M1_DQ_NODE1_DQ10")
	)
	(via
		(at 48.2854 -25.324054)
		(size 0.508)
		(drill 0.254)
		(layers "F.Cu" "B.Cu")
		(net "M1_DQ_NODE1_DQ10")
	)
	(segment
		(start 42.2656 -58.160412)
		(end 41.543224 -57.438036)
		(width 0.2032)
		(layer "In2.Cu")
		(net "M1_DQ_NODE1_DQ10")
	)
	(segment
		(start 36.756848 -56.342534)
		(end 36.462208 -56.342534)
		(width 0.2032)
		(layer "In2.Cu")
		(net "M1_DQ_NODE1_DQ10")
	)
	(segment
		(start 36.257992 -54.82971)
		(end 35.751008 -55.336694)
		(width 0.2032)
		(layer "In2.Cu")
		(net "M1_DQ_NODE1_DQ10")
	)
	(segment
		(start 47.0916 -32.12084)
		(end 46.66996 -31.6992)
		(width 0.2032)
		(layer "In2.Cu")
		(net "M1_DQ_NODE1_DQ10")
	)
	(segment
		(start 46.66996 -31.6992)
		(end 46.66996 -29.238956)
		(width 0.2032)
		(layer "In2.Cu")
		(net "M1_DQ_NODE1_DQ10")
	)
	(segment
		(start 34.9631 -39.531798)
		(end 40.054784 -34.440114)
		(width 0.2032)
		(layer "In2.Cu")
		(net "M1_DQ_NODE1_DQ10")
	)
	(segment
		(start 48.2854 -25.324816)
		(end 48.2854 -25.324054)
		(width 0.2032)
		(layer "In2.Cu")
		(net "M1_DQ_NODE1_DQ10")
	)
	(segment
		(start 36.253928 -55.839614)
		(end 36.760912 -55.33263)
		(width 0.2032)
		(layer "In2.Cu")
		(net "M1_DQ_NODE1_DQ10")
	)
	(segment
		(start 34.9631 -53.240178)
		(end 34.9631 -39.531798)
		(width 0.2032)
		(layer "In2.Cu")
		(net "M1_DQ_NODE1_DQ10")
	)
	(segment
		(start 45.338492 -34.440114)
		(end 47.0916 -32.687006)
		(width 0.2032)
		(layer "In2.Cu")
		(net "M1_DQ_NODE1_DQ10")
	)
	(segment
		(start 36.903914 -57.495186)
		(end 36.903914 -57.201054)
		(width 0.2032)
		(layer "In2.Cu")
		(net "M1_DQ_NODE1_DQ10")
	)
	(segment
		(start 46.66996 -29.238956)
		(end 47.47768 -28.431236)
		(width 0.2032)
		(layer "In2.Cu")
		(net "M1_DQ_NODE1_DQ10")
	)
	(segment
		(start 38.269672 -56.84139)
		(end 37.406834 -57.703974)
		(width 0.2032)
		(layer "In2.Cu")
		(net "M1_DQ_NODE1_DQ10")
	)
	(segment
		(start 35.755072 -54.32679)
		(end 35.755072 -54.03215)
		(width 0.2032)
		(layer "In2.Cu")
		(net "M1_DQ_NODE1_DQ10")
	)
	(segment
		(start 36.462208 -56.342534)
		(end 36.253928 -56.134254)
		(width 0.2032)
		(layer "In2.Cu")
		(net "M1_DQ_NODE1_DQ10")
	)
	(segment
		(start 47.0916 -32.687006)
		(end 47.0916 -32.12084)
		(width 0.2032)
		(layer "In2.Cu")
		(net "M1_DQ_NODE1_DQ10")
	)
	(segment
		(start 36.253928 -56.134254)
		(end 36.253928 -55.839614)
		(width 0.2032)
		(layer "In2.Cu")
		(net "M1_DQ_NODE1_DQ10")
	)
	(segment
		(start 35.456368 -55.336694)
		(end 35.248088 -55.128414)
		(width 0.2032)
		(layer "In2.Cu")
		(net "M1_DQ_NODE1_DQ10")
	)
	(segment
		(start 37.766752 -56.04383)
		(end 37.558472 -55.83555)
		(width 0.2032)
		(layer "In2.Cu")
		(net "M1_DQ_NODE1_DQ10")
	)
	(segment
		(start 35.755072 -54.03215)
		(end 34.9631 -53.240178)
		(width 0.2032)
		(layer "In2.Cu")
		(net "M1_DQ_NODE1_DQ10")
	)
	(segment
		(start 35.248088 -55.128414)
		(end 35.248088 -54.833774)
		(width 0.2032)
		(layer "In2.Cu")
		(net "M1_DQ_NODE1_DQ10")
	)
	(segment
		(start 48.109124 -25.426416)
		(end 48.1838 -25.426416)
		(width 0.2032)
		(layer "In2.Cu")
		(net "M1_DQ_NODE1_DQ10")
	)
	(segment
		(start 36.760912 -55.03799)
		(end 36.552632 -54.82971)
		(width 0.2032)
		(layer "In2.Cu")
		(net "M1_DQ_NODE1_DQ10")
	)
	(segment
		(start 35.248088 -54.833774)
		(end 35.755072 -54.32679)
		(width 0.2032)
		(layer "In2.Cu")
		(net "M1_DQ_NODE1_DQ10")
	)
	(segment
		(start 41.543224 -57.438036)
		(end 39.160958 -57.438036)
		(width 0.2032)
		(layer "In2.Cu")
		(net "M1_DQ_NODE1_DQ10")
	)
	(segment
		(start 36.760912 -55.33263)
		(end 36.760912 -55.03799)
		(width 0.2032)
		(layer "In2.Cu")
		(net "M1_DQ_NODE1_DQ10")
	)
	(segment
		(start 36.552632 -54.82971)
		(end 36.257992 -54.82971)
		(width 0.2032)
		(layer "In2.Cu")
		(net "M1_DQ_NODE1_DQ10")
	)
	(segment
		(start 47.250604 -26.284936)
		(end 48.109124 -25.426416)
		(width 0.2032)
		(layer "In2.Cu")
		(net "M1_DQ_NODE1_DQ10")
	)
	(segment
		(start 39.160958 -57.438036)
		(end 38.564312 -56.84139)
		(width 0.2032)
		(layer "In2.Cu")
		(net "M1_DQ_NODE1_DQ10")
	)
	(segment
		(start 48.1838 -25.426416)
		(end 48.2854 -25.324816)
		(width 0.2032)
		(layer "In2.Cu")
		(net "M1_DQ_NODE1_DQ10")
	)
	(segment
		(start 47.47768 -27.316938)
		(end 47.250604 -27.089862)
		(width 0.2032)
		(layer "In2.Cu")
		(net "M1_DQ_NODE1_DQ10")
	)
	(segment
		(start 37.766752 -56.33847)
		(end 37.766752 -56.04383)
		(width 0.2032)
		(layer "In2.Cu")
		(net "M1_DQ_NODE1_DQ10")
	)
	(segment
		(start 37.112702 -57.703974)
		(end 36.903914 -57.495186)
		(width 0.2032)
		(layer "In2.Cu")
		(net "M1_DQ_NODE1_DQ10")
	)
	(segment
		(start 47.47768 -28.431236)
		(end 47.47768 -27.316938)
		(width 0.2032)
		(layer "In2.Cu")
		(net "M1_DQ_NODE1_DQ10")
	)
	(segment
		(start 47.250604 -27.089862)
		(end 47.250604 -26.284936)
		(width 0.2032)
		(layer "In2.Cu")
		(net "M1_DQ_NODE1_DQ10")
	)
	(segment
		(start 36.903914 -57.201054)
		(end 37.766752 -56.33847)
		(width 0.2032)
		(layer "In2.Cu")
		(net "M1_DQ_NODE1_DQ10")
	)
	(segment
		(start 40.054784 -34.440114)
		(end 45.338492 -34.440114)
		(width 0.2032)
		(layer "In2.Cu")
		(net "M1_DQ_NODE1_DQ10")
	)
	(segment
		(start 37.406834 -57.703974)
		(end 37.112702 -57.703974)
		(width 0.2032)
		(layer "In2.Cu")
		(net "M1_DQ_NODE1_DQ10")
	)
	(segment
		(start 37.558472 -55.83555)
		(end 37.263832 -55.83555)
		(width 0.2032)
		(layer "In2.Cu")
		(net "M1_DQ_NODE1_DQ10")
	)
	(segment
		(start 45.22216 -58.160412)
		(end 42.2656 -58.160412)
		(width 0.2032)
		(layer "In2.Cu")
		(net "M1_DQ_NODE1_DQ10")
	)
	(segment
		(start 37.263832 -55.83555)
		(end 36.756848 -56.342534)
		(width 0.2032)
		(layer "In2.Cu")
		(net "M1_DQ_NODE1_DQ10")
	)
	(segment
		(start 35.751008 -55.336694)
		(end 35.456368 -55.336694)
		(width 0.2032)
		(layer "In2.Cu")
		(net "M1_DQ_NODE1_DQ10")
	)
	(segment
		(start 38.564312 -56.84139)
		(end 38.269672 -56.84139)
		(width 0.2032)
		(layer "In2.Cu")
		(net "M1_DQ_NODE1_DQ10")
	)
	(segment
		(start 149.277578 -57.649872)
		(end 149.277578 -57.903618)
		(width 0.1016)
		(layer "F.Cu")
		(net "PU_SATA_NODE1_GPIO4")
	)
	(segment
		(start 148.330666 -59.916822)
		(end 148.330666 -58.85053)
		(width 0.1016)
		(layer "F.Cu")
		(net "PU_SATA_NODE1_GPIO4")
	)
	(segment
		(start 148.330666 -58.85053)
		(end 148.737066 -58.44413)
		(width 0.1016)
		(layer "F.Cu")
		(net "PU_SATA_NODE1_GPIO4")
	)
	(segment
		(start 149.277578 -57.903618)
		(end 148.737066 -58.44413)
		(width 0.1016)
		(layer "F.Cu")
		(net "PU_SATA_NODE1_GPIO4")
	)
	(via
		(at 148.737066 -58.44413)
		(size 0.508)
		(drill 0.254)
		(layers "F.Cu" "B.Cu")
		(net "PU_SATA_NODE1_GPIO4")
	)
	(segment
		(start 58.131456 -128.059434)
		(end 57.730136 -127.658114)
		(width 0.3556)
		(layer "F.Cu")
		(net "BMC_NODE1_USBVREF")
	)
	(segment
		(start 58.14187 -128.059434)
		(end 58.131456 -128.059434)
		(width 0.3556)
		(layer "F.Cu")
		(net "BMC_NODE1_USBVREF")
	)
	(via
		(at 57.730136 -127.658114)
		(size 0.49022)
		(drill 0.254)
		(layers "F.Cu" "B.Cu")
		(net "BMC_NODE1_USBVREF")
	)
	(segment
		(start 57.745122 -127.643128)
		(end 57.730136 -127.658114)
		(width 0.508)
		(layer "B.Cu")
		(net "BMC_NODE1_USBVREF")
	)
	(segment
		(start 57.745122 -126.518162)
		(end 57.745122 -127.643128)
		(width 0.508)
		(layer "B.Cu")
		(net "BMC_NODE1_USBVREF")
	)
	(segment
		(start 61.304678 -86.143846)
		(end 61.015372 -85.85454)
		(width 0.1016)
		(layer "F.Cu")
		(net "LPC_CPU_NODE1_LAD1_R")
	)
	(segment
		(start 61.503306 -86.143846)
		(end 61.304678 -86.143846)
		(width 0.1016)
		(layer "F.Cu")
		(net "LPC_CPU_NODE1_LAD1_R")
	)
	(via
		(at 61.015372 -85.85454)
		(size 0.508)
		(drill 0.254)
		(layers "F.Cu" "B.Cu")
		(net "LPC_CPU_NODE1_LAD1_R")
	)
	(via
		(at 62.295532 -91.050872)
		(size 0.6604)
		(drill 0.3302)
		(layers "F.Cu" "B.Cu")
		(net "LPC_CPU_NODE1_LAD1_R")
	)
	(segment
		(start 61.19749 -86.636606)
		(end 61.544454 -86.98357)
		(width 0.1016)
		(layer "B.Cu")
		(net "LPC_CPU_NODE1_LAD1_R")
	)
	(segment
		(start 61.544454 -86.98357)
		(end 61.949584 -88.517476)
		(width 0.1016)
		(layer "B.Cu")
		(net "LPC_CPU_NODE1_LAD1_R")
	)
	(segment
		(start 62.652402 -92.070936)
		(end 62.296802 -91.050872)
		(width 0.1016)
		(layer "B.Cu")
		(net "LPC_CPU_NODE1_LAD1_R")
	)
	(segment
		(start 62.652402 -92.3671)
		(end 62.652402 -92.070936)
		(width 0.1016)
		(layer "B.Cu")
		(net "LPC_CPU_NODE1_LAD1_R")
	)
	(segment
		(start 61.949584 -88.517476)
		(end 61.949584 -90.179906)
		(width 0.1016)
		(layer "B.Cu")
		(net "LPC_CPU_NODE1_LAD1_R")
	)
	(segment
		(start 62.25032 -93.779594)
		(end 62.25032 -93.688408)
		(width 0.1016)
		(layer "B.Cu")
		(net "LPC_CPU_NODE1_LAD1_R")
	)
	(segment
		(start 60.11672 -95.913194)
		(end 62.25032 -93.779594)
		(width 0.1016)
		(layer "B.Cu")
		(net "LPC_CPU_NODE1_LAD1_R")
	)
	(segment
		(start 60.118498 -96.296734)
		(end 60.11672 -96.296734)
		(width 0.1016)
		(layer "B.Cu")
		(net "LPC_CPU_NODE1_LAD1_R")
	)
	(segment
		(start 61.015372 -85.85454)
		(end 61.19749 -86.036658)
		(width 0.1016)
		(layer "B.Cu")
		(net "LPC_CPU_NODE1_LAD1_R")
	)
	(segment
		(start 60.11672 -96.296734)
		(end 60.11672 -95.913194)
		(width 0.1016)
		(layer "B.Cu")
		(net "LPC_CPU_NODE1_LAD1_R")
	)
	(segment
		(start 62.25032 -93.688408)
		(end 62.652402 -92.3671)
		(width 0.1016)
		(layer "B.Cu")
		(net "LPC_CPU_NODE1_LAD1_R")
	)
	(segment
		(start 61.19749 -86.036658)
		(end 61.19749 -86.636606)
		(width 0.1016)
		(layer "B.Cu")
		(net "LPC_CPU_NODE1_LAD1_R")
	)
	(segment
		(start 61.949584 -90.179906)
		(end 62.295532 -91.050872)
		(width 0.1016)
		(layer "B.Cu")
		(net "LPC_CPU_NODE1_LAD1_R")
	)
	(segment
		(start 62.296802 -91.050872)
		(end 62.295532 -91.050872)
		(width 0.1016)
		(layer "B.Cu")
		(net "LPC_CPU_NODE1_LAD1_R")
	)
	(segment
		(start 65.715642 -67.741038)
		(end 65.715642 -67.748658)
		(width 0.1016)
		(layer "F.Cu")
		(net "M_DDR3_NODE1_ECC4")
	)
	(segment
		(start 65.715642 -67.748658)
		(end 65.342262 -68.122038)
		(width 0.1016)
		(layer "F.Cu")
		(net "M_DDR3_NODE1_ECC4")
	)
	(segment
		(start 61.650118 -29.149802)
		(end 61.650118 -27.013662)
		(width 0.1651)
		(layer "F.Cu")
		(net "M_DDR3_NODE1_ECC4")
	)
	(segment
		(start 61.650118 -27.013662)
		(end 61.699902 -26.963878)
		(width 0.1651)
		(layer "F.Cu")
		(net "M_DDR3_NODE1_ECC4")
	)
	(via
		(at 65.342262 -68.122038)
		(size 0.508)
		(drill 0.254)
		(layers "F.Cu" "B.Cu")
		(net "M_DDR3_NODE1_ECC4")
	)
	(via
		(at 61.699902 -26.963878)
		(size 0.508)
		(drill 0.254)
		(layers "F.Cu" "B.Cu")
		(net "M_DDR3_NODE1_ECC4")
	)
	(segment
		(start 61.298582 -31.46298)
		(end 61.547502 -31.46298)
		(width 0.2032)
		(layer "In7.Cu")
		(net "M_DDR3_NODE1_ECC4")
	)
	(segment
		(start 58.248042 -33.845754)
		(end 57.27192 -34.821876)
		(width 0.2032)
		(layer "In7.Cu")
		(net "M_DDR3_NODE1_ECC4")
	)
	(segment
		(start 55.644288 -39.273988)
		(end 55.938928 -39.273988)
		(width 0.2032)
		(layer "In7.Cu")
		(net "M_DDR3_NODE1_ECC4")
	)
	(segment
		(start 64.154304 -66.596006)
		(end 64.356488 -66.79819)
		(width 0.1016)
		(layer "In7.Cu")
		(net "M_DDR3_NODE1_ECC4")
	)
	(segment
		(start 62.608206 -63.991236)
		(end 62.80912 -63.991236)
		(width 0.1016)
		(layer "In7.Cu")
		(net "M_DDR3_NODE1_ECC4")
	)
	(segment
		(start 57.89676 -53.42001)
		(end 57.89676 -58.089038)
		(width 0.2032)
		(layer "In7.Cu")
		(net "M_DDR3_NODE1_ECC4")
	)
	(segment
		(start 60.075064 -60.660788)
		(end 61.20384 -61.789564)
		(width 0.1016)
		(layer "In7.Cu")
		(net "M_DDR3_NODE1_ECC4")
	)
	(segment
		(start 57.89676 -58.089038)
		(end 58.5216 -58.713878)
		(width 0.2032)
		(layer "In7.Cu")
		(net "M_DDR3_NODE1_ECC4")
	)
	(segment
		(start 61.898022 -27.161998)
		(end 61.898022 -28.426918)
		(width 0.2032)
		(layer "In7.Cu")
		(net "M_DDR3_NODE1_ECC4")
	)
	(segment
		(start 65.009014 -67.317366)
		(end 65.08369 -67.317366)
		(width 0.1016)
		(layer "In7.Cu")
		(net "M_DDR3_NODE1_ECC4")
	)
	(segment
		(start 55.938928 -39.273988)
		(end 56.147208 -39.482268)
		(width 0.2032)
		(layer "In7.Cu")
		(net "M_DDR3_NODE1_ECC4")
	)
	(segment
		(start 62.80912 -63.991236)
		(end 64.154304 -65.33642)
		(width 0.1016)
		(layer "In7.Cu")
		(net "M_DDR3_NODE1_ECC4")
	)
	(segment
		(start 61.547502 -31.46298)
		(end 61.755782 -31.67126)
		(width 0.2032)
		(layer "In7.Cu")
		(net "M_DDR3_NODE1_ECC4")
	)
	(segment
		(start 61.755782 -31.67126)
		(end 61.755782 -32.05734)
		(width 0.2032)
		(layer "In7.Cu")
		(net "M_DDR3_NODE1_ECC4")
	)
	(segment
		(start 61.090302 -31.2547)
		(end 61.298582 -31.46298)
		(width 0.2032)
		(layer "In7.Cu")
		(net "M_DDR3_NODE1_ECC4")
	)
	(segment
		(start 58.5216 -58.713878)
		(end 58.5216 -59.615832)
		(width 0.2032)
		(layer "In7.Cu")
		(net "M_DDR3_NODE1_ECC4")
	)
	(segment
		(start 65.342262 -67.575938)
		(end 65.342262 -68.122038)
		(width 0.1016)
		(layer "In7.Cu")
		(net "M_DDR3_NODE1_ECC4")
	)
	(segment
		(start 59.874404 -60.094114)
		(end 60.075064 -60.294774)
		(width 0.2032)
		(layer "In7.Cu")
		(net "M_DDR3_NODE1_ECC4")
	)
	(segment
		(start 58.999882 -60.094114)
		(end 59.874404 -60.094114)
		(width 0.2032)
		(layer "In7.Cu")
		(net "M_DDR3_NODE1_ECC4")
	)
	(segment
		(start 61.755782 -28.569158)
		(end 61.755782 -29.1211)
		(width 0.2032)
		(layer "In7.Cu")
		(net "M_DDR3_NODE1_ECC4")
	)
	(segment
		(start 58.5216 -59.615832)
		(end 58.999882 -60.094114)
		(width 0.2032)
		(layer "In7.Cu")
		(net "M_DDR3_NODE1_ECC4")
	)
	(segment
		(start 53.81498 -49.33823)
		(end 57.89676 -53.42001)
		(width 0.2032)
		(layer "In7.Cu")
		(net "M_DDR3_NODE1_ECC4")
	)
	(segment
		(start 57.27192 -36.640516)
		(end 53.815488 -40.096948)
		(width 0.2032)
		(layer "In7.Cu")
		(net "M_DDR3_NODE1_ECC4")
	)
	(segment
		(start 61.755782 -29.1211)
		(end 61.547502 -29.32938)
		(width 0.2032)
		(layer "In7.Cu")
		(net "M_DDR3_NODE1_ECC4")
	)
	(segment
		(start 61.20384 -62.58687)
		(end 62.608206 -63.991236)
		(width 0.1016)
		(layer "In7.Cu")
		(net "M_DDR3_NODE1_ECC4")
	)
	(segment
		(start 57.27192 -34.821876)
		(end 57.27192 -36.640516)
		(width 0.2032)
		(layer "In7.Cu")
		(net "M_DDR3_NODE1_ECC4")
	)
	(segment
		(start 64.154304 -65.33642)
		(end 64.154304 -66.596006)
		(width 0.1016)
		(layer "In7.Cu")
		(net "M_DDR3_NODE1_ECC4")
	)
	(segment
		(start 60.075064 -60.294774)
		(end 60.075064 -60.660788)
		(width 0.1016)
		(layer "In7.Cu")
		(net "M_DDR3_NODE1_ECC4")
	)
	(segment
		(start 60.6425 -29.32938)
		(end 60.43422 -29.53766)
		(width 0.2032)
		(layer "In7.Cu")
		(net "M_DDR3_NODE1_ECC4")
	)
	(segment
		(start 53.815488 -40.096948)
		(end 53.815488 -40.391588)
		(width 0.2032)
		(layer "In7.Cu")
		(net "M_DDR3_NODE1_ECC4")
	)
	(segment
		(start 59.967368 -33.845754)
		(end 58.248042 -33.845754)
		(width 0.2032)
		(layer "In7.Cu")
		(net "M_DDR3_NODE1_ECC4")
	)
	(segment
		(start 56.147208 -39.482268)
		(end 56.147208 -39.776908)
		(width 0.2032)
		(layer "In7.Cu")
		(net "M_DDR3_NODE1_ECC4")
	)
	(segment
		(start 61.547502 -30.75178)
		(end 61.298582 -30.75178)
		(width 0.2032)
		(layer "In7.Cu")
		(net "M_DDR3_NODE1_ECC4")
	)
	(segment
		(start 54.023768 -40.599868)
		(end 54.318408 -40.599868)
		(width 0.2032)
		(layer "In7.Cu")
		(net "M_DDR3_NODE1_ECC4")
	)
	(segment
		(start 61.20384 -61.789564)
		(end 61.20384 -62.58687)
		(width 0.1016)
		(layer "In7.Cu")
		(net "M_DDR3_NODE1_ECC4")
	)
	(segment
		(start 61.898022 -28.426918)
		(end 61.755782 -28.569158)
		(width 0.2032)
		(layer "In7.Cu")
		(net "M_DDR3_NODE1_ECC4")
	)
	(segment
		(start 56.147208 -39.776908)
		(end 53.81498 -42.109136)
		(width 0.2032)
		(layer "In7.Cu")
		(net "M_DDR3_NODE1_ECC4")
	)
	(segment
		(start 53.815488 -40.391588)
		(end 54.023768 -40.599868)
		(width 0.2032)
		(layer "In7.Cu")
		(net "M_DDR3_NODE1_ECC4")
	)
	(segment
		(start 61.090302 -30.96006)
		(end 61.090302 -31.2547)
		(width 0.2032)
		(layer "In7.Cu")
		(net "M_DDR3_NODE1_ECC4")
	)
	(segment
		(start 61.699902 -26.963878)
		(end 61.898022 -27.161998)
		(width 0.2032)
		(layer "In7.Cu")
		(net "M_DDR3_NODE1_ECC4")
	)
	(segment
		(start 64.489838 -66.79819)
		(end 65.009014 -67.317366)
		(width 0.1016)
		(layer "In7.Cu")
		(net "M_DDR3_NODE1_ECC4")
	)
	(segment
		(start 61.755782 -32.05734)
		(end 59.967368 -33.845754)
		(width 0.2032)
		(layer "In7.Cu")
		(net "M_DDR3_NODE1_ECC4")
	)
	(segment
		(start 61.547502 -29.32938)
		(end 60.6425 -29.32938)
		(width 0.2032)
		(layer "In7.Cu")
		(net "M_DDR3_NODE1_ECC4")
	)
	(segment
		(start 54.318408 -40.599868)
		(end 55.644288 -39.273988)
		(width 0.2032)
		(layer "In7.Cu")
		(net "M_DDR3_NODE1_ECC4")
	)
	(segment
		(start 65.08369 -67.317366)
		(end 65.342262 -67.575938)
		(width 0.1016)
		(layer "In7.Cu")
		(net "M_DDR3_NODE1_ECC4")
	)
	(segment
		(start 61.755782 -30.24886)
		(end 61.755782 -30.5435)
		(width 0.2032)
		(layer "In7.Cu")
		(net "M_DDR3_NODE1_ECC4")
	)
	(segment
		(start 64.356488 -66.79819)
		(end 64.489838 -66.79819)
		(width 0.1016)
		(layer "In7.Cu")
		(net "M_DDR3_NODE1_ECC4")
	)
	(segment
		(start 61.547502 -30.04058)
		(end 61.755782 -30.24886)
		(width 0.2032)
		(layer "In7.Cu")
		(net "M_DDR3_NODE1_ECC4")
	)
	(segment
		(start 61.298582 -30.75178)
		(end 61.090302 -30.96006)
		(width 0.2032)
		(layer "In7.Cu")
		(net "M_DDR3_NODE1_ECC4")
	)
	(segment
		(start 60.6425 -30.04058)
		(end 61.547502 -30.04058)
		(width 0.2032)
		(layer "In7.Cu")
		(net "M_DDR3_NODE1_ECC4")
	)
	(segment
		(start 60.43422 -29.53766)
		(end 60.43422 -29.8323)
		(width 0.2032)
		(layer "In7.Cu")
		(net "M_DDR3_NODE1_ECC4")
	)
	(segment
		(start 61.755782 -30.5435)
		(end 61.547502 -30.75178)
		(width 0.2032)
		(layer "In7.Cu")
		(net "M_DDR3_NODE1_ECC4")
	)
	(segment
		(start 60.43422 -29.8323)
		(end 60.6425 -30.04058)
		(width 0.2032)
		(layer "In7.Cu")
		(net "M_DDR3_NODE1_ECC4")
	)
	(segment
		(start 53.81498 -42.109136)
		(end 53.81498 -49.33823)
		(width 0.2032)
		(layer "In7.Cu")
		(net "M_DDR3_NODE1_ECC4")
	)
	(segment
		(start 153.958036 -136.718802)
		(end 153.489406 -137.187432)
		(width 0.1016)
		(layer "F.Cu")
		(net "RST_BTN_NODE1_C_L")
	)
	(segment
		(start 153.155904 -137.187432)
		(end 153.155904 -138.203432)
		(width 0.1016)
		(layer "F.Cu")
		(net "RST_BTN_NODE1_C_L")
	)
	(segment
		(start 154.7622 -136.718802)
		(end 153.958036 -136.718802)
		(width 0.1016)
		(layer "F.Cu")
		(net "RST_BTN_NODE1_C_L")
	)
	(segment
		(start 155.039568 -133.849618)
		(end 155.90774 -134.71779)
		(width 0.1016)
		(layer "F.Cu")
		(net "RST_BTN_NODE1_C_L")
	)
	(segment
		(start 155.90774 -136.43737)
		(end 155.82138 -136.52373)
		(width 0.1016)
		(layer "F.Cu")
		(net "RST_BTN_NODE1_C_L")
	)
	(segment
		(start 155.90774 -134.71779)
		(end 155.90774 -136.43737)
		(width 0.1016)
		(layer "F.Cu")
		(net "RST_BTN_NODE1_C_L")
	)
	(segment
		(start 155.82138 -136.52373)
		(end 155.626308 -136.718802)
		(width 0.1016)
		(layer "F.Cu")
		(net "RST_BTN_NODE1_C_L")
	)
	(segment
		(start 153.489406 -137.187432)
		(end 153.155904 -137.187432)
		(width 0.1016)
		(layer "F.Cu")
		(net "RST_BTN_NODE1_C_L")
	)
	(segment
		(start 155.626308 -136.718802)
		(end 154.7622 -136.718802)
		(width 0.1016)
		(layer "F.Cu")
		(net "RST_BTN_NODE1_C_L")
	)
	(via
		(at 155.82138 -136.52373)
		(size 0.508)
		(drill 0.254)
		(layers "F.Cu" "B.Cu")
		(net "RST_BTN_NODE1_C_L")
	)
	(segment
		(start 125.464316 -64.918336)
		(end 128.05664 -64.918336)
		(width 0.1016)
		(layer "F.Cu")
		(net "N21116716")
	)
	(segment
		(start 133.93674 -66.188336)
		(end 132.737352 -66.188336)
		(width 0.1016)
		(layer "F.Cu")
		(net "N21116716")
	)
	(segment
		(start 129.948432 -66.188336)
		(end 132.737352 -66.188336)
		(width 0.1016)
		(layer "F.Cu")
		(net "N21116716")
	)
	(segment
		(start 134.22884 -63.142876)
		(end 134.22884 -65.896236)
		(width 0.1016)
		(layer "F.Cu")
		(net "N21116716")
	)
	(segment
		(start 134.22884 -65.896236)
		(end 133.93674 -66.188336)
		(width 0.1016)
		(layer "F.Cu")
		(net "N21116716")
	)
	(segment
		(start 133.26745 -61.330332)
		(end 133.26745 -62.181486)
		(width 0.1016)
		(layer "F.Cu")
		(net "N21116716")
	)
	(segment
		(start 128.678432 -64.918336)
		(end 129.948432 -66.188336)
		(width 0.1016)
		(layer "F.Cu")
		(net "N21116716")
	)
	(segment
		(start 128.05664 -64.918336)
		(end 128.678432 -64.918336)
		(width 0.1016)
		(layer "F.Cu")
		(net "N21116716")
	)
	(segment
		(start 133.26745 -62.181486)
		(end 134.22884 -63.142876)
		(width 0.1016)
		(layer "F.Cu")
		(net "N21116716")
	)
	(via
		(at 128.05664 -64.918336)
		(size 0.508)
		(drill 0.254)
		(layers "F.Cu" "B.Cu")
		(net "N21116716")
	)
	(segment
		(start 151.351996 -60.01893)
		(end 151.224996 -60.14593)
		(width 0.1016)
		(layer "F.Cu")
		(net "NODE1_USB_TESTMODE")
	)
	(segment
		(start 150.181056 -60.75807)
		(end 150.793196 -60.14593)
		(width 0.1016)
		(layer "F.Cu")
		(net "NODE1_USB_TESTMODE")
	)
	(segment
		(start 150.793196 -60.14593)
		(end 151.224996 -60.14593)
		(width 0.1016)
		(layer "F.Cu")
		(net "NODE1_USB_TESTMODE")
	)
	(segment
		(start 152.145746 -60.01893)
		(end 151.351996 -60.01893)
		(width 0.1016)
		(layer "F.Cu")
		(net "NODE1_USB_TESTMODE")
	)
	(segment
		(start 149.57171 -60.75807)
		(end 150.181056 -60.75807)
		(width 0.1016)
		(layer "F.Cu")
		(net "NODE1_USB_TESTMODE")
	)
	(via
		(at 151.224996 -60.14593)
		(size 0.508)
		(drill 0.254)
		(layers "F.Cu" "B.Cu")
		(net "NODE1_USB_TESTMODE")
	)
	(segment
		(start 24.35352 -39.331392)
		(end 19.642836 -39.331392)
		(width 0.1016)
		(layer "F.Cu")
		(net "SMB_BMC_NODE1_DDC_DAT")
	)
	(segment
		(start 62.141862 -143.259556)
		(end 62.14364 -143.259556)
		(width 0.1016)
		(layer "F.Cu")
		(net "SMB_BMC_NODE1_DDC_DAT")
	)
	(segment
		(start 24.750014 -47.199296)
		(end 23.736046 -48.213264)
		(width 0.1016)
		(layer "F.Cu")
		(net "SMB_BMC_NODE1_DDC_DAT")
	)
	(segment
		(start 25.0952 -40.073072)
		(end 24.35352 -39.331392)
		(width 0.1016)
		(layer "F.Cu")
		(net "SMB_BMC_NODE1_DDC_DAT")
	)
	(segment
		(start 25.0952 -42.59199)
		(end 25.0952 -44.147486)
		(width 0.1016)
		(layer "F.Cu")
		(net "SMB_BMC_NODE1_DDC_DAT")
	)
	(segment
		(start 19.642836 -39.331392)
		(end 19.31162 -39.662608)
		(width 0.1016)
		(layer "F.Cu")
		(net "SMB_BMC_NODE1_DDC_DAT")
	)
	(segment
		(start 25.973278 -44.500546)
		(end 25.973278 -46.48708)
		(width 0.1016)
		(layer "F.Cu")
		(net "SMB_BMC_NODE1_DDC_DAT")
	)
	(segment
		(start 62.44844 -143.564356)
		(end 62.44844 -146.062446)
		(width 0.1016)
		(layer "F.Cu")
		(net "SMB_BMC_NODE1_DDC_DAT")
	)
	(segment
		(start 25.0952 -44.147486)
		(end 25.44826 -44.500546)
		(width 0.1016)
		(layer "F.Cu")
		(net "SMB_BMC_NODE1_DDC_DAT")
	)
	(segment
		(start 25.261062 -47.199296)
		(end 24.750014 -47.199296)
		(width 0.1016)
		(layer "F.Cu")
		(net "SMB_BMC_NODE1_DDC_DAT")
	)
	(segment
		(start 62.14364 -143.259556)
		(end 62.44844 -143.564356)
		(width 0.1016)
		(layer "F.Cu")
		(net "SMB_BMC_NODE1_DDC_DAT")
	)
	(segment
		(start 25.44826 -44.500546)
		(end 25.973278 -44.500546)
		(width 0.1016)
		(layer "F.Cu")
		(net "SMB_BMC_NODE1_DDC_DAT")
	)
	(segment
		(start 25.973278 -46.48708)
		(end 25.261062 -47.199296)
		(width 0.1016)
		(layer "F.Cu")
		(net "SMB_BMC_NODE1_DDC_DAT")
	)
	(segment
		(start 25.0952 -42.59199)
		(end 25.0952 -40.073072)
		(width 0.1016)
		(layer "F.Cu")
		(net "SMB_BMC_NODE1_DDC_DAT")
	)
	(via
		(at 19.31162 -39.662608)
		(size 0.508)
		(drill 0.254)
		(layers "F.Cu" "B.Cu")
		(net "SMB_BMC_NODE1_DDC_DAT")
	)
	(via
		(at 62.44844 -146.062446)
		(size 0.508)
		(drill 0.254)
		(layers "F.Cu" "B.Cu")
		(net "SMB_BMC_NODE1_DDC_DAT")
	)
	(segment
		(start 17.171162 -72.446896)
		(end 15.16126 -74.456798)
		(width 0.1143)
		(layer "In6.Cu")
		(net "SMB_BMC_NODE1_DDC_DAT")
	)
	(segment
		(start 6.0452 -136.58215)
		(end 9.762236 -140.299186)
		(width 0.1143)
		(layer "In6.Cu")
		(net "SMB_BMC_NODE1_DDC_DAT")
	)
	(segment
		(start 30.087062 -142.235936)
		(end 35.780726 -147.9296)
		(width 0.1143)
		(layer "In6.Cu")
		(net "SMB_BMC_NODE1_DDC_DAT")
	)
	(segment
		(start 16.633444 -141.933422)
		(end 19.23034 -141.933422)
		(width 0.1143)
		(layer "In6.Cu")
		(net "SMB_BMC_NODE1_DDC_DAT")
	)
	(segment
		(start 21.30298 -142.614142)
		(end 21.958554 -142.614142)
		(width 0.1143)
		(layer "In6.Cu")
		(net "SMB_BMC_NODE1_DDC_DAT")
	)
	(segment
		(start 15.63878 -41.765982)
		(end 15.63878 -56.306212)
		(width 0.1143)
		(layer "In6.Cu")
		(net "SMB_BMC_NODE1_DDC_DAT")
	)
	(segment
		(start 22.33676 -142.235936)
		(end 30.087062 -142.235936)
		(width 0.1143)
		(layer "In6.Cu")
		(net "SMB_BMC_NODE1_DDC_DAT")
	)
	(segment
		(start 38.062154 -147.9296)
		(end 41.12768 -150.995126)
		(width 0.1143)
		(layer "In6.Cu")
		(net "SMB_BMC_NODE1_DDC_DAT")
	)
	(segment
		(start 21.958554 -142.614142)
		(end 22.33676 -142.235936)
		(width 0.1143)
		(layer "In6.Cu")
		(net "SMB_BMC_NODE1_DDC_DAT")
	)
	(segment
		(start 6.0452 -96.674686)
		(end 6.0452 -136.58215)
		(width 0.1143)
		(layer "In6.Cu")
		(net "SMB_BMC_NODE1_DDC_DAT")
	)
	(segment
		(start 17.742154 -39.662608)
		(end 15.63878 -41.765982)
		(width 0.1143)
		(layer "In6.Cu")
		(net "SMB_BMC_NODE1_DDC_DAT")
	)
	(segment
		(start 20.1676 -142.870682)
		(end 21.04644 -142.870682)
		(width 0.1143)
		(layer "In6.Cu")
		(net "SMB_BMC_NODE1_DDC_DAT")
	)
	(segment
		(start 35.780726 -147.9296)
		(end 38.062154 -147.9296)
		(width 0.1143)
		(layer "In6.Cu")
		(net "SMB_BMC_NODE1_DDC_DAT")
	)
	(segment
		(start 15.16126 -87.519764)
		(end 11.54684 -91.134184)
		(width 0.1143)
		(layer "In6.Cu")
		(net "SMB_BMC_NODE1_DDC_DAT")
	)
	(segment
		(start 21.04644 -142.870682)
		(end 21.30298 -142.614142)
		(width 0.1143)
		(layer "In6.Cu")
		(net "SMB_BMC_NODE1_DDC_DAT")
	)
	(segment
		(start 59.704478 -149.251924)
		(end 62.44844 -146.507962)
		(width 0.1143)
		(layer "In6.Cu")
		(net "SMB_BMC_NODE1_DDC_DAT")
	)
	(segment
		(start 62.44844 -146.507962)
		(end 62.44844 -146.062446)
		(width 0.1143)
		(layer "In6.Cu")
		(net "SMB_BMC_NODE1_DDC_DAT")
	)
	(segment
		(start 12.33678 -140.804138)
		(end 15.50416 -140.804138)
		(width 0.1143)
		(layer "In6.Cu")
		(net "SMB_BMC_NODE1_DDC_DAT")
	)
	(segment
		(start 15.50416 -140.804138)
		(end 16.633444 -141.933422)
		(width 0.1143)
		(layer "In6.Cu")
		(net "SMB_BMC_NODE1_DDC_DAT")
	)
	(segment
		(start 15.16126 -74.456798)
		(end 15.16126 -87.519764)
		(width 0.1143)
		(layer "In6.Cu")
		(net "SMB_BMC_NODE1_DDC_DAT")
	)
	(segment
		(start 15.63878 -56.306212)
		(end 17.171162 -57.838594)
		(width 0.1143)
		(layer "In6.Cu")
		(net "SMB_BMC_NODE1_DDC_DAT")
	)
	(segment
		(start 19.31162 -39.662608)
		(end 17.742154 -39.662608)
		(width 0.1143)
		(layer "In6.Cu")
		(net "SMB_BMC_NODE1_DDC_DAT")
	)
	(segment
		(start 55.939436 -149.251924)
		(end 59.704478 -149.251924)
		(width 0.1143)
		(layer "In6.Cu")
		(net "SMB_BMC_NODE1_DDC_DAT")
	)
	(segment
		(start 19.23034 -141.933422)
		(end 20.1676 -142.870682)
		(width 0.1143)
		(layer "In6.Cu")
		(net "SMB_BMC_NODE1_DDC_DAT")
	)
	(segment
		(start 11.54684 -91.134184)
		(end 11.54684 -91.175332)
		(width 0.1143)
		(layer "In6.Cu")
		(net "SMB_BMC_NODE1_DDC_DAT")
	)
	(segment
		(start 11.831828 -140.299186)
		(end 12.33678 -140.804138)
		(width 0.1143)
		(layer "In6.Cu")
		(net "SMB_BMC_NODE1_DDC_DAT")
	)
	(segment
		(start 41.12768 -150.995126)
		(end 49.614836 -150.995126)
		(width 0.1143)
		(layer "In6.Cu")
		(net "SMB_BMC_NODE1_DDC_DAT")
	)
	(segment
		(start 9.762236 -140.299186)
		(end 11.831828 -140.299186)
		(width 0.1143)
		(layer "In6.Cu")
		(net "SMB_BMC_NODE1_DDC_DAT")
	)
	(segment
		(start 11.54684 -91.175332)
		(end 6.0452 -96.674686)
		(width 0.1143)
		(layer "In6.Cu")
		(net "SMB_BMC_NODE1_DDC_DAT")
	)
	(segment
		(start 17.171162 -57.838594)
		(end 17.171162 -72.446896)
		(width 0.1143)
		(layer "In6.Cu")
		(net "SMB_BMC_NODE1_DDC_DAT")
	)
	(segment
		(start 54.42585 -150.76551)
		(end 55.939436 -149.251924)
		(width 0.1143)
		(layer "In6.Cu")
		(net "SMB_BMC_NODE1_DDC_DAT")
	)
	(segment
		(start 49.844452 -150.76551)
		(end 54.42585 -150.76551)
		(width 0.1143)
		(layer "In6.Cu")
		(net "SMB_BMC_NODE1_DDC_DAT")
	)
	(segment
		(start 49.614836 -150.995126)
		(end 49.844452 -150.76551)
		(width 0.1143)
		(layer "In6.Cu")
		(net "SMB_BMC_NODE1_DDC_DAT")
	)
	(segment
		(start 50.974498 -65.10147)
		(end 51.048158 -65.10147)
		(width 0.1016)
		(layer "F.Cu")
		(net "M1_DQ_NODE1_DQ3")
	)
	(segment
		(start 44.550076 -22.500844)
		(end 44.550076 -20.94992)
		(width 0.1651)
		(layer "F.Cu")
		(net "M1_DQ_NODE1_DQ3")
	)
	(segment
		(start 50.62093 -65.455038)
		(end 50.974498 -65.10147)
		(width 0.1016)
		(layer "F.Cu")
		(net "M1_DQ_NODE1_DQ3")
	)
	(segment
		(start 44.121832 -22.929088)
		(end 44.550076 -22.500844)
		(width 0.1651)
		(layer "F.Cu")
		(net "M1_DQ_NODE1_DQ3")
	)
	(segment
		(start 44.1706 -24.806148)
		(end 44.121832 -24.75738)
		(width 0.1651)
		(layer "F.Cu")
		(net "M1_DQ_NODE1_DQ3")
	)
	(segment
		(start 44.121832 -24.75738)
		(end 44.121832 -22.929088)
		(width 0.1651)
		(layer "F.Cu")
		(net "M1_DQ_NODE1_DQ3")
	)
	(segment
		(start 50.525426 -65.455038)
		(end 50.62093 -65.455038)
		(width 0.1016)
		(layer "F.Cu")
		(net "M1_DQ_NODE1_DQ3")
	)
	(via
		(at 44.1706 -24.806148)
		(size 0.508)
		(drill 0.254)
		(layers "F.Cu" "B.Cu")
		(net "M1_DQ_NODE1_DQ3")
	)
	(via
		(at 51.048158 -65.10147)
		(size 0.508)
		(drill 0.254)
		(layers "F.Cu" "B.Cu")
		(net "M1_DQ_NODE1_DQ3")
	)
	(segment
		(start 36.69792 -52.014628)
		(end 36.69792 -47.795434)
		(width 0.2032)
		(layer "In7.Cu")
		(net "M1_DQ_NODE1_DQ3")
	)
	(segment
		(start 50.27676 -63.54445)
		(end 50.27676 -64.028066)
		(width 0.1016)
		(layer "In7.Cu")
		(net "M1_DQ_NODE1_DQ3")
	)
	(segment
		(start 48.03394 -59.627516)
		(end 48.65878 -60.252356)
		(width 0.1016)
		(layer "In7.Cu")
		(net "M1_DQ_NODE1_DQ3")
	)
	(segment
		(start 42.239946 -54.059582)
		(end 46.0502 -57.869836)
		(width 0.2032)
		(layer "In7.Cu")
		(net "M1_DQ_NODE1_DQ3")
	)
	(segment
		(start 44.2341 -25.871932)
		(end 45.105574 -26.743406)
		(width 0.2032)
		(layer "In7.Cu")
		(net "M1_DQ_NODE1_DQ3")
	)
	(segment
		(start 36.195 -52.222908)
		(end 36.48964 -52.222908)
		(width 0.2032)
		(layer "In7.Cu")
		(net "M1_DQ_NODE1_DQ3")
	)
	(segment
		(start 37.42182 -47.808134)
		(end 37.42182 -52.10556)
		(width 0.2032)
		(layer "In7.Cu")
		(net "M1_DQ_NODE1_DQ3")
	)
	(segment
		(start 46.966886 -59.043316)
		(end 47.551086 -59.627516)
		(width 0.2032)
		(layer "In7.Cu")
		(net "M1_DQ_NODE1_DQ3")
	)
	(segment
		(start 39.375842 -54.059582)
		(end 42.239946 -54.059582)
		(width 0.2032)
		(layer "In7.Cu")
		(net "M1_DQ_NODE1_DQ3")
	)
	(segment
		(start 44.1706 -24.806148)
		(end 44.2341 -24.869648)
		(width 0.2032)
		(layer "In7.Cu")
		(net "M1_DQ_NODE1_DQ3")
	)
	(segment
		(start 36.9062 -47.587154)
		(end 37.20084 -47.587154)
		(width 0.2032)
		(layer "In7.Cu")
		(net "M1_DQ_NODE1_DQ3")
	)
	(segment
		(start 49.30648 -62.57417)
		(end 50.27676 -63.54445)
		(width 0.1016)
		(layer "In7.Cu")
		(net "M1_DQ_NODE1_DQ3")
	)
	(segment
		(start 36.48964 -52.222908)
		(end 36.69792 -52.014628)
		(width 0.2032)
		(layer "In7.Cu")
		(net "M1_DQ_NODE1_DQ3")
	)
	(segment
		(start 45.62729 -32.026352)
		(end 45.62729 -33.702244)
		(width 0.2032)
		(layer "In7.Cu")
		(net "M1_DQ_NODE1_DQ3")
	)
	(segment
		(start 35.98672 -42.925746)
		(end 35.98672 -52.014628)
		(width 0.2032)
		(layer "In7.Cu")
		(net "M1_DQ_NODE1_DQ3")
	)
	(segment
		(start 44.2341 -24.869648)
		(end 44.2341 -25.871932)
		(width 0.2032)
		(layer "In7.Cu")
		(net "M1_DQ_NODE1_DQ3")
	)
	(segment
		(start 45.105574 -26.743406)
		(end 45.105574 -28.093924)
		(width 0.2032)
		(layer "In7.Cu")
		(net "M1_DQ_NODE1_DQ3")
	)
	(segment
		(start 46.06798 -29.05633)
		(end 46.06798 -31.585662)
		(width 0.2032)
		(layer "In7.Cu")
		(net "M1_DQ_NODE1_DQ3")
	)
	(segment
		(start 46.0502 -57.869836)
		(end 46.0502 -58.735214)
		(width 0.2032)
		(layer "In7.Cu")
		(net "M1_DQ_NODE1_DQ3")
	)
	(segment
		(start 35.98672 -52.014628)
		(end 36.195 -52.222908)
		(width 0.2032)
		(layer "In7.Cu")
		(net "M1_DQ_NODE1_DQ3")
	)
	(segment
		(start 50.27676 -64.028066)
		(end 51.048158 -64.799464)
		(width 0.1016)
		(layer "In7.Cu")
		(net "M1_DQ_NODE1_DQ3")
	)
	(segment
		(start 48.65878 -60.252356)
		(end 48.65878 -62.168024)
		(width 0.1016)
		(layer "In7.Cu")
		(net "M1_DQ_NODE1_DQ3")
	)
	(segment
		(start 37.42182 -52.10556)
		(end 39.375842 -54.059582)
		(width 0.2032)
		(layer "In7.Cu")
		(net "M1_DQ_NODE1_DQ3")
	)
	(segment
		(start 46.358302 -59.043316)
		(end 46.966886 -59.043316)
		(width 0.2032)
		(layer "In7.Cu")
		(net "M1_DQ_NODE1_DQ3")
	)
	(segment
		(start 36.93541 -41.977056)
		(end 35.98672 -42.925746)
		(width 0.2032)
		(layer "In7.Cu")
		(net "M1_DQ_NODE1_DQ3")
	)
	(segment
		(start 37.20084 -47.587154)
		(end 37.42182 -47.808134)
		(width 0.2032)
		(layer "In7.Cu")
		(net "M1_DQ_NODE1_DQ3")
	)
	(segment
		(start 46.0502 -58.735214)
		(end 46.358302 -59.043316)
		(width 0.2032)
		(layer "In7.Cu")
		(net "M1_DQ_NODE1_DQ3")
	)
	(segment
		(start 37.352478 -41.977056)
		(end 36.93541 -41.977056)
		(width 0.2032)
		(layer "In7.Cu")
		(net "M1_DQ_NODE1_DQ3")
	)
	(segment
		(start 45.62729 -33.702244)
		(end 37.352478 -41.977056)
		(width 0.2032)
		(layer "In7.Cu")
		(net "M1_DQ_NODE1_DQ3")
	)
	(segment
		(start 45.105574 -28.093924)
		(end 46.06798 -29.05633)
		(width 0.2032)
		(layer "In7.Cu")
		(net "M1_DQ_NODE1_DQ3")
	)
	(segment
		(start 48.65878 -62.168024)
		(end 49.064926 -62.57417)
		(width 0.1016)
		(layer "In7.Cu")
		(net "M1_DQ_NODE1_DQ3")
	)
	(segment
		(start 49.064926 -62.57417)
		(end 49.30648 -62.57417)
		(width 0.1016)
		(layer "In7.Cu")
		(net "M1_DQ_NODE1_DQ3")
	)
	(segment
		(start 46.06798 -31.585662)
		(end 45.62729 -32.026352)
		(width 0.2032)
		(layer "In7.Cu")
		(net "M1_DQ_NODE1_DQ3")
	)
	(segment
		(start 36.69792 -47.795434)
		(end 36.9062 -47.587154)
		(width 0.2032)
		(layer "In7.Cu")
		(net "M1_DQ_NODE1_DQ3")
	)
	(segment
		(start 47.551086 -59.627516)
		(end 48.03394 -59.627516)
		(width 0.2032)
		(layer "In7.Cu")
		(net "M1_DQ_NODE1_DQ3")
	)
	(segment
		(start 51.048158 -64.799464)
		(end 51.048158 -65.10147)
		(width 0.1016)
		(layer "In7.Cu")
		(net "M1_DQ_NODE1_DQ3")
	)
	(via
		(at 190.175642 -115.654328)
		(size 0.508)
		(drill 0.254)
		(layers "F.Cu" "B.Cu")
		(net "P12V_NODE1_PWRGD_EN")
	)
	(segment
		(start 163.770056 -148.547328)
		(end 163.770056 -146.900646)
		(width 0.1016)
		(layer "F.Cu")
		(net "N21357373")
	)
	(segment
		(start 163.770056 -146.900646)
		(end 164.30498 -146.365722)
		(width 0.1016)
		(layer "F.Cu")
		(net "N21357373")
	)
	(via
		(at 164.30498 -146.365722)
		(size 0.508)
		(drill 0.254)
		(layers "F.Cu" "B.Cu")
		(net "N21357373")
	)
	(segment
		(start 165.462204 -145.208498)
		(end 164.30498 -146.365722)
		(width 0.1016)
		(layer "B.Cu")
		(net "N21357373")
	)
	(segment
		(start 166.151814 -145.208498)
		(end 165.462204 -145.208498)
		(width 0.1016)
		(layer "B.Cu")
		(net "N21357373")
	)
	(segment
		(start 138.350498 -59.688222)
		(end 138.679174 -60.016898)
		(width 0.1016)
		(layer "F.Cu")
		(net "SATA_NODE1_GPIO2")
	)
	(segment
		(start 140.68933 -61.15812)
		(end 139.820396 -61.15812)
		(width 0.1016)
		(layer "F.Cu")
		(net "SATA_NODE1_GPIO2")
	)
	(segment
		(start 139.820396 -61.15812)
		(end 138.679174 -60.016898)
		(width 0.1016)
		(layer "F.Cu")
		(net "SATA_NODE1_GPIO2")
	)
	(segment
		(start 137.993628 -60.704222)
		(end 137.993628 -59.688222)
		(width 0.1016)
		(layer "F.Cu")
		(net "SATA_NODE1_GPIO2")
	)
	(segment
		(start 137.993628 -59.688222)
		(end 138.350498 -59.688222)
		(width 0.1016)
		(layer "F.Cu")
		(net "SATA_NODE1_GPIO2")
	)
	(via
		(at 138.679174 -60.016898)
		(size 0.508)
		(drill 0.254)
		(layers "F.Cu" "B.Cu")
		(net "SATA_NODE1_GPIO2")
	)
	(segment
		(start 70.941692 -143.960596)
		(end 70.941692 -143.259556)
		(width 0.1016)
		(layer "F.Cu")
		(net "BMC_NODE1_JTAG_TRST")
	)
	(segment
		(start 71.706486 -148.076412)
		(end 71.706486 -146.984974)
		(width 0.1016)
		(layer "F.Cu")
		(net "BMC_NODE1_JTAG_TRST")
	)
	(segment
		(start 71.706486 -146.984974)
		(end 72.52462 -146.16684)
		(width 0.1016)
		(layer "F.Cu")
		(net "BMC_NODE1_JTAG_TRST")
	)
	(segment
		(start 72.52462 -145.542508)
		(end 71.199248 -144.217136)
		(width 0.1016)
		(layer "F.Cu")
		(net "BMC_NODE1_JTAG_TRST")
	)
	(segment
		(start 72.52462 -146.16684)
		(end 72.52462 -145.542508)
		(width 0.1016)
		(layer "F.Cu")
		(net "BMC_NODE1_JTAG_TRST")
	)
	(segment
		(start 71.198232 -144.217136)
		(end 70.941692 -143.960596)
		(width 0.1016)
		(layer "F.Cu")
		(net "BMC_NODE1_JTAG_TRST")
	)
	(segment
		(start 71.199248 -144.217136)
		(end 71.198232 -144.217136)
		(width 0.1016)
		(layer "F.Cu")
		(net "BMC_NODE1_JTAG_TRST")
	)
	(via
		(at 72.52462 -145.542508)
		(size 0.508)
		(drill 0.254)
		(layers "F.Cu" "B.Cu")
		(net "BMC_NODE1_JTAG_TRST")
	)
	(segment
		(start 57.503314 -86.143846)
		(end 56.764682 -85.405214)
		(width 0.1016)
		(layer "F.Cu")
		(net "PD_CPU_NODE1_DFX_GPIO_GRP1_7")
	)
	(segment
		(start 56.764682 -85.405214)
		(end 56.66613 -85.405214)
		(width 0.1016)
		(layer "F.Cu")
		(net "PD_CPU_NODE1_DFX_GPIO_GRP1_7")
	)
	(segment
		(start 57.530746 -86.143846)
		(end 57.503314 -86.143846)
		(width 0.1016)
		(layer "F.Cu")
		(net "PD_CPU_NODE1_DFX_GPIO_GRP1_7")
	)
	(via
		(at 56.66613 -85.405214)
		(size 0.508)
		(drill 0.254)
		(layers "F.Cu" "B.Cu")
		(net "PD_CPU_NODE1_DFX_GPIO_GRP1_7")
	)
	(via
		(at 52.966366 -93.162882)
		(size 0.6604)
		(drill 0.3302)
		(layers "F.Cu" "B.Cu")
		(net "PD_CPU_NODE1_DFX_GPIO_GRP1_7")
	)
	(segment
		(start 56.66613 -85.405214)
		(end 55.795418 -86.275926)
		(width 0.1016)
		(layer "B.Cu")
		(net "PD_CPU_NODE1_DFX_GPIO_GRP1_7")
	)
	(segment
		(start 54.779164 -91.504008)
		(end 54.233572 -91.504008)
		(width 0.1016)
		(layer "B.Cu")
		(net "PD_CPU_NODE1_DFX_GPIO_GRP1_7")
	)
	(segment
		(start 55.795418 -88.573864)
		(end 55.453026 -88.916256)
		(width 0.1016)
		(layer "B.Cu")
		(net "PD_CPU_NODE1_DFX_GPIO_GRP1_7")
	)
	(segment
		(start 55.795418 -86.275926)
		(end 55.795418 -88.573864)
		(width 0.1016)
		(layer "B.Cu")
		(net "PD_CPU_NODE1_DFX_GPIO_GRP1_7")
	)
	(segment
		(start 55.453026 -90.830146)
		(end 54.779164 -91.504008)
		(width 0.1016)
		(layer "B.Cu")
		(net "PD_CPU_NODE1_DFX_GPIO_GRP1_7")
	)
	(segment
		(start 52.966366 -92.771214)
		(end 52.966366 -93.162882)
		(width 0.1016)
		(layer "B.Cu")
		(net "PD_CPU_NODE1_DFX_GPIO_GRP1_7")
	)
	(segment
		(start 51.990498 -96.296734)
		(end 51.990498 -94.142814)
		(width 0.1016)
		(layer "B.Cu")
		(net "PD_CPU_NODE1_DFX_GPIO_GRP1_7")
	)
	(segment
		(start 55.453026 -88.916256)
		(end 55.453026 -90.830146)
		(width 0.1016)
		(layer "B.Cu")
		(net "PD_CPU_NODE1_DFX_GPIO_GRP1_7")
	)
	(segment
		(start 54.233572 -91.504008)
		(end 52.966366 -92.771214)
		(width 0.1016)
		(layer "B.Cu")
		(net "PD_CPU_NODE1_DFX_GPIO_GRP1_7")
	)
	(segment
		(start 51.990498 -94.142814)
		(end 52.966366 -93.166946)
		(width 0.1016)
		(layer "B.Cu")
		(net "PD_CPU_NODE1_DFX_GPIO_GRP1_7")
	)
	(segment
		(start 52.966366 -93.166946)
		(end 52.966366 -93.162882)
		(width 0.1016)
		(layer "B.Cu")
		(net "PD_CPU_NODE1_DFX_GPIO_GRP1_7")
	)
	(segment
		(start 91.980766 -22.425914)
		(end 91.981782 -22.425914)
		(width 0.1651)
		(layer "F.Cu")
		(net "M1_DQ_NODE1_DQ48")
	)
	(segment
		(start 91.981782 -22.425914)
		(end 91.981782 -23.082758)
		(width 0.1651)
		(layer "F.Cu")
		(net "M1_DQ_NODE1_DQ48")
	)
	(segment
		(start 91.950286 -20.94992)
		(end 91.950286 -22.395434)
		(width 0.1651)
		(layer "F.Cu")
		(net "M1_DQ_NODE1_DQ48")
	)
	(segment
		(start 75.377802 -66.965068)
		(end 75.377802 -64.44996)
		(width 0.1016)
		(layer "F.Cu")
		(net "M1_DQ_NODE1_DQ48")
	)
	(segment
		(start 74.207116 -67.255898)
		(end 75.086972 -67.255898)
		(width 0.1016)
		(layer "F.Cu")
		(net "M1_DQ_NODE1_DQ48")
	)
	(segment
		(start 75.086972 -67.255898)
		(end 75.377802 -66.965068)
		(width 0.1016)
		(layer "F.Cu")
		(net "M1_DQ_NODE1_DQ48")
	)
	(segment
		(start 91.950286 -22.395434)
		(end 91.980766 -22.425914)
		(width 0.1651)
		(layer "F.Cu")
		(net "M1_DQ_NODE1_DQ48")
	)
	(segment
		(start 73.806304 -67.65671)
		(end 74.207116 -67.255898)
		(width 0.1016)
		(layer "F.Cu")
		(net "M1_DQ_NODE1_DQ48")
	)
	(segment
		(start 75.377802 -64.44996)
		(end 75.23734 -64.309498)
		(width 0.1016)
		(layer "F.Cu")
		(net "M1_DQ_NODE1_DQ48")
	)
	(via
		(at 91.981782 -23.082758)
		(size 0.508)
		(drill 0.254)
		(layers "F.Cu" "B.Cu")
		(net "M1_DQ_NODE1_DQ48")
	)
	(via
		(at 75.23734 -64.309498)
		(size 0.508)
		(drill 0.254)
		(layers "F.Cu" "B.Cu")
		(net "M1_DQ_NODE1_DQ48")
	)
	(segment
		(start 90.516456 -21.053298)
		(end 91.740482 -21.053298)
		(width 0.2032)
		(layer "In7.Cu")
		(net "M1_DQ_NODE1_DQ48")
	)
	(segment
		(start 91.981782 -21.294598)
		(end 91.981782 -23.082758)
		(width 0.2032)
		(layer "In7.Cu")
		(net "M1_DQ_NODE1_DQ48")
	)
	(segment
		(start 82.808826 -44.426124)
		(end 82.808826 -44.078398)
		(width 0.2032)
		(layer "In7.Cu")
		(net "M1_DQ_NODE1_DQ48")
	)
	(segment
		(start 88.181942 -21.325078)
		(end 88.453722 -21.053298)
		(width 0.2032)
		(layer "In7.Cu")
		(net "M1_DQ_NODE1_DQ48")
	)
	(segment
		(start 90.308176 -21.261578)
		(end 90.516456 -21.053298)
		(width 0.2032)
		(layer "In7.Cu")
		(net "M1_DQ_NODE1_DQ48")
	)
	(segment
		(start 89.596976 -21.261578)
		(end 89.596976 -22.347682)
		(width 0.2032)
		(layer "In7.Cu")
		(net "M1_DQ_NODE1_DQ48")
	)
	(segment
		(start 90.099896 -22.555962)
		(end 90.308176 -22.347682)
		(width 0.2032)
		(layer "In7.Cu")
		(net "M1_DQ_NODE1_DQ48")
	)
	(segment
		(start 88.08212 -32.14878)
		(end 88.08212 -26.231596)
		(width 0.2032)
		(layer "In7.Cu")
		(net "M1_DQ_NODE1_DQ48")
	)
	(segment
		(start 91.740482 -21.053298)
		(end 91.981782 -21.294598)
		(width 0.2032)
		(layer "In7.Cu")
		(net "M1_DQ_NODE1_DQ48")
	)
	(segment
		(start 88.19896 -26.055066)
		(end 88.4428 -25.811226)
		(width 0.2032)
		(layer "In7.Cu")
		(net "M1_DQ_NODE1_DQ48")
	)
	(segment
		(start 88.19896 -26.114756)
		(end 88.19896 -26.055066)
		(width 0.2032)
		(layer "In7.Cu")
		(net "M1_DQ_NODE1_DQ48")
	)
	(segment
		(start 82.808826 -44.078398)
		(end 87.5284 -39.358824)
		(width 0.2032)
		(layer "In7.Cu")
		(net "M1_DQ_NODE1_DQ48")
	)
	(segment
		(start 89.596976 -22.347682)
		(end 89.805256 -22.555962)
		(width 0.2032)
		(layer "In7.Cu")
		(net "M1_DQ_NODE1_DQ48")
	)
	(segment
		(start 88.453722 -21.053298)
		(end 89.388696 -21.053298)
		(width 0.2032)
		(layer "In7.Cu")
		(net "M1_DQ_NODE1_DQ48")
	)
	(segment
		(start 80.27924 -48.260762)
		(end 80.27924 -46.95571)
		(width 0.2032)
		(layer "In7.Cu")
		(net "M1_DQ_NODE1_DQ48")
	)
	(segment
		(start 74.696828 -63.768986)
		(end 74.696828 -62.40653)
		(width 0.1016)
		(layer "In7.Cu")
		(net "M1_DQ_NODE1_DQ48")
	)
	(segment
		(start 88.4428 -22.899116)
		(end 88.181942 -22.638258)
		(width 0.2032)
		(layer "In7.Cu")
		(net "M1_DQ_NODE1_DQ48")
	)
	(segment
		(start 74.696828 -62.40653)
		(end 74.88682 -62.216538)
		(width 0.1016)
		(layer "In7.Cu")
		(net "M1_DQ_NODE1_DQ48")
	)
	(segment
		(start 89.388696 -21.053298)
		(end 89.596976 -21.261578)
		(width 0.2032)
		(layer "In7.Cu")
		(net "M1_DQ_NODE1_DQ48")
	)
	(segment
		(start 75.23734 -64.309498)
		(end 74.696828 -63.768986)
		(width 0.1016)
		(layer "In7.Cu")
		(net "M1_DQ_NODE1_DQ48")
	)
	(segment
		(start 74.88682 -62.216538)
		(end 74.88682 -53.653182)
		(width 0.2032)
		(layer "In7.Cu")
		(net "M1_DQ_NODE1_DQ48")
	)
	(segment
		(start 87.5284 -32.7025)
		(end 88.08212 -32.14878)
		(width 0.2032)
		(layer "In7.Cu")
		(net "M1_DQ_NODE1_DQ48")
	)
	(segment
		(start 88.08212 -26.231596)
		(end 88.19896 -26.114756)
		(width 0.2032)
		(layer "In7.Cu")
		(net "M1_DQ_NODE1_DQ48")
	)
	(segment
		(start 74.88682 -53.653182)
		(end 80.27924 -48.260762)
		(width 0.2032)
		(layer "In7.Cu")
		(net "M1_DQ_NODE1_DQ48")
	)
	(segment
		(start 80.27924 -46.95571)
		(end 82.808826 -44.426124)
		(width 0.2032)
		(layer "In7.Cu")
		(net "M1_DQ_NODE1_DQ48")
	)
	(segment
		(start 88.181942 -22.638258)
		(end 88.181942 -21.325078)
		(width 0.2032)
		(layer "In7.Cu")
		(net "M1_DQ_NODE1_DQ48")
	)
	(segment
		(start 89.805256 -22.555962)
		(end 90.099896 -22.555962)
		(width 0.2032)
		(layer "In7.Cu")
		(net "M1_DQ_NODE1_DQ48")
	)
	(segment
		(start 87.5284 -39.358824)
		(end 87.5284 -32.7025)
		(width 0.2032)
		(layer "In7.Cu")
		(net "M1_DQ_NODE1_DQ48")
	)
	(segment
		(start 88.4428 -25.811226)
		(end 88.4428 -22.899116)
		(width 0.2032)
		(layer "In7.Cu")
		(net "M1_DQ_NODE1_DQ48")
	)
	(segment
		(start 90.308176 -22.347682)
		(end 90.308176 -21.261578)
		(width 0.2032)
		(layer "In7.Cu")
		(net "M1_DQ_NODE1_DQ48")
	)
	(segment
		(start 187.254642 -113.495328)
		(end 187.254642 -114.264694)
		(width 0.1016)
		(layer "F.Cu")
		(net "PWRGD_NODE1_P12V_PG_R")
	)
	(segment
		(start 185.817764 -113.948972)
		(end 185.97499 -113.948972)
		(width 0.1016)
		(layer "F.Cu")
		(net "PWRGD_NODE1_P12V_PG_R")
	)
	(segment
		(start 185.817764 -114.967512)
		(end 185.817764 -113.948972)
		(width 0.1016)
		(layer "F.Cu")
		(net "PWRGD_NODE1_P12V_PG_R")
	)
	(segment
		(start 185.97499 -113.948972)
		(end 186.522614 -114.496596)
		(width 0.1016)
		(layer "F.Cu")
		(net "PWRGD_NODE1_P12V_PG_R")
	)
	(segment
		(start 187.254642 -114.264694)
		(end 187.02274 -114.496596)
		(width 0.1016)
		(layer "F.Cu")
		(net "PWRGD_NODE1_P12V_PG_R")
	)
	(segment
		(start 186.522614 -114.496596)
		(end 187.02274 -114.496596)
		(width 0.1016)
		(layer "F.Cu")
		(net "PWRGD_NODE1_P12V_PG_R")
	)
	(via
		(at 187.02274 -114.496596)
		(size 0.508)
		(drill 0.254)
		(layers "F.Cu" "B.Cu")
		(net "PWRGD_NODE1_P12V_PG_R")
	)
	(segment
		(start 163.46678 -145.476722)
		(end 164.30498 -144.638522)
		(width 0.1016)
		(layer "F.Cu")
		(net "N21357353")
	)
	(segment
		(start 163.26993 -147.959572)
		(end 163.46678 -147.762722)
		(width 0.1016)
		(layer "F.Cu")
		(net "N21357353")
	)
	(segment
		(start 163.26993 -148.547328)
		(end 163.26993 -147.959572)
		(width 0.1016)
		(layer "F.Cu")
		(net "N21357353")
	)
	(segment
		(start 163.46678 -147.762722)
		(end 163.46678 -145.476722)
		(width 0.1016)
		(layer "F.Cu")
		(net "N21357353")
	)
	(via
		(at 164.30498 -144.638522)
		(size 0.508)
		(drill 0.254)
		(layers "F.Cu" "B.Cu")
		(net "N21357353")
	)
	(segment
		(start 163.427918 -144.51203)
		(end 164.178488 -144.51203)
		(width 0.1016)
		(layer "B.Cu")
		(net "N21357353")
	)
	(segment
		(start 164.178488 -144.51203)
		(end 164.30498 -144.638522)
		(width 0.1016)
		(layer "B.Cu")
		(net "N21357353")
	)
	(segment
		(start 70.141846 -143.259556)
		(end 70.141846 -145.494502)
		(width 0.1016)
		(layer "F.Cu")
		(net "BMC_NODE1_JTAG_TDI")
	)
	(segment
		(start 69.547486 -146.088862)
		(end 69.674486 -145.961862)
		(width 0.1016)
		(layer "F.Cu")
		(net "BMC_NODE1_JTAG_TDI")
	)
	(segment
		(start 69.547486 -148.076412)
		(end 69.547486 -146.088862)
		(width 0.1016)
		(layer "F.Cu")
		(net "BMC_NODE1_JTAG_TDI")
	)
	(segment
		(start 70.141846 -145.494502)
		(end 69.674486 -145.961862)
		(width 0.1016)
		(layer "F.Cu")
		(net "BMC_NODE1_JTAG_TDI")
	)
	(via
		(at 69.674486 -145.961862)
		(size 0.508)
		(drill 0.254)
		(layers "F.Cu" "B.Cu")
		(net "BMC_NODE1_JTAG_TDI")
	)
	(segment
		(start 65.475866 -83.095846)
		(end 65.437512 -83.095846)
		(width 0.1016)
		(layer "F.Cu")
		(net "NODE1_BIOS_MB_REV_ID0")
	)
	(segment
		(start 65.437512 -83.095846)
		(end 64.769492 -83.763866)
		(width 0.1016)
		(layer "F.Cu")
		(net "NODE1_BIOS_MB_REV_ID0")
	)
	(via
		(at 64.769492 -83.763866)
		(size 0.508)
		(drill 0.254)
		(layers "F.Cu" "B.Cu")
		(net "NODE1_BIOS_MB_REV_ID0")
	)
	(via
		(at 64.62903 -92.707714)
		(size 0.6604)
		(drill 0.3302)
		(layers "F.Cu" "B.Cu")
		(net "NODE1_BIOS_MB_REV_ID0")
	)
	(segment
		(start 64.182498 -95.471742)
		(end 64.485266 -95.168974)
		(width 0.1016)
		(layer "B.Cu")
		(net "NODE1_BIOS_MB_REV_ID0")
	)
	(segment
		(start 64.62903 -92.50934)
		(end 64.62903 -92.707714)
		(width 0.1016)
		(layer "B.Cu")
		(net "NODE1_BIOS_MB_REV_ID0")
	)
	(segment
		(start 64.73698 -90.577162)
		(end 64.73698 -92.40139)
		(width 0.1016)
		(layer "B.Cu")
		(net "NODE1_BIOS_MB_REV_ID0")
	)
	(segment
		(start 64.769492 -83.763866)
		(end 65.526412 -84.520786)
		(width 0.1016)
		(layer "B.Cu")
		(net "NODE1_BIOS_MB_REV_ID0")
	)
	(segment
		(start 65.526412 -87.005668)
		(end 65.430908 -87.101172)
		(width 0.1016)
		(layer "B.Cu")
		(net "NODE1_BIOS_MB_REV_ID0")
	)
	(segment
		(start 65.526412 -84.520786)
		(end 65.526412 -87.005668)
		(width 0.1016)
		(layer "B.Cu")
		(net "NODE1_BIOS_MB_REV_ID0")
	)
	(segment
		(start 64.182498 -96.296734)
		(end 64.182498 -95.471742)
		(width 0.1016)
		(layer "B.Cu")
		(net "NODE1_BIOS_MB_REV_ID0")
	)
	(segment
		(start 65.198498 -96.296734)
		(end 64.182498 -96.296734)
		(width 0.1016)
		(layer "B.Cu")
		(net "NODE1_BIOS_MB_REV_ID0")
	)
	(segment
		(start 64.73698 -92.40139)
		(end 64.62903 -92.50934)
		(width 0.1016)
		(layer "B.Cu")
		(net "NODE1_BIOS_MB_REV_ID0")
	)
	(segment
		(start 65.430908 -87.101172)
		(end 65.003172 -88.701372)
		(width 0.1016)
		(layer "B.Cu")
		(net "NODE1_BIOS_MB_REV_ID0")
	)
	(segment
		(start 65.003172 -88.701372)
		(end 65.003172 -90.31097)
		(width 0.1016)
		(layer "B.Cu")
		(net "NODE1_BIOS_MB_REV_ID0")
	)
	(segment
		(start 65.003172 -90.31097)
		(end 64.73698 -90.577162)
		(width 0.1016)
		(layer "B.Cu")
		(net "NODE1_BIOS_MB_REV_ID0")
	)
	(segment
		(start 64.485266 -92.851478)
		(end 64.62903 -92.707714)
		(width 0.1016)
		(layer "B.Cu")
		(net "NODE1_BIOS_MB_REV_ID0")
	)
	(segment
		(start 64.485266 -95.168974)
		(end 64.485266 -92.851478)
		(width 0.1016)
		(layer "B.Cu")
		(net "NODE1_BIOS_MB_REV_ID0")
	)
	(segment
		(start 75.055222 -27.071828)
		(end 76.038202 -27.071828)
		(width 0.1651)
		(layer "F.Cu")
		(net "M_DDR3_NODE1_CK1N")
	)
	(segment
		(start 75.419458 -26.159714)
		(end 74.938128 -26.641044)
		(width 0.1651)
		(layer "F.Cu")
		(net "M_DDR3_NODE1_CK1N")
	)
	(segment
		(start 62.586362 -66.217038)
		(end 62.836806 -66.467482)
		(width 0.09906)
		(layer "F.Cu")
		(net "M_DDR3_NODE1_CK1N")
	)
	(segment
		(start 76.038202 -27.071828)
		(end 76.492862 -27.526488)
		(width 0.1651)
		(layer "F.Cu")
		(net "M_DDR3_NODE1_CK1N")
	)
	(segment
		(start 76.492862 -27.526488)
		(end 76.492862 -27.931618)
		(width 0.1651)
		(layer "F.Cu")
		(net "M_DDR3_NODE1_CK1N")
	)
	(segment
		(start 62.836806 -66.467482)
		(end 62.836806 -66.583306)
		(width 0.09906)
		(layer "F.Cu")
		(net "M_DDR3_NODE1_CK1N")
	)
	(segment
		(start 76.492862 -27.931618)
		(end 76.650088 -28.088844)
		(width 0.1651)
		(layer "F.Cu")
		(net "M_DDR3_NODE1_CK1N")
	)
	(segment
		(start 62.443106 -66.217038)
		(end 62.586362 -66.217038)
		(width 0.09906)
		(layer "F.Cu")
		(net "M_DDR3_NODE1_CK1N")
	)
	(segment
		(start 74.938128 -26.954734)
		(end 75.055222 -27.071828)
		(width 0.1651)
		(layer "F.Cu")
		(net "M_DDR3_NODE1_CK1N")
	)
	(segment
		(start 74.938128 -26.641044)
		(end 74.938128 -26.954734)
		(width 0.1651)
		(layer "F.Cu")
		(net "M_DDR3_NODE1_CK1N")
	)
	(segment
		(start 76.650088 -28.088844)
		(end 76.650088 -29.149802)
		(width 0.1651)
		(layer "F.Cu")
		(net "M_DDR3_NODE1_CK1N")
	)
	(via
		(at 62.836806 -66.583306)
		(size 0.508)
		(drill 0.254)
		(layers "F.Cu" "B.Cu")
		(net "M_DDR3_NODE1_CK1N")
	)
	(via
		(at 75.419458 -26.159714)
		(size 0.508)
		(drill 0.254)
		(layers "F.Cu" "B.Cu")
		(net "M_DDR3_NODE1_CK1N")
	)
	(segment
		(start 73.180702 -36.505388)
		(end 74.165206 -36.505388)
		(width 0.2032)
		(layer "In2.Cu")
		(net "M_DDR3_NODE1_CK1N")
	)
	(segment
		(start 72.04964 -41.891712)
		(end 72.04964 -42.196512)
		(width 0.2032)
		(layer "In2.Cu")
		(net "M_DDR3_NODE1_CK1N")
	)
	(segment
		(start 62.6872 -62.916308)
		(end 61.403738 -64.19977)
		(width 0.2032)
		(layer "In2.Cu")
		(net "M_DDR3_NODE1_CK1N")
	)
	(segment
		(start 62.207648 -65.603882)
		(end 62.207648 -66.456052)
		(width 0.09906)
		(layer "In2.Cu")
		(net "M_DDR3_NODE1_CK1N")
	)
	(segment
		(start 73.70318 -42.801286)
		(end 73.70318 -43.898312)
		(width 0.2032)
		(layer "In2.Cu")
		(net "M_DDR3_NODE1_CK1N")
	)
	(segment
		(start 62.334902 -66.583306)
		(end 62.836806 -66.583306)
		(width 0.09906)
		(layer "In2.Cu")
		(net "M_DDR3_NODE1_CK1N")
	)
	(segment
		(start 73.771506 -34.422588)
		(end 74.168 -34.819082)
		(width 0.2032)
		(layer "In2.Cu")
		(net "M_DDR3_NODE1_CK1N")
	)
	(segment
		(start 61.911992 -64.868806)
		(end 62.271148 -65.227962)
		(width 0.2032)
		(layer "In2.Cu")
		(net "M_DDR3_NODE1_CK1N")
	)
	(segment
		(start 74.168 -34.819082)
		(end 74.168 -35.397694)
		(width 0.2032)
		(layer "In2.Cu")
		(net "M_DDR3_NODE1_CK1N")
	)
	(segment
		(start 62.271148 -65.227962)
		(end 62.271148 -65.514474)
		(width 0.2032)
		(layer "In2.Cu")
		(net "M_DDR3_NODE1_CK1N")
	)
	(segment
		(start 74.56678 -36.906962)
		(end 74.56678 -37.475414)
		(width 0.2032)
		(layer "In2.Cu")
		(net "M_DDR3_NODE1_CK1N")
	)
	(segment
		(start 71.116698 -45.91685)
		(end 71.116698 -46.484794)
		(width 0.2032)
		(layer "In2.Cu")
		(net "M_DDR3_NODE1_CK1N")
	)
	(segment
		(start 73.301606 -42.399712)
		(end 73.70318 -42.801286)
		(width 0.2032)
		(layer "In2.Cu")
		(net "M_DDR3_NODE1_CK1N")
	)
	(segment
		(start 74.0156 -39.731696)
		(end 74.0156 -41.14673)
		(width 0.2032)
		(layer "In2.Cu")
		(net "M_DDR3_NODE1_CK1N")
	)
	(segment
		(start 74.95286 -27.034236)
		(end 75.1586 -27.239976)
		(width 0.2032)
		(layer "In2.Cu")
		(net "M_DDR3_NODE1_CK1N")
	)
	(segment
		(start 74.168 -35.397694)
		(end 73.771506 -35.794188)
		(width 0.2032)
		(layer "In2.Cu")
		(net "M_DDR3_NODE1_CK1N")
	)
	(segment
		(start 72.25284 -41.688512)
		(end 72.04964 -41.891712)
		(width 0.2032)
		(layer "In2.Cu")
		(net "M_DDR3_NODE1_CK1N")
	)
	(segment
		(start 70.536308 -45.048932)
		(end 70.536308 -45.33646)
		(width 0.2032)
		(layer "In2.Cu")
		(net "M_DDR3_NODE1_CK1N")
	)
	(segment
		(start 73.771506 -35.794188)
		(end 73.180702 -35.794188)
		(width 0.2032)
		(layer "In2.Cu")
		(net "M_DDR3_NODE1_CK1N")
	)
	(segment
		(start 70.7517 -44.83354)
		(end 70.536308 -45.048932)
		(width 0.2032)
		(layer "In2.Cu")
		(net "M_DDR3_NODE1_CK1N")
	)
	(segment
		(start 72.972422 -38.085268)
		(end 72.972422 -38.688518)
		(width 0.2032)
		(layer "In2.Cu")
		(net "M_DDR3_NODE1_CK1N")
	)
	(segment
		(start 71.116698 -46.484794)
		(end 70.231 -47.370492)
		(width 0.2032)
		(layer "In2.Cu")
		(net "M_DDR3_NODE1_CK1N")
	)
	(segment
		(start 70.231 -47.370492)
		(end 69.784722 -47.370492)
		(width 0.2032)
		(layer "In2.Cu")
		(net "M_DDR3_NODE1_CK1N")
	)
	(segment
		(start 62.271148 -65.514474)
		(end 62.271148 -65.540382)
		(width 0.09906)
		(layer "In2.Cu")
		(net "M_DDR3_NODE1_CK1N")
	)
	(segment
		(start 72.972422 -34.214308)
		(end 73.180702 -34.422588)
		(width 0.2032)
		(layer "In2.Cu")
		(net "M_DDR3_NODE1_CK1N")
	)
	(segment
		(start 62.271148 -65.540382)
		(end 62.207648 -65.603882)
		(width 0.09906)
		(layer "In2.Cu")
		(net "M_DDR3_NODE1_CK1N")
	)
	(segment
		(start 74.08418 -29.632148)
		(end 74.08418 -31.67126)
		(width 0.2032)
		(layer "In2.Cu")
		(net "M_DDR3_NODE1_CK1N")
	)
	(segment
		(start 75.419458 -26.159714)
		(end 74.95286 -26.626312)
		(width 0.2032)
		(layer "In2.Cu")
		(net "M_DDR3_NODE1_CK1N")
	)
	(segment
		(start 71.619618 -45.41393)
		(end 71.039228 -44.83354)
		(width 0.2032)
		(layer "In2.Cu")
		(net "M_DDR3_NODE1_CK1N")
	)
	(segment
		(start 73.119742 -31.977838)
		(end 72.972422 -32.125158)
		(width 0.2032)
		(layer "In2.Cu")
		(net "M_DDR3_NODE1_CK1N")
	)
	(segment
		(start 69.08038 -48.074834)
		(end 69.08038 -48.520858)
		(width 0.2032)
		(layer "In2.Cu")
		(net "M_DDR3_NODE1_CK1N")
	)
	(segment
		(start 74.165206 -36.505388)
		(end 74.56678 -36.906962)
		(width 0.2032)
		(layer "In2.Cu")
		(net "M_DDR3_NODE1_CK1N")
	)
	(segment
		(start 72.972422 -38.688518)
		(end 74.0156 -39.731696)
		(width 0.2032)
		(layer "In2.Cu")
		(net "M_DDR3_NODE1_CK1N")
	)
	(segment
		(start 70.536308 -45.33646)
		(end 71.116698 -45.91685)
		(width 0.2032)
		(layer "In2.Cu")
		(net "M_DDR3_NODE1_CK1N")
	)
	(segment
		(start 72.972422 -32.125158)
		(end 72.972422 -34.214308)
		(width 0.2032)
		(layer "In2.Cu")
		(net "M_DDR3_NODE1_CK1N")
	)
	(segment
		(start 74.95286 -26.626312)
		(end 74.95286 -27.034236)
		(width 0.2032)
		(layer "In2.Cu")
		(net "M_DDR3_NODE1_CK1N")
	)
	(segment
		(start 72.972422 -36.002468)
		(end 72.972422 -36.297108)
		(width 0.2032)
		(layer "In2.Cu")
		(net "M_DDR3_NODE1_CK1N")
	)
	(segment
		(start 72.04964 -42.196512)
		(end 72.25284 -42.399712)
		(width 0.2032)
		(layer "In2.Cu")
		(net "M_DDR3_NODE1_CK1N")
	)
	(segment
		(start 72.972422 -36.297108)
		(end 73.180702 -36.505388)
		(width 0.2032)
		(layer "In2.Cu")
		(net "M_DDR3_NODE1_CK1N")
	)
	(segment
		(start 69.784722 -47.370492)
		(end 69.08038 -48.074834)
		(width 0.2032)
		(layer "In2.Cu")
		(net "M_DDR3_NODE1_CK1N")
	)
	(segment
		(start 69.08038 -48.520858)
		(end 62.6872 -54.914292)
		(width 0.2032)
		(layer "In2.Cu")
		(net "M_DDR3_NODE1_CK1N")
	)
	(segment
		(start 73.180702 -37.876988)
		(end 72.972422 -38.085268)
		(width 0.2032)
		(layer "In2.Cu")
		(net "M_DDR3_NODE1_CK1N")
	)
	(segment
		(start 72.25284 -42.399712)
		(end 73.301606 -42.399712)
		(width 0.2032)
		(layer "In2.Cu")
		(net "M_DDR3_NODE1_CK1N")
	)
	(segment
		(start 61.571124 -64.868806)
		(end 61.911992 -64.868806)
		(width 0.2032)
		(layer "In2.Cu")
		(net "M_DDR3_NODE1_CK1N")
	)
	(segment
		(start 74.08418 -31.67126)
		(end 73.777602 -31.977838)
		(width 0.2032)
		(layer "In2.Cu")
		(net "M_DDR3_NODE1_CK1N")
	)
	(segment
		(start 74.56678 -37.475414)
		(end 74.165206 -37.876988)
		(width 0.2032)
		(layer "In2.Cu")
		(net "M_DDR3_NODE1_CK1N")
	)
	(segment
		(start 74.165206 -37.876988)
		(end 73.180702 -37.876988)
		(width 0.2032)
		(layer "In2.Cu")
		(net "M_DDR3_NODE1_CK1N")
	)
	(segment
		(start 73.180702 -35.794188)
		(end 72.972422 -36.002468)
		(width 0.2032)
		(layer "In2.Cu")
		(net "M_DDR3_NODE1_CK1N")
	)
	(segment
		(start 73.180702 -34.422588)
		(end 73.771506 -34.422588)
		(width 0.2032)
		(layer "In2.Cu")
		(net "M_DDR3_NODE1_CK1N")
	)
	(segment
		(start 73.70318 -43.898312)
		(end 72.187562 -45.41393)
		(width 0.2032)
		(layer "In2.Cu")
		(net "M_DDR3_NODE1_CK1N")
	)
	(segment
		(start 71.039228 -44.83354)
		(end 70.7517 -44.83354)
		(width 0.2032)
		(layer "In2.Cu")
		(net "M_DDR3_NODE1_CK1N")
	)
	(segment
		(start 62.6872 -54.914292)
		(end 62.6872 -62.916308)
		(width 0.2032)
		(layer "In2.Cu")
		(net "M_DDR3_NODE1_CK1N")
	)
	(segment
		(start 73.473818 -41.688512)
		(end 72.25284 -41.688512)
		(width 0.2032)
		(layer "In2.Cu")
		(net "M_DDR3_NODE1_CK1N")
	)
	(segment
		(start 61.403738 -64.19977)
		(end 61.403738 -64.70142)
		(width 0.2032)
		(layer "In2.Cu")
		(net "M_DDR3_NODE1_CK1N")
	)
	(segment
		(start 72.187562 -45.41393)
		(end 71.619618 -45.41393)
		(width 0.2032)
		(layer "In2.Cu")
		(net "M_DDR3_NODE1_CK1N")
	)
	(segment
		(start 74.0156 -41.14673)
		(end 73.473818 -41.688512)
		(width 0.2032)
		(layer "In2.Cu")
		(net "M_DDR3_NODE1_CK1N")
	)
	(segment
		(start 62.207648 -66.456052)
		(end 62.334902 -66.583306)
		(width 0.09906)
		(layer "In2.Cu")
		(net "M_DDR3_NODE1_CK1N")
	)
	(segment
		(start 73.777602 -31.977838)
		(end 73.119742 -31.977838)
		(width 0.2032)
		(layer "In2.Cu")
		(net "M_DDR3_NODE1_CK1N")
	)
	(segment
		(start 75.1586 -28.557728)
		(end 74.08418 -29.632148)
		(width 0.2032)
		(layer "In2.Cu")
		(net "M_DDR3_NODE1_CK1N")
	)
	(segment
		(start 75.1586 -27.239976)
		(end 75.1586 -28.557728)
		(width 0.2032)
		(layer "In2.Cu")
		(net "M_DDR3_NODE1_CK1N")
	)
	(segment
		(start 61.403738 -64.70142)
		(end 61.571124 -64.868806)
		(width 0.2032)
		(layer "In2.Cu")
		(net "M_DDR3_NODE1_CK1N")
	)
	(segment
		(start 150.886414 -67.346068)
		(end 150.893018 -67.352672)
		(width 0.1016)
		(layer "F.Cu")
		(net "CLK_25M_SATA_NODE1")
	)
	(segment
		(start 149.57171 -66.758058)
		(end 150.191724 -66.758058)
		(width 0.1016)
		(layer "F.Cu")
		(net "CLK_25M_SATA_NODE1")
	)
	(segment
		(start 132.919978 -106.104944)
		(end 140.23086 -98.794062)
		(width 0.1016)
		(layer "F.Cu")
		(net "CLK_25M_SATA_NODE1")
	)
	(segment
		(start 132.919978 -108.560108)
		(end 132.919978 -106.104944)
		(width 0.1016)
		(layer "F.Cu")
		(net "CLK_25M_SATA_NODE1")
	)
	(segment
		(start 132.03936 -109.440726)
		(end 132.919978 -108.560108)
		(width 0.1016)
		(layer "F.Cu")
		(net "CLK_25M_SATA_NODE1")
	)
	(segment
		(start 132.03936 -109.469174)
		(end 132.03936 -109.440726)
		(width 0.1016)
		(layer "F.Cu")
		(net "CLK_25M_SATA_NODE1")
	)
	(segment
		(start 150.191724 -66.758058)
		(end 150.779734 -67.346068)
		(width 0.1016)
		(layer "F.Cu")
		(net "CLK_25M_SATA_NODE1")
	)
	(segment
		(start 150.779734 -67.346068)
		(end 150.886414 -67.346068)
		(width 0.1016)
		(layer "F.Cu")
		(net "CLK_25M_SATA_NODE1")
	)
	(via
		(at 150.893018 -67.352672)
		(size 0.508)
		(drill 0.254)
		(layers "F.Cu" "B.Cu")
		(net "CLK_25M_SATA_NODE1")
	)
	(via
		(at 140.23086 -98.794062)
		(size 0.508)
		(drill 0.254)
		(layers "F.Cu" "B.Cu")
		(net "CLK_25M_SATA_NODE1")
	)
	(segment
		(start 140.60932 -88.1634)
		(end 140.60932 -98.236278)
		(width 0.1016)
		(layer "B.Cu")
		(net "CLK_25M_SATA_NODE1")
	)
	(segment
		(start 151.995886 -72.851772)
		(end 151.995886 -78.365858)
		(width 0.1016)
		(layer "B.Cu")
		(net "CLK_25M_SATA_NODE1")
	)
	(segment
		(start 150.921466 -69.856604)
		(end 150.921466 -71.777352)
		(width 0.1016)
		(layer "B.Cu")
		(net "CLK_25M_SATA_NODE1")
	)
	(segment
		(start 149.913086 -80.448658)
		(end 148.324062 -80.448658)
		(width 0.1016)
		(layer "B.Cu")
		(net "CLK_25M_SATA_NODE1")
	)
	(segment
		(start 148.324062 -80.448658)
		(end 140.60932 -88.1634)
		(width 0.1016)
		(layer "B.Cu")
		(net "CLK_25M_SATA_NODE1")
	)
	(segment
		(start 150.921466 -71.777352)
		(end 151.995886 -72.851772)
		(width 0.1016)
		(layer "B.Cu")
		(net "CLK_25M_SATA_NODE1")
	)
	(segment
		(start 140.60932 -98.236278)
		(end 140.23086 -98.614738)
		(width 0.1016)
		(layer "B.Cu")
		(net "CLK_25M_SATA_NODE1")
	)
	(segment
		(start 150.893018 -67.352672)
		(end 150.329392 -67.916298)
		(width 0.1016)
		(layer "B.Cu")
		(net "CLK_25M_SATA_NODE1")
	)
	(segment
		(start 150.329392 -67.916298)
		(end 150.329392 -69.26453)
		(width 0.1016)
		(layer "B.Cu")
		(net "CLK_25M_SATA_NODE1")
	)
	(segment
		(start 151.995886 -78.365858)
		(end 149.913086 -80.448658)
		(width 0.1016)
		(layer "B.Cu")
		(net "CLK_25M_SATA_NODE1")
	)
	(segment
		(start 140.23086 -98.614738)
		(end 140.23086 -98.794062)
		(width 0.1016)
		(layer "B.Cu")
		(net "CLK_25M_SATA_NODE1")
	)
	(segment
		(start 150.329392 -69.26453)
		(end 150.921466 -69.856604)
		(width 0.1016)
		(layer "B.Cu")
		(net "CLK_25M_SATA_NODE1")
	)
	(segment
		(start 170.00982 -139.383008)
		(end 169.87774 -139.250928)
		(width 0.1016)
		(layer "F.Cu")
		(net "FM_CPLD_NODE1_PWR_BTN_L")
	)
	(segment
		(start 173.500542 -124.875544)
		(end 173.500542 -126.115572)
		(width 0.1016)
		(layer "F.Cu")
		(net "FM_CPLD_NODE1_PWR_BTN_L")
	)
	(segment
		(start 173.500542 -126.115572)
		(end 172.92066 -126.695454)
		(width 0.1016)
		(layer "F.Cu")
		(net "FM_CPLD_NODE1_PWR_BTN_L")
	)
	(segment
		(start 169.87774 -137.805922)
		(end 167.123618 -135.0518)
		(width 0.1016)
		(layer "F.Cu")
		(net "FM_CPLD_NODE1_PWR_BTN_L")
	)
	(segment
		(start 167.123618 -135.0518)
		(end 165.78326 -135.0518)
		(width 0.1016)
		(layer "F.Cu")
		(net "FM_CPLD_NODE1_PWR_BTN_L")
	)
	(segment
		(start 170.750992 -139.7508)
		(end 170.750992 -139.383008)
		(width 0.1016)
		(layer "F.Cu")
		(net "FM_CPLD_NODE1_PWR_BTN_L")
	)
	(segment
		(start 174.01032 -124.365766)
		(end 173.500542 -124.875544)
		(width 0.1016)
		(layer "F.Cu")
		(net "FM_CPLD_NODE1_PWR_BTN_L")
	)
	(segment
		(start 170.923966 -139.923774)
		(end 170.750992 -139.7508)
		(width 0.1016)
		(layer "F.Cu")
		(net "FM_CPLD_NODE1_PWR_BTN_L")
	)
	(segment
		(start 170.750992 -139.383008)
		(end 170.00982 -139.383008)
		(width 0.1016)
		(layer "F.Cu")
		(net "FM_CPLD_NODE1_PWR_BTN_L")
	)
	(segment
		(start 173.45152 -138.95451)
		(end 173.45152 -139.583922)
		(width 0.1016)
		(layer "F.Cu")
		(net "FM_CPLD_NODE1_PWR_BTN_L")
	)
	(segment
		(start 173.45152 -139.583922)
		(end 173.111668 -139.923774)
		(width 0.1016)
		(layer "F.Cu")
		(net "FM_CPLD_NODE1_PWR_BTN_L")
	)
	(segment
		(start 173.111668 -139.923774)
		(end 170.923966 -139.923774)
		(width 0.1016)
		(layer "F.Cu")
		(net "FM_CPLD_NODE1_PWR_BTN_L")
	)
	(segment
		(start 172.92066 -126.695454)
		(end 172.92066 -128.148334)
		(width 0.1016)
		(layer "F.Cu")
		(net "FM_CPLD_NODE1_PWR_BTN_L")
	)
	(segment
		(start 169.87774 -139.250928)
		(end 169.87774 -137.805922)
		(width 0.1016)
		(layer "F.Cu")
		(net "FM_CPLD_NODE1_PWR_BTN_L")
	)
	(segment
		(start 165.78326 -135.0518)
		(end 165.78326 -135.050022)
		(width 0.1016)
		(layer "F.Cu")
		(net "FM_CPLD_NODE1_PWR_BTN_L")
	)
	(via
		(at 165.78326 -135.050022)
		(size 0.508)
		(drill 0.254)
		(layers "F.Cu" "B.Cu")
		(net "FM_CPLD_NODE1_PWR_BTN_L")
	)
	(via
		(at 172.92066 -128.148334)
		(size 0.508)
		(drill 0.254)
		(layers "F.Cu" "B.Cu")
		(net "FM_CPLD_NODE1_PWR_BTN_L")
	)
	(segment
		(start 170.2562 -130.895344)
		(end 170.2562 -130.593592)
		(width 0.1143)
		(layer "In2.Cu")
		(net "FM_CPLD_NODE1_PWR_BTN_L")
	)
	(segment
		(start 170.2562 -130.593592)
		(end 172.701458 -128.148334)
		(width 0.1143)
		(layer "In2.Cu")
		(net "FM_CPLD_NODE1_PWR_BTN_L")
	)
	(segment
		(start 166.67734 -134.475982)
		(end 166.67734 -134.474204)
		(width 0.1143)
		(layer "In2.Cu")
		(net "FM_CPLD_NODE1_PWR_BTN_L")
	)
	(segment
		(start 166.67734 -134.474204)
		(end 170.2562 -130.895344)
		(width 0.1143)
		(layer "In2.Cu")
		(net "FM_CPLD_NODE1_PWR_BTN_L")
	)
	(segment
		(start 165.78326 -135.050022)
		(end 166.1033 -135.050022)
		(width 0.1143)
		(layer "In2.Cu")
		(net "FM_CPLD_NODE1_PWR_BTN_L")
	)
	(segment
		(start 172.701458 -128.148334)
		(end 172.92066 -128.148334)
		(width 0.1143)
		(layer "In2.Cu")
		(net "FM_CPLD_NODE1_PWR_BTN_L")
	)
	(segment
		(start 166.1033 -135.050022)
		(end 166.67734 -134.475982)
		(width 0.1143)
		(layer "In2.Cu")
		(net "FM_CPLD_NODE1_PWR_BTN_L")
	)
	(segment
		(start 141.848078 -76.485496)
		(end 142.02156 -76.658978)
		(width 0.1016)
		(layer "F.Cu")
		(net "SATA_SPI_DO_NODE1_R")
	)
	(segment
		(start 144.849596 -75.517756)
		(end 143.752062 -76.61529)
		(width 0.1016)
		(layer "F.Cu")
		(net "SATA_SPI_DO_NODE1_R")
	)
	(segment
		(start 145.53057 -68.799202)
		(end 145.53057 -70.361556)
		(width 0.1016)
		(layer "F.Cu")
		(net "SATA_SPI_DO_NODE1_R")
	)
	(segment
		(start 143.708374 -76.658978)
		(end 143.752062 -76.61529)
		(width 0.1016)
		(layer "F.Cu")
		(net "SATA_SPI_DO_NODE1_R")
	)
	(segment
		(start 142.02156 -76.658978)
		(end 143.708374 -76.658978)
		(width 0.1016)
		(layer "F.Cu")
		(net "SATA_SPI_DO_NODE1_R")
	)
	(segment
		(start 145.53057 -70.361556)
		(end 144.849596 -71.04253)
		(width 0.1016)
		(layer "F.Cu")
		(net "SATA_SPI_DO_NODE1_R")
	)
	(segment
		(start 144.849596 -71.04253)
		(end 144.849596 -75.517756)
		(width 0.1016)
		(layer "F.Cu")
		(net "SATA_SPI_DO_NODE1_R")
	)
	(segment
		(start 139.76223 -76.485496)
		(end 141.848078 -76.485496)
		(width 0.1016)
		(layer "F.Cu")
		(net "SATA_SPI_DO_NODE1_R")
	)
	(via
		(at 143.752062 -76.61529)
		(size 0.508)
		(drill 0.254)
		(layers "F.Cu" "B.Cu")
		(net "SATA_SPI_DO_NODE1_R")
	)
	(segment
		(start 67.869308 -62.400434)
		(end 67.847972 -62.379098)
		(width 0.1016)
		(layer "F.Cu")
		(net "M1_DQ_NODE1_DQ34")
	)
	(segment
		(start 86.655402 -24.494998)
		(end 86.65718 -24.494998)
		(width 0.1651)
		(layer "F.Cu")
		(net "M1_DQ_NODE1_DQ34")
	)
	(segment
		(start 86.37524 -24.214836)
		(end 86.655402 -24.494998)
		(width 0.1651)
		(layer "F.Cu")
		(net "M1_DQ_NODE1_DQ34")
	)
	(segment
		(start 85.951822 -20.951444)
		(end 85.951822 -22.937978)
		(width 0.1651)
		(layer "F.Cu")
		(net "M1_DQ_NODE1_DQ34")
	)
	(segment
		(start 67.869308 -62.993778)
		(end 67.869308 -62.400434)
		(width 0.1016)
		(layer "F.Cu")
		(net "M1_DQ_NODE1_DQ34")
	)
	(segment
		(start 86.37524 -23.361396)
		(end 86.37524 -24.214836)
		(width 0.1651)
		(layer "F.Cu")
		(net "M1_DQ_NODE1_DQ34")
	)
	(segment
		(start 85.950298 -20.94992)
		(end 85.951822 -20.951444)
		(width 0.1651)
		(layer "F.Cu")
		(net "M1_DQ_NODE1_DQ34")
	)
	(segment
		(start 87.13978 -24.977598)
		(end 87.13978 -25.240488)
		(width 0.1651)
		(layer "F.Cu")
		(net "M1_DQ_NODE1_DQ34")
	)
	(segment
		(start 85.951822 -22.937978)
		(end 86.37524 -23.361396)
		(width 0.1651)
		(layer "F.Cu")
		(net "M1_DQ_NODE1_DQ34")
	)
	(segment
		(start 86.65718 -24.494998)
		(end 87.13978 -24.977598)
		(width 0.1651)
		(layer "F.Cu")
		(net "M1_DQ_NODE1_DQ34")
	)
	(via
		(at 67.847972 -62.379098)
		(size 0.508)
		(drill 0.254)
		(layers "F.Cu" "B.Cu")
		(net "M1_DQ_NODE1_DQ34")
	)
	(via
		(at 87.13978 -25.240488)
		(size 0.508)
		(drill 0.254)
		(layers "F.Cu" "B.Cu")
		(net "M1_DQ_NODE1_DQ34")
	)
	(segment
		(start 67.192144 -63.034418)
		(end 67.358514 -62.868048)
		(width 0.1016)
		(layer "In7.Cu")
		(net "M1_DQ_NODE1_DQ34")
	)
	(segment
		(start 87.06612 -25.314148)
		(end 87.06612 -29.535882)
		(width 0.2032)
		(layer "In7.Cu")
		(net "M1_DQ_NODE1_DQ34")
	)
	(segment
		(start 81.679288 -43.82262)
		(end 81.679288 -44.116752)
		(width 0.2032)
		(layer "In7.Cu")
		(net "M1_DQ_NODE1_DQ34")
	)
	(segment
		(start 80.673448 -44.82846)
		(end 80.673448 -45.122592)
		(width 0.2032)
		(layer "In7.Cu")
		(net "M1_DQ_NODE1_DQ34")
	)
	(segment
		(start 68.834254 -65.609216)
		(end 67.192144 -63.967106)
		(width 0.1016)
		(layer "In7.Cu")
		(net "M1_DQ_NODE1_DQ34")
	)
	(segment
		(start 81.679288 -44.116752)
		(end 81.407 -44.38904)
		(width 0.2032)
		(layer "In7.Cu")
		(net "M1_DQ_NODE1_DQ34")
	)
	(segment
		(start 87.06612 -29.535882)
		(end 86.33968 -30.262322)
		(width 0.2032)
		(layer "In7.Cu")
		(net "M1_DQ_NODE1_DQ34")
	)
	(segment
		(start 81.679034 -43.655488)
		(end 81.679288 -43.82262)
		(width 0.2032)
		(layer "In7.Cu")
		(net "M1_DQ_NODE1_DQ34")
	)
	(segment
		(start 80.40116 -45.39488)
		(end 79.939642 -45.39488)
		(width 0.2032)
		(layer "In7.Cu")
		(net "M1_DQ_NODE1_DQ34")
	)
	(segment
		(start 69.3928 -65.609216)
		(end 68.834254 -65.609216)
		(width 0.1016)
		(layer "In7.Cu")
		(net "M1_DQ_NODE1_DQ34")
	)
	(segment
		(start 74.121264 -59.546998)
		(end 74.121264 -61.717936)
		(width 0.2032)
		(layer "In7.Cu")
		(net "M1_DQ_NODE1_DQ34")
	)
	(segment
		(start 79.26324 -46.071282)
		(end 79.26324 -47.835058)
		(width 0.2032)
		(layer "In7.Cu")
		(net "M1_DQ_NODE1_DQ34")
	)
	(segment
		(start 74.17308 -63.022988)
		(end 72.814688 -64.38138)
		(width 0.2032)
		(layer "In7.Cu")
		(net "M1_DQ_NODE1_DQ34")
	)
	(segment
		(start 74.121264 -61.717936)
		(end 74.172064 -61.768736)
		(width 0.2032)
		(layer "In7.Cu")
		(net "M1_DQ_NODE1_DQ34")
	)
	(segment
		(start 74.172064 -61.768736)
		(end 74.17308 -61.768736)
		(width 0.2032)
		(layer "In7.Cu")
		(net "M1_DQ_NODE1_DQ34")
	)
	(segment
		(start 87.13978 -25.240488)
		(end 87.06612 -25.314148)
		(width 0.2032)
		(layer "In7.Cu")
		(net "M1_DQ_NODE1_DQ34")
	)
	(segment
		(start 79.26324 -47.835058)
		(end 73.87082 -53.227478)
		(width 0.2032)
		(layer "In7.Cu")
		(net "M1_DQ_NODE1_DQ34")
	)
	(segment
		(start 80.945482 -44.38904)
		(end 80.673194 -44.661328)
		(width 0.2032)
		(layer "In7.Cu")
		(net "M1_DQ_NODE1_DQ34")
	)
	(segment
		(start 86.33968 -30.262322)
		(end 86.33968 -38.748716)
		(width 0.2032)
		(layer "In7.Cu")
		(net "M1_DQ_NODE1_DQ34")
	)
	(segment
		(start 73.87082 -53.227478)
		(end 73.87082 -59.296554)
		(width 0.2032)
		(layer "In7.Cu")
		(net "M1_DQ_NODE1_DQ34")
	)
	(segment
		(start 80.673194 -44.661328)
		(end 80.673448 -44.82846)
		(width 0.2032)
		(layer "In7.Cu")
		(net "M1_DQ_NODE1_DQ34")
	)
	(segment
		(start 72.814688 -64.38138)
		(end 70.967092 -64.38138)
		(width 0.2032)
		(layer "In7.Cu")
		(net "M1_DQ_NODE1_DQ34")
	)
	(segment
		(start 86.337902 -38.99662)
		(end 81.679034 -43.655488)
		(width 0.2032)
		(layer "In7.Cu")
		(net "M1_DQ_NODE1_DQ34")
	)
	(segment
		(start 67.192144 -63.967106)
		(end 67.192144 -63.034418)
		(width 0.1016)
		(layer "In7.Cu")
		(net "M1_DQ_NODE1_DQ34")
	)
	(segment
		(start 70.967092 -64.38138)
		(end 69.739256 -65.609216)
		(width 0.2032)
		(layer "In7.Cu")
		(net "M1_DQ_NODE1_DQ34")
	)
	(segment
		(start 80.673448 -45.122592)
		(end 80.40116 -45.39488)
		(width 0.2032)
		(layer "In7.Cu")
		(net "M1_DQ_NODE1_DQ34")
	)
	(segment
		(start 86.33968 -38.748716)
		(end 86.337902 -38.748716)
		(width 0.2032)
		(layer "In7.Cu")
		(net "M1_DQ_NODE1_DQ34")
	)
	(segment
		(start 69.739256 -65.609216)
		(end 69.3928 -65.609216)
		(width 0.2032)
		(layer "In7.Cu")
		(net "M1_DQ_NODE1_DQ34")
	)
	(segment
		(start 79.939642 -45.39488)
		(end 79.26324 -46.071282)
		(width 0.2032)
		(layer "In7.Cu")
		(net "M1_DQ_NODE1_DQ34")
	)
	(segment
		(start 74.17308 -61.768736)
		(end 74.17308 -63.022988)
		(width 0.2032)
		(layer "In7.Cu")
		(net "M1_DQ_NODE1_DQ34")
	)
	(segment
		(start 73.87082 -59.296554)
		(end 74.121264 -59.546998)
		(width 0.2032)
		(layer "In7.Cu")
		(net "M1_DQ_NODE1_DQ34")
	)
	(segment
		(start 81.407 -44.38904)
		(end 80.945482 -44.38904)
		(width 0.2032)
		(layer "In7.Cu")
		(net "M1_DQ_NODE1_DQ34")
	)
	(segment
		(start 86.337902 -38.748716)
		(end 86.337902 -38.99662)
		(width 0.2032)
		(layer "In7.Cu")
		(net "M1_DQ_NODE1_DQ34")
	)
	(segment
		(start 67.359022 -62.868048)
		(end 67.847972 -62.379098)
		(width 0.1016)
		(layer "In7.Cu")
		(net "M1_DQ_NODE1_DQ34")
	)
	(segment
		(start 67.358514 -62.868048)
		(end 67.359022 -62.868048)
		(width 0.1016)
		(layer "In7.Cu")
		(net "M1_DQ_NODE1_DQ34")
	)
	(segment
		(start 148.730462 -59.916822)
		(end 148.730462 -59.287664)
		(width 0.1016)
		(layer "F.Cu")
		(net "SATA_NODE1_GPIO5")
	)
	(segment
		(start 148.730462 -59.287664)
		(end 149.370796 -58.64733)
		(width 0.1016)
		(layer "F.Cu")
		(net "SATA_NODE1_GPIO5")
	)
	(segment
		(start 151.309578 -57.649872)
		(end 150.293578 -57.649872)
		(width 0.1016)
		(layer "F.Cu")
		(net "SATA_NODE1_GPIO5")
	)
	(segment
		(start 150.107396 -58.64733)
		(end 150.293578 -58.461148)
		(width 0.1016)
		(layer "F.Cu")
		(net "SATA_NODE1_GPIO5")
	)
	(segment
		(start 150.293578 -57.649872)
		(end 150.293578 -58.461148)
		(width 0.1016)
		(layer "F.Cu")
		(net "SATA_NODE1_GPIO5")
	)
	(segment
		(start 149.370796 -58.64733)
		(end 150.107396 -58.64733)
		(width 0.1016)
		(layer "F.Cu")
		(net "SATA_NODE1_GPIO5")
	)
	(via
		(at 150.293578 -58.461148)
		(size 0.508)
		(drill 0.254)
		(layers "F.Cu" "B.Cu")
		(net "SATA_NODE1_GPIO5")
	)
	(segment
		(start 62.939422 -141.65961)
		(end 62.540896 -142.058136)
		(width 0.1016)
		(layer "F.Cu")
		(net "BMC_NODE1_GFX_GREEN")
	)
	(segment
		(start 18.25752 -49.608486)
		(end 17.986756 -49.608486)
		(width 0.1016)
		(layer "F.Cu")
		(net "BMC_NODE1_GFX_GREEN")
	)
	(segment
		(start 16.905732 -50.68951)
		(end 17.50822 -50.087022)
		(width 0.1016)
		(layer "F.Cu")
		(net "BMC_NODE1_GFX_GREEN")
	)
	(segment
		(start 17.986756 -49.608486)
		(end 17.50822 -50.087022)
		(width 0.1016)
		(layer "F.Cu")
		(net "BMC_NODE1_GFX_GREEN")
	)
	(segment
		(start 16.718534 -50.68951)
		(end 16.905732 -50.68951)
		(width 0.1016)
		(layer "F.Cu")
		(net "BMC_NODE1_GFX_GREEN")
	)
	(segment
		(start 62.941708 -141.65961)
		(end 62.939422 -141.65961)
		(width 0.1016)
		(layer "F.Cu")
		(net "BMC_NODE1_GFX_GREEN")
	)
	(via
		(at 17.50822 -50.087022)
		(size 0.508)
		(drill 0.254)
		(layers "F.Cu" "B.Cu")
		(net "BMC_NODE1_GFX_GREEN")
	)
	(via
		(at 61.679836 -143.320262)
		(size 0.6604)
		(drill 0.3302)
		(layers "F.Cu" "B.Cu")
		(net "BMC_NODE1_GFX_GREEN")
	)
	(via
		(at 62.540896 -142.058136)
		(size 0.49022)
		(drill 0.254)
		(layers "F.Cu" "B.Cu")
		(net "BMC_NODE1_GFX_GREEN")
	)
	(segment
		(start 59.997086 -146.019012)
		(end 59.997086 -145.003012)
		(width 0.1016)
		(layer "B.Cu")
		(net "BMC_NODE1_GFX_GREEN")
	)
	(segment
		(start 61.679836 -143.320262)
		(end 62.073536 -142.926562)
		(width 0.1016)
		(layer "B.Cu")
		(net "BMC_NODE1_GFX_GREEN")
	)
	(segment
		(start 62.073536 -142.738348)
		(end 62.540896 -142.270988)
		(width 0.1016)
		(layer "B.Cu")
		(net "BMC_NODE1_GFX_GREEN")
	)
	(segment
		(start 59.997086 -145.003012)
		(end 61.679836 -143.320262)
		(width 0.1016)
		(layer "B.Cu")
		(net "BMC_NODE1_GFX_GREEN")
	)
	(segment
		(start 62.073536 -142.926562)
		(end 62.073536 -142.738348)
		(width 0.1016)
		(layer "B.Cu")
		(net "BMC_NODE1_GFX_GREEN")
	)
	(segment
		(start 62.540896 -142.270988)
		(end 62.540896 -142.058136)
		(width 0.1016)
		(layer "B.Cu")
		(net "BMC_NODE1_GFX_GREEN")
	)
	(segment
		(start 18.4277 -86.532974)
		(end 18.4277 -84.541868)
		(width 0.1143)
		(layer "In6.Cu")
		(net "BMC_NODE1_GFX_GREEN")
	)
	(segment
		(start 11.12012 -136.54532)
		(end 7.82828 -133.25348)
		(width 0.1143)
		(layer "In6.Cu")
		(net "BMC_NODE1_GFX_GREEN")
	)
	(segment
		(start 40.3479 -147.030948)
		(end 39.48811 -146.169888)
		(width 0.1143)
		(layer "In6.Cu")
		(net "BMC_NODE1_GFX_GREEN")
	)
	(segment
		(start 37.67836 -146.169888)
		(end 36.271454 -144.762982)
		(width 0.1143)
		(layer "In6.Cu")
		(net "BMC_NODE1_GFX_GREEN")
	)
	(segment
		(start 21.78558 -59.033156)
		(end 19.499326 -56.746902)
		(width 0.1143)
		(layer "In6.Cu")
		(net "BMC_NODE1_GFX_GREEN")
	)
	(segment
		(start 54.661816 -147.984972)
		(end 51.861212 -147.984972)
		(width 0.1143)
		(layer "In6.Cu")
		(net "BMC_NODE1_GFX_GREEN")
	)
	(segment
		(start 16.9291 -80.412336)
		(end 21.93544 -75.405996)
		(width 0.1143)
		(layer "In6.Cu")
		(net "BMC_NODE1_GFX_GREEN")
	)
	(segment
		(start 21.2344 -61.253878)
		(end 21.78558 -60.702698)
		(width 0.1143)
		(layer "In6.Cu")
		(net "BMC_NODE1_GFX_GREEN")
	)
	(segment
		(start 21.93544 -75.405996)
		(end 21.93544 -64.935354)
		(width 0.1143)
		(layer "In6.Cu")
		(net "BMC_NODE1_GFX_GREEN")
	)
	(segment
		(start 15.715488 -138.328908)
		(end 11.725148 -138.328908)
		(width 0.1143)
		(layer "In6.Cu")
		(net "BMC_NODE1_GFX_GREEN")
	)
	(segment
		(start 16.9291 -86.330282)
		(end 16.9291 -80.412336)
		(width 0.1143)
		(layer "In6.Cu")
		(net "BMC_NODE1_GFX_GREEN")
	)
	(segment
		(start 17.148556 -86.549738)
		(end 16.9291 -86.330282)
		(width 0.1143)
		(layer "In6.Cu")
		(net "BMC_NODE1_GFX_GREEN")
	)
	(segment
		(start 36.271454 -144.762982)
		(end 32.174688 -140.66901)
		(width 0.1143)
		(layer "In6.Cu")
		(net "BMC_NODE1_GFX_GREEN")
	)
	(segment
		(start 11.12012 -137.72388)
		(end 11.12012 -136.54532)
		(width 0.1143)
		(layer "In6.Cu")
		(net "BMC_NODE1_GFX_GREEN")
	)
	(segment
		(start 11.725148 -138.328908)
		(end 11.12012 -137.72388)
		(width 0.1143)
		(layer "In6.Cu")
		(net "BMC_NODE1_GFX_GREEN")
	)
	(segment
		(start 17.982184 -140.595604)
		(end 15.715488 -138.328908)
		(width 0.1143)
		(layer "In6.Cu")
		(net "BMC_NODE1_GFX_GREEN")
	)
	(segment
		(start 62.540896 -142.058136)
		(end 62.944756 -142.461996)
		(width 0.1143)
		(layer "In6.Cu")
		(net "BMC_NODE1_GFX_GREEN")
	)
	(segment
		(start 21.2344 -64.234314)
		(end 21.2344 -61.253878)
		(width 0.1143)
		(layer "In6.Cu")
		(net "BMC_NODE1_GFX_GREEN")
	)
	(segment
		(start 17.50822 -53.36286)
		(end 17.50822 -50.087022)
		(width 0.1143)
		(layer "In6.Cu")
		(net "BMC_NODE1_GFX_GREEN")
	)
	(segment
		(start 17.94764 -53.80228)
		(end 17.50822 -53.36286)
		(width 0.1143)
		(layer "In6.Cu")
		(net "BMC_NODE1_GFX_GREEN")
	)
	(segment
		(start 43.5102 -148.78304)
		(end 42.387266 -147.660106)
		(width 0.1143)
		(layer "In6.Cu")
		(net "BMC_NODE1_GFX_GREEN")
	)
	(segment
		(start 51.861212 -147.984972)
		(end 51.80076 -147.92452)
		(width 0.1143)
		(layer "In6.Cu")
		(net "BMC_NODE1_GFX_GREEN")
	)
	(segment
		(start 18.676366 -56.746902)
		(end 17.94764 -56.018176)
		(width 0.1143)
		(layer "In6.Cu")
		(net "BMC_NODE1_GFX_GREEN")
	)
	(segment
		(start 19.499326 -56.746902)
		(end 18.676366 -56.746902)
		(width 0.1143)
		(layer "In6.Cu")
		(net "BMC_NODE1_GFX_GREEN")
	)
	(segment
		(start 32.174688 -140.66901)
		(end 32.100774 -140.595604)
		(width 0.1143)
		(layer "In6.Cu")
		(net "BMC_NODE1_GFX_GREEN")
	)
	(segment
		(start 62.944756 -143.028416)
		(end 59.704478 -146.268694)
		(width 0.1143)
		(layer "In6.Cu")
		(net "BMC_NODE1_GFX_GREEN")
	)
	(segment
		(start 49.456086 -148.78304)
		(end 43.5102 -148.78304)
		(width 0.1143)
		(layer "In6.Cu")
		(net "BMC_NODE1_GFX_GREEN")
	)
	(segment
		(start 17.6784 -84.541868)
		(end 17.6784 -86.330282)
		(width 0.1143)
		(layer "In6.Cu")
		(net "BMC_NODE1_GFX_GREEN")
	)
	(segment
		(start 56.378094 -146.268694)
		(end 54.661816 -147.984972)
		(width 0.1143)
		(layer "In6.Cu")
		(net "BMC_NODE1_GFX_GREEN")
	)
	(segment
		(start 17.6784 -86.330282)
		(end 17.458944 -86.549738)
		(width 0.1143)
		(layer "In6.Cu")
		(net "BMC_NODE1_GFX_GREEN")
	)
	(segment
		(start 42.387266 -147.660106)
		(end 42.04462 -147.660106)
		(width 0.1143)
		(layer "In6.Cu")
		(net "BMC_NODE1_GFX_GREEN")
	)
	(segment
		(start 62.944756 -142.461996)
		(end 62.944756 -143.028416)
		(width 0.1143)
		(layer "In6.Cu")
		(net "BMC_NODE1_GFX_GREEN")
	)
	(segment
		(start 42.04462 -147.660106)
		(end 41.415462 -147.030948)
		(width 0.1143)
		(layer "In6.Cu")
		(net "BMC_NODE1_GFX_GREEN")
	)
	(segment
		(start 17.458944 -86.549738)
		(end 17.148556 -86.549738)
		(width 0.1143)
		(layer "In6.Cu")
		(net "BMC_NODE1_GFX_GREEN")
	)
	(segment
		(start 51.80076 -147.92452)
		(end 50.314606 -147.92452)
		(width 0.1143)
		(layer "In6.Cu")
		(net "BMC_NODE1_GFX_GREEN")
	)
	(segment
		(start 39.48811 -146.169888)
		(end 37.67836 -146.169888)
		(width 0.1143)
		(layer "In6.Cu")
		(net "BMC_NODE1_GFX_GREEN")
	)
	(segment
		(start 32.100774 -140.595604)
		(end 17.982184 -140.595604)
		(width 0.1143)
		(layer "In6.Cu")
		(net "BMC_NODE1_GFX_GREEN")
	)
	(segment
		(start 50.314606 -147.92452)
		(end 49.456086 -148.78304)
		(width 0.1143)
		(layer "In6.Cu")
		(net "BMC_NODE1_GFX_GREEN")
	)
	(segment
		(start 17.8308 -84.389468)
		(end 17.6784 -84.541868)
		(width 0.1143)
		(layer "In6.Cu")
		(net "BMC_NODE1_GFX_GREEN")
	)
	(segment
		(start 21.78558 -60.702698)
		(end 21.78558 -59.033156)
		(width 0.1143)
		(layer "In6.Cu")
		(net "BMC_NODE1_GFX_GREEN")
	)
	(segment
		(start 18.4277 -84.541868)
		(end 18.2753 -84.389468)
		(width 0.1143)
		(layer "In6.Cu")
		(net "BMC_NODE1_GFX_GREEN")
	)
	(segment
		(start 59.704478 -146.268694)
		(end 56.378094 -146.268694)
		(width 0.1143)
		(layer "In6.Cu")
		(net "BMC_NODE1_GFX_GREEN")
	)
	(segment
		(start 7.82828 -97.132394)
		(end 18.4277 -86.532974)
		(width 0.1143)
		(layer "In6.Cu")
		(net "BMC_NODE1_GFX_GREEN")
	)
	(segment
		(start 17.94764 -56.018176)
		(end 17.94764 -53.80228)
		(width 0.1143)
		(layer "In6.Cu")
		(net "BMC_NODE1_GFX_GREEN")
	)
	(segment
		(start 18.2753 -84.389468)
		(end 17.8308 -84.389468)
		(width 0.1143)
		(layer "In6.Cu")
		(net "BMC_NODE1_GFX_GREEN")
	)
	(segment
		(start 21.93544 -64.935354)
		(end 21.2344 -64.234314)
		(width 0.1143)
		(layer "In6.Cu")
		(net "BMC_NODE1_GFX_GREEN")
	)
	(segment
		(start 7.82828 -133.25348)
		(end 7.82828 -97.132394)
		(width 0.1143)
		(layer "In6.Cu")
		(net "BMC_NODE1_GFX_GREEN")
	)
	(segment
		(start 41.415462 -147.030948)
		(end 40.3479 -147.030948)
		(width 0.1143)
		(layer "In6.Cu")
		(net "BMC_NODE1_GFX_GREEN")
	)
	(segment
		(start 61.217302 -88.04656)
		(end 61.217302 -88.82888)
		(width 0.1016)
		(layer "F.Cu")
		(net "SPI_CPU_NODE1_CS0_R_L")
	)
	(segment
		(start 62.161166 -96.309942)
		(end 62.161166 -96.04121)
		(width 0.1016)
		(layer "F.Cu")
		(net "SPI_CPU_NODE1_CS0_R_L")
	)
	(segment
		(start 61.266324 -88.877902)
		(end 61.266324 -89.219786)
		(width 0.1016)
		(layer "F.Cu")
		(net "SPI_CPU_NODE1_CS0_R_L")
	)
	(segment
		(start 60.945522 -90.654124)
		(end 60.81014 -90.789506)
		(width 0.1016)
		(layer "F.Cu")
		(net "SPI_CPU_NODE1_CS0_R_L")
	)
	(segment
		(start 61.26861 -94.764352)
		(end 61.26861 -95.148654)
		(width 0.1016)
		(layer "F.Cu")
		(net "SPI_CPU_NODE1_CS0_R_L")
	)
	(segment
		(start 61.217302 -88.82888)
		(end 61.266324 -88.877902)
		(width 0.1016)
		(layer "F.Cu")
		(net "SPI_CPU_NODE1_CS0_R_L")
	)
	(segment
		(start 61.266324 -89.219786)
		(end 60.945522 -89.540588)
		(width 0.1016)
		(layer "F.Cu")
		(net "SPI_CPU_NODE1_CS0_R_L")
	)
	(segment
		(start 60.81014 -94.305882)
		(end 61.26861 -94.764352)
		(width 0.1016)
		(layer "F.Cu")
		(net "SPI_CPU_NODE1_CS0_R_L")
	)
	(segment
		(start 60.81014 -90.789506)
		(end 60.81014 -94.305882)
		(width 0.1016)
		(layer "F.Cu")
		(net "SPI_CPU_NODE1_CS0_R_L")
	)
	(segment
		(start 62.161166 -96.04121)
		(end 61.26861 -95.148654)
		(width 0.1016)
		(layer "F.Cu")
		(net "SPI_CPU_NODE1_CS0_R_L")
	)
	(segment
		(start 60.945522 -89.540588)
		(end 60.945522 -90.654124)
		(width 0.1016)
		(layer "F.Cu")
		(net "SPI_CPU_NODE1_CS0_R_L")
	)
	(via
		(at 61.26861 -95.148654)
		(size 0.762)
		(drill 0.381)
		(layers "F.Cu" "B.Cu")
		(net "SPI_CPU_NODE1_CS0_R_L")
	)
	(segment
		(start 81.46796 -25.044146)
		(end 81.46796 -24.02967)
		(width 0.1651)
		(layer "F.Cu")
		(net "M_DDR3_NODE1_CS1_L")
	)
	(segment
		(start 64.060324 -62.55004)
		(end 64.045592 -62.55004)
		(width 0.1016)
		(layer "F.Cu")
		(net "M_DDR3_NODE1_CS1_L")
	)
	(segment
		(start 81.148682 -22.084538)
		(end 81.150206 -22.083014)
		(width 0.1651)
		(layer "F.Cu")
		(net "M_DDR3_NODE1_CS1_L")
	)
	(segment
		(start 65.257172 -60.440824)
		(end 65.257172 -61.353192)
		(width 0.1016)
		(layer "F.Cu")
		(net "M_DDR3_NODE1_CS1_L")
	)
	(segment
		(start 81.150206 -22.083014)
		(end 81.150206 -20.94992)
		(width 0.1651)
		(layer "F.Cu")
		(net "M_DDR3_NODE1_CS1_L")
	)
	(segment
		(start 65.5193 -60.178696)
		(end 65.257172 -60.440824)
		(width 0.1016)
		(layer "F.Cu")
		(net "M_DDR3_NODE1_CS1_L")
	)
	(segment
		(start 81.46796 -24.02967)
		(end 81.148682 -23.710392)
		(width 0.1651)
		(layer "F.Cu")
		(net "M_DDR3_NODE1_CS1_L")
	)
	(segment
		(start 65.257172 -61.353192)
		(end 64.060324 -62.55004)
		(width 0.1016)
		(layer "F.Cu")
		(net "M_DDR3_NODE1_CS1_L")
	)
	(segment
		(start 81.148682 -23.710392)
		(end 81.148682 -22.084538)
		(width 0.1651)
		(layer "F.Cu")
		(net "M_DDR3_NODE1_CS1_L")
	)
	(via
		(at 81.46796 -25.044146)
		(size 0.508)
		(drill 0.254)
		(layers "F.Cu" "B.Cu")
		(net "M_DDR3_NODE1_CS1_L")
	)
	(via
		(at 65.5193 -60.178696)
		(size 0.508)
		(drill 0.254)
		(layers "F.Cu" "B.Cu")
		(net "M_DDR3_NODE1_CS1_L")
	)
	(segment
		(start 82.520282 -33.672526)
		(end 82.312002 -33.464246)
		(width 0.2032)
		(layer "In2.Cu")
		(net "M_DDR3_NODE1_CS1_L")
	)
	(segment
		(start 82.520282 -32.544766)
		(end 82.520282 -32.008318)
		(width 0.2032)
		(layer "In2.Cu")
		(net "M_DDR3_NODE1_CS1_L")
	)
	(segment
		(start 81.05902 -29.493718)
		(end 81.05902 -26.706068)
		(width 0.2032)
		(layer "In2.Cu")
		(net "M_DDR3_NODE1_CS1_L")
	)
	(segment
		(start 81.46796 -26.297128)
		(end 81.46796 -25.044146)
		(width 0.2032)
		(layer "In2.Cu")
		(net "M_DDR3_NODE1_CS1_L")
	)
	(segment
		(start 68.570602 -57.75452)
		(end 69.97192 -57.75452)
		(width 0.2032)
		(layer "In2.Cu")
		(net "M_DDR3_NODE1_CS1_L")
	)
	(segment
		(start 82.9691 -43.047158)
		(end 83.17738 -42.838878)
		(width 0.2032)
		(layer "In2.Cu")
		(net "M_DDR3_NODE1_CS1_L")
	)
	(segment
		(start 72.32396 -55.151528)
		(end 73.21042 -54.265068)
		(width 0.2032)
		(layer "In2.Cu")
		(net "M_DDR3_NODE1_CS1_L")
	)
	(segment
		(start 83.17738 -41.416478)
		(end 83.17738 -41.121838)
		(width 0.2032)
		(layer "In2.Cu")
		(net "M_DDR3_NODE1_CS1_L")
	)
	(segment
		(start 83.17738 -43.966638)
		(end 82.9691 -43.758358)
		(width 0.2032)
		(layer "In2.Cu")
		(net "M_DDR3_NODE1_CS1_L")
	)
	(segment
		(start 81.768442 -32.753046)
		(end 82.312002 -32.753046)
		(width 0.2032)
		(layer "In2.Cu")
		(net "M_DDR3_NODE1_CS1_L")
	)
	(segment
		(start 82.520282 -34.032698)
		(end 82.520282 -33.672526)
		(width 0.2032)
		(layer "In2.Cu")
		(net "M_DDR3_NODE1_CS1_L")
	)
	(segment
		(start 81.560162 -32.961326)
		(end 81.768442 -32.753046)
		(width 0.2032)
		(layer "In2.Cu")
		(net "M_DDR3_NODE1_CS1_L")
	)
	(segment
		(start 82.105754 -30.540452)
		(end 81.05902 -29.493718)
		(width 0.2032)
		(layer "In2.Cu")
		(net "M_DDR3_NODE1_CS1_L")
	)
	(segment
		(start 69.97192 -57.75452)
		(end 72.32396 -55.40248)
		(width 0.2032)
		(layer "In2.Cu")
		(net "M_DDR3_NODE1_CS1_L")
	)
	(segment
		(start 82.25536 -44.972478)
		(end 82.25536 -44.677838)
		(width 0.2032)
		(layer "In2.Cu")
		(net "M_DDR3_NODE1_CS1_L")
	)
	(segment
		(start 83.17738 -42.544238)
		(end 82.9691 -42.335958)
		(width 0.2032)
		(layer "In2.Cu")
		(net "M_DDR3_NODE1_CS1_L")
	)
	(segment
		(start 82.25536 -43.550078)
		(end 82.25536 -43.255438)
		(width 0.2032)
		(layer "In2.Cu")
		(net "M_DDR3_NODE1_CS1_L")
	)
	(segment
		(start 82.46364 -40.202358)
		(end 82.9691 -40.202358)
		(width 0.2032)
		(layer "In2.Cu")
		(net "M_DDR3_NODE1_CS1_L")
	)
	(segment
		(start 82.25536 -40.410638)
		(end 82.46364 -40.202358)
		(width 0.2032)
		(layer "In2.Cu")
		(net "M_DDR3_NODE1_CS1_L")
	)
	(segment
		(start 82.312002 -33.464246)
		(end 81.768442 -33.464246)
		(width 0.2032)
		(layer "In2.Cu")
		(net "M_DDR3_NODE1_CS1_L")
	)
	(segment
		(start 68.424044 -57.75452)
		(end 68.570602 -57.75452)
		(width 0.1016)
		(layer "In2.Cu")
		(net "M_DDR3_NODE1_CS1_L")
	)
	(segment
		(start 83.17738 -45.389038)
		(end 82.9691 -45.180758)
		(width 0.2032)
		(layer "In2.Cu")
		(net "M_DDR3_NODE1_CS1_L")
	)
	(segment
		(start 83.17738 -39.337996)
		(end 82.177382 -38.337998)
		(width 0.2032)
		(layer "In2.Cu")
		(net "M_DDR3_NODE1_CS1_L")
	)
	(segment
		(start 82.46364 -43.758358)
		(end 82.25536 -43.550078)
		(width 0.2032)
		(layer "In2.Cu")
		(net "M_DDR3_NODE1_CS1_L")
	)
	(segment
		(start 82.46364 -43.047158)
		(end 82.9691 -43.047158)
		(width 0.2032)
		(layer "In2.Cu")
		(net "M_DDR3_NODE1_CS1_L")
	)
	(segment
		(start 72.32396 -55.40248)
		(end 72.32396 -55.151528)
		(width 0.2032)
		(layer "In2.Cu")
		(net "M_DDR3_NODE1_CS1_L")
	)
	(segment
		(start 82.46364 -40.913558)
		(end 82.25536 -40.705278)
		(width 0.2032)
		(layer "In2.Cu")
		(net "M_DDR3_NODE1_CS1_L")
	)
	(segment
		(start 82.46364 -45.180758)
		(end 82.25536 -44.972478)
		(width 0.2032)
		(layer "In2.Cu")
		(net "M_DDR3_NODE1_CS1_L")
	)
	(segment
		(start 83.17738 -42.838878)
		(end 83.17738 -42.544238)
		(width 0.2032)
		(layer "In2.Cu")
		(net "M_DDR3_NODE1_CS1_L")
	)
	(segment
		(start 82.9691 -40.913558)
		(end 82.46364 -40.913558)
		(width 0.2032)
		(layer "In2.Cu")
		(net "M_DDR3_NODE1_CS1_L")
	)
	(segment
		(start 82.9691 -40.202358)
		(end 83.17738 -39.994078)
		(width 0.2032)
		(layer "In2.Cu")
		(net "M_DDR3_NODE1_CS1_L")
	)
	(segment
		(start 83.17738 -44.261278)
		(end 83.17738 -43.966638)
		(width 0.2032)
		(layer "In2.Cu")
		(net "M_DDR3_NODE1_CS1_L")
	)
	(segment
		(start 82.312002 -32.753046)
		(end 82.520282 -32.544766)
		(width 0.2032)
		(layer "In2.Cu")
		(net "M_DDR3_NODE1_CS1_L")
	)
	(segment
		(start 75.520804 -52.787296)
		(end 76.542646 -52.787296)
		(width 0.2032)
		(layer "In2.Cu")
		(net "M_DDR3_NODE1_CS1_L")
	)
	(segment
		(start 83.17738 -41.121838)
		(end 82.9691 -40.913558)
		(width 0.2032)
		(layer "In2.Cu")
		(net "M_DDR3_NODE1_CS1_L")
	)
	(segment
		(start 82.79384 -31.019496)
		(end 82.314796 -30.540452)
		(width 0.2032)
		(layer "In2.Cu")
		(net "M_DDR3_NODE1_CS1_L")
	)
	(segment
		(start 82.520282 -32.008318)
		(end 82.79384 -31.73476)
		(width 0.2032)
		(layer "In2.Cu")
		(net "M_DDR3_NODE1_CS1_L")
	)
	(segment
		(start 82.9691 -42.335958)
		(end 82.46364 -42.335958)
		(width 0.2032)
		(layer "In2.Cu")
		(net "M_DDR3_NODE1_CS1_L")
	)
	(segment
		(start 82.9691 -43.758358)
		(end 82.46364 -43.758358)
		(width 0.2032)
		(layer "In2.Cu")
		(net "M_DDR3_NODE1_CS1_L")
	)
	(segment
		(start 81.05902 -26.706068)
		(end 81.46796 -26.297128)
		(width 0.2032)
		(layer "In2.Cu")
		(net "M_DDR3_NODE1_CS1_L")
	)
	(segment
		(start 82.46364 -44.469558)
		(end 82.9691 -44.469558)
		(width 0.2032)
		(layer "In2.Cu")
		(net "M_DDR3_NODE1_CS1_L")
	)
	(segment
		(start 74.043032 -54.265068)
		(end 75.520804 -52.787296)
		(width 0.2032)
		(layer "In2.Cu")
		(net "M_DDR3_NODE1_CS1_L")
	)
	(segment
		(start 83.17738 -39.994078)
		(end 83.17738 -39.337996)
		(width 0.2032)
		(layer "In2.Cu")
		(net "M_DDR3_NODE1_CS1_L")
	)
	(segment
		(start 82.25536 -42.127678)
		(end 82.25536 -41.833038)
		(width 0.2032)
		(layer "In2.Cu")
		(net "M_DDR3_NODE1_CS1_L")
	)
	(segment
		(start 73.21042 -54.265068)
		(end 74.043032 -54.265068)
		(width 0.2032)
		(layer "In2.Cu")
		(net "M_DDR3_NODE1_CS1_L")
	)
	(segment
		(start 82.46364 -42.335958)
		(end 82.25536 -42.127678)
		(width 0.2032)
		(layer "In2.Cu")
		(net "M_DDR3_NODE1_CS1_L")
	)
	(segment
		(start 81.768442 -33.464246)
		(end 81.560162 -33.255966)
		(width 0.2032)
		(layer "In2.Cu")
		(net "M_DDR3_NODE1_CS1_L")
	)
	(segment
		(start 83.17738 -46.152562)
		(end 83.17738 -45.389038)
		(width 0.2032)
		(layer "In2.Cu")
		(net "M_DDR3_NODE1_CS1_L")
	)
	(segment
		(start 82.25536 -44.677838)
		(end 82.46364 -44.469558)
		(width 0.2032)
		(layer "In2.Cu")
		(net "M_DDR3_NODE1_CS1_L")
	)
	(segment
		(start 76.542646 -52.787296)
		(end 83.17738 -46.152562)
		(width 0.2032)
		(layer "In2.Cu")
		(net "M_DDR3_NODE1_CS1_L")
	)
	(segment
		(start 82.9691 -44.469558)
		(end 83.17738 -44.261278)
		(width 0.2032)
		(layer "In2.Cu")
		(net "M_DDR3_NODE1_CS1_L")
	)
	(segment
		(start 82.9691 -41.624758)
		(end 83.17738 -41.416478)
		(width 0.2032)
		(layer "In2.Cu")
		(net "M_DDR3_NODE1_CS1_L")
	)
	(segment
		(start 82.314796 -30.540452)
		(end 82.105754 -30.540452)
		(width 0.2032)
		(layer "In2.Cu")
		(net "M_DDR3_NODE1_CS1_L")
	)
	(segment
		(start 82.25536 -40.705278)
		(end 82.25536 -40.410638)
		(width 0.2032)
		(layer "In2.Cu")
		(net "M_DDR3_NODE1_CS1_L")
	)
	(segment
		(start 82.25536 -43.255438)
		(end 82.46364 -43.047158)
		(width 0.2032)
		(layer "In2.Cu")
		(net "M_DDR3_NODE1_CS1_L")
	)
	(segment
		(start 81.560162 -33.255966)
		(end 81.560162 -32.961326)
		(width 0.2032)
		(layer "In2.Cu")
		(net "M_DDR3_NODE1_CS1_L")
	)
	(segment
		(start 82.46364 -41.624758)
		(end 82.9691 -41.624758)
		(width 0.2032)
		(layer "In2.Cu")
		(net "M_DDR3_NODE1_CS1_L")
	)
	(segment
		(start 82.9691 -45.180758)
		(end 82.46364 -45.180758)
		(width 0.2032)
		(layer "In2.Cu")
		(net "M_DDR3_NODE1_CS1_L")
	)
	(segment
		(start 65.5193 -60.178696)
		(end 65.999868 -60.178696)
		(width 0.1016)
		(layer "In2.Cu")
		(net "M_DDR3_NODE1_CS1_L")
	)
	(segment
		(start 82.177382 -34.375598)
		(end 82.520282 -34.032698)
		(width 0.2032)
		(layer "In2.Cu")
		(net "M_DDR3_NODE1_CS1_L")
	)
	(segment
		(start 82.177382 -38.337998)
		(end 82.177382 -34.375598)
		(width 0.2032)
		(layer "In2.Cu")
		(net "M_DDR3_NODE1_CS1_L")
	)
	(segment
		(start 82.79384 -31.73476)
		(end 82.79384 -31.019496)
		(width 0.2032)
		(layer "In2.Cu")
		(net "M_DDR3_NODE1_CS1_L")
	)
	(segment
		(start 82.25536 -41.833038)
		(end 82.46364 -41.624758)
		(width 0.2032)
		(layer "In2.Cu")
		(net "M_DDR3_NODE1_CS1_L")
	)
	(segment
		(start 65.999868 -60.178696)
		(end 68.424044 -57.75452)
		(width 0.1016)
		(layer "In2.Cu")
		(net "M_DDR3_NODE1_CS1_L")
	)
	(segment
		(start 138.486896 -114.461798)
		(end 138.486896 -113.351818)
		(width 0.1016)
		(layer "F.Cu")
		(net "SEL_DOT_SRC5")
	)
	(segment
		(start 137.125964 -115.31473)
		(end 137.449052 -114.991642)
		(width 0.1016)
		(layer "F.Cu")
		(net "SEL_DOT_SRC5")
	)
	(segment
		(start 137.449052 -114.991642)
		(end 137.957052 -114.991642)
		(width 0.1016)
		(layer "F.Cu")
		(net "SEL_DOT_SRC5")
	)
	(segment
		(start 138.781536 -113.057178)
		(end 139.304522 -112.534192)
		(width 0.1016)
		(layer "F.Cu")
		(net "SEL_DOT_SRC5")
	)
	(segment
		(start 139.304522 -112.534192)
		(end 139.870434 -112.534192)
		(width 0.1016)
		(layer "F.Cu")
		(net "SEL_DOT_SRC5")
	)
	(segment
		(start 139.87526 -112.529366)
		(end 139.870434 -112.534192)
		(width 0.1016)
		(layer "F.Cu")
		(net "SEL_DOT_SRC5")
	)
	(segment
		(start 139.87526 -111.507778)
		(end 139.87526 -112.529366)
		(width 0.1016)
		(layer "F.Cu")
		(net "SEL_DOT_SRC5")
	)
	(segment
		(start 138.486896 -113.351818)
		(end 138.781536 -113.057178)
		(width 0.1016)
		(layer "F.Cu")
		(net "SEL_DOT_SRC5")
	)
	(segment
		(start 137.957052 -114.991642)
		(end 138.486896 -114.461798)
		(width 0.1016)
		(layer "F.Cu")
		(net "SEL_DOT_SRC5")
	)
	(segment
		(start 136.503664 -115.31473)
		(end 137.125964 -115.31473)
		(width 0.1016)
		(layer "F.Cu")
		(net "SEL_DOT_SRC5")
	)
	(via
		(at 138.781536 -113.057178)
		(size 0.508)
		(drill 0.254)
		(layers "F.Cu" "B.Cu")
		(net "SEL_DOT_SRC5")
	)
	(segment
		(start 144.570196 -70.83933)
		(end 144.570196 -74.62393)
		(width 0.1016)
		(layer "F.Cu")
		(net "SATA_SPI_CS_NODE1_R")
	)
	(segment
		(start 145.13052 -69.545454)
		(end 145.205196 -69.62013)
		(width 0.1016)
		(layer "F.Cu")
		(net "SATA_SPI_CS_NODE1_R")
	)
	(segment
		(start 144.570196 -74.62393)
		(end 143.653256 -75.54087)
		(width 0.1016)
		(layer "F.Cu")
		(net "SATA_SPI_CS_NODE1_R")
	)
	(segment
		(start 143.653256 -75.54087)
		(end 142.827248 -75.54087)
		(width 0.1016)
		(layer "F.Cu")
		(net "SATA_SPI_CS_NODE1_R")
	)
	(segment
		(start 139.76223 -75.393296)
		(end 142.279878 -75.393296)
		(width 0.1016)
		(layer "F.Cu")
		(net "SATA_SPI_CS_NODE1_R")
	)
	(segment
		(start 142.827248 -75.54087)
		(end 142.62735 -75.740768)
		(width 0.1016)
		(layer "F.Cu")
		(net "SATA_SPI_CS_NODE1_R")
	)
	(segment
		(start 142.279878 -75.393296)
		(end 142.62735 -75.740768)
		(width 0.1016)
		(layer "F.Cu")
		(net "SATA_SPI_CS_NODE1_R")
	)
	(segment
		(start 145.13052 -68.799202)
		(end 145.13052 -69.545454)
		(width 0.1016)
		(layer "F.Cu")
		(net "SATA_SPI_CS_NODE1_R")
	)
	(segment
		(start 145.205196 -70.20433)
		(end 144.570196 -70.83933)
		(width 0.1016)
		(layer "F.Cu")
		(net "SATA_SPI_CS_NODE1_R")
	)
	(segment
		(start 145.205196 -69.62013)
		(end 145.205196 -70.20433)
		(width 0.1016)
		(layer "F.Cu")
		(net "SATA_SPI_CS_NODE1_R")
	)
	(via
		(at 142.62735 -75.740768)
		(size 0.508)
		(drill 0.254)
		(layers "F.Cu" "B.Cu")
		(net "SATA_SPI_CS_NODE1_R")
	)
	(segment
		(start 69.703696 -142.821406)
		(end 69.703696 -144.103852)
		(width 0.1016)
		(layer "F.Cu")
		(net "BMC_NODE1_JTAG_TMS")
	)
	(segment
		(start 68.480686 -148.076412)
		(end 68.480686 -146.408902)
		(width 0.1016)
		(layer "F.Cu")
		(net "BMC_NODE1_JTAG_TMS")
	)
	(segment
		(start 69.341746 -142.459456)
		(end 69.703696 -142.821406)
		(width 0.1016)
		(layer "F.Cu")
		(net "BMC_NODE1_JTAG_TMS")
	)
	(segment
		(start 68.480686 -145.326862)
		(end 68.480686 -146.408902)
		(width 0.1016)
		(layer "F.Cu")
		(net "BMC_NODE1_JTAG_TMS")
	)
	(segment
		(start 69.703696 -144.103852)
		(end 68.480686 -145.326862)
		(width 0.1016)
		(layer "F.Cu")
		(net "BMC_NODE1_JTAG_TMS")
	)
	(via
		(at 68.480686 -146.408902)
		(size 0.508)
		(drill 0.254)
		(layers "F.Cu" "B.Cu")
		(net "BMC_NODE1_JTAG_TMS")
	)
	(segment
		(start 88.35009 -23.56231)
		(end 87.821262 -24.091138)
		(width 0.1651)
		(layer "F.Cu")
		(net "M1_DQ_NODE1_DQ41")
	)
	(segment
		(start 70.583044 -68.351654)
		(end 70.216776 -68.717922)
		(width 0.1016)
		(layer "F.Cu")
		(net "M1_DQ_NODE1_DQ41")
	)
	(segment
		(start 70.583044 -68.324222)
		(end 70.583044 -68.351654)
		(width 0.1016)
		(layer "F.Cu")
		(net "M1_DQ_NODE1_DQ41")
	)
	(segment
		(start 87.821262 -24.091138)
		(end 87.597742 -24.091138)
		(width 0.1651)
		(layer "F.Cu")
		(net "M1_DQ_NODE1_DQ41")
	)
	(segment
		(start 88.35009 -20.94992)
		(end 88.35009 -23.56231)
		(width 0.1651)
		(layer "F.Cu")
		(net "M1_DQ_NODE1_DQ41")
	)
	(via
		(at 70.216776 -68.717922)
		(size 0.508)
		(drill 0.254)
		(layers "F.Cu" "B.Cu")
		(net "M1_DQ_NODE1_DQ41")
	)
	(via
		(at 87.597742 -24.091138)
		(size 0.508)
		(drill 0.254)
		(layers "F.Cu" "B.Cu")
		(net "M1_DQ_NODE1_DQ41")
	)
	(segment
		(start 77.130402 -56.704992)
		(end 86.402418 -47.432976)
		(width 0.2032)
		(layer "In2.Cu")
		(net "M1_DQ_NODE1_DQ41")
	)
	(segment
		(start 87.31504 -45.658786)
		(end 87.60968 -45.658786)
		(width 0.2032)
		(layer "In2.Cu")
		(net "M1_DQ_NODE1_DQ41")
	)
	(segment
		(start 87.81796 -38.1762)
		(end 86.03488 -36.39312)
		(width 0.2032)
		(layer "In2.Cu")
		(net "M1_DQ_NODE1_DQ41")
	)
	(segment
		(start 69.215762 -63.762382)
		(end 70.283324 -62.69482)
		(width 0.2032)
		(layer "In2.Cu")
		(net "M1_DQ_NODE1_DQ41")
	)
	(segment
		(start 87.60968 -45.658786)
		(end 87.81796 -45.450506)
		(width 0.2032)
		(layer "In2.Cu")
		(net "M1_DQ_NODE1_DQ41")
	)
	(segment
		(start 70.216776 -68.717922)
		(end 70.014084 -68.51523)
		(width 0.1016)
		(layer "In2.Cu")
		(net "M1_DQ_NODE1_DQ41")
	)
	(segment
		(start 70.283324 -62.69482)
		(end 70.849744 -62.69482)
		(width 0.2032)
		(layer "In2.Cu")
		(net "M1_DQ_NODE1_DQ41")
	)
	(segment
		(start 86.03488 -30.428184)
		(end 86.598506 -29.864558)
		(width 0.2032)
		(layer "In2.Cu")
		(net "M1_DQ_NODE1_DQ41")
	)
	(segment
		(start 68.291964 -64.890142)
		(end 68.977002 -64.205104)
		(width 0.1016)
		(layer "In2.Cu")
		(net "M1_DQ_NODE1_DQ41")
	)
	(segment
		(start 71.19112 -61.81217)
		(end 76.298298 -56.704992)
		(width 0.2032)
		(layer "In2.Cu")
		(net "M1_DQ_NODE1_DQ41")
	)
	(segment
		(start 87.81796 -45.450506)
		(end 87.81796 -38.1762)
		(width 0.2032)
		(layer "In2.Cu")
		(net "M1_DQ_NODE1_DQ41")
	)
	(segment
		(start 68.291964 -67.427348)
		(end 68.291964 -64.890142)
		(width 0.1016)
		(layer "In2.Cu")
		(net "M1_DQ_NODE1_DQ41")
	)
	(segment
		(start 68.977002 -64.001142)
		(end 69.215762 -63.762382)
		(width 0.1016)
		(layer "In2.Cu")
		(net "M1_DQ_NODE1_DQ41")
	)
	(segment
		(start 88.090502 -24.583898)
		(end 87.597742 -24.091138)
		(width 0.2032)
		(layer "In2.Cu")
		(net "M1_DQ_NODE1_DQ41")
	)
	(segment
		(start 87.807292 -29.864558)
		(end 88.090502 -29.581348)
		(width 0.2032)
		(layer "In2.Cu")
		(net "M1_DQ_NODE1_DQ41")
	)
	(segment
		(start 68.977002 -64.205104)
		(end 68.977002 -64.001142)
		(width 0.1016)
		(layer "In2.Cu")
		(net "M1_DQ_NODE1_DQ41")
	)
	(segment
		(start 69.651372 -68.208652)
		(end 69.073268 -68.208652)
		(width 0.1016)
		(layer "In2.Cu")
		(net "M1_DQ_NODE1_DQ41")
	)
	(segment
		(start 88.090502 -29.581348)
		(end 88.090502 -24.583898)
		(width 0.2032)
		(layer "In2.Cu")
		(net "M1_DQ_NODE1_DQ41")
	)
	(segment
		(start 87.10676 -45.450506)
		(end 87.31504 -45.658786)
		(width 0.2032)
		(layer "In2.Cu")
		(net "M1_DQ_NODE1_DQ41")
	)
	(segment
		(start 86.39556 -44.240196)
		(end 86.60384 -44.031916)
		(width 0.2032)
		(layer "In2.Cu")
		(net "M1_DQ_NODE1_DQ41")
	)
	(segment
		(start 76.298298 -56.704992)
		(end 77.130402 -56.704992)
		(width 0.2032)
		(layer "In2.Cu")
		(net "M1_DQ_NODE1_DQ41")
	)
	(segment
		(start 86.39556 -47.426118)
		(end 86.39556 -44.240196)
		(width 0.2032)
		(layer "In2.Cu")
		(net "M1_DQ_NODE1_DQ41")
	)
	(segment
		(start 70.014084 -68.51523)
		(end 69.95795 -68.51523)
		(width 0.1016)
		(layer "In2.Cu")
		(net "M1_DQ_NODE1_DQ41")
	)
	(segment
		(start 87.10676 -44.240196)
		(end 87.10676 -45.450506)
		(width 0.2032)
		(layer "In2.Cu")
		(net "M1_DQ_NODE1_DQ41")
	)
	(segment
		(start 86.402418 -47.432976)
		(end 86.39556 -47.426118)
		(width 0.2032)
		(layer "In2.Cu")
		(net "M1_DQ_NODE1_DQ41")
	)
	(segment
		(start 70.849744 -62.69482)
		(end 71.19112 -62.353444)
		(width 0.2032)
		(layer "In2.Cu")
		(net "M1_DQ_NODE1_DQ41")
	)
	(segment
		(start 86.598506 -29.864558)
		(end 87.807292 -29.864558)
		(width 0.2032)
		(layer "In2.Cu")
		(net "M1_DQ_NODE1_DQ41")
	)
	(segment
		(start 71.19112 -62.353444)
		(end 71.19112 -61.81217)
		(width 0.2032)
		(layer "In2.Cu")
		(net "M1_DQ_NODE1_DQ41")
	)
	(segment
		(start 86.89848 -44.031916)
		(end 87.10676 -44.240196)
		(width 0.2032)
		(layer "In2.Cu")
		(net "M1_DQ_NODE1_DQ41")
	)
	(segment
		(start 69.95795 -68.51523)
		(end 69.651372 -68.208652)
		(width 0.1016)
		(layer "In2.Cu")
		(net "M1_DQ_NODE1_DQ41")
	)
	(segment
		(start 69.073268 -68.208652)
		(end 68.291964 -67.427348)
		(width 0.1016)
		(layer "In2.Cu")
		(net "M1_DQ_NODE1_DQ41")
	)
	(segment
		(start 86.60384 -44.031916)
		(end 86.89848 -44.031916)
		(width 0.2032)
		(layer "In2.Cu")
		(net "M1_DQ_NODE1_DQ41")
	)
	(segment
		(start 86.03488 -36.39312)
		(end 86.03488 -30.428184)
		(width 0.2032)
		(layer "In2.Cu")
		(net "M1_DQ_NODE1_DQ41")
	)
	(segment
		(start 136.25576 -111.183674)
		(end 136.25576 -111.588804)
		(width 0.1016)
		(layer "F.Cu")
		(net "CLKREQA_NODE1_N")
	)
	(segment
		(start 135.547862 -111.865156)
		(end 135.979408 -111.865156)
		(width 0.1016)
		(layer "F.Cu")
		(net "CLKREQA_NODE1_N")
	)
	(segment
		(start 136.498584 -111.183674)
		(end 136.25576 -111.183674)
		(width 0.1016)
		(layer "F.Cu")
		(net "CLKREQA_NODE1_N")
	)
	(segment
		(start 133.953758 -113.330736)
		(end 134.121652 -113.162842)
		(width 0.1016)
		(layer "F.Cu")
		(net "CLKREQA_NODE1_N")
	)
	(segment
		(start 134.121652 -113.162842)
		(end 134.121652 -112.686846)
		(width 0.1016)
		(layer "F.Cu")
		(net "CLKREQA_NODE1_N")
	)
	(segment
		(start 133.953758 -113.96472)
		(end 133.953758 -113.330736)
		(width 0.1016)
		(layer "F.Cu")
		(net "CLKREQA_NODE1_N")
	)
	(segment
		(start 134.4295 -112.378998)
		(end 135.03402 -112.378998)
		(width 0.1016)
		(layer "F.Cu")
		(net "CLKREQA_NODE1_N")
	)
	(segment
		(start 136.25576 -111.588804)
		(end 135.979408 -111.865156)
		(width 0.1016)
		(layer "F.Cu")
		(net "CLKREQA_NODE1_N")
	)
	(segment
		(start 137.39876 -108.770674)
		(end 136.781286 -109.388148)
		(width 0.1016)
		(layer "F.Cu")
		(net "CLKREQA_NODE1_N")
	)
	(segment
		(start 136.781286 -110.900972)
		(end 136.498584 -111.183674)
		(width 0.1016)
		(layer "F.Cu")
		(net "CLKREQA_NODE1_N")
	)
	(segment
		(start 135.03402 -112.378998)
		(end 135.547862 -111.865156)
		(width 0.1016)
		(layer "F.Cu")
		(net "CLKREQA_NODE1_N")
	)
	(segment
		(start 134.121652 -112.686846)
		(end 134.4295 -112.378998)
		(width 0.1016)
		(layer "F.Cu")
		(net "CLKREQA_NODE1_N")
	)
	(segment
		(start 136.781286 -109.388148)
		(end 136.781286 -110.900972)
		(width 0.1016)
		(layer "F.Cu")
		(net "CLKREQA_NODE1_N")
	)
	(via
		(at 135.979408 -111.865156)
		(size 0.508)
		(drill 0.254)
		(layers "F.Cu" "B.Cu")
		(net "CLKREQA_NODE1_N")
	)
	(segment
		(start 181.01056 -117.365526)
		(end 182.9181 -117.365526)
		(width 0.1016)
		(layer "F.Cu")
		(net "PWRGD_NODE1_P12V_PG")
	)
	(segment
		(start 182.9181 -117.365526)
		(end 184.55132 -115.732306)
		(width 0.1016)
		(layer "F.Cu")
		(net "PWRGD_NODE1_P12V_PG")
	)
	(segment
		(start 184.587134 -115.767612)
		(end 184.55132 -115.731798)
		(width 0.1016)
		(layer "F.Cu")
		(net "PWRGD_NODE1_P12V_PG")
	)
	(segment
		(start 185.817764 -115.767612)
		(end 184.587134 -115.767612)
		(width 0.1016)
		(layer "F.Cu")
		(net "PWRGD_NODE1_P12V_PG")
	)
	(segment
		(start 184.55132 -115.732306)
		(end 184.55132 -115.731798)
		(width 0.1016)
		(layer "F.Cu")
		(net "PWRGD_NODE1_P12V_PG")
	)
	(via
		(at 184.55132 -115.731798)
		(size 0.508)
		(drill 0.254)
		(layers "F.Cu" "B.Cu")
		(net "PWRGD_NODE1_P12V_PG")
	)
	(segment
		(start 107.925616 -151.967692)
		(end 108.690664 -151.967692)
		(width 0.1016)
		(layer "F.Cu")
		(net "N52411159")
	)
	(segment
		(start 108.690664 -151.967692)
		(end 109.05236 -151.605996)
		(width 0.1016)
		(layer "F.Cu")
		(net "N52411159")
	)
	(segment
		(start 109.56036 -152.113996)
		(end 109.56036 -152.381966)
		(width 0.1016)
		(layer "F.Cu")
		(net "N52411159")
	)
	(segment
		(start 109.05236 -151.605996)
		(end 109.56036 -152.113996)
		(width 0.1016)
		(layer "F.Cu")
		(net "N52411159")
	)
	(via
		(at 109.05236 -151.605996)
		(size 0.508)
		(drill 0.254)
		(layers "F.Cu" "B.Cu")
		(net "N52411159")
	)
	(segment
		(start 71.033132 -146.190462)
		(end 71.033132 -145.908522)
		(width 0.1016)
		(layer "F.Cu")
		(net "BMC_NODE1_JTAG_TCK")
	)
	(segment
		(start 70.639686 -146.583908)
		(end 71.033132 -146.190462)
		(width 0.1016)
		(layer "F.Cu")
		(net "BMC_NODE1_JTAG_TCK")
	)
	(segment
		(start 70.141846 -142.720822)
		(end 70.535292 -143.114268)
		(width 0.1016)
		(layer "F.Cu")
		(net "BMC_NODE1_JTAG_TCK")
	)
	(segment
		(start 70.535292 -143.114268)
		(end 70.535292 -145.410682)
		(width 0.1016)
		(layer "F.Cu")
		(net "BMC_NODE1_JTAG_TCK")
	)
	(segment
		(start 70.141846 -142.459456)
		(end 70.141846 -142.720822)
		(width 0.1016)
		(layer "F.Cu")
		(net "BMC_NODE1_JTAG_TCK")
	)
	(segment
		(start 70.639686 -148.076412)
		(end 70.639686 -146.583908)
		(width 0.1016)
		(layer "F.Cu")
		(net "BMC_NODE1_JTAG_TCK")
	)
	(segment
		(start 70.535292 -145.410682)
		(end 71.033132 -145.908522)
		(width 0.1016)
		(layer "F.Cu")
		(net "BMC_NODE1_JTAG_TCK")
	)
	(via
		(at 71.033132 -145.908522)
		(size 0.508)
		(drill 0.254)
		(layers "F.Cu" "B.Cu")
		(net "BMC_NODE1_JTAG_TCK")
	)
	(segment
		(start 58.42254 -95.023686)
		(end 58.42254 -94.8182)
		(width 0.1016)
		(layer "F.Cu")
		(net "PD_CPU_NODE1_DFX_GPIO_GRP1_1")
	)
	(segment
		(start 57.067196 -90.728292)
		(end 57.236868 -90.897964)
		(width 0.1016)
		(layer "F.Cu")
		(net "PD_CPU_NODE1_DFX_GPIO_GRP1_1")
	)
	(segment
		(start 59.113166 -96.309942)
		(end 59.113166 -95.714312)
		(width 0.1016)
		(layer "F.Cu")
		(net "PD_CPU_NODE1_DFX_GPIO_GRP1_1")
	)
	(segment
		(start 57.236868 -90.897964)
		(end 57.236868 -93.632528)
		(width 0.1016)
		(layer "F.Cu")
		(net "PD_CPU_NODE1_DFX_GPIO_GRP1_1")
	)
	(segment
		(start 57.468008 -88.723978)
		(end 57.067196 -89.12479)
		(width 0.1016)
		(layer "F.Cu")
		(net "PD_CPU_NODE1_DFX_GPIO_GRP1_1")
	)
	(segment
		(start 57.468008 -87.863172)
		(end 57.468008 -88.723978)
		(width 0.1016)
		(layer "F.Cu")
		(net "PD_CPU_NODE1_DFX_GPIO_GRP1_1")
	)
	(segment
		(start 57.067196 -89.12479)
		(end 57.067196 -90.728292)
		(width 0.1016)
		(layer "F.Cu")
		(net "PD_CPU_NODE1_DFX_GPIO_GRP1_1")
	)
	(segment
		(start 59.113166 -95.714312)
		(end 58.42254 -95.023686)
		(width 0.1016)
		(layer "F.Cu")
		(net "PD_CPU_NODE1_DFX_GPIO_GRP1_1")
	)
	(segment
		(start 57.897268 -87.433912)
		(end 57.468008 -87.863172)
		(width 0.1016)
		(layer "F.Cu")
		(net "PD_CPU_NODE1_DFX_GPIO_GRP1_1")
	)
	(segment
		(start 57.236868 -93.632528)
		(end 58.42254 -94.8182)
		(width 0.1016)
		(layer "F.Cu")
		(net "PD_CPU_NODE1_DFX_GPIO_GRP1_1")
	)
	(segment
		(start 57.897268 -87.341964)
		(end 57.897268 -87.433912)
		(width 0.1016)
		(layer "F.Cu")
		(net "PD_CPU_NODE1_DFX_GPIO_GRP1_1")
	)
	(via
		(at 58.42254 -94.8182)
		(size 0.508)
		(drill 0.254)
		(layers "F.Cu" "B.Cu")
		(net "PD_CPU_NODE1_DFX_GPIO_GRP1_1")
	)
	(segment
		(start 147.247356 -70.392544)
		(end 147.247356 -78.61554)
		(width 0.127)
		(layer "F.Cu")
		(net "P2E_CPU_SATA_NODE1_TX_DN")
	)
	(segment
		(start 147.130516 -69.445378)
		(end 147.075144 -69.584824)
		(width 0.127)
		(layer "F.Cu")
		(net "P2E_CPU_SATA_NODE1_TX_DN")
	)
	(segment
		(start 147.075144 -69.584824)
		(end 147.075144 -70.220332)
		(width 0.127)
		(layer "F.Cu")
		(net "P2E_CPU_SATA_NODE1_TX_DN")
	)
	(segment
		(start 147.075144 -70.220332)
		(end 147.247356 -70.392544)
		(width 0.127)
		(layer "F.Cu")
		(net "P2E_CPU_SATA_NODE1_TX_DN")
	)
	(segment
		(start 147.130516 -68.799202)
		(end 147.130516 -69.445378)
		(width 0.127)
		(layer "F.Cu")
		(net "P2E_CPU_SATA_NODE1_TX_DN")
	)
	(segment
		(start 147.247356 -78.61554)
		(end 147.7391 -79.107284)
		(width 0.127)
		(layer "F.Cu")
		(net "P2E_CPU_SATA_NODE1_TX_DN")
	)
	(via
		(at 147.7391 -79.107284)
		(size 0.508)
		(drill 0.254)
		(layers "F.Cu" "B.Cu")
		(net "P2E_CPU_SATA_NODE1_TX_DN")
	)
	(segment
		(start 54.029102 -38.523672)
		(end 53.878734 -38.508178)
		(width 0.127)
		(layer "B.Cu")
		(net "P2E_CPU_SATA_NODE1_TX_DN")
	)
	(segment
		(start 44.733972 -59.323986)
		(end 44.818554 -59.402218)
		(width 0.127)
		(layer "B.Cu")
		(net "P2E_CPU_SATA_NODE1_TX_DN")
	)
	(segment
		(start 139.412218 -76.503022)
		(end 139.312396 -76.480924)
		(width 0.127)
		(layer "B.Cu")
		(net "P2E_CPU_SATA_NODE1_TX_DN")
	)
	(segment
		(start 122.06097 -62.33668)
		(end 119.172482 -58.548778)
		(width 0.127)
		(layer "B.Cu")
		(net "P2E_CPU_SATA_NODE1_TX_DN")
	)
	(segment
		(start 44.9326 -59.722004)
		(end 44.609258 -60.045346)
		(width 0.127)
		(layer "B.Cu")
		(net "P2E_CPU_SATA_NODE1_TX_DN")
	)
	(segment
		(start 147.46986 -78.838044)
		(end 147.46986 -78.187296)
		(width 0.127)
		(layer "B.Cu")
		(net "P2E_CPU_SATA_NODE1_TX_DN")
	)
	(segment
		(start 115.927886 -56.267858)
		(end 109.725206 -54.935628)
		(width 0.127)
		(layer "B.Cu")
		(net "P2E_CPU_SATA_NODE1_TX_DN")
	)
	(segment
		(start 47.617888 -40.771318)
		(end 46.007782 -42.340784)
		(width 0.127)
		(layer "B.Cu")
		(net "P2E_CPU_SATA_NODE1_TX_DN")
	)
	(segment
		(start 44.022772 -46.982126)
		(end 43.642026 -58.187336)
		(width 0.127)
		(layer "B.Cu")
		(net "P2E_CPU_SATA_NODE1_TX_DN")
	)
	(segment
		(start 46.007782 -42.340784)
		(end 44.022772 -46.982126)
		(width 0.127)
		(layer "B.Cu")
		(net "P2E_CPU_SATA_NODE1_TX_DN")
	)
	(segment
		(start 43.984418 -58.810906)
		(end 44.733972 -59.323986)
		(width 0.127)
		(layer "B.Cu")
		(net "P2E_CPU_SATA_NODE1_TX_DN")
	)
	(segment
		(start 130.379724 -70.464426)
		(end 122.06097 -62.33668)
		(width 0.127)
		(layer "B.Cu")
		(net "P2E_CPU_SATA_NODE1_TX_DN")
	)
	(segment
		(start 58.828432 -39.03853)
		(end 58.828432 -39.02075)
		(width 0.127)
		(layer "B.Cu")
		(net "P2E_CPU_SATA_NODE1_TX_DN")
	)
	(segment
		(start 139.312396 -76.480924)
		(end 136.521952 -75.871832)
		(width 0.127)
		(layer "B.Cu")
		(net "P2E_CPU_SATA_NODE1_TX_DN")
	)
	(segment
		(start 43.642026 -58.187336)
		(end 43.984418 -58.810906)
		(width 0.127)
		(layer "B.Cu")
		(net "P2E_CPU_SATA_NODE1_TX_DN")
	)
	(segment
		(start 71.52513 -42.294048)
		(end 71.502016 -42.294048)
		(width 0.127)
		(layer "B.Cu")
		(net "P2E_CPU_SATA_NODE1_TX_DN")
	)
	(segment
		(start 93.524832 -43.60799)
		(end 89.25814 -43.353228)
		(width 0.127)
		(layer "B.Cu")
		(net "P2E_CPU_SATA_NODE1_TX_DN")
	)
	(segment
		(start 143.352774 -77.583284)
		(end 139.412218 -76.503022)
		(width 0.127)
		(layer "B.Cu")
		(net "P2E_CPU_SATA_NODE1_TX_DN")
	)
	(segment
		(start 136.521952 -75.871832)
		(end 134.42696 -75.359768)
		(width 0.127)
		(layer "B.Cu")
		(net "P2E_CPU_SATA_NODE1_TX_DN")
	)
	(segment
		(start 44.9326 -59.516264)
		(end 44.9326 -59.722004)
		(width 0.127)
		(layer "B.Cu")
		(net "P2E_CPU_SATA_NODE1_TX_DN")
	)
	(segment
		(start 131.83362 -73.238614)
		(end 130.379724 -70.464426)
		(width 0.127)
		(layer "B.Cu")
		(net "P2E_CPU_SATA_NODE1_TX_DN")
	)
	(segment
		(start 147.7391 -79.107284)
		(end 147.46986 -78.838044)
		(width 0.127)
		(layer "B.Cu")
		(net "P2E_CPU_SATA_NODE1_TX_DN")
	)
	(segment
		(start 58.828432 -39.02075)
		(end 54.029102 -38.523672)
		(width 0.127)
		(layer "B.Cu")
		(net "P2E_CPU_SATA_NODE1_TX_DN")
	)
	(segment
		(start 134.42696 -75.359768)
		(end 131.83362 -73.238614)
		(width 0.127)
		(layer "B.Cu")
		(net "P2E_CPU_SATA_NODE1_TX_DN")
	)
	(segment
		(start 53.878734 -38.508178)
		(end 52.733194 -38.573202)
		(width 0.127)
		(layer "B.Cu")
		(net "P2E_CPU_SATA_NODE1_TX_DN")
	)
	(segment
		(start 109.725206 -54.935628)
		(end 109.423708 -54.724808)
		(width 0.127)
		(layer "B.Cu")
		(net "P2E_CPU_SATA_NODE1_TX_DN")
	)
	(segment
		(start 109.423708 -54.724808)
		(end 93.524832 -43.60799)
		(width 0.127)
		(layer "B.Cu")
		(net "P2E_CPU_SATA_NODE1_TX_DN")
	)
	(segment
		(start 52.733194 -38.573202)
		(end 47.617888 -40.771318)
		(width 0.127)
		(layer "B.Cu")
		(net "P2E_CPU_SATA_NODE1_TX_DN")
	)
	(segment
		(start 119.172482 -58.548778)
		(end 115.927886 -56.267858)
		(width 0.127)
		(layer "B.Cu")
		(net "P2E_CPU_SATA_NODE1_TX_DN")
	)
	(segment
		(start 71.502016 -42.294048)
		(end 58.828432 -39.03853)
		(width 0.127)
		(layer "B.Cu")
		(net "P2E_CPU_SATA_NODE1_TX_DN")
	)
	(segment
		(start 44.818554 -59.402218)
		(end 44.9326 -59.516264)
		(width 0.127)
		(layer "B.Cu")
		(net "P2E_CPU_SATA_NODE1_TX_DN")
	)
	(segment
		(start 89.25814 -43.353228)
		(end 71.52513 -42.294048)
		(width 0.127)
		(layer "B.Cu")
		(net "P2E_CPU_SATA_NODE1_TX_DN")
	)
	(segment
		(start 146.865848 -77.583284)
		(end 143.352774 -77.583284)
		(width 0.127)
		(layer "B.Cu")
		(net "P2E_CPU_SATA_NODE1_TX_DN")
	)
	(segment
		(start 147.46986 -78.187296)
		(end 146.865848 -77.583284)
		(width 0.127)
		(layer "B.Cu")
		(net "P2E_CPU_SATA_NODE1_TX_DN")
	)
	(segment
		(start 61.58484 -60.348114)
		(end 61.58484 -61.653674)
		(width 0.1016)
		(layer "F.Cu")
		(net "M_DDR3_NODE1_MA0")
	)
	(segment
		(start 61.742828 -63.68923)
		(end 61.523118 -63.90894)
		(width 0.1016)
		(layer "F.Cu")
		(net "M_DDR3_NODE1_MA0")
	)
	(segment
		(start 61.523118 -63.90894)
		(end 61.523118 -64.591438)
		(width 0.1016)
		(layer "F.Cu")
		(net "M_DDR3_NODE1_MA0")
	)
	(segment
		(start 61.503814 -62.39764)
		(end 61.503814 -63.184786)
		(width 0.1016)
		(layer "F.Cu")
		(net "M_DDR3_NODE1_MA0")
	)
	(segment
		(start 61.742828 -63.4238)
		(end 61.742828 -63.68923)
		(width 0.1016)
		(layer "F.Cu")
		(net "M_DDR3_NODE1_MA0")
	)
	(segment
		(start 61.503814 -63.184786)
		(end 61.742828 -63.4238)
		(width 0.1016)
		(layer "F.Cu")
		(net "M_DDR3_NODE1_MA0")
	)
	(segment
		(start 61.503052 -62.396878)
		(end 61.503814 -62.39764)
		(width 0.1016)
		(layer "F.Cu")
		(net "M_DDR3_NODE1_MA0")
	)
	(segment
		(start 61.523118 -64.591438)
		(end 61.388752 -64.725804)
		(width 0.1016)
		(layer "F.Cu")
		(net "M_DDR3_NODE1_MA0")
	)
	(segment
		(start 74.55027 -20.94992)
		(end 74.55027 -24.12111)
		(width 0.2286)
		(layer "F.Cu")
		(net "M_DDR3_NODE1_MA0")
	)
	(segment
		(start 61.503052 -61.735462)
		(end 61.503052 -62.396878)
		(width 0.1016)
		(layer "F.Cu")
		(net "M_DDR3_NODE1_MA0")
	)
	(segment
		(start 61.58484 -61.653674)
		(end 61.503052 -61.735462)
		(width 0.1016)
		(layer "F.Cu")
		(net "M_DDR3_NODE1_MA0")
	)
	(via
		(at 61.58484 -60.348114)
		(size 0.508)
		(drill 0.254)
		(layers "F.Cu" "B.Cu")
		(net "M_DDR3_NODE1_MA0")
	)
	(via
		(at 74.55027 -24.12111)
		(size 0.508)
		(drill 0.254)
		(layers "F.Cu" "B.Cu")
		(net "M_DDR3_NODE1_MA0")
	)
	(segment
		(start 72.72528 -30.33014)
		(end 71.61276 -31.44266)
		(width 0.2286)
		(layer "In2.Cu")
		(net "M_DDR3_NODE1_MA0")
	)
	(segment
		(start 67.68846 -42.956988)
		(end 67.68846 -47.989998)
		(width 0.2286)
		(layer "In2.Cu")
		(net "M_DDR3_NODE1_MA0")
	)
	(segment
		(start 68.62826 -46.229524)
		(end 68.42506 -46.026324)
		(width 0.2286)
		(layer "In2.Cu")
		(net "M_DDR3_NODE1_MA0")
	)
	(segment
		(start 73.39838 -25.577038)
		(end 73.39838 -26.427684)
		(width 0.2286)
		(layer "In2.Cu")
		(net "M_DDR3_NODE1_MA0")
	)
	(segment
		(start 70.76948 -43.075098)
		(end 70.56628 -43.278298)
		(width 0.2286)
		(layer "In2.Cu")
		(net "M_DDR3_NODE1_MA0")
	)
	(segment
		(start 69.16166 -42.326052)
		(end 69.377306 -42.541698)
		(width 0.2286)
		(layer "In2.Cu")
		(net "M_DDR3_NODE1_MA0")
	)
	(segment
		(start 68.42506 -42.956988)
		(end 68.209414 -42.741342)
		(width 0.2286)
		(layer "In2.Cu")
		(net "M_DDR3_NODE1_MA0")
	)
	(segment
		(start 69.377306 -42.541698)
		(end 70.56628 -42.541698)
		(width 0.2286)
		(layer "In2.Cu")
		(net "M_DDR3_NODE1_MA0")
	)
	(segment
		(start 69.16166 -43.493944)
		(end 69.16166 -46.026324)
		(width 0.2286)
		(layer "In2.Cu")
		(net "M_DDR3_NODE1_MA0")
	)
	(segment
		(start 70.76948 -42.744898)
		(end 70.76948 -43.075098)
		(width 0.2286)
		(layer "In2.Cu")
		(net "M_DDR3_NODE1_MA0")
	)
	(segment
		(start 67.68846 -47.989998)
		(end 61.3283 -54.350158)
		(width 0.2286)
		(layer "In2.Cu")
		(net "M_DDR3_NODE1_MA0")
	)
	(segment
		(start 68.209414 -42.741342)
		(end 67.904106 -42.741342)
		(width 0.2286)
		(layer "In2.Cu")
		(net "M_DDR3_NODE1_MA0")
	)
	(segment
		(start 68.95846 -46.229524)
		(end 68.62826 -46.229524)
		(width 0.2286)
		(layer "In2.Cu")
		(net "M_DDR3_NODE1_MA0")
	)
	(segment
		(start 74.55154 -24.423878)
		(end 73.39838 -25.577038)
		(width 0.2286)
		(layer "In2.Cu")
		(net "M_DDR3_NODE1_MA0")
	)
	(segment
		(start 61.3283 -60.091574)
		(end 61.58484 -60.348114)
		(width 0.2286)
		(layer "In2.Cu")
		(net "M_DDR3_NODE1_MA0")
	)
	(segment
		(start 73.7489 -28.027884)
		(end 72.72528 -29.051504)
		(width 0.2286)
		(layer "In2.Cu")
		(net "M_DDR3_NODE1_MA0")
	)
	(segment
		(start 70.56628 -43.278298)
		(end 69.377306 -43.278298)
		(width 0.2286)
		(layer "In2.Cu")
		(net "M_DDR3_NODE1_MA0")
	)
	(segment
		(start 74.55027 -24.12111)
		(end 74.55027 -24.121618)
		(width 0.2286)
		(layer "In2.Cu")
		(net "M_DDR3_NODE1_MA0")
	)
	(segment
		(start 71.61276 -40.395906)
		(end 70.746112 -41.262554)
		(width 0.2286)
		(layer "In2.Cu")
		(net "M_DDR3_NODE1_MA0")
	)
	(segment
		(start 69.377306 -43.278298)
		(end 69.16166 -43.493944)
		(width 0.2286)
		(layer "In2.Cu")
		(net "M_DDR3_NODE1_MA0")
	)
	(segment
		(start 69.16166 -41.4782)
		(end 69.16166 -42.326052)
		(width 0.2286)
		(layer "In2.Cu")
		(net "M_DDR3_NODE1_MA0")
	)
	(segment
		(start 73.39838 -26.427684)
		(end 73.7489 -26.778204)
		(width 0.2286)
		(layer "In2.Cu")
		(net "M_DDR3_NODE1_MA0")
	)
	(segment
		(start 71.61276 -31.44266)
		(end 71.61276 -40.395906)
		(width 0.2286)
		(layer "In2.Cu")
		(net "M_DDR3_NODE1_MA0")
	)
	(segment
		(start 68.42506 -46.026324)
		(end 68.42506 -42.956988)
		(width 0.2286)
		(layer "In2.Cu")
		(net "M_DDR3_NODE1_MA0")
	)
	(segment
		(start 70.746112 -41.262554)
		(end 69.377306 -41.262554)
		(width 0.2286)
		(layer "In2.Cu")
		(net "M_DDR3_NODE1_MA0")
	)
	(segment
		(start 74.55154 -24.121618)
		(end 74.55154 -24.423878)
		(width 0.2286)
		(layer "In2.Cu")
		(net "M_DDR3_NODE1_MA0")
	)
	(segment
		(start 69.377306 -41.262554)
		(end 69.16166 -41.4782)
		(width 0.2286)
		(layer "In2.Cu")
		(net "M_DDR3_NODE1_MA0")
	)
	(segment
		(start 67.904106 -42.741342)
		(end 67.68846 -42.956988)
		(width 0.2286)
		(layer "In2.Cu")
		(net "M_DDR3_NODE1_MA0")
	)
	(segment
		(start 72.72528 -29.051504)
		(end 72.72528 -30.33014)
		(width 0.2286)
		(layer "In2.Cu")
		(net "M_DDR3_NODE1_MA0")
	)
	(segment
		(start 61.3283 -54.350158)
		(end 61.3283 -60.091574)
		(width 0.2286)
		(layer "In2.Cu")
		(net "M_DDR3_NODE1_MA0")
	)
	(segment
		(start 70.56628 -42.541698)
		(end 70.76948 -42.744898)
		(width 0.2286)
		(layer "In2.Cu")
		(net "M_DDR3_NODE1_MA0")
	)
	(segment
		(start 73.7489 -26.778204)
		(end 73.7489 -28.027884)
		(width 0.2286)
		(layer "In2.Cu")
		(net "M_DDR3_NODE1_MA0")
	)
	(segment
		(start 69.16166 -46.026324)
		(end 68.95846 -46.229524)
		(width 0.2286)
		(layer "In2.Cu")
		(net "M_DDR3_NODE1_MA0")
	)
	(segment
		(start 74.55027 -24.121618)
		(end 74.55154 -24.121618)
		(width 0.2286)
		(layer "In2.Cu")
		(net "M_DDR3_NODE1_MA0")
	)
	(segment
		(start 34.508694 -181.007512)
		(end 35.102292 -181.007512)
		(width 0.254)
		(layer "F.Cu")
		(net "VSENSE_HSC_NODE1")
	)
	(segment
		(start 34.139124 -182.215282)
		(end 34.139124 -181.377082)
		(width 0.254)
		(layer "F.Cu")
		(net "VSENSE_HSC_NODE1")
	)
	(segment
		(start 34.139124 -181.377082)
		(end 34.508694 -181.007512)
		(width 0.254)
		(layer "F.Cu")
		(net "VSENSE_HSC_NODE1")
	)
	(segment
		(start 35.102292 -181.007512)
		(end 36.621974 -181.007512)
		(width 0.254)
		(layer "F.Cu")
		(net "VSENSE_HSC_NODE1")
	)
	(via
		(at 35.102292 -181.007512)
		(size 0.508)
		(drill 0.254)
		(layers "F.Cu" "B.Cu")
		(net "VSENSE_HSC_NODE1")
	)
	(segment
		(start 100.387658 -160.81629)
		(end 102.029006 -160.81629)
		(width 0.1016)
		(layer "F.Cu")
		(net "N52411102")
	)
	(segment
		(start 102.029006 -160.81629)
		(end 102.355142 -160.490154)
		(width 0.1016)
		(layer "F.Cu")
		(net "N52411102")
	)
	(segment
		(start 102.355142 -160.490154)
		(end 103.1494 -160.490154)
		(width 0.1016)
		(layer "F.Cu")
		(net "N52411102")
	)
	(segment
		(start 104.125268 -160.490154)
		(end 103.1494 -160.490154)
		(width 0.1016)
		(layer "F.Cu")
		(net "N52411102")
	)
	(segment
		(start 104.125268 -160.489138)
		(end 104.125268 -160.490154)
		(width 0.1016)
		(layer "F.Cu")
		(net "N52411102")
	)
	(via
		(at 103.1494 -160.490154)
		(size 0.508)
		(drill 0.254)
		(layers "F.Cu" "B.Cu")
		(net "N52411102")
	)
	(segment
		(start 65.413636 -87.82685)
		(end 65.209928 -88.030558)
		(width 0.1016)
		(layer "F.Cu")
		(net "SPC_CPU_NODE1_DCD_L")
	)
	(segment
		(start 68.030852 -94.619572)
		(end 68.571364 -94.619572)
		(width 0.1016)
		(layer "F.Cu")
		(net "SPC_CPU_NODE1_DCD_L")
	)
	(segment
		(start 65.093342 -88.030558)
		(end 64.755522 -88.368378)
		(width 0.1016)
		(layer "F.Cu")
		(net "SPC_CPU_NODE1_DCD_L")
	)
	(segment
		(start 64.18961 -85.924898)
		(end 64.812418 -86.547706)
		(width 0.1016)
		(layer "F.Cu")
		(net "SPC_CPU_NODE1_DCD_L")
	)
	(segment
		(start 70.289166 -96.309942)
		(end 70.261734 -96.309942)
		(width 0.1016)
		(layer "F.Cu")
		(net "SPC_CPU_NODE1_DCD_L")
	)
	(segment
		(start 64.755522 -88.958928)
		(end 64.613536 -89.100914)
		(width 0.1016)
		(layer "F.Cu")
		(net "SPC_CPU_NODE1_DCD_L")
	)
	(segment
		(start 64.986916 -86.547706)
		(end 65.413636 -86.974426)
		(width 0.1016)
		(layer "F.Cu")
		(net "SPC_CPU_NODE1_DCD_L")
	)
	(segment
		(start 64.613536 -89.100914)
		(end 64.613536 -91.202256)
		(width 0.1016)
		(layer "F.Cu")
		(net "SPC_CPU_NODE1_DCD_L")
	)
	(segment
		(start 68.571364 -94.619572)
		(end 69.095874 -95.144082)
		(width 0.1016)
		(layer "F.Cu")
		(net "SPC_CPU_NODE1_DCD_L")
	)
	(segment
		(start 64.18961 -85.762846)
		(end 64.18961 -85.924898)
		(width 0.1016)
		(layer "F.Cu")
		(net "SPC_CPU_NODE1_DCD_L")
	)
	(segment
		(start 65.413636 -86.974426)
		(end 65.413636 -87.82685)
		(width 0.1016)
		(layer "F.Cu")
		(net "SPC_CPU_NODE1_DCD_L")
	)
	(segment
		(start 64.613536 -91.202256)
		(end 68.030852 -94.619572)
		(width 0.1016)
		(layer "F.Cu")
		(net "SPC_CPU_NODE1_DCD_L")
	)
	(segment
		(start 65.209928 -88.030558)
		(end 65.093342 -88.030558)
		(width 0.1016)
		(layer "F.Cu")
		(net "SPC_CPU_NODE1_DCD_L")
	)
	(segment
		(start 64.812418 -86.547706)
		(end 64.986916 -86.547706)
		(width 0.1016)
		(layer "F.Cu")
		(net "SPC_CPU_NODE1_DCD_L")
	)
	(segment
		(start 70.261734 -96.309942)
		(end 69.095874 -95.144082)
		(width 0.1016)
		(layer "F.Cu")
		(net "SPC_CPU_NODE1_DCD_L")
	)
	(segment
		(start 64.755522 -88.368378)
		(end 64.755522 -88.958928)
		(width 0.1016)
		(layer "F.Cu")
		(net "SPC_CPU_NODE1_DCD_L")
	)
	(via
		(at 69.095874 -95.144082)
		(size 0.762)
		(drill 0.381)
		(layers "F.Cu" "B.Cu")
		(net "SPC_CPU_NODE1_DCD_L")
	)
	(segment
		(start 146.942556 -70.519036)
		(end 146.942556 -78.633828)
		(width 0.127)
		(layer "F.Cu")
		(net "P2E_CPU_SATA_NODE1_TX_DP")
	)
	(segment
		(start 146.942556 -78.633828)
		(end 146.4691 -79.107284)
		(width 0.127)
		(layer "F.Cu")
		(net "P2E_CPU_SATA_NODE1_TX_DP")
	)
	(segment
		(start 146.730466 -69.448934)
		(end 146.770344 -69.584824)
		(width 0.127)
		(layer "F.Cu")
		(net "P2E_CPU_SATA_NODE1_TX_DP")
	)
	(segment
		(start 146.730466 -68.799202)
		(end 146.730466 -69.448934)
		(width 0.127)
		(layer "F.Cu")
		(net "P2E_CPU_SATA_NODE1_TX_DP")
	)
	(segment
		(start 146.770344 -70.346824)
		(end 146.942556 -70.519036)
		(width 0.127)
		(layer "F.Cu")
		(net "P2E_CPU_SATA_NODE1_TX_DP")
	)
	(segment
		(start 146.770344 -69.584824)
		(end 146.770344 -70.346824)
		(width 0.127)
		(layer "F.Cu")
		(net "P2E_CPU_SATA_NODE1_TX_DP")
	)
	(via
		(at 146.4691 -79.107284)
		(size 0.508)
		(drill 0.254)
		(layers "F.Cu" "B.Cu")
		(net "P2E_CPU_SATA_NODE1_TX_DP")
	)
	(segment
		(start 93.420692 -43.907202)
		(end 89.239852 -43.65752)
		(width 0.127)
		(layer "B.Cu")
		(net "P2E_CPU_SATA_NODE1_TX_DP")
	)
	(segment
		(start 51.68011 -39.505382)
		(end 51.329844 -39.656004)
		(width 0.127)
		(layer "B.Cu")
		(net "P2E_CPU_SATA_NODE1_TX_DP")
	)
	(segment
		(start 71.515986 -42.598848)
		(end 71.463408 -42.598848)
		(width 0.127)
		(layer "B.Cu")
		(net "P2E_CPU_SATA_NODE1_TX_DP")
	)
	(segment
		(start 108.604558 -54.524402)
		(end 108.604812 -54.524402)
		(width 0.127)
		(layer "B.Cu")
		(net "P2E_CPU_SATA_NODE1_TX_DP")
	)
	(segment
		(start 53.871622 -38.813994)
		(end 52.804314 -38.8747)
		(width 0.127)
		(layer "B.Cu")
		(net "P2E_CPU_SATA_NODE1_TX_DP")
	)
	(segment
		(start 143.311626 -77.888084)
		(end 139.3317 -76.797154)
		(width 0.127)
		(layer "B.Cu")
		(net "P2E_CPU_SATA_NODE1_TX_DP")
	)
	(segment
		(start 47.7901 -41.029128)
		(end 46.264322 -42.516806)
		(width 0.127)
		(layer "B.Cu")
		(net "P2E_CPU_SATA_NODE1_TX_DP")
	)
	(segment
		(start 50.801778 -39.735252)
		(end 50.730658 -39.913306)
		(width 0.127)
		(layer "B.Cu")
		(net "P2E_CPU_SATA_NODE1_TX_DP")
	)
	(segment
		(start 145.264378 -78.02753)
		(end 145.125186 -77.888084)
		(width 0.127)
		(layer "B.Cu")
		(net "P2E_CPU_SATA_NODE1_TX_DP")
	)
	(segment
		(start 49.852326 -40.143176)
		(end 49.781206 -40.32123)
		(width 0.127)
		(layer "B.Cu")
		(net "P2E_CPU_SATA_NODE1_TX_DP")
	)
	(segment
		(start 48.481488 -40.879776)
		(end 48.303688 -40.808402)
		(width 0.127)
		(layer "B.Cu")
		(net "P2E_CPU_SATA_NODE1_TX_DP")
	)
	(segment
		(start 45.2374 -59.389772)
		(end 45.2374 -59.657488)
		(width 0.127)
		(layer "B.Cu")
		(net "P2E_CPU_SATA_NODE1_TX_DP")
	)
	(segment
		(start 121.833386 -62.541404)
		(end 118.958614 -58.771028)
		(width 0.127)
		(layer "B.Cu")
		(net "P2E_CPU_SATA_NODE1_TX_DP")
	)
	(segment
		(start 115.803172 -56.5531)
		(end 109.601 -55.22087)
		(width 0.127)
		(layer "B.Cu")
		(net "P2E_CPU_SATA_NODE1_TX_DP")
	)
	(segment
		(start 146.739356 -77.888084)
		(end 145.78457 -77.888084)
		(width 0.127)
		(layer "B.Cu")
		(net "P2E_CPU_SATA_NODE1_TX_DP")
	)
	(segment
		(start 89.239852 -43.65752)
		(end 71.515986 -42.598848)
		(width 0.127)
		(layer "B.Cu")
		(net "P2E_CPU_SATA_NODE1_TX_DP")
	)
	(segment
		(start 139.252198 -76.779882)
		(end 139.246864 -76.778612)
		(width 0.127)
		(layer "B.Cu")
		(net "P2E_CPU_SATA_NODE1_TX_DP")
	)
	(segment
		(start 46.264322 -42.516806)
		(end 44.32554 -47.049436)
		(width 0.127)
		(layer "B.Cu")
		(net "P2E_CPU_SATA_NODE1_TX_DP")
	)
	(segment
		(start 49.43094 -40.471852)
		(end 49.25314 -40.400478)
		(width 0.127)
		(layer "B.Cu")
		(net "P2E_CPU_SATA_NODE1_TX_DP")
	)
	(segment
		(start 145.125186 -77.888084)
		(end 143.311626 -77.888084)
		(width 0.127)
		(layer "B.Cu")
		(net "P2E_CPU_SATA_NODE1_TX_DP")
	)
	(segment
		(start 139.246864 -76.778612)
		(end 136.453118 -76.169012)
		(width 0.127)
		(layer "B.Cu")
		(net "P2E_CPU_SATA_NODE1_TX_DP")
	)
	(segment
		(start 51.75123 -39.327328)
		(end 51.68011 -39.505382)
		(width 0.127)
		(layer "B.Cu")
		(net "P2E_CPU_SATA_NODE1_TX_DP")
	)
	(segment
		(start 109.601 -55.22087)
		(end 108.604558 -54.524402)
		(width 0.127)
		(layer "B.Cu")
		(net "P2E_CPU_SATA_NODE1_TX_DP")
	)
	(segment
		(start 50.730658 -39.913306)
		(end 50.380392 -40.063928)
		(width 0.127)
		(layer "B.Cu")
		(net "P2E_CPU_SATA_NODE1_TX_DP")
	)
	(segment
		(start 43.94962 -58.11393)
		(end 44.216574 -58.60034)
		(width 0.127)
		(layer "B.Cu")
		(net "P2E_CPU_SATA_NODE1_TX_DP")
	)
	(segment
		(start 71.463408 -42.598848)
		(end 58.658506 -39.309802)
		(width 0.127)
		(layer "B.Cu")
		(net "P2E_CPU_SATA_NODE1_TX_DP")
	)
	(segment
		(start 134.28726 -75.639676)
		(end 131.59232 -73.435464)
		(width 0.127)
		(layer "B.Cu")
		(net "P2E_CPU_SATA_NODE1_TX_DP")
	)
	(segment
		(start 146.4691 -79.107284)
		(end 146.924776 -79.107284)
		(width 0.127)
		(layer "B.Cu")
		(net "P2E_CPU_SATA_NODE1_TX_DP")
	)
	(segment
		(start 44.32554 -47.049436)
		(end 43.94962 -58.11393)
		(width 0.127)
		(layer "B.Cu")
		(net "P2E_CPU_SATA_NODE1_TX_DP")
	)
	(segment
		(start 48.303688 -40.808402)
		(end 47.7901 -41.029128)
		(width 0.127)
		(layer "B.Cu")
		(net "P2E_CPU_SATA_NODE1_TX_DP")
	)
	(segment
		(start 108.604812 -54.524402)
		(end 93.420692 -43.907202)
		(width 0.127)
		(layer "B.Cu")
		(net "P2E_CPU_SATA_NODE1_TX_DP")
	)
	(segment
		(start 51.329844 -39.656004)
		(end 51.152044 -39.58463)
		(width 0.127)
		(layer "B.Cu")
		(net "P2E_CPU_SATA_NODE1_TX_DP")
	)
	(segment
		(start 49.781206 -40.32123)
		(end 49.43094 -40.471852)
		(width 0.127)
		(layer "B.Cu")
		(net "P2E_CPU_SATA_NODE1_TX_DP")
	)
	(segment
		(start 146.924776 -79.107284)
		(end 147.16506 -78.867)
		(width 0.127)
		(layer "B.Cu")
		(net "P2E_CPU_SATA_NODE1_TX_DP")
	)
	(segment
		(start 45.030136 -59.182508)
		(end 45.2374 -59.389772)
		(width 0.127)
		(layer "B.Cu")
		(net "P2E_CPU_SATA_NODE1_TX_DP")
	)
	(segment
		(start 44.92498 -59.084972)
		(end 45.030136 -59.182508)
		(width 0.127)
		(layer "B.Cu")
		(net "P2E_CPU_SATA_NODE1_TX_DP")
	)
	(segment
		(start 131.59232 -73.435464)
		(end 130.132074 -70.64883)
		(width 0.127)
		(layer "B.Cu")
		(net "P2E_CPU_SATA_NODE1_TX_DP")
	)
	(segment
		(start 58.658506 -39.309802)
		(end 53.871622 -38.813994)
		(width 0.127)
		(layer "B.Cu")
		(net "P2E_CPU_SATA_NODE1_TX_DP")
	)
	(segment
		(start 145.78457 -77.888084)
		(end 145.645378 -78.02753)
		(width 0.127)
		(layer "B.Cu")
		(net "P2E_CPU_SATA_NODE1_TX_DP")
	)
	(segment
		(start 118.958614 -58.771028)
		(end 115.803172 -56.5531)
		(width 0.127)
		(layer "B.Cu")
		(net "P2E_CPU_SATA_NODE1_TX_DP")
	)
	(segment
		(start 147.16506 -78.313788)
		(end 146.739356 -77.888084)
		(width 0.127)
		(layer "B.Cu")
		(net "P2E_CPU_SATA_NODE1_TX_DP")
	)
	(segment
		(start 139.3317 -76.797154)
		(end 139.252198 -76.779882)
		(width 0.127)
		(layer "B.Cu")
		(net "P2E_CPU_SATA_NODE1_TX_DP")
	)
	(segment
		(start 136.453118 -76.169012)
		(end 134.28726 -75.639676)
		(width 0.127)
		(layer "B.Cu")
		(net "P2E_CPU_SATA_NODE1_TX_DP")
	)
	(segment
		(start 52.804314 -38.8747)
		(end 51.75123 -39.327328)
		(width 0.127)
		(layer "B.Cu")
		(net "P2E_CPU_SATA_NODE1_TX_DP")
	)
	(segment
		(start 44.216574 -58.60034)
		(end 44.92498 -59.084972)
		(width 0.127)
		(layer "B.Cu")
		(net "P2E_CPU_SATA_NODE1_TX_DP")
	)
	(segment
		(start 49.25314 -40.400478)
		(end 48.902874 -40.5511)
		(width 0.127)
		(layer "B.Cu")
		(net "P2E_CPU_SATA_NODE1_TX_DP")
	)
	(segment
		(start 145.645378 -78.02753)
		(end 145.264378 -78.02753)
		(width 0.127)
		(layer "B.Cu")
		(net "P2E_CPU_SATA_NODE1_TX_DP")
	)
	(segment
		(start 51.152044 -39.58463)
		(end 50.801778 -39.735252)
		(width 0.127)
		(layer "B.Cu")
		(net "P2E_CPU_SATA_NODE1_TX_DP")
	)
	(segment
		(start 50.202592 -39.992554)
		(end 49.852326 -40.143176)
		(width 0.127)
		(layer "B.Cu")
		(net "P2E_CPU_SATA_NODE1_TX_DP")
	)
	(segment
		(start 48.831754 -40.729154)
		(end 48.481488 -40.879776)
		(width 0.127)
		(layer "B.Cu")
		(net "P2E_CPU_SATA_NODE1_TX_DP")
	)
	(segment
		(start 147.16506 -78.867)
		(end 147.16506 -78.313788)
		(width 0.127)
		(layer "B.Cu")
		(net "P2E_CPU_SATA_NODE1_TX_DP")
	)
	(segment
		(start 121.833894 -62.541404)
		(end 121.833386 -62.541404)
		(width 0.127)
		(layer "B.Cu")
		(net "P2E_CPU_SATA_NODE1_TX_DP")
	)
	(segment
		(start 50.380392 -40.063928)
		(end 50.202592 -39.992554)
		(width 0.127)
		(layer "B.Cu")
		(net "P2E_CPU_SATA_NODE1_TX_DP")
	)
	(segment
		(start 48.902874 -40.5511)
		(end 48.831754 -40.729154)
		(width 0.127)
		(layer "B.Cu")
		(net "P2E_CPU_SATA_NODE1_TX_DP")
	)
	(segment
		(start 130.132074 -70.64883)
		(end 121.833894 -62.541404)
		(width 0.127)
		(layer "B.Cu")
		(net "P2E_CPU_SATA_NODE1_TX_DP")
	)
	(segment
		(start 45.2374 -59.657488)
		(end 45.625258 -60.045346)
		(width 0.127)
		(layer "B.Cu")
		(net "P2E_CPU_SATA_NODE1_TX_DP")
	)
	(segment
		(start 60.076334 -49.71415)
		(end 60.29198 -49.929796)
		(width 0.2286)
		(layer "F.Cu")
		(net "M_DDR3_NODE1_MA15")
	)
	(segment
		(start 60.965334 -39.501826)
		(end 61.18098 -39.717472)
		(width 0.2286)
		(layer "F.Cu")
		(net "M_DDR3_NODE1_MA15")
	)
	(segment
		(start 59.664346 -48.24095)
		(end 60.076334 -48.24095)
		(width 0.2286)
		(layer "F.Cu")
		(net "M_DDR3_NODE1_MA15")
	)
	(segment
		(start 59.70778 -41.419018)
		(end 59.923426 -41.634664)
		(width 0.2286)
		(layer "F.Cu")
		(net "M_DDR3_NODE1_MA15")
	)
	(segment
		(start 65.07734 -30.831282)
		(end 65.07734 -31.222442)
		(width 0.2286)
		(layer "F.Cu")
		(net "M_DDR3_NODE1_MA15")
	)
	(segment
		(start 57.32018 -58.34253)
		(end 57.114948 -58.547762)
		(width 0.2286)
		(layer "F.Cu")
		(net "M_DDR3_NODE1_MA15")
	)
	(segment
		(start 65.07734 -31.222442)
		(end 64.83858 -31.461202)
		(width 0.2286)
		(layer "F.Cu")
		(net "M_DDR3_NODE1_MA15")
	)
	(segment
		(start 57.32018 -53.32984)
		(end 57.32018 -58.34253)
		(width 0.2286)
		(layer "F.Cu")
		(net "M_DDR3_NODE1_MA15")
	)
	(segment
		(start 60.660026 -39.501826)
		(end 60.965334 -39.501826)
		(width 0.2286)
		(layer "F.Cu")
		(net "M_DDR3_NODE1_MA15")
	)
	(segment
		(start 60.228734 -41.634664)
		(end 60.44438 -41.419018)
		(width 0.2286)
		(layer "F.Cu")
		(net "M_DDR3_NODE1_MA15")
	)
	(segment
		(start 61.476382 -37.229034)
		(end 61.260228 -37.445188)
		(width 0.2286)
		(layer "F.Cu")
		(net "M_DDR3_NODE1_MA15")
	)
	(segment
		(start 62.04204 -40.461692)
		(end 62.04204 -40.767)
		(width 0.2286)
		(layer "F.Cu")
		(net "M_DDR3_NODE1_MA15")
	)
	(segment
		(start 62.302136 -36.40328)
		(end 62.302136 -36.70808)
		(width 0.2286)
		(layer "F.Cu")
		(net "M_DDR3_NODE1_MA15")
	)
	(segment
		(start 60.44438 -39.717472)
		(end 60.660026 -39.501826)
		(width 0.2286)
		(layer "F.Cu")
		(net "M_DDR3_NODE1_MA15")
	)
	(segment
		(start 61.18098 -40.0304)
		(end 61.396626 -40.246046)
		(width 0.2286)
		(layer "F.Cu")
		(net "M_DDR3_NODE1_MA15")
	)
	(segment
		(start 60.076334 -48.24095)
		(end 60.29198 -48.456596)
		(width 0.2286)
		(layer "F.Cu")
		(net "M_DDR3_NODE1_MA15")
	)
	(segment
		(start 61.396626 -40.982646)
		(end 61.18098 -41.198292)
		(width 0.2286)
		(layer "F.Cu")
		(net "M_DDR3_NODE1_MA15")
	)
	(segment
		(start 62.51829 -36.187126)
		(end 62.302136 -36.40328)
		(width 0.2286)
		(layer "F.Cu")
		(net "M_DDR3_NODE1_MA15")
	)
	(segment
		(start 64.83858 -31.461202)
		(end 64.83858 -32.912812)
		(width 0.2286)
		(layer "F.Cu")
		(net "M_DDR3_NODE1_MA15")
	)
	(segment
		(start 63.94704 -33.475168)
		(end 63.94704 -30.806136)
		(width 0.2286)
		(layer "F.Cu")
		(net "M_DDR3_NODE1_MA15")
	)
	(segment
		(start 67.848988 -32.455104)
		(end 68.850256 -31.453836)
		(width 0.2286)
		(layer "F.Cu")
		(net "M_DDR3_NODE1_MA15")
	)
	(segment
		(start 57.114948 -58.547762)
		(end 56.66486 -58.99785)
		(width 0.1016)
		(layer "F.Cu")
		(net "M_DDR3_NODE1_MA15")
	)
	(segment
		(start 60.29198 -48.456596)
		(end 60.29198 -48.761904)
		(width 0.2286)
		(layer "F.Cu")
		(net "M_DDR3_NODE1_MA15")
	)
	(segment
		(start 63.866014 -34.839402)
		(end 63.344044 -35.361372)
		(width 0.2286)
		(layer "F.Cu")
		(net "M_DDR3_NODE1_MA15")
	)
	(segment
		(start 60.739274 -38.270942)
		(end 60.434474 -38.270942)
		(width 0.2286)
		(layer "F.Cu")
		(net "M_DDR3_NODE1_MA15")
	)
	(segment
		(start 60.29198 -49.929796)
		(end 60.29198 -50.235104)
		(width 0.2286)
		(layer "F.Cu")
		(net "M_DDR3_NODE1_MA15")
	)
	(segment
		(start 61.18098 -41.749218)
		(end 59.70778 -43.222418)
		(width 0.2286)
		(layer "F.Cu")
		(net "M_DDR3_NODE1_MA15")
	)
	(segment
		(start 62.222888 -37.36594)
		(end 61.918088 -37.36594)
		(width 0.2286)
		(layer "F.Cu")
		(net "M_DDR3_NODE1_MA15")
	)
	(segment
		(start 62.04204 -40.767)
		(end 61.826394 -40.982646)
		(width 0.2286)
		(layer "F.Cu")
		(net "M_DDR3_NODE1_MA15")
	)
	(segment
		(start 60.076334 -48.97755)
		(end 59.664346 -48.97755)
		(width 0.2286)
		(layer "F.Cu")
		(net "M_DDR3_NODE1_MA15")
	)
	(segment
		(start 62.439042 -36.844986)
		(end 62.439042 -37.149786)
		(width 0.2286)
		(layer "F.Cu")
		(net "M_DDR3_NODE1_MA15")
	)
	(segment
		(start 61.826394 -40.246046)
		(end 62.04204 -40.461692)
		(width 0.2286)
		(layer "F.Cu")
		(net "M_DDR3_NODE1_MA15")
	)
	(segment
		(start 64.50584 -34.526982)
		(end 64.78016 -34.252662)
		(width 0.2286)
		(layer "F.Cu")
		(net "M_DDR3_NODE1_MA15")
	)
	(segment
		(start 56.66486 -58.99785)
		(end 56.66486 -60.475114)
		(width 0.1016)
		(layer "F.Cu")
		(net "M_DDR3_NODE1_MA15")
	)
	(segment
		(start 60.076334 -50.45075)
		(end 59.664346 -50.45075)
		(width 0.2286)
		(layer "F.Cu")
		(net "M_DDR3_NODE1_MA15")
	)
	(segment
		(start 59.4487 -48.025304)
		(end 59.664346 -48.24095)
		(width 0.2286)
		(layer "F.Cu")
		(net "M_DDR3_NODE1_MA15")
	)
	(segment
		(start 64.864234 -30.618176)
		(end 65.07734 -30.831282)
		(width 0.2286)
		(layer "F.Cu")
		(net "M_DDR3_NODE1_MA15")
	)
	(segment
		(start 63.48095 -36.107878)
		(end 63.264796 -36.324032)
		(width 0.2286)
		(layer "F.Cu")
		(net "M_DDR3_NODE1_MA15")
	)
	(segment
		(start 64.19342 -34.839402)
		(end 63.866014 -34.839402)
		(width 0.2286)
		(layer "F.Cu")
		(net "M_DDR3_NODE1_MA15")
	)
	(segment
		(start 63.48095 -35.803078)
		(end 63.48095 -36.107878)
		(width 0.2286)
		(layer "F.Cu")
		(net "M_DDR3_NODE1_MA15")
	)
	(segment
		(start 61.838586 -38.328346)
		(end 61.838586 -38.633654)
		(width 0.2286)
		(layer "F.Cu")
		(net "M_DDR3_NODE1_MA15")
	)
	(segment
		(start 63.344044 -35.666172)
		(end 63.48095 -35.803078)
		(width 0.2286)
		(layer "F.Cu")
		(net "M_DDR3_NODE1_MA15")
	)
	(segment
		(start 67.549014 -32.455104)
		(end 67.848988 -32.455104)
		(width 0.2286)
		(layer "F.Cu")
		(net "M_DDR3_NODE1_MA15")
	)
	(segment
		(start 64.115696 -33.643824)
		(end 63.94704 -33.475168)
		(width 0.2286)
		(layer "F.Cu")
		(net "M_DDR3_NODE1_MA15")
	)
	(segment
		(start 66.85788 -31.76397)
		(end 67.549014 -32.455104)
		(width 0.2286)
		(layer "F.Cu")
		(net "M_DDR3_NODE1_MA15")
	)
	(segment
		(start 61.18098 -39.717472)
		(end 61.18098 -40.0304)
		(width 0.2286)
		(layer "F.Cu")
		(net "M_DDR3_NODE1_MA15")
	)
	(segment
		(start 64.135 -30.618176)
		(end 64.864234 -30.618176)
		(width 0.2286)
		(layer "F.Cu")
		(net "M_DDR3_NODE1_MA15")
	)
	(segment
		(start 66.55054 -33.028128)
		(end 66.11366 -32.591502)
		(width 0.2286)
		(layer "F.Cu")
		(net "M_DDR3_NODE1_MA15")
	)
	(segment
		(start 59.923426 -41.634664)
		(end 60.228734 -41.634664)
		(width 0.2286)
		(layer "F.Cu")
		(net "M_DDR3_NODE1_MA15")
	)
	(segment
		(start 59.664346 -49.71415)
		(end 60.076334 -49.71415)
		(width 0.2286)
		(layer "F.Cu")
		(net "M_DDR3_NODE1_MA15")
	)
	(segment
		(start 59.70778 -44.485814)
		(end 59.4487 -44.744894)
		(width 0.2286)
		(layer "F.Cu")
		(net "M_DDR3_NODE1_MA15")
	)
	(segment
		(start 62.302136 -36.70808)
		(end 62.439042 -36.844986)
		(width 0.2286)
		(layer "F.Cu")
		(net "M_DDR3_NODE1_MA15")
	)
	(segment
		(start 64.78016 -34.252662)
		(end 64.78016 -33.935924)
		(width 0.2286)
		(layer "F.Cu")
		(net "M_DDR3_NODE1_MA15")
	)
	(segment
		(start 56.665368 -60.475622)
		(end 56.665368 -62.55004)
		(width 0.1016)
		(layer "F.Cu")
		(net "M_DDR3_NODE1_MA15")
	)
	(segment
		(start 59.70778 -43.222418)
		(end 59.70778 -44.485814)
		(width 0.2286)
		(layer "F.Cu")
		(net "M_DDR3_NODE1_MA15")
	)
	(segment
		(start 63.94704 -30.806136)
		(end 64.135 -30.618176)
		(width 0.2286)
		(layer "F.Cu")
		(net "M_DDR3_NODE1_MA15")
	)
	(segment
		(start 64.83858 -32.912812)
		(end 65.703704 -33.777936)
		(width 0.2286)
		(layer "F.Cu")
		(net "M_DDR3_NODE1_MA15")
	)
	(segment
		(start 59.70778 -38.997636)
		(end 59.70778 -41.419018)
		(width 0.2286)
		(layer "F.Cu")
		(net "M_DDR3_NODE1_MA15")
	)
	(segment
		(start 56.66486 -60.475114)
		(end 56.665368 -60.475622)
		(width 0.1016)
		(layer "F.Cu")
		(net "M_DDR3_NODE1_MA15")
	)
	(segment
		(start 59.28106 -51.36896)
		(end 57.32018 -53.32984)
		(width 0.2286)
		(layer "F.Cu")
		(net "M_DDR3_NODE1_MA15")
	)
	(segment
		(start 62.959996 -36.324032)
		(end 62.82309 -36.187126)
		(width 0.2286)
		(layer "F.Cu")
		(net "M_DDR3_NODE1_MA15")
	)
	(segment
		(start 59.4487 -49.498504)
		(end 59.664346 -49.71415)
		(width 0.2286)
		(layer "F.Cu")
		(net "M_DDR3_NODE1_MA15")
	)
	(segment
		(start 61.781182 -37.229034)
		(end 61.476382 -37.229034)
		(width 0.2286)
		(layer "F.Cu")
		(net "M_DDR3_NODE1_MA15")
	)
	(segment
		(start 61.317632 -38.8493)
		(end 60.739274 -38.270942)
		(width 0.2286)
		(layer "F.Cu")
		(net "M_DDR3_NODE1_MA15")
	)
	(segment
		(start 62.439042 -37.149786)
		(end 62.222888 -37.36594)
		(width 0.2286)
		(layer "F.Cu")
		(net "M_DDR3_NODE1_MA15")
	)
	(segment
		(start 60.29198 -48.761904)
		(end 60.076334 -48.97755)
		(width 0.2286)
		(layer "F.Cu")
		(net "M_DDR3_NODE1_MA15")
	)
	(segment
		(start 61.396626 -40.246046)
		(end 61.826394 -40.246046)
		(width 0.2286)
		(layer "F.Cu")
		(net "M_DDR3_NODE1_MA15")
	)
	(segment
		(start 61.838586 -38.633654)
		(end 61.62294 -38.8493)
		(width 0.2286)
		(layer "F.Cu")
		(net "M_DDR3_NODE1_MA15")
	)
	(segment
		(start 60.434474 -38.270942)
		(end 59.70778 -38.997636)
		(width 0.2286)
		(layer "F.Cu")
		(net "M_DDR3_NODE1_MA15")
	)
	(segment
		(start 59.4487 -44.744894)
		(end 59.4487 -48.025304)
		(width 0.2286)
		(layer "F.Cu")
		(net "M_DDR3_NODE1_MA15")
	)
	(segment
		(start 65.703704 -33.777936)
		(end 66.100452 -33.777936)
		(width 0.2286)
		(layer "F.Cu")
		(net "M_DDR3_NODE1_MA15")
	)
	(segment
		(start 59.664346 -50.45075)
		(end 59.28106 -50.834036)
		(width 0.2286)
		(layer "F.Cu")
		(net "M_DDR3_NODE1_MA15")
	)
	(segment
		(start 61.918088 -37.36594)
		(end 61.781182 -37.229034)
		(width 0.2286)
		(layer "F.Cu")
		(net "M_DDR3_NODE1_MA15")
	)
	(segment
		(start 62.82309 -36.187126)
		(end 62.51829 -36.187126)
		(width 0.2286)
		(layer "F.Cu")
		(net "M_DDR3_NODE1_MA15")
	)
	(segment
		(start 64.48806 -33.643824)
		(end 64.115696 -33.643824)
		(width 0.2286)
		(layer "F.Cu")
		(net "M_DDR3_NODE1_MA15")
	)
	(segment
		(start 66.11366 -32.126428)
		(end 66.476118 -31.76397)
		(width 0.2286)
		(layer "F.Cu")
		(net "M_DDR3_NODE1_MA15")
	)
	(segment
		(start 59.28106 -50.834036)
		(end 59.28106 -51.36896)
		(width 0.2286)
		(layer "F.Cu")
		(net "M_DDR3_NODE1_MA15")
	)
	(segment
		(start 59.4487 -49.193196)
		(end 59.4487 -49.498504)
		(width 0.2286)
		(layer "F.Cu")
		(net "M_DDR3_NODE1_MA15")
	)
	(segment
		(start 66.11366 -32.591502)
		(end 66.11366 -32.126428)
		(width 0.2286)
		(layer "F.Cu")
		(net "M_DDR3_NODE1_MA15")
	)
	(segment
		(start 60.29198 -50.235104)
		(end 60.076334 -50.45075)
		(width 0.2286)
		(layer "F.Cu")
		(net "M_DDR3_NODE1_MA15")
	)
	(segment
		(start 61.260228 -37.749988)
		(end 61.838586 -38.328346)
		(width 0.2286)
		(layer "F.Cu")
		(net "M_DDR3_NODE1_MA15")
	)
	(segment
		(start 66.476118 -31.76397)
		(end 66.85788 -31.76397)
		(width 0.2286)
		(layer "F.Cu")
		(net "M_DDR3_NODE1_MA15")
	)
	(segment
		(start 60.44438 -41.419018)
		(end 60.44438 -39.717472)
		(width 0.2286)
		(layer "F.Cu")
		(net "M_DDR3_NODE1_MA15")
	)
	(segment
		(start 63.344044 -35.361372)
		(end 63.344044 -35.666172)
		(width 0.2286)
		(layer "F.Cu")
		(net "M_DDR3_NODE1_MA15")
	)
	(segment
		(start 64.50584 -34.526982)
		(end 64.19342 -34.839402)
		(width 0.2286)
		(layer "F.Cu")
		(net "M_DDR3_NODE1_MA15")
	)
	(segment
		(start 64.78016 -33.935924)
		(end 64.48806 -33.643824)
		(width 0.2286)
		(layer "F.Cu")
		(net "M_DDR3_NODE1_MA15")
	)
	(segment
		(start 68.850256 -31.453836)
		(end 68.850256 -29.149802)
		(width 0.2286)
		(layer "F.Cu")
		(net "M_DDR3_NODE1_MA15")
	)
	(segment
		(start 63.264796 -36.324032)
		(end 62.959996 -36.324032)
		(width 0.2286)
		(layer "F.Cu")
		(net "M_DDR3_NODE1_MA15")
	)
	(segment
		(start 61.826394 -40.982646)
		(end 61.396626 -40.982646)
		(width 0.2286)
		(layer "F.Cu")
		(net "M_DDR3_NODE1_MA15")
	)
	(segment
		(start 66.100452 -33.777936)
		(end 66.55054 -33.327848)
		(width 0.2286)
		(layer "F.Cu")
		(net "M_DDR3_NODE1_MA15")
	)
	(segment
		(start 61.62294 -38.8493)
		(end 61.317632 -38.8493)
		(width 0.2286)
		(layer "F.Cu")
		(net "M_DDR3_NODE1_MA15")
	)
	(segment
		(start 61.18098 -41.198292)
		(end 61.18098 -41.749218)
		(width 0.2286)
		(layer "F.Cu")
		(net "M_DDR3_NODE1_MA15")
	)
	(segment
		(start 66.55054 -33.327848)
		(end 66.55054 -33.028128)
		(width 0.2286)
		(layer "F.Cu")
		(net "M_DDR3_NODE1_MA15")
	)
	(segment
		(start 59.664346 -48.97755)
		(end 59.4487 -49.193196)
		(width 0.2286)
		(layer "F.Cu")
		(net "M_DDR3_NODE1_MA15")
	)
	(segment
		(start 61.260228 -37.445188)
		(end 61.260228 -37.749988)
		(width 0.2286)
		(layer "F.Cu")
		(net "M_DDR3_NODE1_MA15")
	)
	(via
		(at 64.50584 -34.526982)
		(size 0.762)
		(drill 0.381)
		(layers "F.Cu" "B.Cu")
		(net "M_DDR3_NODE1_MA15")
	)
	(segment
		(start 132.768086 -57.869328)
		(end 131.99618 -58.641234)
		(width 0.1016)
		(layer "F.Cu")
		(net "SATA_SPI_DI_NODE1")
	)
	(segment
		(start 131.99618 -58.641234)
		(end 131.99618 -59.505088)
		(width 0.1016)
		(layer "F.Cu")
		(net "SATA_SPI_DI_NODE1")
	)
	(segment
		(start 131.99745 -59.506358)
		(end 131.99745 -60.530232)
		(width 0.1016)
		(layer "F.Cu")
		(net "SATA_SPI_DI_NODE1")
	)
	(segment
		(start 144.265396 -70.73773)
		(end 144.265396 -73.353168)
		(width 0.1016)
		(layer "F.Cu")
		(net "SATA_SPI_DI_NODE1")
	)
	(segment
		(start 144.73047 -69.526404)
		(end 144.874996 -69.67093)
		(width 0.1016)
		(layer "F.Cu")
		(net "SATA_SPI_DI_NODE1")
	)
	(segment
		(start 144.874996 -70.12813)
		(end 144.265396 -70.73773)
		(width 0.1016)
		(layer "F.Cu")
		(net "SATA_SPI_DI_NODE1")
	)
	(segment
		(start 144.73047 -68.799202)
		(end 144.73047 -69.526404)
		(width 0.1016)
		(layer "F.Cu")
		(net "SATA_SPI_DI_NODE1")
	)
	(segment
		(start 144.874996 -69.67093)
		(end 144.874996 -70.12813)
		(width 0.1016)
		(layer "F.Cu")
		(net "SATA_SPI_DI_NODE1")
	)
	(segment
		(start 144.265396 -73.353168)
		(end 143.986504 -73.63206)
		(width 0.1016)
		(layer "F.Cu")
		(net "SATA_SPI_DI_NODE1")
	)
	(segment
		(start 135.688832 -57.869328)
		(end 132.768086 -57.869328)
		(width 0.1016)
		(layer "F.Cu")
		(net "SATA_SPI_DI_NODE1")
	)
	(segment
		(start 131.99618 -59.505088)
		(end 131.99745 -59.506358)
		(width 0.1016)
		(layer "F.Cu")
		(net "SATA_SPI_DI_NODE1")
	)
	(via
		(at 143.986504 -73.63206)
		(size 0.508)
		(drill 0.254)
		(layers "F.Cu" "B.Cu")
		(net "SATA_SPI_DI_NODE1")
	)
	(via
		(at 135.688832 -57.869328)
		(size 0.508)
		(drill 0.254)
		(layers "F.Cu" "B.Cu")
		(net "SATA_SPI_DI_NODE1")
	)
	(segment
		(start 133.354572 -62.726824)
		(end 133.354572 -62.474348)
		(width 0.1016)
		(layer "B.Cu")
		(net "SATA_SPI_DI_NODE1")
	)
	(segment
		(start 133.354572 -63.693548)
		(end 133.533134 -63.514986)
		(width 0.1016)
		(layer "B.Cu")
		(net "SATA_SPI_DI_NODE1")
	)
	(segment
		(start 135.578088 -63.083948)
		(end 135.399526 -62.905386)
		(width 0.1016)
		(layer "B.Cu")
		(net "SATA_SPI_DI_NODE1")
	)
	(segment
		(start 135.399526 -63.514986)
		(end 135.578088 -63.336424)
		(width 0.1016)
		(layer "B.Cu")
		(net "SATA_SPI_DI_NODE1")
	)
	(segment
		(start 137.436352 -72.982582)
		(end 136.325102 -71.871332)
		(width 0.1016)
		(layer "B.Cu")
		(net "SATA_SPI_DI_NODE1")
	)
	(segment
		(start 133.533134 -62.905386)
		(end 133.354572 -62.726824)
		(width 0.1016)
		(layer "B.Cu")
		(net "SATA_SPI_DI_NODE1")
	)
	(segment
		(start 133.354572 -62.474348)
		(end 133.533134 -62.295786)
		(width 0.1016)
		(layer "B.Cu")
		(net "SATA_SPI_DI_NODE1")
	)
	(segment
		(start 143.986504 -73.63206)
		(end 143.557752 -73.203308)
		(width 0.1016)
		(layer "B.Cu")
		(net "SATA_SPI_DI_NODE1")
	)
	(segment
		(start 135.399526 -62.905386)
		(end 133.533134 -62.905386)
		(width 0.1016)
		(layer "B.Cu")
		(net "SATA_SPI_DI_NODE1")
	)
	(segment
		(start 143.557752 -73.203308)
		(end 141.70914 -73.203308)
		(width 0.1016)
		(layer "B.Cu")
		(net "SATA_SPI_DI_NODE1")
	)
	(segment
		(start 135.578088 -63.336424)
		(end 135.578088 -63.083948)
		(width 0.1016)
		(layer "B.Cu")
		(net "SATA_SPI_DI_NODE1")
	)
	(segment
		(start 133.533134 -63.514986)
		(end 135.399526 -63.514986)
		(width 0.1016)
		(layer "B.Cu")
		(net "SATA_SPI_DI_NODE1")
	)
	(segment
		(start 135.578088 -57.980072)
		(end 135.688832 -57.869328)
		(width 0.1016)
		(layer "B.Cu")
		(net "SATA_SPI_DI_NODE1")
	)
	(segment
		(start 141.70914 -73.203308)
		(end 141.488414 -72.982582)
		(width 0.1016)
		(layer "B.Cu")
		(net "SATA_SPI_DI_NODE1")
	)
	(segment
		(start 135.578088 -65.875662)
		(end 135.578088 -64.303148)
		(width 0.1016)
		(layer "B.Cu")
		(net "SATA_SPI_DI_NODE1")
	)
	(segment
		(start 133.533134 -62.295786)
		(end 135.399526 -62.295786)
		(width 0.1016)
		(layer "B.Cu")
		(net "SATA_SPI_DI_NODE1")
	)
	(segment
		(start 135.399526 -64.124586)
		(end 133.533134 -64.124586)
		(width 0.1016)
		(layer "B.Cu")
		(net "SATA_SPI_DI_NODE1")
	)
	(segment
		(start 133.533134 -64.124586)
		(end 133.354572 -63.946024)
		(width 0.1016)
		(layer "B.Cu")
		(net "SATA_SPI_DI_NODE1")
	)
	(segment
		(start 141.488414 -72.982582)
		(end 137.436352 -72.982582)
		(width 0.1016)
		(layer "B.Cu")
		(net "SATA_SPI_DI_NODE1")
	)
	(segment
		(start 133.354572 -63.946024)
		(end 133.354572 -63.693548)
		(width 0.1016)
		(layer "B.Cu")
		(net "SATA_SPI_DI_NODE1")
	)
	(segment
		(start 135.578088 -62.117224)
		(end 135.578088 -57.980072)
		(width 0.1016)
		(layer "B.Cu")
		(net "SATA_SPI_DI_NODE1")
	)
	(segment
		(start 136.325102 -66.622676)
		(end 135.578088 -65.875662)
		(width 0.1016)
		(layer "B.Cu")
		(net "SATA_SPI_DI_NODE1")
	)
	(segment
		(start 136.325102 -71.871332)
		(end 136.325102 -66.622676)
		(width 0.1016)
		(layer "B.Cu")
		(net "SATA_SPI_DI_NODE1")
	)
	(segment
		(start 135.578088 -64.303148)
		(end 135.399526 -64.124586)
		(width 0.1016)
		(layer "B.Cu")
		(net "SATA_SPI_DI_NODE1")
	)
	(segment
		(start 135.399526 -62.295786)
		(end 135.578088 -62.117224)
		(width 0.1016)
		(layer "B.Cu")
		(net "SATA_SPI_DI_NODE1")
	)
	(segment
		(start 65.400682 -90.401902)
		(end 66.94805 -91.94927)
		(width 0.1016)
		(layer "F.Cu")
		(net "SPC_CPU_NODE1_CTS_L")
	)
	(segment
		(start 67.308984 -92.4687)
		(end 66.94805 -92.4687)
		(width 0.1016)
		(layer "F.Cu")
		(net "SPC_CPU_NODE1_CTS_L")
	)
	(segment
		(start 68.681854 -93.84157)
		(end 67.308984 -92.4687)
		(width 0.1016)
		(layer "F.Cu")
		(net "SPC_CPU_NODE1_CTS_L")
	)
	(segment
		(start 65.400682 -89.58834)
		(end 65.400682 -90.401902)
		(width 0.1016)
		(layer "F.Cu")
		(net "SPC_CPU_NODE1_CTS_L")
	)
	(segment
		(start 65.720214 -88.82888)
		(end 65.777872 -88.886538)
		(width 0.1016)
		(layer "F.Cu")
		(net "SPC_CPU_NODE1_CTS_L")
	)
	(segment
		(start 66.94805 -91.94927)
		(end 66.94805 -92.4687)
		(width 0.1016)
		(layer "F.Cu")
		(net "SPC_CPU_NODE1_CTS_L")
	)
	(segment
		(start 65.720214 -88.04656)
		(end 65.720214 -88.82888)
		(width 0.1016)
		(layer "F.Cu")
		(net "SPC_CPU_NODE1_CTS_L")
	)
	(segment
		(start 71.305166 -95.852488)
		(end 69.294248 -93.84157)
		(width 0.1016)
		(layer "F.Cu")
		(net "SPC_CPU_NODE1_CTS_L")
	)
	(segment
		(start 69.294248 -93.84157)
		(end 68.681854 -93.84157)
		(width 0.1016)
		(layer "F.Cu")
		(net "SPC_CPU_NODE1_CTS_L")
	)
	(segment
		(start 65.777872 -89.21115)
		(end 65.400682 -89.58834)
		(width 0.1016)
		(layer "F.Cu")
		(net "SPC_CPU_NODE1_CTS_L")
	)
	(segment
		(start 71.305166 -96.309942)
		(end 71.305166 -95.852488)
		(width 0.1016)
		(layer "F.Cu")
		(net "SPC_CPU_NODE1_CTS_L")
	)
	(segment
		(start 65.777872 -88.886538)
		(end 65.777872 -89.21115)
		(width 0.1016)
		(layer "F.Cu")
		(net "SPC_CPU_NODE1_CTS_L")
	)
	(via
		(at 66.94805 -92.4687)
		(size 0.762)
		(drill 0.381)
		(layers "F.Cu" "B.Cu")
		(net "SPC_CPU_NODE1_CTS_L")
	)
	(segment
		(start 60.450222 -29.149802)
		(end 60.450222 -26.372058)
		(width 0.1651)
		(layer "F.Cu")
		(net "M1_DQ_NODE1_DQ31")
	)
	(segment
		(start 54.698138 -59.435238)
		(end 53.83149 -58.56859)
		(width 0.1016)
		(layer "F.Cu")
		(net "M1_DQ_NODE1_DQ31")
	)
	(segment
		(start 54.698138 -63.13551)
		(end 54.698138 -59.435238)
		(width 0.1016)
		(layer "F.Cu")
		(net "M1_DQ_NODE1_DQ31")
	)
	(segment
		(start 54.280816 -64.047878)
		(end 54.280816 -63.552832)
		(width 0.1016)
		(layer "F.Cu")
		(net "M1_DQ_NODE1_DQ31")
	)
	(segment
		(start 60.450222 -26.372058)
		(end 60.394342 -26.316178)
		(width 0.1651)
		(layer "F.Cu")
		(net "M1_DQ_NODE1_DQ31")
	)
	(segment
		(start 54.280816 -63.552832)
		(end 54.698138 -63.13551)
		(width 0.1016)
		(layer "F.Cu")
		(net "M1_DQ_NODE1_DQ31")
	)
	(via
		(at 53.83149 -58.56859)
		(size 0.508)
		(drill 0.254)
		(layers "F.Cu" "B.Cu")
		(net "M1_DQ_NODE1_DQ31")
	)
	(via
		(at 60.394342 -26.316178)
		(size 0.508)
		(drill 0.254)
		(layers "F.Cu" "B.Cu")
		(net "M1_DQ_NODE1_DQ31")
	)
	(segment
		(start 61.16828 -33.162748)
		(end 61.16828 -31.167324)
		(width 0.2032)
		(layer "In2.Cu")
		(net "M1_DQ_NODE1_DQ31")
	)
	(segment
		(start 54.8894 -57.831228)
		(end 54.8894 -57.556146)
		(width 0.1016)
		(layer "In2.Cu")
		(net "M1_DQ_NODE1_DQ31")
	)
	(segment
		(start 55.27802 -47.308516)
		(end 55.06974 -47.516796)
		(width 0.2032)
		(layer "In2.Cu")
		(net "M1_DQ_NODE1_DQ31")
	)
	(segment
		(start 54.152038 -58.56859)
		(end 54.8894 -57.831228)
		(width 0.1016)
		(layer "In2.Cu")
		(net "M1_DQ_NODE1_DQ31")
	)
	(segment
		(start 55.06974 -47.516796)
		(end 54.7751 -47.516796)
		(width 0.2032)
		(layer "In2.Cu")
		(net "M1_DQ_NODE1_DQ31")
	)
	(segment
		(start 54.56682 -47.308516)
		(end 54.56682 -39.764208)
		(width 0.2032)
		(layer "In2.Cu")
		(net "M1_DQ_NODE1_DQ31")
	)
	(segment
		(start 55.98922 -47.716694)
		(end 55.98922 -40.285162)
		(width 0.2032)
		(layer "In2.Cu")
		(net "M1_DQ_NODE1_DQ31")
	)
	(segment
		(start 61.16828 -31.167324)
		(end 60.39358 -30.392624)
		(width 0.2032)
		(layer "In2.Cu")
		(net "M1_DQ_NODE1_DQ31")
	)
	(segment
		(start 55.78602 -40.081962)
		(end 55.48122 -40.081962)
		(width 0.2032)
		(layer "In2.Cu")
		(net "M1_DQ_NODE1_DQ31")
	)
	(segment
		(start 54.7751 -47.516796)
		(end 54.56682 -47.308516)
		(width 0.2032)
		(layer "In2.Cu")
		(net "M1_DQ_NODE1_DQ31")
	)
	(segment
		(start 54.8894 -48.816514)
		(end 55.98922 -47.716694)
		(width 0.2032)
		(layer "In2.Cu")
		(net "M1_DQ_NODE1_DQ31")
	)
	(segment
		(start 60.39358 -26.316178)
		(end 60.394342 -26.316178)
		(width 0.2032)
		(layer "In2.Cu")
		(net "M1_DQ_NODE1_DQ31")
	)
	(segment
		(start 55.27802 -40.285162)
		(end 55.27802 -47.308516)
		(width 0.2032)
		(layer "In2.Cu")
		(net "M1_DQ_NODE1_DQ31")
	)
	(segment
		(start 60.39358 -30.392624)
		(end 60.39358 -26.316178)
		(width 0.2032)
		(layer "In2.Cu")
		(net "M1_DQ_NODE1_DQ31")
	)
	(segment
		(start 53.83149 -58.56859)
		(end 54.152038 -58.56859)
		(width 0.1016)
		(layer "In2.Cu")
		(net "M1_DQ_NODE1_DQ31")
	)
	(segment
		(start 55.48122 -40.081962)
		(end 55.27802 -40.285162)
		(width 0.2032)
		(layer "In2.Cu")
		(net "M1_DQ_NODE1_DQ31")
	)
	(segment
		(start 55.98922 -40.285162)
		(end 55.78602 -40.081962)
		(width 0.2032)
		(layer "In2.Cu")
		(net "M1_DQ_NODE1_DQ31")
	)
	(segment
		(start 54.56682 -39.764208)
		(end 61.16828 -33.162748)
		(width 0.2032)
		(layer "In2.Cu")
		(net "M1_DQ_NODE1_DQ31")
	)
	(segment
		(start 54.8894 -57.556146)
		(end 54.8894 -48.816514)
		(width 0.2032)
		(layer "In2.Cu")
		(net "M1_DQ_NODE1_DQ31")
	)
	(segment
		(start 148.378164 -70.581774)
		(end 148.378164 -70.209156)
		(width 0.127)
		(layer "F.Cu")
		(net "P2E_CPU_SATA_NODE1_RX_C_DP")
	)
	(segment
		(start 148.378164 -69.638418)
		(end 148.378164 -70.209156)
		(width 0.127)
		(layer "F.Cu")
		(net "P2E_CPU_SATA_NODE1_RX_C_DP")
	)
	(segment
		(start 149.633178 -73.537572)
		(end 150.005796 -73.164954)
		(width 0.127)
		(layer "F.Cu")
		(net "P2E_CPU_SATA_NODE1_RX_C_DP")
	)
	(segment
		(start 150.005796 -73.164954)
		(end 150.005796 -72.209406)
		(width 0.127)
		(layer "F.Cu")
		(net "P2E_CPU_SATA_NODE1_RX_C_DP")
	)
	(segment
		(start 148.330666 -68.799202)
		(end 148.330666 -69.505576)
		(width 0.127)
		(layer "F.Cu")
		(net "P2E_CPU_SATA_NODE1_RX_C_DP")
	)
	(segment
		(start 150.005796 -72.209406)
		(end 148.378164 -70.581774)
		(width 0.127)
		(layer "F.Cu")
		(net "P2E_CPU_SATA_NODE1_RX_C_DP")
	)
	(segment
		(start 148.330666 -69.505576)
		(end 148.378164 -69.638418)
		(width 0.127)
		(layer "F.Cu")
		(net "P2E_CPU_SATA_NODE1_RX_C_DP")
	)
	(via
		(at 148.378164 -70.209156)
		(size 0.4064)
		(drill 0.2032)
		(layers "F.Cu" "B.Cu")
		(net "P2E_CPU_SATA_NODE1_RX_C_DP")
	)
	(segment
		(start 55.214012 -87.700358)
		(end 55.214012 -87.93988)
		(width 0.1016)
		(layer "F.Cu")
		(net "PD_CPU_NODE1_DFX_GPIO_GRP0_1")
	)
	(segment
		(start 55.214012 -87.93988)
		(end 53.968396 -89.185496)
		(width 0.1016)
		(layer "F.Cu")
		(net "PD_CPU_NODE1_DFX_GPIO_GRP0_1")
	)
	(segment
		(start 53.968396 -90.525346)
		(end 52.571142 -91.9226)
		(width 0.1016)
		(layer "F.Cu")
		(net "PD_CPU_NODE1_DFX_GPIO_GRP0_1")
	)
	(segment
		(start 53.968396 -89.185496)
		(end 53.968396 -90.525346)
		(width 0.1016)
		(layer "F.Cu")
		(net "PD_CPU_NODE1_DFX_GPIO_GRP0_1")
	)
	(segment
		(start 53.017166 -96.309942)
		(end 53.017166 -92.368624)
		(width 0.1016)
		(layer "F.Cu")
		(net "PD_CPU_NODE1_DFX_GPIO_GRP0_1")
	)
	(segment
		(start 53.017166 -92.368624)
		(end 52.571142 -91.9226)
		(width 0.1016)
		(layer "F.Cu")
		(net "PD_CPU_NODE1_DFX_GPIO_GRP0_1")
	)
	(via
		(at 52.571142 -91.9226)
		(size 0.508)
		(drill 0.254)
		(layers "F.Cu" "B.Cu")
		(net "PD_CPU_NODE1_DFX_GPIO_GRP0_1")
	)
	(segment
		(start 57.00522 -22.96668)
		(end 57.00522 -22.30755)
		(width 0.1651)
		(layer "F.Cu")
		(net "M1_DQ_NODE1_DQ25")
	)
	(segment
		(start 57.15 -22.16277)
		(end 57.150254 -22.16277)
		(width 0.1651)
		(layer "F.Cu")
		(net "M1_DQ_NODE1_DQ25")
	)
	(segment
		(start 57.00522 -22.30755)
		(end 57.15 -22.16277)
		(width 0.1651)
		(layer "F.Cu")
		(net "M1_DQ_NODE1_DQ25")
	)
	(segment
		(start 57.150254 -22.16277)
		(end 57.150254 -20.94992)
		(width 0.1651)
		(layer "F.Cu")
		(net "M1_DQ_NODE1_DQ25")
	)
	(segment
		(start 58.122058 -24.083518)
		(end 57.00522 -22.96668)
		(width 0.1651)
		(layer "F.Cu")
		(net "M1_DQ_NODE1_DQ25")
	)
	(segment
		(start 55.389272 -63.158624)
		(end 55.76189 -62.786006)
		(width 0.1016)
		(layer "F.Cu")
		(net "M1_DQ_NODE1_DQ25")
	)
	(segment
		(start 59.203082 -24.083518)
		(end 58.122058 -24.083518)
		(width 0.1651)
		(layer "F.Cu")
		(net "M1_DQ_NODE1_DQ25")
	)
	(segment
		(start 55.76189 -60.90539)
		(end 55.15229 -60.29579)
		(width 0.1016)
		(layer "F.Cu")
		(net "M1_DQ_NODE1_DQ25")
	)
	(segment
		(start 55.76189 -62.786006)
		(end 55.76189 -60.90539)
		(width 0.1016)
		(layer "F.Cu")
		(net "M1_DQ_NODE1_DQ25")
	)
	(via
		(at 59.203082 -24.083518)
		(size 0.508)
		(drill 0.254)
		(layers "F.Cu" "B.Cu")
		(net "M1_DQ_NODE1_DQ25")
	)
	(via
		(at 55.15229 -60.29579)
		(size 0.508)
		(drill 0.254)
		(layers "F.Cu" "B.Cu")
		(net "M1_DQ_NODE1_DQ25")
	)
	(segment
		(start 52.84216 -49.629568)
		(end 54.04612 -49.629568)
		(width 0.2032)
		(layer "In2.Cu")
		(net "M1_DQ_NODE1_DQ25")
	)
	(segment
		(start 53.89118 -40.078406)
		(end 53.68671 -40.282876)
		(width 0.2032)
		(layer "In2.Cu")
		(net "M1_DQ_NODE1_DQ25")
	)
	(segment
		(start 53.616606 -58.140346)
		(end 53.36794 -58.389012)
		(width 0.1016)
		(layer "In2.Cu")
		(net "M1_DQ_NODE1_DQ25")
	)
	(segment
		(start 53.649372 -59.020456)
		(end 54.131464 -59.020456)
		(width 0.1016)
		(layer "In2.Cu")
		(net "M1_DQ_NODE1_DQ25")
	)
	(segment
		(start 53.82514 -41.298368)
		(end 53.82514 -41.603168)
		(width 0.2032)
		(layer "In2.Cu")
		(net "M1_DQ_NODE1_DQ25")
	)
	(segment
		(start 52.98694 -41.095168)
		(end 53.62194 -41.095168)
		(width 0.2032)
		(layer "In2.Cu")
		(net "M1_DQ_NODE1_DQ25")
	)
	(segment
		(start 52.77866 -43.939968)
		(end 53.4162 -43.939968)
		(width 0.2032)
		(layer "In2.Cu")
		(net "M1_DQ_NODE1_DQ25")
	)
	(segment
		(start 58.86196 -25.89276)
		(end 59.46394 -26.49474)
		(width 0.2032)
		(layer "In2.Cu")
		(net "M1_DQ_NODE1_DQ25")
	)
	(segment
		(start 54.2544 -57.03697)
		(end 54.2544 -57.613296)
		(width 0.1016)
		(layer "In2.Cu")
		(net "M1_DQ_NODE1_DQ25")
	)
	(segment
		(start 52.63388 -49.126648)
		(end 52.63388 -49.421288)
		(width 0.2032)
		(layer "In2.Cu")
		(net "M1_DQ_NODE1_DQ25")
	)
	(segment
		(start 58.86196 -24.42464)
		(end 58.86196 -25.89276)
		(width 0.2032)
		(layer "In2.Cu")
		(net "M1_DQ_NODE1_DQ25")
	)
	(segment
		(start 53.75656 -45.570648)
		(end 53.75656 -45.865288)
		(width 0.2032)
		(layer "In2.Cu")
		(net "M1_DQ_NODE1_DQ25")
	)
	(segment
		(start 53.8734 -46.993048)
		(end 53.8734 -47.287688)
		(width 0.2032)
		(layer "In2.Cu")
		(net "M1_DQ_NODE1_DQ25")
	)
	(segment
		(start 54.04612 -49.629568)
		(end 54.2544 -49.837848)
		(width 0.2032)
		(layer "In2.Cu")
		(net "M1_DQ_NODE1_DQ25")
	)
	(segment
		(start 53.8988 -48.415448)
		(end 53.8988 -48.710088)
		(width 0.2032)
		(layer "In2.Cu")
		(net "M1_DQ_NODE1_DQ25")
	)
	(segment
		(start 60.39612 -32.97428)
		(end 54.2544 -39.116)
		(width 0.2032)
		(layer "In2.Cu")
		(net "M1_DQ_NODE1_DQ25")
	)
	(segment
		(start 54.2544 -50.301906)
		(end 53.85816 -50.698146)
		(width 0.2032)
		(layer "In2.Cu")
		(net "M1_DQ_NODE1_DQ25")
	)
	(segment
		(start 53.4162 -43.939968)
		(end 53.62448 -44.148248)
		(width 0.2032)
		(layer "In2.Cu")
		(net "M1_DQ_NODE1_DQ25")
	)
	(segment
		(start 53.66512 -47.495968)
		(end 53.3527 -47.495968)
		(width 0.2032)
		(layer "In2.Cu")
		(net "M1_DQ_NODE1_DQ25")
	)
	(segment
		(start 59.46394 -26.49474)
		(end 59.46394 -27.265376)
		(width 0.2032)
		(layer "In2.Cu")
		(net "M1_DQ_NODE1_DQ25")
	)
	(segment
		(start 53.66512 -46.784768)
		(end 53.8734 -46.993048)
		(width 0.2032)
		(layer "In2.Cu")
		(net "M1_DQ_NODE1_DQ25")
	)
	(segment
		(start 53.62194 -41.095168)
		(end 53.82514 -41.298368)
		(width 0.2032)
		(layer "In2.Cu")
		(net "M1_DQ_NODE1_DQ25")
	)
	(segment
		(start 59.660282 -28.545282)
		(end 59.65952 -28.545282)
		(width 0.2032)
		(layer "In2.Cu")
		(net "M1_DQ_NODE1_DQ25")
	)
	(segment
		(start 59.65952 -30.626558)
		(end 60.39612 -31.363158)
		(width 0.2032)
		(layer "In2.Cu")
		(net "M1_DQ_NODE1_DQ25")
	)
	(segment
		(start 53.00218 -45.154088)
		(end 53.21046 -45.362368)
		(width 0.2032)
		(layer "In2.Cu")
		(net "M1_DQ_NODE1_DQ25")
	)
	(segment
		(start 54.254908 -39.116)
		(end 53.89118 -39.479728)
		(width 0.2032)
		(layer "In2.Cu")
		(net "M1_DQ_NODE1_DQ25")
	)
	(segment
		(start 53.72862 -43.025568)
		(end 53.52542 -43.228768)
		(width 0.2032)
		(layer "In2.Cu")
		(net "M1_DQ_NODE1_DQ25")
	)
	(segment
		(start 51.98872 -42.309288)
		(end 52.197 -42.517568)
		(width 0.2032)
		(layer "In2.Cu")
		(net "M1_DQ_NODE1_DQ25")
	)
	(segment
		(start 53.21046 -45.362368)
		(end 53.54828 -45.362368)
		(width 0.2032)
		(layer "In2.Cu")
		(net "M1_DQ_NODE1_DQ25")
	)
	(segment
		(start 60.39612 -31.363158)
		(end 60.39612 -32.97428)
		(width 0.2032)
		(layer "In2.Cu")
		(net "M1_DQ_NODE1_DQ25")
	)
	(segment
		(start 59.65952 -28.545282)
		(end 59.65952 -30.626558)
		(width 0.2032)
		(layer "In2.Cu")
		(net "M1_DQ_NODE1_DQ25")
	)
	(segment
		(start 53.62194 -41.806368)
		(end 52.197 -41.806368)
		(width 0.2032)
		(layer "In2.Cu")
		(net "M1_DQ_NODE1_DQ25")
	)
	(segment
		(start 53.8734 -47.287688)
		(end 53.66512 -47.495968)
		(width 0.2032)
		(layer "In2.Cu")
		(net "M1_DQ_NODE1_DQ25")
	)
	(segment
		(start 53.04028 -46.576488)
		(end 53.24856 -46.784768)
		(width 0.2032)
		(layer "In2.Cu")
		(net "M1_DQ_NODE1_DQ25")
	)
	(segment
		(start 53.24856 -46.784768)
		(end 53.66512 -46.784768)
		(width 0.2032)
		(layer "In2.Cu")
		(net "M1_DQ_NODE1_DQ25")
	)
	(segment
		(start 53.3527 -47.495968)
		(end 53.14442 -47.704248)
		(width 0.2032)
		(layer "In2.Cu")
		(net "M1_DQ_NODE1_DQ25")
	)
	(segment
		(start 53.54828 -46.073568)
		(end 53.24856 -46.073568)
		(width 0.2032)
		(layer "In2.Cu")
		(net "M1_DQ_NODE1_DQ25")
	)
	(segment
		(start 53.69052 -48.207168)
		(end 53.8988 -48.415448)
		(width 0.2032)
		(layer "In2.Cu")
		(net "M1_DQ_NODE1_DQ25")
	)
	(segment
		(start 53.14442 -47.998888)
		(end 53.3527 -48.207168)
		(width 0.2032)
		(layer "In2.Cu")
		(net "M1_DQ_NODE1_DQ25")
	)
	(segment
		(start 53.72862 -42.720768)
		(end 53.72862 -43.025568)
		(width 0.2032)
		(layer "In2.Cu")
		(net "M1_DQ_NODE1_DQ25")
	)
	(segment
		(start 53.52542 -42.517568)
		(end 53.72862 -42.720768)
		(width 0.2032)
		(layer "In2.Cu")
		(net "M1_DQ_NODE1_DQ25")
	)
	(segment
		(start 53.54828 -45.362368)
		(end 53.75656 -45.570648)
		(width 0.2032)
		(layer "In2.Cu")
		(net "M1_DQ_NODE1_DQ25")
	)
	(segment
		(start 53.36794 -58.739024)
		(end 53.649372 -59.020456)
		(width 0.1016)
		(layer "In2.Cu")
		(net "M1_DQ_NODE1_DQ25")
	)
	(segment
		(start 53.04028 -46.281848)
		(end 53.04028 -46.576488)
		(width 0.2032)
		(layer "In2.Cu")
		(net "M1_DQ_NODE1_DQ25")
	)
	(segment
		(start 53.088032 -40.282876)
		(end 52.77866 -40.592248)
		(width 0.2032)
		(layer "In2.Cu")
		(net "M1_DQ_NODE1_DQ25")
	)
	(segment
		(start 53.8988 -48.710088)
		(end 53.69052 -48.918368)
		(width 0.2032)
		(layer "In2.Cu")
		(net "M1_DQ_NODE1_DQ25")
	)
	(segment
		(start 53.85816 -50.940208)
		(end 54.2544 -51.336448)
		(width 0.2032)
		(layer "In2.Cu")
		(net "M1_DQ_NODE1_DQ25")
	)
	(segment
		(start 53.85816 -50.698146)
		(end 53.85816 -50.940208)
		(width 0.2032)
		(layer "In2.Cu")
		(net "M1_DQ_NODE1_DQ25")
	)
	(segment
		(start 53.00218 -44.859448)
		(end 53.00218 -45.154088)
		(width 0.2032)
		(layer "In2.Cu")
		(net "M1_DQ_NODE1_DQ25")
	)
	(segment
		(start 53.3527 -48.207168)
		(end 53.69052 -48.207168)
		(width 0.2032)
		(layer "In2.Cu")
		(net "M1_DQ_NODE1_DQ25")
	)
	(segment
		(start 53.72735 -58.140346)
		(end 53.616606 -58.140346)
		(width 0.1016)
		(layer "In2.Cu")
		(net "M1_DQ_NODE1_DQ25")
	)
	(segment
		(start 53.75656 -45.865288)
		(end 53.54828 -46.073568)
		(width 0.2032)
		(layer "In2.Cu")
		(net "M1_DQ_NODE1_DQ25")
	)
	(segment
		(start 55.15229 -60.041282)
		(end 55.15229 -60.29579)
		(width 0.1016)
		(layer "In2.Cu")
		(net "M1_DQ_NODE1_DQ25")
	)
	(segment
		(start 52.84216 -48.918368)
		(end 52.63388 -49.126648)
		(width 0.2032)
		(layer "In2.Cu")
		(net "M1_DQ_NODE1_DQ25")
	)
	(segment
		(start 53.69052 -48.918368)
		(end 52.84216 -48.918368)
		(width 0.2032)
		(layer "In2.Cu")
		(net "M1_DQ_NODE1_DQ25")
	)
	(segment
		(start 53.68671 -40.282876)
		(end 53.088032 -40.282876)
		(width 0.2032)
		(layer "In2.Cu")
		(net "M1_DQ_NODE1_DQ25")
	)
	(segment
		(start 52.77866 -43.228768)
		(end 52.57038 -43.437048)
		(width 0.2032)
		(layer "In2.Cu")
		(net "M1_DQ_NODE1_DQ25")
	)
	(segment
		(start 53.82514 -41.603168)
		(end 53.62194 -41.806368)
		(width 0.2032)
		(layer "In2.Cu")
		(net "M1_DQ_NODE1_DQ25")
	)
	(segment
		(start 52.63388 -49.421288)
		(end 52.84216 -49.629568)
		(width 0.2032)
		(layer "In2.Cu")
		(net "M1_DQ_NODE1_DQ25")
	)
	(segment
		(start 53.62448 -44.442888)
		(end 53.4162 -44.651168)
		(width 0.2032)
		(layer "In2.Cu")
		(net "M1_DQ_NODE1_DQ25")
	)
	(segment
		(start 52.77866 -40.592248)
		(end 52.77866 -40.886888)
		(width 0.2032)
		(layer "In2.Cu")
		(net "M1_DQ_NODE1_DQ25")
	)
	(segment
		(start 54.2544 -51.336448)
		(end 54.2544 -57.03697)
		(width 0.2032)
		(layer "In2.Cu")
		(net "M1_DQ_NODE1_DQ25")
	)
	(segment
		(start 53.21046 -44.651168)
		(end 53.00218 -44.859448)
		(width 0.2032)
		(layer "In2.Cu")
		(net "M1_DQ_NODE1_DQ25")
	)
	(segment
		(start 53.89118 -39.479728)
		(end 53.89118 -40.078406)
		(width 0.2032)
		(layer "In2.Cu")
		(net "M1_DQ_NODE1_DQ25")
	)
	(segment
		(start 53.62448 -44.148248)
		(end 53.62448 -44.442888)
		(width 0.2032)
		(layer "In2.Cu")
		(net "M1_DQ_NODE1_DQ25")
	)
	(segment
		(start 51.98872 -42.014648)
		(end 51.98872 -42.309288)
		(width 0.2032)
		(layer "In2.Cu")
		(net "M1_DQ_NODE1_DQ25")
	)
	(segment
		(start 52.57038 -43.437048)
		(end 52.57038 -43.731688)
		(width 0.2032)
		(layer "In2.Cu")
		(net "M1_DQ_NODE1_DQ25")
	)
	(segment
		(start 52.57038 -43.731688)
		(end 52.77866 -43.939968)
		(width 0.2032)
		(layer "In2.Cu")
		(net "M1_DQ_NODE1_DQ25")
	)
	(segment
		(start 54.2544 -49.837848)
		(end 54.2544 -50.301906)
		(width 0.2032)
		(layer "In2.Cu")
		(net "M1_DQ_NODE1_DQ25")
	)
	(segment
		(start 53.14442 -47.704248)
		(end 53.14442 -47.998888)
		(width 0.2032)
		(layer "In2.Cu")
		(net "M1_DQ_NODE1_DQ25")
	)
	(segment
		(start 52.197 -41.806368)
		(end 51.98872 -42.014648)
		(width 0.2032)
		(layer "In2.Cu")
		(net "M1_DQ_NODE1_DQ25")
	)
	(segment
		(start 54.2544 -39.116)
		(end 54.254908 -39.116)
		(width 0.2032)
		(layer "In2.Cu")
		(net "M1_DQ_NODE1_DQ25")
	)
	(segment
		(start 59.203082 -24.083518)
		(end 58.86196 -24.42464)
		(width 0.2032)
		(layer "In2.Cu")
		(net "M1_DQ_NODE1_DQ25")
	)
	(segment
		(start 53.24856 -46.073568)
		(end 53.04028 -46.281848)
		(width 0.2032)
		(layer "In2.Cu")
		(net "M1_DQ_NODE1_DQ25")
	)
	(segment
		(start 53.52542 -43.228768)
		(end 52.77866 -43.228768)
		(width 0.2032)
		(layer "In2.Cu")
		(net "M1_DQ_NODE1_DQ25")
	)
	(segment
		(start 59.660282 -27.461718)
		(end 59.660282 -28.545282)
		(width 0.2032)
		(layer "In2.Cu")
		(net "M1_DQ_NODE1_DQ25")
	)
	(segment
		(start 52.197 -42.517568)
		(end 53.52542 -42.517568)
		(width 0.2032)
		(layer "In2.Cu")
		(net "M1_DQ_NODE1_DQ25")
	)
	(segment
		(start 53.36794 -58.389012)
		(end 53.36794 -58.739024)
		(width 0.1016)
		(layer "In2.Cu")
		(net "M1_DQ_NODE1_DQ25")
	)
	(segment
		(start 53.4162 -44.651168)
		(end 53.21046 -44.651168)
		(width 0.2032)
		(layer "In2.Cu")
		(net "M1_DQ_NODE1_DQ25")
	)
	(segment
		(start 54.131464 -59.020456)
		(end 55.15229 -60.041282)
		(width 0.1016)
		(layer "In2.Cu")
		(net "M1_DQ_NODE1_DQ25")
	)
	(segment
		(start 59.46394 -27.265376)
		(end 59.660282 -27.461718)
		(width 0.2032)
		(layer "In2.Cu")
		(net "M1_DQ_NODE1_DQ25")
	)
	(segment
		(start 52.77866 -40.886888)
		(end 52.98694 -41.095168)
		(width 0.2032)
		(layer "In2.Cu")
		(net "M1_DQ_NODE1_DQ25")
	)
	(segment
		(start 54.2544 -57.613296)
		(end 53.72735 -58.140346)
		(width 0.1016)
		(layer "In2.Cu")
		(net "M1_DQ_NODE1_DQ25")
	)
	(segment
		(start 17.75714 -18.196814)
		(end 17.75714 -14.722094)
		(width 0.1016)
		(layer "F.Cu")
		(net "N54251517")
	)
	(segment
		(start 13.965174 -15.09268)
		(end 13.965174 -15.860522)
		(width 0.1016)
		(layer "F.Cu")
		(net "N54251517")
	)
	(segment
		(start 17.75714 -14.722094)
		(end 17.56156 -14.526514)
		(width 0.1016)
		(layer "F.Cu")
		(net "N54251517")
	)
	(segment
		(start 14.53134 -14.526514)
		(end 13.965174 -15.09268)
		(width 0.1016)
		(layer "F.Cu")
		(net "N54251517")
	)
	(segment
		(start 16.438118 -20.20316)
		(end 16.438118 -19.515836)
		(width 0.1016)
		(layer "F.Cu")
		(net "N54251517")
	)
	(segment
		(start 17.56156 -14.526514)
		(end 14.53134 -14.526514)
		(width 0.1016)
		(layer "F.Cu")
		(net "N54251517")
	)
	(segment
		(start 16.438118 -19.515836)
		(end 17.75714 -18.196814)
		(width 0.1016)
		(layer "F.Cu")
		(net "N54251517")
	)
	(via
		(at 13.965174 -15.09268)
		(size 0.508)
		(drill 0.254)
		(layers "F.Cu" "B.Cu")
		(net "N54251517")
	)
	(segment
		(start 155.04541 -60.764674)
		(end 155.04541 -60.310014)
		(width 0.1016)
		(layer "F.Cu")
		(net "TP_SATA_NODE1")
	)
	(segment
		(start 154.59456 -61.838078)
		(end 155.060396 -61.372242)
		(width 0.1016)
		(layer "F.Cu")
		(net "TP_SATA_NODE1")
	)
	(segment
		(start 150.61819 -61.838078)
		(end 154.59456 -61.838078)
		(width 0.1016)
		(layer "F.Cu")
		(net "TP_SATA_NODE1")
	)
	(segment
		(start 155.060396 -60.77966)
		(end 155.04541 -60.764674)
		(width 0.1016)
		(layer "F.Cu")
		(net "TP_SATA_NODE1")
	)
	(segment
		(start 155.060396 -61.372242)
		(end 155.060396 -60.77966)
		(width 0.1016)
		(layer "F.Cu")
		(net "TP_SATA_NODE1")
	)
	(segment
		(start 149.57171 -61.557916)
		(end 150.338028 -61.557916)
		(width 0.1016)
		(layer "F.Cu")
		(net "TP_SATA_NODE1")
	)
	(segment
		(start 150.338028 -61.557916)
		(end 150.61819 -61.838078)
		(width 0.1016)
		(layer "F.Cu")
		(net "TP_SATA_NODE1")
	)
	(via
		(at 155.04541 -60.310014)
		(size 0.508)
		(drill 0.254)
		(layers "F.Cu" "B.Cu")
		(net "TP_SATA_NODE1")
	)
	(segment
		(start 146.733006 -136.421622)
		(end 145.785078 -137.36955)
		(width 0.1016)
		(layer "F.Cu")
		(net "IRQ_LVC3_CPU_NODE1_WAKE_L")
	)
	(segment
		(start 77.7367 -109.516672)
		(end 78.20787 -109.045502)
		(width 0.1016)
		(layer "F.Cu")
		(net "IRQ_LVC3_CPU_NODE1_WAKE_L")
	)
	(segment
		(start 151.09444 -96.419162)
		(end 151.84374 -95.669862)
		(width 0.1016)
		(layer "F.Cu")
		(net "IRQ_LVC3_CPU_NODE1_WAKE_L")
	)
	(segment
		(start 150.284942 -129.07518)
		(end 152.06218 -129.07518)
		(width 0.1016)
		(layer "F.Cu")
		(net "IRQ_LVC3_CPU_NODE1_WAKE_L")
	)
	(segment
		(start 70.68439 -117.625622)
		(end 69.039486 -119.270526)
		(width 0.1016)
		(layer "F.Cu")
		(net "IRQ_LVC3_CPU_NODE1_WAKE_L")
	)
	(segment
		(start 142.194026 -73.077324)
		(end 141.534388 -72.417686)
		(width 0.1016)
		(layer "F.Cu")
		(net "IRQ_LVC3_CPU_NODE1_WAKE_L")
	)
	(segment
		(start 153.82494 -103.5939)
		(end 152.57272 -104.84612)
		(width 0.1016)
		(layer "F.Cu")
		(net "IRQ_LVC3_CPU_NODE1_WAKE_L")
	)
	(segment
		(start 143.345916 -72.714358)
		(end 143.183864 -72.714358)
		(width 0.1016)
		(layer "F.Cu")
		(net "IRQ_LVC3_CPU_NODE1_WAKE_L")
	)
	(segment
		(start 48.317658 -150.37308)
		(end 48.317658 -149.686772)
		(width 0.1016)
		(layer "F.Cu")
		(net "IRQ_LVC3_CPU_NODE1_WAKE_L")
	)
	(segment
		(start 148.30806 -136.421622)
		(end 146.733006 -136.421622)
		(width 0.1016)
		(layer "F.Cu")
		(net "IRQ_LVC3_CPU_NODE1_WAKE_L")
	)
	(segment
		(start 78.1812 -118.836186)
		(end 76.84262 -118.836186)
		(width 0.1016)
		(layer "F.Cu")
		(net "IRQ_LVC3_CPU_NODE1_WAKE_L")
	)
	(segment
		(start 76.84262 -118.836186)
		(end 75.632056 -117.625622)
		(width 0.1016)
		(layer "F.Cu")
		(net "IRQ_LVC3_CPU_NODE1_WAKE_L")
	)
	(segment
		(start 151.09444 -100.352352)
		(end 151.09444 -96.419162)
		(width 0.1016)
		(layer "F.Cu")
		(net "IRQ_LVC3_CPU_NODE1_WAKE_L")
	)
	(segment
		(start 156.38526 -158.886144)
		(end 157.05963 -158.886144)
		(width 0.1016)
		(layer "F.Cu")
		(net "IRQ_LVC3_CPU_NODE1_WAKE_L")
	)
	(segment
		(start 75.632056 -117.625622)
		(end 70.68439 -117.625622)
		(width 0.1016)
		(layer "F.Cu")
		(net "IRQ_LVC3_CPU_NODE1_WAKE_L")
	)
	(segment
		(start 69.792596 -81.88071)
		(end 70.374002 -81.88071)
		(width 0.1016)
		(layer "F.Cu")
		(net "IRQ_LVC3_CPU_NODE1_WAKE_L")
	)
	(segment
		(start 70.374002 -81.88071)
		(end 70.629018 -82.135726)
		(width 0.1016)
		(layer "F.Cu")
		(net "IRQ_LVC3_CPU_NODE1_WAKE_L")
	)
	(segment
		(start 148.30806 -136.421622)
		(end 148.30806 -131.052062)
		(width 0.1016)
		(layer "F.Cu")
		(net "IRQ_LVC3_CPU_NODE1_WAKE_L")
	)
	(segment
		(start 79.63662 -109.553502)
		(end 79.63662 -110.86084)
		(width 0.1016)
		(layer "F.Cu")
		(net "IRQ_LVC3_CPU_NODE1_WAKE_L")
	)
	(segment
		(start 151.84374 -95.669862)
		(end 151.84374 -83.891628)
		(width 0.1016)
		(layer "F.Cu")
		(net "IRQ_LVC3_CPU_NODE1_WAKE_L")
	)
	(segment
		(start 49.64176 -148.36267)
		(end 50.51806 -148.36267)
		(width 0.1016)
		(layer "F.Cu")
		(net "IRQ_LVC3_CPU_NODE1_WAKE_L")
	)
	(segment
		(start 170.1673 -127.209042)
		(end 168.30802 -127.209042)
		(width 0.1016)
		(layer "F.Cu")
		(net "IRQ_LVC3_CPU_NODE1_WAKE_L")
	)
	(segment
		(start 157.269942 -158.675832)
		(end 157.269942 -157.647132)
		(width 0.1016)
		(layer "F.Cu")
		(net "IRQ_LVC3_CPU_NODE1_WAKE_L")
	)
	(segment
		(start 172.010324 -125.365764)
		(end 170.1673 -127.209042)
		(width 0.1016)
		(layer "F.Cu")
		(net "IRQ_LVC3_CPU_NODE1_WAKE_L")
	)
	(segment
		(start 78.20787 -109.045502)
		(end 79.12862 -109.045502)
		(width 0.1016)
		(layer "F.Cu")
		(net "IRQ_LVC3_CPU_NODE1_WAKE_L")
	)
	(segment
		(start 69.039486 -119.270526)
		(end 69.039486 -119.958612)
		(width 0.1016)
		(layer "F.Cu")
		(net "IRQ_LVC3_CPU_NODE1_WAKE_L")
	)
	(segment
		(start 69.440044 -81.528158)
		(end 69.792596 -81.88071)
		(width 0.1016)
		(layer "F.Cu")
		(net "IRQ_LVC3_CPU_NODE1_WAKE_L")
	)
	(segment
		(start 78.1812 -118.836186)
		(end 77.7367 -118.391686)
		(width 0.1016)
		(layer "F.Cu")
		(net "IRQ_LVC3_CPU_NODE1_WAKE_L")
	)
	(segment
		(start 48.317658 -149.686772)
		(end 49.64176 -148.36267)
		(width 0.1016)
		(layer "F.Cu")
		(net "IRQ_LVC3_CPU_NODE1_WAKE_L")
	)
	(segment
		(start 148.30806 -131.052062)
		(end 150.284942 -129.07518)
		(width 0.1016)
		(layer "F.Cu")
		(net "IRQ_LVC3_CPU_NODE1_WAKE_L")
	)
	(segment
		(start 157.05963 -158.886144)
		(end 157.269942 -158.675832)
		(width 0.1016)
		(layer "F.Cu")
		(net "IRQ_LVC3_CPU_NODE1_WAKE_L")
	)
	(segment
		(start 69.039486 -119.958612)
		(end 68.353686 -120.644412)
		(width 0.1016)
		(layer "F.Cu")
		(net "IRQ_LVC3_CPU_NODE1_WAKE_L")
	)
	(segment
		(start 70.629018 -82.135726)
		(end 70.629018 -82.763868)
		(width 0.1016)
		(layer "F.Cu")
		(net "IRQ_LVC3_CPU_NODE1_WAKE_L")
	)
	(segment
		(start 142.820898 -73.077324)
		(end 142.194026 -73.077324)
		(width 0.1016)
		(layer "F.Cu")
		(net "IRQ_LVC3_CPU_NODE1_WAKE_L")
	)
	(segment
		(start 155.444952 -103.5939)
		(end 153.82494 -103.5939)
		(width 0.1016)
		(layer "F.Cu")
		(net "IRQ_LVC3_CPU_NODE1_WAKE_L")
	)
	(segment
		(start 145.785078 -137.36955)
		(end 145.316702 -137.36955)
		(width 0.1016)
		(layer "F.Cu")
		(net "IRQ_LVC3_CPU_NODE1_WAKE_L")
	)
	(segment
		(start 143.183864 -72.714358)
		(end 142.820898 -73.077324)
		(width 0.1016)
		(layer "F.Cu")
		(net "IRQ_LVC3_CPU_NODE1_WAKE_L")
	)
	(segment
		(start 79.12862 -109.045502)
		(end 79.63662 -109.553502)
		(width 0.1016)
		(layer "F.Cu")
		(net "IRQ_LVC3_CPU_NODE1_WAKE_L")
	)
	(segment
		(start 77.7367 -118.391686)
		(end 77.7367 -109.516672)
		(width 0.1016)
		(layer "F.Cu")
		(net "IRQ_LVC3_CPU_NODE1_WAKE_L")
	)
	(segment
		(start 151.84374 -83.891628)
		(end 152.031954 -83.703414)
		(width 0.1016)
		(layer "F.Cu")
		(net "IRQ_LVC3_CPU_NODE1_WAKE_L")
	)
	(via
		(at 152.06218 -129.07518)
		(size 0.508)
		(drill 0.254)
		(layers "F.Cu" "B.Cu")
		(net "IRQ_LVC3_CPU_NODE1_WAKE_L")
	)
	(via
		(at 78.1812 -118.836186)
		(size 0.508)
		(drill 0.254)
		(layers "F.Cu" "B.Cu")
		(net "IRQ_LVC3_CPU_NODE1_WAKE_L")
	)
	(via
		(at 151.09444 -100.352352)
		(size 0.508)
		(drill 0.254)
		(layers "F.Cu" "B.Cu")
		(net "IRQ_LVC3_CPU_NODE1_WAKE_L")
	)
	(via
		(at 141.534388 -72.417686)
		(size 0.508)
		(drill 0.254)
		(layers "F.Cu" "B.Cu")
		(net "IRQ_LVC3_CPU_NODE1_WAKE_L")
	)
	(via
		(at 152.57272 -104.84612)
		(size 0.508)
		(drill 0.254)
		(layers "F.Cu" "B.Cu")
		(net "IRQ_LVC3_CPU_NODE1_WAKE_L")
	)
	(via
		(at 168.30802 -127.209042)
		(size 0.508)
		(drill 0.254)
		(layers "F.Cu" "B.Cu")
		(net "IRQ_LVC3_CPU_NODE1_WAKE_L")
	)
	(via
		(at 77.93228 -86.905084)
		(size 0.508)
		(drill 0.254)
		(layers "F.Cu" "B.Cu")
		(net "IRQ_LVC3_CPU_NODE1_WAKE_L")
	)
	(via
		(at 152.031954 -83.703414)
		(size 0.508)
		(drill 0.254)
		(layers "F.Cu" "B.Cu")
		(net "IRQ_LVC3_CPU_NODE1_WAKE_L")
	)
	(via
		(at 156.38526 -158.886144)
		(size 0.508)
		(drill 0.254)
		(layers "F.Cu" "B.Cu")
		(net "IRQ_LVC3_CPU_NODE1_WAKE_L")
	)
	(via
		(at 148.30806 -136.421622)
		(size 0.508)
		(drill 0.254)
		(layers "F.Cu" "B.Cu")
		(net "IRQ_LVC3_CPU_NODE1_WAKE_L")
	)
	(via
		(at 70.629018 -82.763868)
		(size 0.508)
		(drill 0.254)
		(layers "F.Cu" "B.Cu")
		(net "IRQ_LVC3_CPU_NODE1_WAKE_L")
	)
	(via
		(at 50.51806 -148.36267)
		(size 0.508)
		(drill 0.254)
		(layers "F.Cu" "B.Cu")
		(net "IRQ_LVC3_CPU_NODE1_WAKE_L")
	)
	(via
		(at 79.63662 -110.86084)
		(size 0.508)
		(drill 0.254)
		(layers "F.Cu" "B.Cu")
		(net "IRQ_LVC3_CPU_NODE1_WAKE_L")
	)
	(segment
		(start 77.37348 -87.463884)
		(end 77.93228 -86.905084)
		(width 0.1016)
		(layer "B.Cu")
		(net "IRQ_LVC3_CPU_NODE1_WAKE_L")
	)
	(segment
		(start 77.09535 -87.463884)
		(end 77.37348 -87.463884)
		(width 0.1016)
		(layer "B.Cu")
		(net "IRQ_LVC3_CPU_NODE1_WAKE_L")
	)
	(segment
		(start 72.67702 -84.341462)
		(end 73.130664 -84.341462)
		(width 0.1143)
		(layer "In2.Cu")
		(net "IRQ_LVC3_CPU_NODE1_WAKE_L")
	)
	(segment
		(start 83.847178 -93.255084)
		(end 83.847178 -104.452166)
		(width 0.1143)
		(layer "In2.Cu")
		(net "IRQ_LVC3_CPU_NODE1_WAKE_L")
	)
	(segment
		(start 78.52156 -134.52856)
		(end 79.39024 -133.65988)
		(width 0.1143)
		(layer "In2.Cu")
		(net "IRQ_LVC3_CPU_NODE1_WAKE_L")
	)
	(segment
		(start 83.847178 -104.452166)
		(end 81.88198 -106.417364)
		(width 0.1143)
		(layer "In2.Cu")
		(net "IRQ_LVC3_CPU_NODE1_WAKE_L")
	)
	(segment
		(start 152.06218 -129.07518)
		(end 152.57272 -128.56464)
		(width 0.1143)
		(layer "In2.Cu")
		(net "IRQ_LVC3_CPU_NODE1_WAKE_L")
	)
	(segment
		(start 81.88198 -107.008676)
		(end 79.77124 -109.119416)
		(width 0.1143)
		(layer "In2.Cu")
		(net "IRQ_LVC3_CPU_NODE1_WAKE_L")
	)
	(segment
		(start 148.951442 -83.703414)
		(end 152.031954 -83.703414)
		(width 0.1143)
		(layer "In2.Cu")
		(net "IRQ_LVC3_CPU_NODE1_WAKE_L")
	)
	(segment
		(start 79.39024 -133.65988)
		(end 79.39024 -119.973344)
		(width 0.1143)
		(layer "In2.Cu")
		(net "IRQ_LVC3_CPU_NODE1_WAKE_L")
	)
	(segment
		(start 71.228204 -83.403694)
		(end 71.739252 -83.403694)
		(width 0.1143)
		(layer "In2.Cu")
		(net "IRQ_LVC3_CPU_NODE1_WAKE_L")
	)
	(segment
		(start 62.39129 -149.575774)
		(end 64.591438 -149.575774)
		(width 0.1143)
		(layer "In2.Cu")
		(net "IRQ_LVC3_CPU_NODE1_WAKE_L")
	)
	(segment
		(start 152.57272 -128.56464)
		(end 152.57272 -104.84612)
		(width 0.1143)
		(layer "In2.Cu")
		(net "IRQ_LVC3_CPU_NODE1_WAKE_L")
	)
	(segment
		(start 62.173612 -149.358096)
		(end 62.39129 -149.575774)
		(width 0.1143)
		(layer "In2.Cu")
		(net "IRQ_LVC3_CPU_NODE1_WAKE_L")
	)
	(segment
		(start 80.509618 -92.236798)
		(end 82.828892 -92.236798)
		(width 0.1143)
		(layer "In2.Cu")
		(net "IRQ_LVC3_CPU_NODE1_WAKE_L")
	)
	(segment
		(start 79.77124 -109.119416)
		(end 79.77124 -110.72622)
		(width 0.1143)
		(layer "In2.Cu")
		(net "IRQ_LVC3_CPU_NODE1_WAKE_L")
	)
	(segment
		(start 50.51806 -148.36267)
		(end 51.513486 -149.358096)
		(width 0.1143)
		(layer "In2.Cu")
		(net "IRQ_LVC3_CPU_NODE1_WAKE_L")
	)
	(segment
		(start 74.63536 -85.846158)
		(end 76.059538 -85.846158)
		(width 0.1143)
		(layer "In2.Cu")
		(net "IRQ_LVC3_CPU_NODE1_WAKE_L")
	)
	(segment
		(start 64.591438 -149.575774)
		(end 65.25006 -148.917152)
		(width 0.1143)
		(layer "In2.Cu")
		(net "IRQ_LVC3_CPU_NODE1_WAKE_L")
	)
	(segment
		(start 81.88198 -106.417364)
		(end 81.88198 -107.008676)
		(width 0.1143)
		(layer "In2.Cu")
		(net "IRQ_LVC3_CPU_NODE1_WAKE_L")
	)
	(segment
		(start 70.629018 -82.763868)
		(end 70.629018 -82.804508)
		(width 0.1143)
		(layer "In2.Cu")
		(net "IRQ_LVC3_CPU_NODE1_WAKE_L")
	)
	(segment
		(start 67.267328 -148.917152)
		(end 67.81038 -148.3741)
		(width 0.1143)
		(layer "In2.Cu")
		(net "IRQ_LVC3_CPU_NODE1_WAKE_L")
	)
	(segment
		(start 151.84374 -101.101652)
		(end 151.84374 -104.11714)
		(width 0.1143)
		(layer "In2.Cu")
		(net "IRQ_LVC3_CPU_NODE1_WAKE_L")
	)
	(segment
		(start 67.81038 -148.3741)
		(end 72.713088 -148.3741)
		(width 0.1143)
		(layer "In2.Cu")
		(net "IRQ_LVC3_CPU_NODE1_WAKE_L")
	)
	(segment
		(start 78.306422 -118.889526)
		(end 78.23454 -118.889526)
		(width 0.1143)
		(layer "In2.Cu")
		(net "IRQ_LVC3_CPU_NODE1_WAKE_L")
	)
	(segment
		(start 141.534388 -76.28636)
		(end 148.951442 -83.703414)
		(width 0.1143)
		(layer "In2.Cu")
		(net "IRQ_LVC3_CPU_NODE1_WAKE_L")
	)
	(segment
		(start 73.240646 -147.846542)
		(end 76.113386 -147.846542)
		(width 0.1143)
		(layer "In2.Cu")
		(net "IRQ_LVC3_CPU_NODE1_WAKE_L")
	)
	(segment
		(start 78.52156 -145.438368)
		(end 78.52156 -134.52856)
		(width 0.1143)
		(layer "In2.Cu")
		(net "IRQ_LVC3_CPU_NODE1_WAKE_L")
	)
	(segment
		(start 70.629018 -82.804508)
		(end 71.228204 -83.403694)
		(width 0.1143)
		(layer "In2.Cu")
		(net "IRQ_LVC3_CPU_NODE1_WAKE_L")
	)
	(segment
		(start 79.39024 -119.973344)
		(end 78.306422 -118.889526)
		(width 0.1143)
		(layer "In2.Cu")
		(net "IRQ_LVC3_CPU_NODE1_WAKE_L")
	)
	(segment
		(start 71.739252 -83.403694)
		(end 72.67702 -84.341462)
		(width 0.1143)
		(layer "In2.Cu")
		(net "IRQ_LVC3_CPU_NODE1_WAKE_L")
	)
	(segment
		(start 141.534388 -72.417686)
		(end 141.534388 -76.28636)
		(width 0.1143)
		(layer "In2.Cu")
		(net "IRQ_LVC3_CPU_NODE1_WAKE_L")
	)
	(segment
		(start 76.113386 -147.846542)
		(end 78.52156 -145.438368)
		(width 0.1143)
		(layer "In2.Cu")
		(net "IRQ_LVC3_CPU_NODE1_WAKE_L")
	)
	(segment
		(start 65.25006 -148.917152)
		(end 67.267328 -148.917152)
		(width 0.1143)
		(layer "In2.Cu")
		(net "IRQ_LVC3_CPU_NODE1_WAKE_L")
	)
	(segment
		(start 73.130664 -84.341462)
		(end 74.63536 -85.846158)
		(width 0.1143)
		(layer "In2.Cu")
		(net "IRQ_LVC3_CPU_NODE1_WAKE_L")
	)
	(segment
		(start 72.713088 -148.3741)
		(end 73.240646 -147.846542)
		(width 0.1143)
		(layer "In2.Cu")
		(net "IRQ_LVC3_CPU_NODE1_WAKE_L")
	)
	(segment
		(start 76.059538 -85.846158)
		(end 78.55712 -88.34374)
		(width 0.1143)
		(layer "In2.Cu")
		(net "IRQ_LVC3_CPU_NODE1_WAKE_L")
	)
	(segment
		(start 79.77124 -110.72622)
		(end 79.63662 -110.86084)
		(width 0.1143)
		(layer "In2.Cu")
		(net "IRQ_LVC3_CPU_NODE1_WAKE_L")
	)
	(segment
		(start 82.828892 -92.236798)
		(end 83.847178 -93.255084)
		(width 0.1143)
		(layer "In2.Cu")
		(net "IRQ_LVC3_CPU_NODE1_WAKE_L")
	)
	(segment
		(start 151.09444 -100.352352)
		(end 151.84374 -101.101652)
		(width 0.1143)
		(layer "In2.Cu")
		(net "IRQ_LVC3_CPU_NODE1_WAKE_L")
	)
	(segment
		(start 51.513486 -149.358096)
		(end 62.173612 -149.358096)
		(width 0.1143)
		(layer "In2.Cu")
		(net "IRQ_LVC3_CPU_NODE1_WAKE_L")
	)
	(segment
		(start 78.55712 -90.2843)
		(end 80.509618 -92.236798)
		(width 0.1143)
		(layer "In2.Cu")
		(net "IRQ_LVC3_CPU_NODE1_WAKE_L")
	)
	(segment
		(start 78.55712 -88.34374)
		(end 78.55712 -90.2843)
		(width 0.1143)
		(layer "In2.Cu")
		(net "IRQ_LVC3_CPU_NODE1_WAKE_L")
	)
	(segment
		(start 78.23454 -118.889526)
		(end 78.1812 -118.836186)
		(width 0.1143)
		(layer "In2.Cu")
		(net "IRQ_LVC3_CPU_NODE1_WAKE_L")
	)
	(segment
		(start 151.84374 -104.11714)
		(end 152.57272 -104.84612)
		(width 0.1143)
		(layer "In2.Cu")
		(net "IRQ_LVC3_CPU_NODE1_WAKE_L")
	)
	(segment
		(start 72.260206 -83.430618)
		(end 72.490838 -83.199986)
		(width 0.1143)
		(layer "In6.Cu")
		(net "IRQ_LVC3_CPU_NODE1_WAKE_L")
	)
	(segment
		(start 74.358754 -84.72551)
		(end 75.21448 -84.72551)
		(width 0.1143)
		(layer "In6.Cu")
		(net "IRQ_LVC3_CPU_NODE1_WAKE_L")
	)
	(segment
		(start 71.115936 -83.430618)
		(end 72.260206 -83.430618)
		(width 0.1143)
		(layer "In6.Cu")
		(net "IRQ_LVC3_CPU_NODE1_WAKE_L")
	)
	(segment
		(start 70.629018 -82.9437)
		(end 71.115936 -83.430618)
		(width 0.1143)
		(layer "In6.Cu")
		(net "IRQ_LVC3_CPU_NODE1_WAKE_L")
	)
	(segment
		(start 91.439238 -91.130374)
		(end 88.501728 -91.130374)
		(width 0.1143)
		(layer "In6.Cu")
		(net "IRQ_LVC3_CPU_NODE1_WAKE_L")
	)
	(segment
		(start 77.394054 -86.905084)
		(end 77.93228 -86.905084)
		(width 0.1143)
		(layer "In6.Cu")
		(net "IRQ_LVC3_CPU_NODE1_WAKE_L")
	)
	(segment
		(start 77.93228 -87.344758)
		(end 77.93228 -86.905084)
		(width 0.1143)
		(layer "In6.Cu")
		(net "IRQ_LVC3_CPU_NODE1_WAKE_L")
	)
	(segment
		(start 86.139782 -90.303604)
		(end 84.367878 -90.303604)
		(width 0.1143)
		(layer "In6.Cu")
		(net "IRQ_LVC3_CPU_NODE1_WAKE_L")
	)
	(segment
		(start 167.68191 -127.835152)
		(end 168.30802 -127.209042)
		(width 0.1143)
		(layer "In6.Cu")
		(net "IRQ_LVC3_CPU_NODE1_WAKE_L")
	)
	(segment
		(start 152.06218 -129.07518)
		(end 153.302208 -127.835152)
		(width 0.1143)
		(layer "In6.Cu")
		(net "IRQ_LVC3_CPU_NODE1_WAKE_L")
	)
	(segment
		(start 153.302208 -127.835152)
		(end 167.68191 -127.835152)
		(width 0.1143)
		(layer "In6.Cu")
		(net "IRQ_LVC3_CPU_NODE1_WAKE_L")
	)
	(segment
		(start 135.82904 -87.595456)
		(end 94.974156 -87.595456)
		(width 0.1143)
		(layer "In6.Cu")
		(net "IRQ_LVC3_CPU_NODE1_WAKE_L")
	)
	(segment
		(start 150.983696 -100.241608)
		(end 148.475192 -100.241608)
		(width 0.1143)
		(layer "In6.Cu")
		(net "IRQ_LVC3_CPU_NODE1_WAKE_L")
	)
	(segment
		(start 151.09444 -100.352352)
		(end 150.983696 -100.241608)
		(width 0.1143)
		(layer "In6.Cu")
		(net "IRQ_LVC3_CPU_NODE1_WAKE_L")
	)
	(segment
		(start 87.55126 -90.179906)
		(end 86.26348 -90.179906)
		(width 0.1143)
		(layer "In6.Cu")
		(net "IRQ_LVC3_CPU_NODE1_WAKE_L")
	)
	(segment
		(start 83.549744 -89.48547)
		(end 80.072992 -89.48547)
		(width 0.1143)
		(layer "In6.Cu")
		(net "IRQ_LVC3_CPU_NODE1_WAKE_L")
	)
	(segment
		(start 94.974156 -87.595456)
		(end 91.439238 -91.130374)
		(width 0.1143)
		(layer "In6.Cu")
		(net "IRQ_LVC3_CPU_NODE1_WAKE_L")
	)
	(segment
		(start 72.83323 -83.199986)
		(end 74.358754 -84.72551)
		(width 0.1143)
		(layer "In6.Cu")
		(net "IRQ_LVC3_CPU_NODE1_WAKE_L")
	)
	(segment
		(start 86.26348 -90.179906)
		(end 86.139782 -90.303604)
		(width 0.1143)
		(layer "In6.Cu")
		(net "IRQ_LVC3_CPU_NODE1_WAKE_L")
	)
	(segment
		(start 88.501728 -91.130374)
		(end 87.55126 -90.179906)
		(width 0.1143)
		(layer "In6.Cu")
		(net "IRQ_LVC3_CPU_NODE1_WAKE_L")
	)
	(segment
		(start 70.629018 -82.763868)
		(end 70.629018 -82.9437)
		(width 0.1143)
		(layer "In6.Cu")
		(net "IRQ_LVC3_CPU_NODE1_WAKE_L")
	)
	(segment
		(start 75.21448 -84.72551)
		(end 77.394054 -86.905084)
		(width 0.1143)
		(layer "In6.Cu")
		(net "IRQ_LVC3_CPU_NODE1_WAKE_L")
	)
	(segment
		(start 72.490838 -83.199986)
		(end 72.83323 -83.199986)
		(width 0.1143)
		(layer "In6.Cu")
		(net "IRQ_LVC3_CPU_NODE1_WAKE_L")
	)
	(segment
		(start 80.072992 -89.48547)
		(end 77.93228 -87.344758)
		(width 0.1143)
		(layer "In6.Cu")
		(net "IRQ_LVC3_CPU_NODE1_WAKE_L")
	)
	(segment
		(start 148.475192 -100.241608)
		(end 135.82904 -87.595456)
		(width 0.1143)
		(layer "In6.Cu")
		(net "IRQ_LVC3_CPU_NODE1_WAKE_L")
	)
	(segment
		(start 84.367878 -90.303604)
		(end 83.549744 -89.48547)
		(width 0.1143)
		(layer "In6.Cu")
		(net "IRQ_LVC3_CPU_NODE1_WAKE_L")
	)
	(segment
		(start 150.917148 -139.03071)
		(end 148.30806 -136.421622)
		(width 0.1143)
		(layer "In7.Cu")
		(net "IRQ_LVC3_CPU_NODE1_WAKE_L")
	)
	(segment
		(start 150.917148 -147.50288)
		(end 150.917148 -139.03071)
		(width 0.1143)
		(layer "In7.Cu")
		(net "IRQ_LVC3_CPU_NODE1_WAKE_L")
	)
	(segment
		(start 148.61159 -156.765244)
		(end 148.61159 -149.808438)
		(width 0.1143)
		(layer "In7.Cu")
		(net "IRQ_LVC3_CPU_NODE1_WAKE_L")
	)
	(segment
		(start 150.73249 -158.886144)
		(end 148.61159 -156.765244)
		(width 0.1143)
		(layer "In7.Cu")
		(net "IRQ_LVC3_CPU_NODE1_WAKE_L")
	)
	(segment
		(start 148.61159 -149.808438)
		(end 150.917148 -147.50288)
		(width 0.1143)
		(layer "In7.Cu")
		(net "IRQ_LVC3_CPU_NODE1_WAKE_L")
	)
	(segment
		(start 156.38526 -158.886144)
		(end 150.73249 -158.886144)
		(width 0.1143)
		(layer "In7.Cu")
		(net "IRQ_LVC3_CPU_NODE1_WAKE_L")
	)
	(segment
		(start 64.641984 -86.83371)
		(end 64.641984 -88.157558)
		(width 0.1016)
		(layer "F.Cu")
		(net "SPC_CPU_NODE1_DSR_L")
	)
	(segment
		(start 63.489586 -85.168486)
		(end 63.846964 -85.525864)
		(width 0.1016)
		(layer "F.Cu")
		(net "SPC_CPU_NODE1_DSR_L")
	)
	(segment
		(start 64.308736 -91.838526)
		(end 65.086992 -92.616782)
		(width 0.1016)
		(layer "F.Cu")
		(net "SPC_CPU_NODE1_DSR_L")
	)
	(segment
		(start 64.308736 -88.98255)
		(end 64.308736 -91.838526)
		(width 0.1016)
		(layer "F.Cu")
		(net "SPC_CPU_NODE1_DSR_L")
	)
	(segment
		(start 64.641984 -88.157558)
		(end 64.51854 -88.281002)
		(width 0.1016)
		(layer "F.Cu")
		(net "SPC_CPU_NODE1_DSR_L")
	)
	(segment
		(start 63.846964 -86.03869)
		(end 64.641984 -86.83371)
		(width 0.1016)
		(layer "F.Cu")
		(net "SPC_CPU_NODE1_DSR_L")
	)
	(segment
		(start 63.489586 -85.000846)
		(end 63.489586 -85.168486)
		(width 0.1016)
		(layer "F.Cu")
		(net "SPC_CPU_NODE1_DSR_L")
	)
	(segment
		(start 63.846964 -85.525864)
		(end 63.846964 -86.03869)
		(width 0.1016)
		(layer "F.Cu")
		(net "SPC_CPU_NODE1_DSR_L")
	)
	(segment
		(start 65.642744 -92.616782)
		(end 65.086992 -92.616782)
		(width 0.1016)
		(layer "F.Cu")
		(net "SPC_CPU_NODE1_DSR_L")
	)
	(segment
		(start 64.51854 -88.281002)
		(end 64.51854 -88.772746)
		(width 0.1016)
		(layer "F.Cu")
		(net "SPC_CPU_NODE1_DSR_L")
	)
	(segment
		(start 64.51854 -88.772746)
		(end 64.308736 -88.98255)
		(width 0.1016)
		(layer "F.Cu")
		(net "SPC_CPU_NODE1_DSR_L")
	)
	(segment
		(start 69.273166 -96.247204)
		(end 65.642744 -92.616782)
		(width 0.1016)
		(layer "F.Cu")
		(net "SPC_CPU_NODE1_DSR_L")
	)
	(segment
		(start 69.273166 -96.309942)
		(end 69.273166 -96.247204)
		(width 0.1016)
		(layer "F.Cu")
		(net "SPC_CPU_NODE1_DSR_L")
	)
	(via
		(at 65.086992 -92.616782)
		(size 0.762)
		(drill 0.381)
		(layers "F.Cu" "B.Cu")
		(net "SPC_CPU_NODE1_DSR_L")
	)
	(segment
		(start 64.409828 -61.89726)
		(end 65.053972 -61.253116)
		(width 0.1016)
		(layer "F.Cu")
		(net "M_DDR3_NODE1_CKE1")
	)
	(segment
		(start 64.233552 -61.89726)
		(end 64.409828 -61.89726)
		(width 0.1016)
		(layer "F.Cu")
		(net "M_DDR3_NODE1_CKE1")
	)
	(segment
		(start 63.478664 -63.730378)
		(end 63.478664 -63.37681)
		(width 0.1016)
		(layer "F.Cu")
		(net "M_DDR3_NODE1_CKE1")
	)
	(segment
		(start 63.721742 -63.133732)
		(end 63.721742 -62.40907)
		(width 0.1016)
		(layer "F.Cu")
		(net "M_DDR3_NODE1_CKE1")
	)
	(segment
		(start 63.631318 -64.597026)
		(end 63.631318 -63.883032)
		(width 0.1016)
		(layer "F.Cu")
		(net "M_DDR3_NODE1_CKE1")
	)
	(segment
		(start 65.053972 -57.79516)
		(end 64.842898 -57.584086)
		(width 0.1016)
		(layer "F.Cu")
		(net "M_DDR3_NODE1_CKE1")
	)
	(segment
		(start 69.15023 -20.94992)
		(end 69.15023 -22.75459)
		(width 0.1651)
		(layer "F.Cu")
		(net "M_DDR3_NODE1_CKE1")
	)
	(segment
		(start 63.721742 -62.40907)
		(end 64.233552 -61.89726)
		(width 0.1016)
		(layer "F.Cu")
		(net "M_DDR3_NODE1_CKE1")
	)
	(segment
		(start 63.631318 -63.883032)
		(end 63.478664 -63.730378)
		(width 0.1016)
		(layer "F.Cu")
		(net "M_DDR3_NODE1_CKE1")
	)
	(segment
		(start 63.82004 -64.785748)
		(end 63.631318 -64.597026)
		(width 0.1016)
		(layer "F.Cu")
		(net "M_DDR3_NODE1_CKE1")
	)
	(segment
		(start 63.478664 -63.37681)
		(end 63.721742 -63.133732)
		(width 0.1016)
		(layer "F.Cu")
		(net "M_DDR3_NODE1_CKE1")
	)
	(segment
		(start 65.053972 -61.253116)
		(end 65.053972 -57.79516)
		(width 0.1016)
		(layer "F.Cu")
		(net "M_DDR3_NODE1_CKE1")
	)
	(via
		(at 64.842898 -57.584086)
		(size 0.508)
		(drill 0.254)
		(layers "F.Cu" "B.Cu")
		(net "M_DDR3_NODE1_CKE1")
	)
	(via
		(at 69.15023 -22.75459)
		(size 0.508)
		(drill 0.254)
		(layers "F.Cu" "B.Cu")
		(net "M_DDR3_NODE1_CKE1")
	)
	(segment
		(start 78.34122 -22.143466)
		(end 76.923392 -20.725638)
		(width 0.2032)
		(layer "In2.Cu")
		(net "M_DDR3_NODE1_CKE1")
	)
	(segment
		(start 65.9384 -56.833516)
		(end 65.9384 -55.93969)
		(width 0.2032)
		(layer "In2.Cu")
		(net "M_DDR3_NODE1_CKE1")
	)
	(segment
		(start 78.486 -41.725088)
		(end 78.486 -34.15792)
		(width 0.2032)
		(layer "In2.Cu")
		(net "M_DDR3_NODE1_CKE1")
	)
	(segment
		(start 69.06514 -22.6695)
		(end 69.15023 -22.75459)
		(width 0.2032)
		(layer "In2.Cu")
		(net "M_DDR3_NODE1_CKE1")
	)
	(segment
		(start 78.71206 -32.513524)
		(end 78.34122 -32.142684)
		(width 0.2032)
		(layer "In2.Cu")
		(net "M_DDR3_NODE1_CKE1")
	)
	(segment
		(start 70.253098 -20.725638)
		(end 69.06514 -21.913596)
		(width 0.2032)
		(layer "In2.Cu")
		(net "M_DDR3_NODE1_CKE1")
	)
	(segment
		(start 78.486 -34.15792)
		(end 78.71206 -33.93186)
		(width 0.2032)
		(layer "In2.Cu")
		(net "M_DDR3_NODE1_CKE1")
	)
	(segment
		(start 65.9384 -55.93969)
		(end 69.75983 -52.11826)
		(width 0.2032)
		(layer "In2.Cu")
		(net "M_DDR3_NODE1_CKE1")
	)
	(segment
		(start 64.842898 -57.582308)
		(end 65.189608 -57.582308)
		(width 0.2032)
		(layer "In2.Cu")
		(net "M_DDR3_NODE1_CKE1")
	)
	(segment
		(start 78.71206 -33.93186)
		(end 78.71206 -32.513524)
		(width 0.2032)
		(layer "In2.Cu")
		(net "M_DDR3_NODE1_CKE1")
	)
	(segment
		(start 77.8002 -45.498004)
		(end 77.8002 -42.410888)
		(width 0.2032)
		(layer "In2.Cu")
		(net "M_DDR3_NODE1_CKE1")
	)
	(segment
		(start 65.189608 -57.582308)
		(end 65.9384 -56.833516)
		(width 0.2032)
		(layer "In2.Cu")
		(net "M_DDR3_NODE1_CKE1")
	)
	(segment
		(start 69.75983 -52.11826)
		(end 71.179944 -52.11826)
		(width 0.2032)
		(layer "In2.Cu")
		(net "M_DDR3_NODE1_CKE1")
	)
	(segment
		(start 78.34122 -32.142684)
		(end 78.34122 -22.143466)
		(width 0.2032)
		(layer "In2.Cu")
		(net "M_DDR3_NODE1_CKE1")
	)
	(segment
		(start 71.179944 -52.11826)
		(end 77.8002 -45.498004)
		(width 0.2032)
		(layer "In2.Cu")
		(net "M_DDR3_NODE1_CKE1")
	)
	(segment
		(start 64.842898 -57.584086)
		(end 64.842898 -57.582308)
		(width 0.2032)
		(layer "In2.Cu")
		(net "M_DDR3_NODE1_CKE1")
	)
	(segment
		(start 69.06514 -21.913596)
		(end 69.06514 -22.6695)
		(width 0.2032)
		(layer "In2.Cu")
		(net "M_DDR3_NODE1_CKE1")
	)
	(segment
		(start 76.923392 -20.725638)
		(end 70.253098 -20.725638)
		(width 0.2032)
		(layer "In2.Cu")
		(net "M_DDR3_NODE1_CKE1")
	)
	(segment
		(start 77.8002 -42.410888)
		(end 78.486 -41.725088)
		(width 0.2032)
		(layer "In2.Cu")
		(net "M_DDR3_NODE1_CKE1")
	)
	(segment
		(start 32.639254 -182.215282)
		(end 32.295084 -182.215282)
		(width 0.254)
		(layer "F.Cu")
		(net "VR_HSC_NODE1_TIMER")
	)
	(segment
		(start 32.05988 -182.450486)
		(end 32.05988 -183.121046)
		(width 0.254)
		(layer "F.Cu")
		(net "VR_HSC_NODE1_TIMER")
	)
	(segment
		(start 31.655512 -184.653936)
		(end 31.65348 -184.651904)
		(width 0.254)
		(layer "F.Cu")
		(net "VR_HSC_NODE1_TIMER")
	)
	(segment
		(start 32.295084 -182.215282)
		(end 32.05988 -182.450486)
		(width 0.254)
		(layer "F.Cu")
		(net "VR_HSC_NODE1_TIMER")
	)
	(segment
		(start 31.65348 -183.527446)
		(end 32.05988 -183.121046)
		(width 0.254)
		(layer "F.Cu")
		(net "VR_HSC_NODE1_TIMER")
	)
	(segment
		(start 31.65348 -184.651904)
		(end 31.65348 -183.527446)
		(width 0.254)
		(layer "F.Cu")
		(net "VR_HSC_NODE1_TIMER")
	)
	(via
		(at 33.51784 -183.119014)
		(size 0.6604)
		(drill 0.3302)
		(layers "F.Cu" "B.Cu")
		(net "VR_HSC_NODE1_TIMER")
	)
	(via
		(at 32.05988 -183.121046)
		(size 0.508)
		(drill 0.254)
		(layers "F.Cu" "B.Cu")
		(net "VR_HSC_NODE1_TIMER")
	)
	(segment
		(start 33.51784 -183.119014)
		(end 32.061912 -183.119014)
		(width 0.1016)
		(layer "B.Cu")
		(net "VR_HSC_NODE1_TIMER")
	)
	(segment
		(start 32.061912 -183.119014)
		(end 32.05988 -183.121046)
		(width 0.1016)
		(layer "B.Cu")
		(net "VR_HSC_NODE1_TIMER")
	)
	(segment
		(start 150.81758 -32.484822)
		(end 151.114252 -32.484822)
		(width 0.1016)
		(layer "F.Cu")
		(net "N21624804")
	)
	(segment
		(start 149.909022 -32.570928)
		(end 150.731474 -32.570928)
		(width 0.1016)
		(layer "F.Cu")
		(net "N21624804")
	)
	(segment
		(start 152.429972 -32.484822)
		(end 151.114252 -32.484822)
		(width 0.1016)
		(layer "F.Cu")
		(net "N21624804")
	)
	(segment
		(start 150.731474 -32.570928)
		(end 150.81758 -32.484822)
		(width 0.1016)
		(layer "F.Cu")
		(net "N21624804")
	)
	(via
		(at 151.114252 -32.484822)
		(size 0.508)
		(drill 0.254)
		(layers "F.Cu" "B.Cu")
		(net "N21624804")
	)
	(segment
		(start 44.813728 -60.367672)
		(end 44.813728 -60.564776)
		(width 0.127)
		(layer "F.Cu")
		(net "P2E_CPU_SATA_NODE1_RX_DN")
	)
	(segment
		(start 45.900594 -63.429896)
		(end 45.778166 -63.552324)
		(width 0.1016)
		(layer "F.Cu")
		(net "P2E_CPU_SATA_NODE1_RX_DN")
	)
	(segment
		(start 44.813728 -60.564776)
		(end 45.002196 -60.753244)
		(width 0.127)
		(layer "F.Cu")
		(net "P2E_CPU_SATA_NODE1_RX_DN")
	)
	(segment
		(start 40.4495 -60.390532)
		(end 40.45458 -60.39231)
		(width 0.127)
		(layer "F.Cu")
		(net "P2E_CPU_SATA_NODE1_RX_DN")
	)
	(segment
		(start 44.08678 -60.042044)
		(end 44.4881 -60.042044)
		(width 0.127)
		(layer "F.Cu")
		(net "P2E_CPU_SATA_NODE1_RX_DN")
	)
	(segment
		(start 43.25112 -60.042044)
		(end 43.455082 -60.042044)
		(width 0.127)
		(layer "F.Cu")
		(net "P2E_CPU_SATA_NODE1_RX_DN")
	)
	(segment
		(start 45.470572 -62.290452)
		(end 45.470572 -62.315852)
		(width 0.1016)
		(layer "F.Cu")
		(net "P2E_CPU_SATA_NODE1_RX_DN")
	)
	(segment
		(start 43.455082 -60.042044)
		(end 43.619928 -60.20689)
		(width 0.127)
		(layer "F.Cu")
		(net "P2E_CPU_SATA_NODE1_RX_DN")
	)
	(segment
		(start 150.283418 -74.703432)
		(end 150.283418 -76.985876)
		(width 0.127)
		(layer "F.Cu")
		(net "P2E_CPU_SATA_NODE1_RX_DN")
	)
	(segment
		(start 45.470572 -62.315852)
		(end 45.521372 -62.315852)
		(width 0.1016)
		(layer "F.Cu")
		(net "P2E_CPU_SATA_NODE1_RX_DN")
	)
	(segment
		(start 40.448738 -60.390024)
		(end 40.4495 -60.390532)
		(width 0.127)
		(layer "F.Cu")
		(net "P2E_CPU_SATA_NODE1_RX_DN")
	)
	(segment
		(start 43.619928 -60.20689)
		(end 43.922188 -60.20689)
		(width 0.127)
		(layer "F.Cu")
		(net "P2E_CPU_SATA_NODE1_RX_DN")
	)
	(segment
		(start 38.44544 -61.951616)
		(end 40.325548 -60.434728)
		(width 0.127)
		(layer "F.Cu")
		(net "P2E_CPU_SATA_NODE1_RX_DN")
	)
	(segment
		(start 44.4881 -60.042044)
		(end 44.813728 -60.367672)
		(width 0.127)
		(layer "F.Cu")
		(net "P2E_CPU_SATA_NODE1_RX_DN")
	)
	(segment
		(start 43.922188 -60.20689)
		(end 44.08678 -60.042044)
		(width 0.127)
		(layer "F.Cu")
		(net "P2E_CPU_SATA_NODE1_RX_DN")
	)
	(segment
		(start 150.649178 -74.337672)
		(end 150.283418 -74.703432)
		(width 0.127)
		(layer "F.Cu")
		(net "P2E_CPU_SATA_NODE1_RX_DN")
	)
	(segment
		(start 40.325548 -60.434728)
		(end 40.32631 -60.434474)
		(width 0.127)
		(layer "F.Cu")
		(net "P2E_CPU_SATA_NODE1_RX_DN")
	)
	(segment
		(start 45.900594 -63.251588)
		(end 45.900594 -63.429896)
		(width 0.1016)
		(layer "F.Cu")
		(net "P2E_CPU_SATA_NODE1_RX_DN")
	)
	(segment
		(start 45.521372 -62.872366)
		(end 45.900594 -63.251588)
		(width 0.1016)
		(layer "F.Cu")
		(net "P2E_CPU_SATA_NODE1_RX_DN")
	)
	(segment
		(start 36.9697 -62.588394)
		(end 37.942266 -62.588394)
		(width 0.127)
		(layer "F.Cu")
		(net "P2E_CPU_SATA_NODE1_RX_DN")
	)
	(segment
		(start 40.445436 -60.391294)
		(end 40.448738 -60.390024)
		(width 0.127)
		(layer "F.Cu")
		(net "P2E_CPU_SATA_NODE1_RX_DN")
	)
	(segment
		(start 40.45458 -60.39231)
		(end 43.25112 -60.042044)
		(width 0.127)
		(layer "F.Cu")
		(net "P2E_CPU_SATA_NODE1_RX_DN")
	)
	(segment
		(start 45.002196 -60.753244)
		(end 45.1993 -60.753244)
		(width 0.127)
		(layer "F.Cu")
		(net "P2E_CPU_SATA_NODE1_RX_DN")
	)
	(segment
		(start 40.32631 -60.434474)
		(end 40.445436 -60.391294)
		(width 0.127)
		(layer "F.Cu")
		(net "P2E_CPU_SATA_NODE1_RX_DN")
	)
	(segment
		(start 36.6776 -62.880494)
		(end 36.9697 -62.588394)
		(width 0.127)
		(layer "F.Cu")
		(net "P2E_CPU_SATA_NODE1_RX_DN")
	)
	(segment
		(start 37.942266 -62.588394)
		(end 38.44544 -61.951616)
		(width 0.127)
		(layer "F.Cu")
		(net "P2E_CPU_SATA_NODE1_RX_DN")
	)
	(segment
		(start 150.283418 -76.985876)
		(end 150.776178 -77.478636)
		(width 0.127)
		(layer "F.Cu")
		(net "P2E_CPU_SATA_NODE1_RX_DN")
	)
	(segment
		(start 45.1993 -60.753244)
		(end 45.470572 -61.024516)
		(width 0.127)
		(layer "F.Cu")
		(net "P2E_CPU_SATA_NODE1_RX_DN")
	)
	(segment
		(start 45.470572 -61.024516)
		(end 45.470572 -62.290452)
		(width 0.127)
		(layer "F.Cu")
		(net "P2E_CPU_SATA_NODE1_RX_DN")
	)
	(segment
		(start 45.521372 -62.315852)
		(end 45.521372 -62.872366)
		(width 0.1016)
		(layer "F.Cu")
		(net "P2E_CPU_SATA_NODE1_RX_DN")
	)
	(via
		(at 150.776178 -77.478636)
		(size 0.508)
		(drill 0.254)
		(layers "F.Cu" "B.Cu")
		(net "P2E_CPU_SATA_NODE1_RX_DN")
	)
	(via
		(at 36.6776 -62.880494)
		(size 0.508)
		(drill 0.254)
		(layers "F.Cu" "B.Cu")
		(net "P2E_CPU_SATA_NODE1_RX_DN")
	)
	(segment
		(start 51.329336 -37.123624)
		(end 53.526436 -36.993322)
		(width 0.127)
		(layer "B.Cu")
		(net "P2E_CPU_SATA_NODE1_RX_DN")
	)
	(segment
		(start 135.873744 -73.580752)
		(end 135.91032 -73.5965)
		(width 0.127)
		(layer "B.Cu")
		(net "P2E_CPU_SATA_NODE1_RX_DN")
	)
	(segment
		(start 145.562574 -75.700382)
		(end 145.565622 -75.697334)
		(width 0.127)
		(layer "B.Cu")
		(net "P2E_CPU_SATA_NODE1_RX_DN")
	)
	(segment
		(start 149.521926 -75.826874)
		(end 150.261828 -76.566776)
		(width 0.127)
		(layer "B.Cu")
		(net "P2E_CPU_SATA_NODE1_RX_DN")
	)
	(segment
		(start 39.855902 -47.225712)
		(end 45.959268 -39.47668)
		(width 0.127)
		(layer "B.Cu")
		(net "P2E_CPU_SATA_NODE1_RX_DN")
	)
	(segment
		(start 53.526436 -36.993322)
		(end 54.46141 -36.993322)
		(width 0.127)
		(layer "B.Cu")
		(net "P2E_CPU_SATA_NODE1_RX_DN")
	)
	(segment
		(start 134.423912 -72.668638)
		(end 135.873744 -73.580752)
		(width 0.127)
		(layer "B.Cu")
		(net "P2E_CPU_SATA_NODE1_RX_DN")
	)
	(segment
		(start 36.3855 -62.588394)
		(end 35.9537 -62.588394)
		(width 0.127)
		(layer "B.Cu")
		(net "P2E_CPU_SATA_NODE1_RX_DN")
	)
	(segment
		(start 71.705216 -41.078912)
		(end 71.71563 -41.078912)
		(width 0.127)
		(layer "B.Cu")
		(net "P2E_CPU_SATA_NODE1_RX_DN")
	)
	(segment
		(start 150.261828 -76.964286)
		(end 150.776178 -77.478636)
		(width 0.127)
		(layer "B.Cu")
		(net "P2E_CPU_SATA_NODE1_RX_DN")
	)
	(segment
		(start 143.586454 -74.781918)
		(end 145.432272 -75.700382)
		(width 0.127)
		(layer "B.Cu")
		(net "P2E_CPU_SATA_NODE1_RX_DN")
	)
	(segment
		(start 89.25814 -42.126662)
		(end 93.942916 -42.406316)
		(width 0.127)
		(layer "B.Cu")
		(net "P2E_CPU_SATA_NODE1_RX_DN")
	)
	(segment
		(start 110.224062 -53.790342)
		(end 116.576094 -55.15483)
		(width 0.127)
		(layer "B.Cu")
		(net "P2E_CPU_SATA_NODE1_RX_DN")
	)
	(segment
		(start 140.526262 -74.50709)
		(end 143.586454 -74.781918)
		(width 0.127)
		(layer "B.Cu")
		(net "P2E_CPU_SATA_NODE1_RX_DN")
	)
	(segment
		(start 150.261828 -76.566776)
		(end 150.261828 -76.964286)
		(width 0.127)
		(layer "B.Cu")
		(net "P2E_CPU_SATA_NODE1_RX_DN")
	)
	(segment
		(start 122.543824 -60.984892)
		(end 130.688334 -68.235576)
		(width 0.127)
		(layer "B.Cu")
		(net "P2E_CPU_SATA_NODE1_RX_DN")
	)
	(segment
		(start 58.501026 -37.68852)
		(end 71.705216 -41.078912)
		(width 0.127)
		(layer "B.Cu")
		(net "P2E_CPU_SATA_NODE1_RX_DN")
	)
	(segment
		(start 58.473086 -37.68852)
		(end 58.501026 -37.68852)
		(width 0.127)
		(layer "B.Cu")
		(net "P2E_CPU_SATA_NODE1_RX_DN")
	)
	(segment
		(start 93.942916 -42.406316)
		(end 109.480858 -53.270912)
		(width 0.127)
		(layer "B.Cu")
		(net "P2E_CPU_SATA_NODE1_RX_DN")
	)
	(segment
		(start 45.959268 -39.47668)
		(end 51.329336 -37.123624)
		(width 0.127)
		(layer "B.Cu")
		(net "P2E_CPU_SATA_NODE1_RX_DN")
	)
	(segment
		(start 145.432272 -75.700382)
		(end 145.562574 -75.700382)
		(width 0.127)
		(layer "B.Cu")
		(net "P2E_CPU_SATA_NODE1_RX_DN")
	)
	(segment
		(start 35.9537 -62.588394)
		(end 35.372294 -62.215522)
		(width 0.127)
		(layer "B.Cu")
		(net "P2E_CPU_SATA_NODE1_RX_DN")
	)
	(segment
		(start 145.565622 -75.697334)
		(end 146.213068 -75.826874)
		(width 0.127)
		(layer "B.Cu")
		(net "P2E_CPU_SATA_NODE1_RX_DN")
	)
	(segment
		(start 130.688334 -68.235576)
		(end 133.07187 -71.418958)
		(width 0.127)
		(layer "B.Cu")
		(net "P2E_CPU_SATA_NODE1_RX_DN")
	)
	(segment
		(start 135.91032 -73.5965)
		(end 140.526262 -74.50709)
		(width 0.127)
		(layer "B.Cu")
		(net "P2E_CPU_SATA_NODE1_RX_DN")
	)
	(segment
		(start 116.576094 -55.15483)
		(end 120.995694 -58.282586)
		(width 0.127)
		(layer "B.Cu")
		(net "P2E_CPU_SATA_NODE1_RX_DN")
	)
	(segment
		(start 36.6776 -62.880494)
		(end 36.3855 -62.588394)
		(width 0.127)
		(layer "B.Cu")
		(net "P2E_CPU_SATA_NODE1_RX_DN")
	)
	(segment
		(start 146.213068 -75.826874)
		(end 149.521926 -75.826874)
		(width 0.127)
		(layer "B.Cu")
		(net "P2E_CPU_SATA_NODE1_RX_DN")
	)
	(segment
		(start 54.46141 -36.993322)
		(end 58.473086 -37.68852)
		(width 0.127)
		(layer "B.Cu")
		(net "P2E_CPU_SATA_NODE1_RX_DN")
	)
	(segment
		(start 120.995694 -58.282586)
		(end 122.543824 -60.984892)
		(width 0.127)
		(layer "B.Cu")
		(net "P2E_CPU_SATA_NODE1_RX_DN")
	)
	(segment
		(start 71.71563 -41.078912)
		(end 89.25814 -42.126662)
		(width 0.127)
		(layer "B.Cu")
		(net "P2E_CPU_SATA_NODE1_RX_DN")
	)
	(segment
		(start 133.07187 -71.418958)
		(end 134.423912 -72.668638)
		(width 0.127)
		(layer "B.Cu")
		(net "P2E_CPU_SATA_NODE1_RX_DN")
	)
	(segment
		(start 35.372294 -62.215522)
		(end 35.343846 -61.138054)
		(width 0.127)
		(layer "B.Cu")
		(net "P2E_CPU_SATA_NODE1_RX_DN")
	)
	(segment
		(start 109.480858 -53.270912)
		(end 110.224062 -53.790342)
		(width 0.127)
		(layer "B.Cu")
		(net "P2E_CPU_SATA_NODE1_RX_DN")
	)
	(segment
		(start 35.343846 -61.138054)
		(end 39.855902 -47.225712)
		(width 0.127)
		(layer "B.Cu")
		(net "P2E_CPU_SATA_NODE1_RX_DN")
	)
	(segment
		(start 70.141846 -126.459488)
		(end 70.256654 -126.34468)
		(width 0.127)
		(layer "F.Cu")
		(net "P2E_CPU_BMC_NODE1_TX_DN")
	)
	(segment
		(start 70.825614 -123.723146)
		(end 70.825614 -123.506738)
		(width 0.127)
		(layer "F.Cu")
		(net "P2E_CPU_BMC_NODE1_TX_DN")
	)
	(segment
		(start 70.256654 -126.34468)
		(end 70.256654 -125.889004)
		(width 0.127)
		(layer "F.Cu")
		(net "P2E_CPU_BMC_NODE1_TX_DN")
	)
	(segment
		(start 70.654418 -123.894342)
		(end 70.825614 -123.723146)
		(width 0.127)
		(layer "F.Cu")
		(net "P2E_CPU_BMC_NODE1_TX_DN")
	)
	(segment
		(start 70.65899 -123.340114)
		(end 70.65899 -122.959114)
		(width 0.127)
		(layer "F.Cu")
		(net "P2E_CPU_BMC_NODE1_TX_DN")
	)
	(segment
		(start 70.387972 -125.757686)
		(end 70.387972 -125.5141)
		(width 0.127)
		(layer "F.Cu")
		(net "P2E_CPU_BMC_NODE1_TX_DN")
	)
	(segment
		(start 70.668134 -124.888752)
		(end 70.668134 -124.683012)
		(width 0.127)
		(layer "F.Cu")
		(net "P2E_CPU_BMC_NODE1_TX_DN")
	)
	(segment
		(start 70.747636 -122.224038)
		(end 70.47738 -122.224038)
		(width 0.127)
		(layer "F.Cu")
		(net "P2E_CPU_BMC_NODE1_TX_DN")
	)
	(segment
		(start 70.825614 -124.525532)
		(end 70.825614 -124.31903)
		(width 0.127)
		(layer "F.Cu")
		(net "P2E_CPU_BMC_NODE1_TX_DN")
	)
	(segment
		(start 70.494906 -125.407166)
		(end 70.738492 -125.407166)
		(width 0.127)
		(layer "F.Cu")
		(net "P2E_CPU_BMC_NODE1_TX_DN")
	)
	(segment
		(start 70.825614 -122.79249)
		(end 70.825614 -122.302016)
		(width 0.127)
		(layer "F.Cu")
		(net "P2E_CPU_BMC_NODE1_TX_DN")
	)
	(segment
		(start 70.825614 -124.31903)
		(end 70.654418 -124.148088)
		(width 0.127)
		(layer "F.Cu")
		(net "P2E_CPU_BMC_NODE1_TX_DN")
	)
	(segment
		(start 70.387972 -125.5141)
		(end 70.494906 -125.407166)
		(width 0.127)
		(layer "F.Cu")
		(net "P2E_CPU_BMC_NODE1_TX_DN")
	)
	(segment
		(start 70.668134 -124.683012)
		(end 70.825614 -124.525532)
		(width 0.127)
		(layer "F.Cu")
		(net "P2E_CPU_BMC_NODE1_TX_DN")
	)
	(segment
		(start 70.825614 -125.046232)
		(end 70.668134 -124.888752)
		(width 0.127)
		(layer "F.Cu")
		(net "P2E_CPU_BMC_NODE1_TX_DN")
	)
	(segment
		(start 70.825614 -125.320044)
		(end 70.825614 -125.046232)
		(width 0.127)
		(layer "F.Cu")
		(net "P2E_CPU_BMC_NODE1_TX_DN")
	)
	(segment
		(start 70.825614 -122.302016)
		(end 70.747636 -122.224038)
		(width 0.127)
		(layer "F.Cu")
		(net "P2E_CPU_BMC_NODE1_TX_DN")
	)
	(segment
		(start 70.654418 -124.148088)
		(end 70.654418 -123.894342)
		(width 0.127)
		(layer "F.Cu")
		(net "P2E_CPU_BMC_NODE1_TX_DN")
	)
	(segment
		(start 70.65899 -122.959114)
		(end 70.825614 -122.79249)
		(width 0.127)
		(layer "F.Cu")
		(net "P2E_CPU_BMC_NODE1_TX_DN")
	)
	(segment
		(start 70.825614 -123.506738)
		(end 70.65899 -123.340114)
		(width 0.127)
		(layer "F.Cu")
		(net "P2E_CPU_BMC_NODE1_TX_DN")
	)
	(segment
		(start 70.738492 -125.407166)
		(end 70.825614 -125.320044)
		(width 0.127)
		(layer "F.Cu")
		(net "P2E_CPU_BMC_NODE1_TX_DN")
	)
	(segment
		(start 70.256654 -125.889004)
		(end 70.387972 -125.757686)
		(width 0.127)
		(layer "F.Cu")
		(net "P2E_CPU_BMC_NODE1_TX_DN")
	)
	(via
		(at 70.47738 -122.224038)
		(size 0.508)
		(drill 0.254)
		(layers "F.Cu" "B.Cu")
		(net "P2E_CPU_BMC_NODE1_TX_DN")
	)
	(via
		(at 119.838216 -142.51559)
		(size 0.508)
		(drill 0.254)
		(layers "F.Cu" "B.Cu")
		(net "P2E_CPU_BMC_NODE1_TX_DN")
	)
	(segment
		(start 121.00179 -142.404592)
		(end 120.650508 -142.05331)
		(width 0.127)
		(layer "B.Cu")
		(net "P2E_CPU_BMC_NODE1_TX_DN")
	)
	(segment
		(start 120.650508 -142.05331)
		(end 120.300496 -142.05331)
		(width 0.127)
		(layer "B.Cu")
		(net "P2E_CPU_BMC_NODE1_TX_DN")
	)
	(segment
		(start 120.300496 -142.05331)
		(end 119.838216 -142.51559)
		(width 0.127)
		(layer "B.Cu")
		(net "P2E_CPU_BMC_NODE1_TX_DN")
	)
	(segment
		(start 84.54136 -132.036058)
		(end 87.3252 -134.103618)
		(width 0.127)
		(layer "In7.Cu")
		(net "P2E_CPU_BMC_NODE1_TX_DN")
	)
	(segment
		(start 90.943176 -139.847828)
		(end 91.686888 -141.198092)
		(width 0.127)
		(layer "In7.Cu")
		(net "P2E_CPU_BMC_NODE1_TX_DN")
	)
	(segment
		(start 75.547728 -123.119134)
		(end 77.60843 -123.67006)
		(width 0.127)
		(layer "In7.Cu")
		(net "P2E_CPU_BMC_NODE1_TX_DN")
	)
	(segment
		(start 87.3252 -134.103618)
		(end 89.905332 -138.660886)
		(width 0.127)
		(layer "In7.Cu")
		(net "P2E_CPU_BMC_NODE1_TX_DN")
	)
	(segment
		(start 100.892864 -143.200882)
		(end 102.62235 -144.803622)
		(width 0.127)
		(layer "In7.Cu")
		(net "P2E_CPU_BMC_NODE1_TX_DN")
	)
	(segment
		(start 70.77583 -123.155202)
		(end 70.936358 -123.505468)
		(width 0.127)
		(layer "In7.Cu")
		(net "P2E_CPU_BMC_NODE1_TX_DN")
	)
	(segment
		(start 89.905332 -138.660886)
		(end 90.943176 -139.847828)
		(width 0.127)
		(layer "In7.Cu")
		(net "P2E_CPU_BMC_NODE1_TX_DN")
	)
	(segment
		(start 71.069962 -123.657868)
		(end 71.589646 -123.968764)
		(width 0.127)
		(layer "In7.Cu")
		(net "P2E_CPU_BMC_NODE1_TX_DN")
	)
	(segment
		(start 109.996224 -145.83537)
		(end 114.20602 -145.422366)
		(width 0.127)
		(layer "In7.Cu")
		(net "P2E_CPU_BMC_NODE1_TX_DN")
	)
	(segment
		(start 77.60843 -123.67006)
		(end 79.77124 -125.376178)
		(width 0.127)
		(layer "In7.Cu")
		(net "P2E_CPU_BMC_NODE1_TX_DN")
	)
	(segment
		(start 72.158352 -124.050552)
		(end 72.158606 -124.050552)
		(width 0.127)
		(layer "In7.Cu")
		(net "P2E_CPU_BMC_NODE1_TX_DN")
	)
	(segment
		(start 71.7423 -124.017024)
		(end 72.158352 -124.050552)
		(width 0.127)
		(layer "In7.Cu")
		(net "P2E_CPU_BMC_NODE1_TX_DN")
	)
	(segment
		(start 72.158606 -124.050552)
		(end 75.547728 -123.119134)
		(width 0.127)
		(layer "In7.Cu")
		(net "P2E_CPU_BMC_NODE1_TX_DN")
	)
	(segment
		(start 99.81311 -143.08963)
		(end 100.892864 -143.200882)
		(width 0.127)
		(layer "In7.Cu")
		(net "P2E_CPU_BMC_NODE1_TX_DN")
	)
	(segment
		(start 70.77583 -122.522488)
		(end 70.77583 -123.155202)
		(width 0.127)
		(layer "In7.Cu")
		(net "P2E_CPU_BMC_NODE1_TX_DN")
	)
	(segment
		(start 119.349266 -142.02664)
		(end 119.838216 -142.51559)
		(width 0.127)
		(layer "In7.Cu")
		(net "P2E_CPU_BMC_NODE1_TX_DN")
	)
	(segment
		(start 91.720924 -141.246606)
		(end 92.435934 -142.089886)
		(width 0.127)
		(layer "In7.Cu")
		(net "P2E_CPU_BMC_NODE1_TX_DN")
	)
	(segment
		(start 94.890336 -142.86611)
		(end 99.529646 -143.076422)
		(width 0.127)
		(layer "In7.Cu")
		(net "P2E_CPU_BMC_NODE1_TX_DN")
	)
	(segment
		(start 79.77124 -125.376178)
		(end 84.54136 -132.036058)
		(width 0.127)
		(layer "In7.Cu")
		(net "P2E_CPU_BMC_NODE1_TX_DN")
	)
	(segment
		(start 70.936358 -123.505468)
		(end 71.069962 -123.657868)
		(width 0.127)
		(layer "In7.Cu")
		(net "P2E_CPU_BMC_NODE1_TX_DN")
	)
	(segment
		(start 99.529646 -143.076422)
		(end 99.81311 -143.08963)
		(width 0.127)
		(layer "In7.Cu")
		(net "P2E_CPU_BMC_NODE1_TX_DN")
	)
	(segment
		(start 70.47738 -122.224038)
		(end 70.77583 -122.522488)
		(width 0.127)
		(layer "In7.Cu")
		(net "P2E_CPU_BMC_NODE1_TX_DN")
	)
	(segment
		(start 91.687396 -141.198854)
		(end 91.720924 -141.246606)
		(width 0.127)
		(layer "In7.Cu")
		(net "P2E_CPU_BMC_NODE1_TX_DN")
	)
	(segment
		(start 114.20602 -145.422366)
		(end 117.45341 -143.42618)
		(width 0.127)
		(layer "In7.Cu")
		(net "P2E_CPU_BMC_NODE1_TX_DN")
	)
	(segment
		(start 118.853458 -142.02664)
		(end 119.349266 -142.02664)
		(width 0.127)
		(layer "In7.Cu")
		(net "P2E_CPU_BMC_NODE1_TX_DN")
	)
	(segment
		(start 102.62235 -144.803622)
		(end 109.996224 -145.83537)
		(width 0.127)
		(layer "In7.Cu")
		(net "P2E_CPU_BMC_NODE1_TX_DN")
	)
	(segment
		(start 117.45341 -143.42618)
		(end 118.853458 -142.02664)
		(width 0.127)
		(layer "In7.Cu")
		(net "P2E_CPU_BMC_NODE1_TX_DN")
	)
	(segment
		(start 91.686888 -141.198092)
		(end 91.687396 -141.198854)
		(width 0.127)
		(layer "In7.Cu")
		(net "P2E_CPU_BMC_NODE1_TX_DN")
	)
	(segment
		(start 92.435934 -142.089886)
		(end 94.890336 -142.86611)
		(width 0.127)
		(layer "In7.Cu")
		(net "P2E_CPU_BMC_NODE1_TX_DN")
	)
	(segment
		(start 71.589646 -123.968764)
		(end 71.7423 -124.017024)
		(width 0.127)
		(layer "In7.Cu")
		(net "P2E_CPU_BMC_NODE1_TX_DN")
	)
	(segment
		(start 82.79638 -25.099518)
		(end 80.99044 -26.905458)
		(width 0.1016)
		(layer "F.Cu")
		(net "TP_DDR3_NODE1_CS2_L")
	)
	(segment
		(start 79.548482 -26.905458)
		(end 78.450186 -28.003754)
		(width 0.1016)
		(layer "F.Cu")
		(net "TP_DDR3_NODE1_CS2_L")
	)
	(segment
		(start 80.99044 -26.905458)
		(end 79.548482 -26.905458)
		(width 0.1016)
		(layer "F.Cu")
		(net "TP_DDR3_NODE1_CS2_L")
	)
	(segment
		(start 78.450186 -28.003754)
		(end 78.450186 -29.149802)
		(width 0.1016)
		(layer "F.Cu")
		(net "TP_DDR3_NODE1_CS2_L")
	)
	(via
		(at 82.79638 -25.099518)
		(size 0.508)
		(drill 0.254)
		(layers "F.Cu" "B.Cu")
		(net "TP_DDR3_NODE1_CS2_L")
	)
	(segment
		(start 71.687436 -84.803234)
		(end 71.687436 -84.783168)
		(width 0.1016)
		(layer "F.Cu")
		(net "NODE1_BIOS_MB_REV_ID2")
	)
	(segment
		(start 70.989952 -85.500718)
		(end 71.687436 -84.803234)
		(width 0.1016)
		(layer "F.Cu")
		(net "NODE1_BIOS_MB_REV_ID2")
	)
	(segment
		(start 70.964044 -85.500718)
		(end 70.989952 -85.500718)
		(width 0.1016)
		(layer "F.Cu")
		(net "NODE1_BIOS_MB_REV_ID2")
	)
	(via
		(at 71.687436 -84.783168)
		(size 0.508)
		(drill 0.254)
		(layers "F.Cu" "B.Cu")
		(net "NODE1_BIOS_MB_REV_ID2")
	)
	(via
		(at 75.239372 -89.836752)
		(size 0.6604)
		(drill 0.3302)
		(layers "F.Cu" "B.Cu")
		(net "NODE1_BIOS_MB_REV_ID2")
	)
	(segment
		(start 75.38212 -86.728808)
		(end 73.796398 -85.143086)
		(width 0.1016)
		(layer "B.Cu")
		(net "NODE1_BIOS_MB_REV_ID2")
	)
	(segment
		(start 75.239372 -89.836752)
		(end 75.239372 -89.028016)
		(width 0.1016)
		(layer "B.Cu")
		(net "NODE1_BIOS_MB_REV_ID2")
	)
	(segment
		(start 73.796398 -85.143086)
		(end 72.047354 -85.143086)
		(width 0.1016)
		(layer "B.Cu")
		(net "NODE1_BIOS_MB_REV_ID2")
	)
	(segment
		(start 75.471274 -93.731334)
		(end 76.487274 -93.731334)
		(width 0.1016)
		(layer "B.Cu")
		(net "NODE1_BIOS_MB_REV_ID2")
	)
	(segment
		(start 75.239372 -89.836752)
		(end 75.239372 -90.498168)
		(width 0.1016)
		(layer "B.Cu")
		(net "NODE1_BIOS_MB_REV_ID2")
	)
	(segment
		(start 75.471274 -93.240606)
		(end 75.471274 -93.731334)
		(width 0.1016)
		(layer "B.Cu")
		(net "NODE1_BIOS_MB_REV_ID2")
	)
	(segment
		(start 75.239372 -89.028016)
		(end 75.38212 -88.885268)
		(width 0.1016)
		(layer "B.Cu")
		(net "NODE1_BIOS_MB_REV_ID2")
	)
	(segment
		(start 75.239372 -90.498168)
		(end 76.089256 -91.348052)
		(width 0.1016)
		(layer "B.Cu")
		(net "NODE1_BIOS_MB_REV_ID2")
	)
	(segment
		(start 76.089256 -92.622624)
		(end 75.471274 -93.240606)
		(width 0.1016)
		(layer "B.Cu")
		(net "NODE1_BIOS_MB_REV_ID2")
	)
	(segment
		(start 72.047354 -85.143086)
		(end 71.687436 -84.783168)
		(width 0.1016)
		(layer "B.Cu")
		(net "NODE1_BIOS_MB_REV_ID2")
	)
	(segment
		(start 75.38212 -88.885268)
		(end 75.38212 -86.728808)
		(width 0.1016)
		(layer "B.Cu")
		(net "NODE1_BIOS_MB_REV_ID2")
	)
	(segment
		(start 76.089256 -91.348052)
		(end 76.089256 -92.622624)
		(width 0.1016)
		(layer "B.Cu")
		(net "NODE1_BIOS_MB_REV_ID2")
	)
	(segment
		(start 70.419214 -83.830414)
		(end 70.252844 -83.996784)
		(width 0.1016)
		(layer "F.Cu")
		(net "SMB_BMC_NODE1_HSC_ALERT_L")
	)
	(segment
		(start 34.990786 -174.783496)
		(end 35.346132 -174.42815)
		(width 0.1016)
		(layer "F.Cu")
		(net "SMB_BMC_NODE1_HSC_ALERT_L")
	)
	(segment
		(start 71.345044 -83.514438)
		(end 71.188326 -83.514438)
		(width 0.1016)
		(layer "F.Cu")
		(net "SMB_BMC_NODE1_HSC_ALERT_L")
	)
	(segment
		(start 41.38676 -103.171752)
		(end 42.521886 -104.306878)
		(width 0.1016)
		(layer "F.Cu")
		(net "SMB_BMC_NODE1_HSC_ALERT_L")
	)
	(segment
		(start 71.188326 -83.514438)
		(end 70.87235 -83.830414)
		(width 0.1016)
		(layer "F.Cu")
		(net "SMB_BMC_NODE1_HSC_ALERT_L")
	)
	(segment
		(start 72.136762 -104.306878)
		(end 75.028552 -101.415088)
		(width 0.1016)
		(layer "F.Cu")
		(net "SMB_BMC_NODE1_HSC_ALERT_L")
	)
	(segment
		(start 70.252844 -84.72932)
		(end 70.431152 -84.907628)
		(width 0.1016)
		(layer "F.Cu")
		(net "SMB_BMC_NODE1_HSC_ALERT_L")
	)
	(segment
		(start 42.521886 -104.306878)
		(end 72.136762 -104.306878)
		(width 0.1016)
		(layer "F.Cu")
		(net "SMB_BMC_NODE1_HSC_ALERT_L")
	)
	(segment
		(start 34.990786 -175.05045)
		(end 34.990786 -174.783496)
		(width 0.1016)
		(layer "F.Cu")
		(net "SMB_BMC_NODE1_HSC_ALERT_L")
	)
	(segment
		(start 34.990786 -173.81855)
		(end 34.990786 -174.072804)
		(width 0.1016)
		(layer "F.Cu")
		(net "SMB_BMC_NODE1_HSC_ALERT_L")
	)
	(segment
		(start 70.87235 -83.830414)
		(end 70.419214 -83.830414)
		(width 0.1016)
		(layer "F.Cu")
		(net "SMB_BMC_NODE1_HSC_ALERT_L")
	)
	(segment
		(start 34.990786 -174.072804)
		(end 35.346132 -174.42815)
		(width 0.1016)
		(layer "F.Cu")
		(net "SMB_BMC_NODE1_HSC_ALERT_L")
	)
	(segment
		(start 75.028552 -101.415088)
		(end 75.028552 -95.413576)
		(width 0.1016)
		(layer "F.Cu")
		(net "SMB_BMC_NODE1_HSC_ALERT_L")
	)
	(segment
		(start 70.252844 -83.996784)
		(end 70.252844 -84.72932)
		(width 0.1016)
		(layer "F.Cu")
		(net "SMB_BMC_NODE1_HSC_ALERT_L")
	)
	(via
		(at 70.431152 -84.907628)
		(size 0.508)
		(drill 0.254)
		(layers "F.Cu" "B.Cu")
		(net "SMB_BMC_NODE1_HSC_ALERT_L")
	)
	(via
		(at 75.028552 -95.413576)
		(size 0.508)
		(drill 0.254)
		(layers "F.Cu" "B.Cu")
		(net "SMB_BMC_NODE1_HSC_ALERT_L")
	)
	(via
		(at 35.346132 -174.42815)
		(size 0.508)
		(drill 0.254)
		(layers "F.Cu" "B.Cu")
		(net "SMB_BMC_NODE1_HSC_ALERT_L")
	)
	(via
		(at 41.38676 -103.171752)
		(size 0.508)
		(drill 0.254)
		(layers "F.Cu" "B.Cu")
		(net "SMB_BMC_NODE1_HSC_ALERT_L")
	)
	(segment
		(start 75.028298 -95.413322)
		(end 75.028298 -95.167196)
		(width 0.1016)
		(layer "B.Cu")
		(net "SMB_BMC_NODE1_HSC_ALERT_L")
	)
	(segment
		(start 73.279 -89.097358)
		(end 74.11466 -88.261698)
		(width 0.1016)
		(layer "B.Cu")
		(net "SMB_BMC_NODE1_HSC_ALERT_L")
	)
	(segment
		(start 75.028552 -95.413576)
		(end 75.028298 -95.413322)
		(width 0.1016)
		(layer "B.Cu")
		(net "SMB_BMC_NODE1_HSC_ALERT_L")
	)
	(segment
		(start 73.078848 -86.034372)
		(end 72.760078 -85.715602)
		(width 0.1016)
		(layer "B.Cu")
		(net "SMB_BMC_NODE1_HSC_ALERT_L")
	)
	(segment
		(start 74.043032 -91.087194)
		(end 73.279 -90.323162)
		(width 0.1016)
		(layer "B.Cu")
		(net "SMB_BMC_NODE1_HSC_ALERT_L")
	)
	(segment
		(start 71.59625 -85.465666)
		(end 70.98919 -85.465666)
		(width 0.1016)
		(layer "B.Cu")
		(net "SMB_BMC_NODE1_HSC_ALERT_L")
	)
	(segment
		(start 70.98919 -85.465666)
		(end 70.431152 -84.907628)
		(width 0.1016)
		(layer "B.Cu")
		(net "SMB_BMC_NODE1_HSC_ALERT_L")
	)
	(segment
		(start 74.11466 -88.261698)
		(end 74.11466 -86.283546)
		(width 0.1016)
		(layer "B.Cu")
		(net "SMB_BMC_NODE1_HSC_ALERT_L")
	)
	(segment
		(start 71.846186 -85.715602)
		(end 71.59625 -85.465666)
		(width 0.1016)
		(layer "B.Cu")
		(net "SMB_BMC_NODE1_HSC_ALERT_L")
	)
	(segment
		(start 74.043032 -94.18193)
		(end 74.043032 -91.087194)
		(width 0.1016)
		(layer "B.Cu")
		(net "SMB_BMC_NODE1_HSC_ALERT_L")
	)
	(segment
		(start 75.028298 -95.167196)
		(end 74.043032 -94.18193)
		(width 0.1016)
		(layer "B.Cu")
		(net "SMB_BMC_NODE1_HSC_ALERT_L")
	)
	(segment
		(start 74.11466 -86.283546)
		(end 73.865486 -86.034372)
		(width 0.1016)
		(layer "B.Cu")
		(net "SMB_BMC_NODE1_HSC_ALERT_L")
	)
	(segment
		(start 73.279 -90.323162)
		(end 73.279 -89.097358)
		(width 0.1016)
		(layer "B.Cu")
		(net "SMB_BMC_NODE1_HSC_ALERT_L")
	)
	(segment
		(start 72.760078 -85.715602)
		(end 71.846186 -85.715602)
		(width 0.1016)
		(layer "B.Cu")
		(net "SMB_BMC_NODE1_HSC_ALERT_L")
	)
	(segment
		(start 73.865486 -86.034372)
		(end 73.078848 -86.034372)
		(width 0.1016)
		(layer "B.Cu")
		(net "SMB_BMC_NODE1_HSC_ALERT_L")
	)
	(segment
		(start 31.63951 -142.57274)
		(end 31.63951 -171.932346)
		(width 0.1143)
		(layer "In2.Cu")
		(net "SMB_BMC_NODE1_HSC_ALERT_L")
	)
	(segment
		(start 41.38676 -103.171752)
		(end 40.598852 -103.95966)
		(width 0.1143)
		(layer "In2.Cu")
		(net "SMB_BMC_NODE1_HSC_ALERT_L")
	)
	(segment
		(start 33.69056 -173.983396)
		(end 34.901378 -173.983396)
		(width 0.1143)
		(layer "In2.Cu")
		(net "SMB_BMC_NODE1_HSC_ALERT_L")
	)
	(segment
		(start 31.63951 -171.932346)
		(end 33.69056 -173.983396)
		(width 0.1143)
		(layer "In2.Cu")
		(net "SMB_BMC_NODE1_HSC_ALERT_L")
	)
	(segment
		(start 40.629078 -111.164116)
		(end 40.629078 -119.352568)
		(width 0.1143)
		(layer "In2.Cu")
		(net "SMB_BMC_NODE1_HSC_ALERT_L")
	)
	(segment
		(start 40.629078 -119.352568)
		(end 36.09086 -123.890786)
		(width 0.1143)
		(layer "In2.Cu")
		(net "SMB_BMC_NODE1_HSC_ALERT_L")
	)
	(segment
		(start 36.09086 -133.897116)
		(end 32.27451 -137.713466)
		(width 0.1143)
		(layer "In2.Cu")
		(net "SMB_BMC_NODE1_HSC_ALERT_L")
	)
	(segment
		(start 34.901378 -173.983396)
		(end 35.346132 -174.42815)
		(width 0.1143)
		(layer "In2.Cu")
		(net "SMB_BMC_NODE1_HSC_ALERT_L")
	)
	(segment
		(start 40.598852 -103.95966)
		(end 40.598852 -111.13389)
		(width 0.1143)
		(layer "In2.Cu")
		(net "SMB_BMC_NODE1_HSC_ALERT_L")
	)
	(segment
		(start 40.598852 -111.13389)
		(end 40.629078 -111.164116)
		(width 0.1143)
		(layer "In2.Cu")
		(net "SMB_BMC_NODE1_HSC_ALERT_L")
	)
	(segment
		(start 32.27451 -137.713466)
		(end 32.27451 -141.93774)
		(width 0.1143)
		(layer "In2.Cu")
		(net "SMB_BMC_NODE1_HSC_ALERT_L")
	)
	(segment
		(start 32.27451 -141.93774)
		(end 31.63951 -142.57274)
		(width 0.1143)
		(layer "In2.Cu")
		(net "SMB_BMC_NODE1_HSC_ALERT_L")
	)
	(segment
		(start 36.09086 -123.890786)
		(end 36.09086 -133.897116)
		(width 0.1143)
		(layer "In2.Cu")
		(net "SMB_BMC_NODE1_HSC_ALERT_L")
	)
	(segment
		(start 149.928072 -29.884878)
		(end 150.606252 -29.884878)
		(width 0.1016)
		(layer "F.Cu")
		(net "N21624890")
	)
	(segment
		(start 152.429972 -29.884878)
		(end 150.606252 -29.884878)
		(width 0.1016)
		(layer "F.Cu")
		(net "N21624890")
	)
	(segment
		(start 149.909022 -29.903928)
		(end 149.928072 -29.884878)
		(width 0.1016)
		(layer "F.Cu")
		(net "N21624890")
	)
	(via
		(at 150.606252 -29.884878)
		(size 0.508)
		(drill 0.254)
		(layers "F.Cu" "B.Cu")
		(net "N21624890")
	)
	(segment
		(start 139.820396 -61.46673)
		(end 139.555982 -61.46673)
		(width 0.1016)
		(layer "F.Cu")
		(net "SATA_NODE1_GPIO1")
	)
	(segment
		(start 139.911582 -61.557916)
		(end 139.820396 -61.46673)
		(width 0.1016)
		(layer "F.Cu")
		(net "SATA_NODE1_GPIO1")
	)
	(segment
		(start 140.68933 -61.557916)
		(end 139.911582 -61.557916)
		(width 0.1016)
		(layer "F.Cu")
		(net "SATA_NODE1_GPIO1")
	)
	(segment
		(start 137.993628 -61.720222)
		(end 137.993628 -62.736222)
		(width 0.1016)
		(layer "F.Cu")
		(net "SATA_NODE1_GPIO1")
	)
	(segment
		(start 139.555982 -61.46673)
		(end 138.608562 -62.41415)
		(width 0.1016)
		(layer "F.Cu")
		(net "SATA_NODE1_GPIO1")
	)
	(segment
		(start 137.993628 -62.736222)
		(end 138.28649 -62.736222)
		(width 0.1016)
		(layer "F.Cu")
		(net "SATA_NODE1_GPIO1")
	)
	(segment
		(start 138.28649 -62.736222)
		(end 138.608562 -62.41415)
		(width 0.1016)
		(layer "F.Cu")
		(net "SATA_NODE1_GPIO1")
	)
	(via
		(at 138.608562 -62.41415)
		(size 0.508)
		(drill 0.254)
		(layers "F.Cu" "B.Cu")
		(net "SATA_NODE1_GPIO1")
	)
	(segment
		(start 73.63968 -83.120738)
		(end 73.990454 -82.769964)
		(width 0.1016)
		(layer "F.Cu")
		(net "XTAL_CPU_NODE1_X2PAD")
	)
	(segment
		(start 81.56194 -84.838794)
		(end 81.155032 -84.838794)
		(width 0.1016)
		(layer "F.Cu")
		(net "XTAL_CPU_NODE1_X2PAD")
	)
	(segment
		(start 76.41844 -83.608164)
		(end 77.51064 -83.608164)
		(width 0.1016)
		(layer "F.Cu")
		(net "XTAL_CPU_NODE1_X2PAD")
	)
	(segment
		(start 83.984592 -85.940138)
		(end 83.083908 -85.039454)
		(width 0.1016)
		(layer "F.Cu")
		(net "XTAL_CPU_NODE1_X2PAD")
	)
	(segment
		(start 75.58024 -82.769964)
		(end 76.41844 -83.608164)
		(width 0.1016)
		(layer "F.Cu")
		(net "XTAL_CPU_NODE1_X2PAD")
	)
	(segment
		(start 78.74127 -84.838794)
		(end 80.632808 -84.838794)
		(width 0.1016)
		(layer "F.Cu")
		(net "XTAL_CPU_NODE1_X2PAD")
	)
	(segment
		(start 81.155032 -84.838794)
		(end 80.89392 -85.099906)
		(width 0.1016)
		(layer "F.Cu")
		(net "XTAL_CPU_NODE1_X2PAD")
	)
	(segment
		(start 83.083908 -85.039454)
		(end 82.7278 -85.039454)
		(width 0.1016)
		(layer "F.Cu")
		(net "XTAL_CPU_NODE1_X2PAD")
	)
	(segment
		(start 82.7278 -85.039454)
		(end 82.52714 -84.838794)
		(width 0.1016)
		(layer "F.Cu")
		(net "XTAL_CPU_NODE1_X2PAD")
	)
	(segment
		(start 80.632808 -84.838794)
		(end 80.89392 -85.099906)
		(width 0.1016)
		(layer "F.Cu")
		(net "XTAL_CPU_NODE1_X2PAD")
	)
	(segment
		(start 82.52714 -84.838794)
		(end 81.56194 -84.838794)
		(width 0.1016)
		(layer "F.Cu")
		(net "XTAL_CPU_NODE1_X2PAD")
	)
	(segment
		(start 77.51064 -83.608164)
		(end 78.74127 -84.838794)
		(width 0.1016)
		(layer "F.Cu")
		(net "XTAL_CPU_NODE1_X2PAD")
	)
	(segment
		(start 73.990454 -82.769964)
		(end 75.58024 -82.769964)
		(width 0.1016)
		(layer "F.Cu")
		(net "XTAL_CPU_NODE1_X2PAD")
	)
	(segment
		(start 84.45246 -85.940138)
		(end 83.984592 -85.940138)
		(width 0.1016)
		(layer "F.Cu")
		(net "XTAL_CPU_NODE1_X2PAD")
	)
	(via
		(at 80.89392 -85.099906)
		(size 0.508)
		(drill 0.254)
		(layers "F.Cu" "B.Cu")
		(net "XTAL_CPU_NODE1_X2PAD")
	)
	(segment
		(start 66.38798 -23.41118)
		(end 66.38798 -24.787606)
		(width 0.1651)
		(layer "F.Cu")
		(net "M_DDR3_NODE1_ECC2")
	)
	(segment
		(start 66.947796 -65.040256)
		(end 66.947796 -65.091056)
		(width 0.1016)
		(layer "F.Cu")
		(net "M_DDR3_NODE1_ECC2")
	)
	(segment
		(start 66.599054 -64.736218)
		(end 66.643758 -64.736218)
		(width 0.1016)
		(layer "F.Cu")
		(net "M_DDR3_NODE1_ECC2")
	)
	(segment
		(start 66.947796 -65.091056)
		(end 66.998596 -65.141856)
		(width 0.1016)
		(layer "F.Cu")
		(net "M_DDR3_NODE1_ECC2")
	)
	(segment
		(start 66.643758 -64.736218)
		(end 66.947796 -65.040256)
		(width 0.1016)
		(layer "F.Cu")
		(net "M_DDR3_NODE1_ECC2")
	)
	(segment
		(start 66.38798 -24.787606)
		(end 66.975482 -25.375108)
		(width 0.1651)
		(layer "F.Cu")
		(net "M_DDR3_NODE1_ECC2")
	)
	(segment
		(start 66.750184 -20.94992)
		(end 66.750184 -23.048976)
		(width 0.1651)
		(layer "F.Cu")
		(net "M_DDR3_NODE1_ECC2")
	)
	(segment
		(start 66.750184 -23.048976)
		(end 66.38798 -23.41118)
		(width 0.1651)
		(layer "F.Cu")
		(net "M_DDR3_NODE1_ECC2")
	)
	(via
		(at 66.975482 -25.375108)
		(size 0.508)
		(drill 0.254)
		(layers "F.Cu" "B.Cu")
		(net "M_DDR3_NODE1_ECC2")
	)
	(via
		(at 66.998596 -65.141856)
		(size 0.508)
		(drill 0.254)
		(layers "F.Cu" "B.Cu")
		(net "M_DDR3_NODE1_ECC2")
	)
	(segment
		(start 69.10324 -26.790396)
		(end 69.10324 -28.082494)
		(width 0.2032)
		(layer "In7.Cu")
		(net "M_DDR3_NODE1_ECC2")
	)
	(segment
		(start 65.75806 -51.275996)
		(end 65.75806 -59.081924)
		(width 0.2032)
		(layer "In7.Cu")
		(net "M_DDR3_NODE1_ECC2")
	)
	(segment
		(start 65.658238 -38.112954)
		(end 65.658238 -38.40734)
		(width 0.2032)
		(layer "In7.Cu")
		(net "M_DDR3_NODE1_ECC2")
	)
	(segment
		(start 66.975482 -25.375108)
		(end 67.687952 -25.375108)
		(width 0.2032)
		(layer "In7.Cu")
		(net "M_DDR3_NODE1_ECC2")
	)
	(segment
		(start 66.677286 -64.556386)
		(end 66.998596 -64.877696)
		(width 0.1016)
		(layer "In7.Cu")
		(net "M_DDR3_NODE1_ECC2")
	)
	(segment
		(start 65.867026 -37.904166)
		(end 65.658238 -38.112954)
		(width 0.2032)
		(layer "In7.Cu")
		(net "M_DDR3_NODE1_ECC2")
	)
	(segment
		(start 66.161158 -37.904166)
		(end 65.867026 -37.904166)
		(width 0.2032)
		(layer "In7.Cu")
		(net "M_DDR3_NODE1_ECC2")
	)
	(segment
		(start 65.024 -59.815984)
		(end 65.024 -60.592462)
		(width 0.2032)
		(layer "In7.Cu")
		(net "M_DDR3_NODE1_ECC2")
	)
	(segment
		(start 65.25006 -50.122582)
		(end 65.04686 -49.919382)
		(width 0.2032)
		(layer "In7.Cu")
		(net "M_DDR3_NODE1_ECC2")
	)
	(segment
		(start 64.54394 -51.067716)
		(end 65.54978 -51.067716)
		(width 0.2032)
		(layer "In7.Cu")
		(net "M_DDR3_NODE1_ECC2")
	)
	(segment
		(start 69.205602 -34.215832)
		(end 69.72046 -34.73069)
		(width 0.2032)
		(layer "In7.Cu")
		(net "M_DDR3_NODE1_ECC2")
	)
	(segment
		(start 66.60769 -38.350952)
		(end 66.161158 -37.904166)
		(width 0.2032)
		(layer "In7.Cu")
		(net "M_DDR3_NODE1_ECC2")
	)
	(segment
		(start 65.54978 -51.067716)
		(end 65.75806 -51.275996)
		(width 0.2032)
		(layer "In7.Cu")
		(net "M_DDR3_NODE1_ECC2")
	)
	(segment
		(start 65.5193 -61.695584)
		(end 66.052954 -62.229238)
		(width 0.2032)
		(layer "In7.Cu")
		(net "M_DDR3_NODE1_ECC2")
	)
	(segment
		(start 65.658238 -38.40734)
		(end 66.10477 -38.853872)
		(width 0.2032)
		(layer "In7.Cu")
		(net "M_DDR3_NODE1_ECC2")
	)
	(segment
		(start 66.052954 -62.229238)
		(end 66.052954 -63.216282)
		(width 0.2032)
		(layer "In7.Cu")
		(net "M_DDR3_NODE1_ECC2")
	)
	(segment
		(start 66.10477 -38.853872)
		(end 66.10477 -39.148512)
		(width 0.2032)
		(layer "In7.Cu")
		(net "M_DDR3_NODE1_ECC2")
	)
	(segment
		(start 64.33566 -50.859436)
		(end 64.54394 -51.067716)
		(width 0.2032)
		(layer "In7.Cu")
		(net "M_DDR3_NODE1_ECC2")
	)
	(segment
		(start 65.04686 -49.919382)
		(end 65.04686 -46.75505)
		(width 0.2032)
		(layer "In7.Cu")
		(net "M_DDR3_NODE1_ECC2")
	)
	(segment
		(start 64.33566 -46.75505)
		(end 64.33566 -50.859436)
		(width 0.2032)
		(layer "In7.Cu")
		(net "M_DDR3_NODE1_ECC2")
	)
	(segment
		(start 66.10477 -39.148512)
		(end 65.75806 -39.495222)
		(width 0.2032)
		(layer "In7.Cu")
		(net "M_DDR3_NODE1_ECC2")
	)
	(segment
		(start 66.677286 -63.840614)
		(end 66.677286 -64.556386)
		(width 0.1016)
		(layer "In7.Cu")
		(net "M_DDR3_NODE1_ECC2")
	)
	(segment
		(start 70.96252 -31.736792)
		(end 69.205602 -33.49371)
		(width 0.2032)
		(layer "In7.Cu")
		(net "M_DDR3_NODE1_ECC2")
	)
	(segment
		(start 69.72046 -34.73069)
		(end 69.72046 -35.532822)
		(width 0.2032)
		(layer "In7.Cu")
		(net "M_DDR3_NODE1_ECC2")
	)
	(segment
		(start 70.96252 -29.941774)
		(end 70.96252 -31.736792)
		(width 0.2032)
		(layer "In7.Cu")
		(net "M_DDR3_NODE1_ECC2")
	)
	(segment
		(start 65.75806 -49.919382)
		(end 65.55486 -50.122582)
		(width 0.2032)
		(layer "In7.Cu")
		(net "M_DDR3_NODE1_ECC2")
	)
	(segment
		(start 65.75806 -39.495222)
		(end 65.75806 -49.919382)
		(width 0.2032)
		(layer "In7.Cu")
		(net "M_DDR3_NODE1_ECC2")
	)
	(segment
		(start 66.90233 -38.350952)
		(end 66.60769 -38.350952)
		(width 0.2032)
		(layer "In7.Cu")
		(net "M_DDR3_NODE1_ECC2")
	)
	(segment
		(start 64.54394 -46.54677)
		(end 64.33566 -46.75505)
		(width 0.2032)
		(layer "In7.Cu")
		(net "M_DDR3_NODE1_ECC2")
	)
	(segment
		(start 65.04686 -46.75505)
		(end 64.83858 -46.54677)
		(width 0.2032)
		(layer "In7.Cu")
		(net "M_DDR3_NODE1_ECC2")
	)
	(segment
		(start 65.55486 -50.122582)
		(end 65.25006 -50.122582)
		(width 0.2032)
		(layer "In7.Cu")
		(net "M_DDR3_NODE1_ECC2")
	)
	(segment
		(start 67.687952 -25.375108)
		(end 69.10324 -26.790396)
		(width 0.2032)
		(layer "In7.Cu")
		(net "M_DDR3_NODE1_ECC2")
	)
	(segment
		(start 69.10324 -28.082494)
		(end 70.96252 -29.941774)
		(width 0.2032)
		(layer "In7.Cu")
		(net "M_DDR3_NODE1_ECC2")
	)
	(segment
		(start 65.5193 -61.087762)
		(end 65.5193 -61.695584)
		(width 0.2032)
		(layer "In7.Cu")
		(net "M_DDR3_NODE1_ECC2")
	)
	(segment
		(start 66.052954 -63.216282)
		(end 66.677286 -63.840614)
		(width 0.1016)
		(layer "In7.Cu")
		(net "M_DDR3_NODE1_ECC2")
	)
	(segment
		(start 69.205602 -33.49371)
		(end 69.205602 -34.215832)
		(width 0.2032)
		(layer "In7.Cu")
		(net "M_DDR3_NODE1_ECC2")
	)
	(segment
		(start 65.024 -60.592462)
		(end 65.5193 -61.087762)
		(width 0.2032)
		(layer "In7.Cu")
		(net "M_DDR3_NODE1_ECC2")
	)
	(segment
		(start 66.998596 -64.877696)
		(end 66.998596 -65.141856)
		(width 0.1016)
		(layer "In7.Cu")
		(net "M_DDR3_NODE1_ECC2")
	)
	(segment
		(start 64.83858 -46.54677)
		(end 64.54394 -46.54677)
		(width 0.2032)
		(layer "In7.Cu")
		(net "M_DDR3_NODE1_ECC2")
	)
	(segment
		(start 65.75806 -59.081924)
		(end 65.024 -59.815984)
		(width 0.2032)
		(layer "In7.Cu")
		(net "M_DDR3_NODE1_ECC2")
	)
	(segment
		(start 69.72046 -35.532822)
		(end 66.90233 -38.350952)
		(width 0.2032)
		(layer "In7.Cu")
		(net "M_DDR3_NODE1_ECC2")
	)
	(segment
		(start 34.139124 -177.765202)
		(end 34.139124 -176.882044)
		(width 0.1016)
		(layer "F.Cu")
		(net "VR_HSC_NODE1_GATE_R")
	)
	(segment
		(start 34.139124 -176.882044)
		(end 33.90646 -176.64938)
		(width 0.1016)
		(layer "F.Cu")
		(net "VR_HSC_NODE1_GATE_R")
	)
	(segment
		(start 34.103818 -176.027588)
		(end 34.103818 -176.452022)
		(width 0.1016)
		(layer "F.Cu")
		(net "VR_HSC_NODE1_GATE_R")
	)
	(segment
		(start 33.936178 -175.859948)
		(end 34.103818 -176.027588)
		(width 0.1016)
		(layer "F.Cu")
		(net "VR_HSC_NODE1_GATE_R")
	)
	(segment
		(start 32.920178 -175.859948)
		(end 33.936178 -175.859948)
		(width 0.1016)
		(layer "F.Cu")
		(net "VR_HSC_NODE1_GATE_R")
	)
	(segment
		(start 34.103818 -176.452022)
		(end 33.90646 -176.64938)
		(width 0.1016)
		(layer "F.Cu")
		(net "VR_HSC_NODE1_GATE_R")
	)
	(via
		(at 33.90646 -176.64938)
		(size 0.508)
		(drill 0.254)
		(layers "F.Cu" "B.Cu")
		(net "VR_HSC_NODE1_GATE_R")
	)
	(segment
		(start 11.933174 -16.660622)
		(end 11.933174 -17.56664)
		(width 0.1016)
		(layer "F.Cu")
		(net "N54251489")
	)
	(segment
		(start 11.933174 -17.56664)
		(end 11.82878 -17.671034)
		(width 0.1016)
		(layer "F.Cu")
		(net "N54251489")
	)
	(segment
		(start 12.538202 -20.20316)
		(end 12.538202 -19.477736)
		(width 0.1016)
		(layer "F.Cu")
		(net "N54251489")
	)
	(segment
		(start 11.82878 -17.671034)
		(end 11.82878 -18.768314)
		(width 0.1016)
		(layer "F.Cu")
		(net "N54251489")
	)
	(segment
		(start 12.538202 -19.477736)
		(end 11.82878 -18.768314)
		(width 0.1016)
		(layer "F.Cu")
		(net "N54251489")
	)
	(via
		(at 11.82878 -18.768314)
		(size 0.508)
		(drill 0.254)
		(layers "F.Cu" "B.Cu")
		(net "N54251489")
	)
	(segment
		(start 132.443728 -68.939156)
		(end 134.650226 -71.145654)
		(width 0.1016)
		(layer "F.Cu")
		(net "SATA_SPI_DO_NODE1")
	)
	(segment
		(start 134.650226 -73.803256)
		(end 134.650226 -71.145654)
		(width 0.1016)
		(layer "F.Cu")
		(net "SATA_SPI_DO_NODE1")
	)
	(segment
		(start 138.299698 -76.88072)
		(end 138.463274 -77.044296)
		(width 0.1016)
		(layer "F.Cu")
		(net "SATA_SPI_DO_NODE1")
	)
	(segment
		(start 138.299698 -76.649072)
		(end 138.299698 -76.88072)
		(width 0.1016)
		(layer "F.Cu")
		(net "SATA_SPI_DO_NODE1")
	)
	(segment
		(start 138.299698 -77.99832)
		(end 138.463274 -78.161896)
		(width 0.1016)
		(layer "F.Cu")
		(net "SATA_SPI_DO_NODE1")
	)
	(segment
		(start 137.740898 -76.025502)
		(end 137.537698 -75.822302)
		(width 0.1016)
		(layer "F.Cu")
		(net "SATA_SPI_DO_NODE1")
	)
	(segment
		(start 137.740898 -78.55712)
		(end 137.740898 -76.025502)
		(width 0.1016)
		(layer "F.Cu")
		(net "SATA_SPI_DO_NODE1")
	)
	(segment
		(start 141.739112 -77.43952)
		(end 141.575536 -77.603096)
		(width 0.1016)
		(layer "F.Cu")
		(net "SATA_SPI_DO_NODE1")
	)
	(segment
		(start 141.575536 -77.044296)
		(end 141.739112 -77.207872)
		(width 0.1016)
		(layer "F.Cu")
		(net "SATA_SPI_DO_NODE1")
	)
	(segment
		(start 137.904474 -78.720696)
		(end 137.740898 -78.55712)
		(width 0.1016)
		(layer "F.Cu")
		(net "SATA_SPI_DO_NODE1")
	)
	(segment
		(start 136.669272 -75.822302)
		(end 134.650226 -73.803256)
		(width 0.1016)
		(layer "F.Cu")
		(net "SATA_SPI_DO_NODE1")
	)
	(segment
		(start 141.133576 -78.161896)
		(end 141.297152 -78.325472)
		(width 0.1016)
		(layer "F.Cu")
		(net "SATA_SPI_DO_NODE1")
	)
	(segment
		(start 141.133576 -78.720696)
		(end 137.904474 -78.720696)
		(width 0.1016)
		(layer "F.Cu")
		(net "SATA_SPI_DO_NODE1")
	)
	(segment
		(start 131.14782 -68.939156)
		(end 132.443728 -68.939156)
		(width 0.1016)
		(layer "F.Cu")
		(net "SATA_SPI_DO_NODE1")
	)
	(segment
		(start 141.575536 -77.603096)
		(end 138.463274 -77.603096)
		(width 0.1016)
		(layer "F.Cu")
		(net "SATA_SPI_DO_NODE1")
	)
	(segment
		(start 141.739112 -77.207872)
		(end 141.739112 -77.43952)
		(width 0.1016)
		(layer "F.Cu")
		(net "SATA_SPI_DO_NODE1")
	)
	(segment
		(start 125.464316 -67.458336)
		(end 129.667 -67.458336)
		(width 0.1016)
		(layer "F.Cu")
		(net "SATA_SPI_DO_NODE1")
	)
	(segment
		(start 138.463274 -77.044296)
		(end 141.575536 -77.044296)
		(width 0.1016)
		(layer "F.Cu")
		(net "SATA_SPI_DO_NODE1")
	)
	(segment
		(start 138.463274 -76.485496)
		(end 138.299698 -76.649072)
		(width 0.1016)
		(layer "F.Cu")
		(net "SATA_SPI_DO_NODE1")
	)
	(segment
		(start 137.537698 -75.822302)
		(end 136.669272 -75.822302)
		(width 0.1016)
		(layer "F.Cu")
		(net "SATA_SPI_DO_NODE1")
	)
	(segment
		(start 138.463274 -78.161896)
		(end 141.133576 -78.161896)
		(width 0.1016)
		(layer "F.Cu")
		(net "SATA_SPI_DO_NODE1")
	)
	(segment
		(start 141.297152 -78.325472)
		(end 141.297152 -78.55712)
		(width 0.1016)
		(layer "F.Cu")
		(net "SATA_SPI_DO_NODE1")
	)
	(segment
		(start 138.463274 -77.603096)
		(end 138.299698 -77.766672)
		(width 0.1016)
		(layer "F.Cu")
		(net "SATA_SPI_DO_NODE1")
	)
	(segment
		(start 141.297152 -78.55712)
		(end 141.133576 -78.720696)
		(width 0.1016)
		(layer "F.Cu")
		(net "SATA_SPI_DO_NODE1")
	)
	(segment
		(start 138.299698 -77.766672)
		(end 138.299698 -77.99832)
		(width 0.1016)
		(layer "F.Cu")
		(net "SATA_SPI_DO_NODE1")
	)
	(segment
		(start 138.96213 -76.485496)
		(end 138.463274 -76.485496)
		(width 0.1016)
		(layer "F.Cu")
		(net "SATA_SPI_DO_NODE1")
	)
	(segment
		(start 129.667 -67.458336)
		(end 131.14782 -68.939156)
		(width 0.1016)
		(layer "F.Cu")
		(net "SATA_SPI_DO_NODE1")
	)
	(via
		(at 134.650226 -71.145654)
		(size 0.508)
		(drill 0.254)
		(layers "F.Cu" "B.Cu")
		(net "SATA_SPI_DO_NODE1")
	)
	(segment
		(start 66.415666 -66.217038)
		(end 66.420746 -66.217038)
		(width 0.1016)
		(layer "F.Cu")
		(net "M_DDR3_NODE1_ECC0")
	)
	(segment
		(start 66.845688 -66.64198)
		(end 66.870072 -66.64198)
		(width 0.1016)
		(layer "F.Cu")
		(net "M_DDR3_NODE1_ECC0")
	)
	(segment
		(start 60.750196 -20.94992)
		(end 60.750196 -22.693884)
		(width 0.1651)
		(layer "F.Cu")
		(net "M_DDR3_NODE1_ECC0")
	)
	(segment
		(start 66.420746 -66.217038)
		(end 66.845688 -66.64198)
		(width 0.1016)
		(layer "F.Cu")
		(net "M_DDR3_NODE1_ECC0")
	)
	(segment
		(start 60.846716 -22.790404)
		(end 60.849002 -22.790404)
		(width 0.1651)
		(layer "F.Cu")
		(net "M_DDR3_NODE1_ECC0")
	)
	(segment
		(start 60.750196 -22.693884)
		(end 60.846716 -22.790404)
		(width 0.1651)
		(layer "F.Cu")
		(net "M_DDR3_NODE1_ECC0")
	)
	(segment
		(start 60.849002 -22.790404)
		(end 60.849002 -23.387558)
		(width 0.1651)
		(layer "F.Cu")
		(net "M_DDR3_NODE1_ECC0")
	)
	(via
		(at 60.849002 -23.387558)
		(size 0.508)
		(drill 0.254)
		(layers "F.Cu" "B.Cu")
		(net "M_DDR3_NODE1_ECC0")
	)
	(via
		(at 66.870072 -66.64198)
		(size 0.508)
		(drill 0.254)
		(layers "F.Cu" "B.Cu")
		(net "M_DDR3_NODE1_ECC0")
	)
	(segment
		(start 66.935858 -63.637668)
		(end 66.935858 -64.037718)
		(width 0.1016)
		(layer "In7.Cu")
		(net "M_DDR3_NODE1_ECC0")
	)
	(segment
		(start 67.4116 -66.100452)
		(end 66.870072 -66.64198)
		(width 0.1016)
		(layer "In7.Cu")
		(net "M_DDR3_NODE1_ECC0")
	)
	(segment
		(start 70.60692 -33.522158)
		(end 70.8152 -33.730438)
		(width 0.2032)
		(layer "In7.Cu")
		(net "M_DDR3_NODE1_ECC0")
	)
	(segment
		(start 68.041012 -23.818088)
		(end 68.041012 -24.785828)
		(width 0.2032)
		(layer "In7.Cu")
		(net "M_DDR3_NODE1_ECC0")
	)
	(segment
		(start 67.265042 -22.109938)
		(end 67.265042 -23.042118)
		(width 0.2032)
		(layer "In7.Cu")
		(net "M_DDR3_NODE1_ECC0")
	)
	(segment
		(start 70.60692 -33.227518)
		(end 70.60692 -33.522158)
		(width 0.2032)
		(layer "In7.Cu")
		(net "M_DDR3_NODE1_ECC0")
	)
	(segment
		(start 67.265042 -23.042118)
		(end 68.041012 -23.818088)
		(width 0.2032)
		(layer "In7.Cu")
		(net "M_DDR3_NODE1_ECC0")
	)
	(segment
		(start 69.92874 -26.673556)
		(end 69.92874 -27.819604)
		(width 0.2032)
		(layer "In7.Cu")
		(net "M_DDR3_NODE1_ECC0")
	)
	(segment
		(start 66.6242 -60.080144)
		(end 66.6242 -60.217304)
		(width 0.2032)
		(layer "In7.Cu")
		(net "M_DDR3_NODE1_ECC0")
	)
	(segment
		(start 71.501 -33.019238)
		(end 70.8152 -33.019238)
		(width 0.2032)
		(layer "In7.Cu")
		(net "M_DDR3_NODE1_ECC0")
	)
	(segment
		(start 71.70928 -34.445194)
		(end 66.39306 -39.761414)
		(width 0.2032)
		(layer "In7.Cu")
		(net "M_DDR3_NODE1_ECC0")
	)
	(segment
		(start 69.92874 -27.819604)
		(end 71.70928 -29.600144)
		(width 0.2032)
		(layer "In7.Cu")
		(net "M_DDR3_NODE1_ECC0")
	)
	(segment
		(start 71.70928 -29.600144)
		(end 71.70928 -32.810958)
		(width 0.2032)
		(layer "In7.Cu")
		(net "M_DDR3_NODE1_ECC0")
	)
	(segment
		(start 66.62547 -60.217304)
		(end 66.62547 -63.32728)
		(width 0.2032)
		(layer "In7.Cu")
		(net "M_DDR3_NODE1_ECC0")
	)
	(segment
		(start 70.8152 -33.019238)
		(end 70.60692 -33.227518)
		(width 0.2032)
		(layer "In7.Cu")
		(net "M_DDR3_NODE1_ECC0")
	)
	(segment
		(start 71.501 -33.730438)
		(end 71.70928 -33.938718)
		(width 0.2032)
		(layer "In7.Cu")
		(net "M_DDR3_NODE1_ECC0")
	)
	(segment
		(start 61.786262 -21.424138)
		(end 66.579242 -21.424138)
		(width 0.2032)
		(layer "In7.Cu")
		(net "M_DDR3_NODE1_ECC0")
	)
	(segment
		(start 66.6242 -60.217304)
		(end 66.62547 -60.217304)
		(width 0.2032)
		(layer "In7.Cu")
		(net "M_DDR3_NODE1_ECC0")
	)
	(segment
		(start 66.39306 -39.761414)
		(end 66.39306 -59.849004)
		(width 0.2032)
		(layer "In7.Cu")
		(net "M_DDR3_NODE1_ECC0")
	)
	(segment
		(start 66.935858 -64.037718)
		(end 67.4116 -64.51346)
		(width 0.1016)
		(layer "In7.Cu")
		(net "M_DDR3_NODE1_ECC0")
	)
	(segment
		(start 66.579242 -21.424138)
		(end 67.265042 -22.109938)
		(width 0.2032)
		(layer "In7.Cu")
		(net "M_DDR3_NODE1_ECC0")
	)
	(segment
		(start 66.62547 -63.32728)
		(end 66.935858 -63.637668)
		(width 0.1016)
		(layer "In7.Cu")
		(net "M_DDR3_NODE1_ECC0")
	)
	(segment
		(start 68.041012 -24.785828)
		(end 69.92874 -26.673556)
		(width 0.2032)
		(layer "In7.Cu")
		(net "M_DDR3_NODE1_ECC0")
	)
	(segment
		(start 71.70928 -32.810958)
		(end 71.501 -33.019238)
		(width 0.2032)
		(layer "In7.Cu")
		(net "M_DDR3_NODE1_ECC0")
	)
	(segment
		(start 66.39306 -59.849004)
		(end 66.6242 -60.080144)
		(width 0.2032)
		(layer "In7.Cu")
		(net "M_DDR3_NODE1_ECC0")
	)
	(segment
		(start 67.4116 -64.51346)
		(end 67.4116 -66.100452)
		(width 0.1016)
		(layer "In7.Cu")
		(net "M_DDR3_NODE1_ECC0")
	)
	(segment
		(start 70.8152 -33.730438)
		(end 71.501 -33.730438)
		(width 0.2032)
		(layer "In7.Cu")
		(net "M_DDR3_NODE1_ECC0")
	)
	(segment
		(start 61.019182 -23.217378)
		(end 61.019182 -22.191218)
		(width 0.2032)
		(layer "In7.Cu")
		(net "M_DDR3_NODE1_ECC0")
	)
	(segment
		(start 71.70928 -33.938718)
		(end 71.70928 -34.445194)
		(width 0.2032)
		(layer "In7.Cu")
		(net "M_DDR3_NODE1_ECC0")
	)
	(segment
		(start 61.019182 -22.191218)
		(end 61.786262 -21.424138)
		(width 0.2032)
		(layer "In7.Cu")
		(net "M_DDR3_NODE1_ECC0")
	)
	(segment
		(start 60.849002 -23.387558)
		(end 61.019182 -23.217378)
		(width 0.2032)
		(layer "In7.Cu")
		(net "M_DDR3_NODE1_ECC0")
	)
	(segment
		(start 139.531852 -117.006624)
		(end 139.100052 -117.438424)
		(width 0.1016)
		(layer "F.Cu")
		(net "SEL_PCI_27M")
	)
	(segment
		(start 138.160252 -117.150642)
		(end 138.448034 -117.438424)
		(width 0.1016)
		(layer "F.Cu")
		(net "SEL_PCI_27M")
	)
	(segment
		(start 136.503664 -117.314726)
		(end 137.513568 -117.314726)
		(width 0.1016)
		(layer "F.Cu")
		(net "SEL_PCI_27M")
	)
	(segment
		(start 142.35811 -117.082824)
		(end 141.90472 -117.536214)
		(width 0.1016)
		(layer "F.Cu")
		(net "SEL_PCI_27M")
	)
	(segment
		(start 138.448034 -117.438424)
		(end 139.100052 -117.438424)
		(width 0.1016)
		(layer "F.Cu")
		(net "SEL_PCI_27M")
	)
	(segment
		(start 139.94511 -117.006624)
		(end 139.531852 -117.006624)
		(width 0.1016)
		(layer "F.Cu")
		(net "SEL_PCI_27M")
	)
	(segment
		(start 140.4747 -117.536214)
		(end 139.94511 -117.006624)
		(width 0.1016)
		(layer "F.Cu")
		(net "SEL_PCI_27M")
	)
	(segment
		(start 141.90472 -117.536214)
		(end 140.4747 -117.536214)
		(width 0.1016)
		(layer "F.Cu")
		(net "SEL_PCI_27M")
	)
	(segment
		(start 137.677652 -117.150642)
		(end 138.160252 -117.150642)
		(width 0.1016)
		(layer "F.Cu")
		(net "SEL_PCI_27M")
	)
	(segment
		(start 137.513568 -117.314726)
		(end 137.677652 -117.150642)
		(width 0.1016)
		(layer "F.Cu")
		(net "SEL_PCI_27M")
	)
	(via
		(at 139.100052 -117.438424)
		(size 0.508)
		(drill 0.254)
		(layers "F.Cu" "B.Cu")
		(net "SEL_PCI_27M")
	)
	(segment
		(start 41.908222 -180.477668)
		(end 43.060874 -180.477668)
		(width 0.508)
		(layer "F.Cu")
		(net "VR_HSC_NODE1_GATE")
	)
	(segment
		(start 33.936178 -175.059848)
		(end 33.936178 -174.421546)
		(width 0.508)
		(layer "F.Cu")
		(net "VR_HSC_NODE1_GATE")
	)
	(via
		(at 43.060874 -180.477668)
		(size 0.508)
		(drill 0.254)
		(layers "F.Cu" "B.Cu")
		(net "VR_HSC_NODE1_GATE")
	)
	(via
		(at 33.936178 -174.421546)
		(size 0.508)
		(drill 0.254)
		(layers "F.Cu" "B.Cu")
		(net "VR_HSC_NODE1_GATE")
	)
	(segment
		(start 41.740074 -177.705004)
		(end 40.12819 -176.09312)
		(width 0.508)
		(layer "In6.Cu")
		(net "VR_HSC_NODE1_GATE")
	)
	(segment
		(start 41.740074 -179.156868)
		(end 41.740074 -177.705004)
		(width 0.508)
		(layer "In6.Cu")
		(net "VR_HSC_NODE1_GATE")
	)
	(segment
		(start 40.12819 -176.09312)
		(end 35.607752 -176.09312)
		(width 0.508)
		(layer "In6.Cu")
		(net "VR_HSC_NODE1_GATE")
	)
	(segment
		(start 43.060874 -180.477668)
		(end 41.740074 -179.156868)
		(width 0.508)
		(layer "In6.Cu")
		(net "VR_HSC_NODE1_GATE")
	)
	(segment
		(start 35.607752 -176.09312)
		(end 33.936178 -174.421546)
		(width 0.508)
		(layer "In6.Cu")
		(net "VR_HSC_NODE1_GATE")
	)
	(segment
		(start 110.571026 -152.431242)
		(end 110.620302 -152.381966)
		(width 0.1016)
		(layer "F.Cu")
		(net "N52411214")
	)
	(segment
		(start 110.620302 -152.381966)
		(end 111.46028 -152.381966)
		(width 0.1016)
		(layer "F.Cu")
		(net "N52411214")
	)
	(segment
		(start 110.571026 -153.54808)
		(end 110.571026 -152.431242)
		(width 0.1016)
		(layer "F.Cu")
		(net "N52411214")
	)
	(via
		(at 110.571026 -152.431242)
		(size 0.508)
		(drill 0.254)
		(layers "F.Cu" "B.Cu")
		(net "N52411214")
	)
	(segment
		(start 15.698216 -29.000958)
		(end 16.2306 -28.468574)
		(width 0.1016)
		(layer "F.Cu")
		(net "N54251527")
	)
	(segment
		(start 15.698216 -29.250132)
		(end 15.698216 -29.000958)
		(width 0.1016)
		(layer "F.Cu")
		(net "N54251527")
	)
	(segment
		(start 16.438118 -28.261056)
		(end 16.2306 -28.468574)
		(width 0.1016)
		(layer "F.Cu")
		(net "N54251527")
	)
	(segment
		(start 16.438118 -26.04516)
		(end 16.438118 -28.261056)
		(width 0.1016)
		(layer "F.Cu")
		(net "N54251527")
	)
	(via
		(at 16.2306 -28.468574)
		(size 0.508)
		(drill 0.254)
		(layers "F.Cu" "B.Cu")
		(net "N54251527")
	)
	(segment
		(start 150.311104 -67.796156)
		(end 150.311104 -69.061838)
		(width 0.1016)
		(layer "F.Cu")
		(net "SATA_NODE1_ISET")
	)
	(segment
		(start 149.57171 -67.557904)
		(end 150.072852 -67.557904)
		(width 0.1016)
		(layer "F.Cu")
		(net "SATA_NODE1_ISET")
	)
	(segment
		(start 151.529796 -70.203822)
		(end 152.179528 -70.203822)
		(width 0.1016)
		(layer "F.Cu")
		(net "SATA_NODE1_ISET")
	)
	(segment
		(start 150.072852 -67.557904)
		(end 150.311104 -67.796156)
		(width 0.1016)
		(layer "F.Cu")
		(net "SATA_NODE1_ISET")
	)
	(segment
		(start 150.311104 -69.061838)
		(end 151.453088 -70.203822)
		(width 0.1016)
		(layer "F.Cu")
		(net "SATA_NODE1_ISET")
	)
	(segment
		(start 151.453088 -70.203822)
		(end 151.529796 -70.203822)
		(width 0.1016)
		(layer "F.Cu")
		(net "SATA_NODE1_ISET")
	)
	(via
		(at 151.529796 -70.203822)
		(size 0.508)
		(drill 0.254)
		(layers "F.Cu" "B.Cu")
		(net "SATA_NODE1_ISET")
	)
	(segment
		(start 62.020196 -85.381846)
		(end 61.637418 -84.999068)
		(width 0.1016)
		(layer "F.Cu")
		(net "LPC_CPU_NODE1_LAD2_R")
	)
	(segment
		(start 62.20333 -85.381846)
		(end 62.020196 -85.381846)
		(width 0.1016)
		(layer "F.Cu")
		(net "LPC_CPU_NODE1_LAD2_R")
	)
	(segment
		(start 61.637418 -84.999068)
		(end 61.111892 -84.999068)
		(width 0.1016)
		(layer "F.Cu")
		(net "LPC_CPU_NODE1_LAD2_R")
	)
	(via
		(at 62.58814 -88.632792)
		(size 0.6604)
		(drill 0.3302)
		(layers "F.Cu" "B.Cu")
		(net "LPC_CPU_NODE1_LAD2_R")
	)
	(via
		(at 61.111892 -84.999068)
		(size 0.508)
		(drill 0.254)
		(layers "F.Cu" "B.Cu")
		(net "LPC_CPU_NODE1_LAD2_R")
	)
	(segment
		(start 61.111892 -85.376258)
		(end 61.111892 -84.999068)
		(width 0.1016)
		(layer "B.Cu")
		(net "LPC_CPU_NODE1_LAD2_R")
	)
	(segment
		(start 61.421772 -86.02726)
		(end 61.421772 -85.686138)
		(width 0.1016)
		(layer "B.Cu")
		(net "LPC_CPU_NODE1_LAD2_R")
	)
	(segment
		(start 62.58814 -88.632792)
		(end 62.135512 -87.49411)
		(width 0.1016)
		(layer "B.Cu")
		(net "LPC_CPU_NODE1_LAD2_R")
	)
	(segment
		(start 61.421772 -85.686138)
		(end 61.111892 -85.376258)
		(width 0.1016)
		(layer "B.Cu")
		(net "LPC_CPU_NODE1_LAD2_R")
	)
	(segment
		(start 62.514988 -94.087188)
		(end 62.98311 -92.516198)
		(width 0.1016)
		(layer "B.Cu")
		(net "LPC_CPU_NODE1_LAD2_R")
	)
	(segment
		(start 61.992002 -95.7961)
		(end 62.514988 -94.087188)
		(width 0.1016)
		(layer "B.Cu")
		(net "LPC_CPU_NODE1_LAD2_R")
	)
	(segment
		(start 62.135512 -87.49411)
		(end 61.421772 -86.02726)
		(width 0.1016)
		(layer "B.Cu")
		(net "LPC_CPU_NODE1_LAD2_R")
	)
	(segment
		(start 62.98311 -90.22715)
		(end 62.58814 -88.632792)
		(width 0.1016)
		(layer "B.Cu")
		(net "LPC_CPU_NODE1_LAD2_R")
	)
	(segment
		(start 62.98311 -92.516198)
		(end 62.98311 -90.22715)
		(width 0.1016)
		(layer "B.Cu")
		(net "LPC_CPU_NODE1_LAD2_R")
	)
	(segment
		(start 76.503276 -62.99454)
		(end 77.54874 -64.040004)
		(width 0.1651)
		(layer "F.Cu")
		(net "M1_DQ_NODE1_DQ53")
	)
	(segment
		(start 76.143104 -62.99454)
		(end 76.503276 -62.99454)
		(width 0.1651)
		(layer "F.Cu")
		(net "M1_DQ_NODE1_DQ53")
	)
	(segment
		(start 90.155522 -26.464514)
		(end 91.473782 -26.464514)
		(width 0.1651)
		(layer "F.Cu")
		(net "M1_DQ_NODE1_DQ53")
	)
	(segment
		(start 92.850208 -27.84094)
		(end 92.850208 -29.149802)
		(width 0.1651)
		(layer "F.Cu")
		(net "M1_DQ_NODE1_DQ53")
	)
	(segment
		(start 73.843896 -70.191884)
		(end 73.24344 -70.191884)
		(width 0.1016)
		(layer "F.Cu")
		(net "M1_DQ_NODE1_DQ53")
	)
	(segment
		(start 75.069446 -70.504558)
		(end 74.15657 -70.504558)
		(width 0.1016)
		(layer "F.Cu")
		(net "M1_DQ_NODE1_DQ53")
	)
	(segment
		(start 77.54874 -64.040004)
		(end 77.54874 -68.025264)
		(width 0.1651)
		(layer "F.Cu")
		(net "M1_DQ_NODE1_DQ53")
	)
	(segment
		(start 77.54874 -68.025264)
		(end 75.725274 -69.84873)
		(width 0.1651)
		(layer "F.Cu")
		(net "M1_DQ_NODE1_DQ53")
	)
	(segment
		(start 91.473782 -26.464514)
		(end 92.850208 -27.84094)
		(width 0.1651)
		(layer "F.Cu")
		(net "M1_DQ_NODE1_DQ53")
	)
	(segment
		(start 74.15657 -70.504558)
		(end 73.843896 -70.191884)
		(width 0.1016)
		(layer "F.Cu")
		(net "M1_DQ_NODE1_DQ53")
	)
	(segment
		(start 75.725274 -69.84873)
		(end 75.069446 -70.504558)
		(width 0.1016)
		(layer "F.Cu")
		(net "M1_DQ_NODE1_DQ53")
	)
	(via
		(at 76.143104 -62.99454)
		(size 0.508)
		(drill 0.254)
		(layers "F.Cu" "B.Cu")
		(net "M1_DQ_NODE1_DQ53")
	)
	(via
		(at 90.155522 -26.464514)
		(size 0.508)
		(drill 0.254)
		(layers "F.Cu" "B.Cu")
		(net "M1_DQ_NODE1_DQ53")
	)
	(segment
		(start 89.883742 -31.177738)
		(end 89.883742 -33.922208)
		(width 0.2032)
		(layer "In7.Cu")
		(net "M1_DQ_NODE1_DQ53")
	)
	(segment
		(start 89.53754 -28.490672)
		(end 89.53754 -30.831536)
		(width 0.2032)
		(layer "In7.Cu")
		(net "M1_DQ_NODE1_DQ53")
	)
	(segment
		(start 87.417656 -42.6339)
		(end 87.29599 -42.512234)
		(width 0.2032)
		(layer "In7.Cu")
		(net "M1_DQ_NODE1_DQ53")
	)
	(segment
		(start 81.65338 -48.683672)
		(end 76.15682 -54.180232)
		(width 0.2032)
		(layer "In7.Cu")
		(net "M1_DQ_NODE1_DQ53")
	)
	(segment
		(start 87.920576 -42.13098)
		(end 87.920576 -42.42562)
		(width 0.2032)
		(layer "In7.Cu")
		(net "M1_DQ_NODE1_DQ53")
	)
	(segment
		(start 87.920576 -42.42562)
		(end 87.712296 -42.6339)
		(width 0.2032)
		(layer "In7.Cu")
		(net "M1_DQ_NODE1_DQ53")
	)
	(segment
		(start 87.145876 -43.655488)
		(end 86.930484 -43.87088)
		(width 0.2032)
		(layer "In7.Cu")
		(net "M1_DQ_NODE1_DQ53")
	)
	(segment
		(start 82.76971 -46.743874)
		(end 82.76971 -47.038514)
		(width 0.2032)
		(layer "In7.Cu")
		(net "M1_DQ_NODE1_DQ53")
	)
	(segment
		(start 82.873088 -47.141892)
		(end 82.873088 -47.436532)
		(width 0.2032)
		(layer "In7.Cu")
		(net "M1_DQ_NODE1_DQ53")
	)
	(segment
		(start 82.370168 -47.644812)
		(end 82.26679 -47.541434)
		(width 0.2032)
		(layer "In7.Cu")
		(net "M1_DQ_NODE1_DQ53")
	)
	(segment
		(start 86.642956 -43.87088)
		(end 86.29015 -43.518074)
		(width 0.2032)
		(layer "In7.Cu")
		(net "M1_DQ_NODE1_DQ53")
	)
	(segment
		(start 86.930484 -43.87088)
		(end 86.642956 -43.87088)
		(width 0.2032)
		(layer "In7.Cu")
		(net "M1_DQ_NODE1_DQ53")
	)
	(segment
		(start 86.099396 -44.33316)
		(end 86.099396 -44.620688)
		(width 0.2032)
		(layer "In7.Cu")
		(net "M1_DQ_NODE1_DQ53")
	)
	(segment
		(start 82.76971 -47.038514)
		(end 82.873088 -47.141892)
		(width 0.2032)
		(layer "In7.Cu")
		(net "M1_DQ_NODE1_DQ53")
	)
	(segment
		(start 83.98383 -45.529754)
		(end 83.77555 -45.738034)
		(width 0.2032)
		(layer "In7.Cu")
		(net "M1_DQ_NODE1_DQ53")
	)
	(segment
		(start 89.63406 -35.1409)
		(end 89.63406 -38.60038)
		(width 0.2032)
		(layer "In7.Cu")
		(net "M1_DQ_NODE1_DQ53")
	)
	(segment
		(start 87.145876 -43.36796)
		(end 87.145876 -43.655488)
		(width 0.2032)
		(layer "In7.Cu")
		(net "M1_DQ_NODE1_DQ53")
	)
	(segment
		(start 83.376008 -46.638972)
		(end 83.27263 -46.535594)
		(width 0.2032)
		(layer "In7.Cu")
		(net "M1_DQ_NODE1_DQ53")
	)
	(segment
		(start 85.78723 -43.726354)
		(end 85.78723 -44.020994)
		(width 0.2032)
		(layer "In7.Cu")
		(net "M1_DQ_NODE1_DQ53")
	)
	(segment
		(start 83.77555 -46.032674)
		(end 83.878928 -46.136052)
		(width 0.2032)
		(layer "In7.Cu")
		(net "M1_DQ_NODE1_DQ53")
	)
	(segment
		(start 89.63406 -38.60038)
		(end 88.91778 -39.31666)
		(width 0.2032)
		(layer "In7.Cu")
		(net "M1_DQ_NODE1_DQ53")
	)
	(segment
		(start 88.91778 -40.595804)
		(end 87.79891 -41.714674)
		(width 0.2032)
		(layer "In7.Cu")
		(net "M1_DQ_NODE1_DQ53")
	)
	(segment
		(start 84.98967 -44.523914)
		(end 84.78139 -44.732194)
		(width 0.2032)
		(layer "In7.Cu")
		(net "M1_DQ_NODE1_DQ53")
	)
	(segment
		(start 89.53754 -30.831536)
		(end 89.883742 -31.177738)
		(width 0.2032)
		(layer "In7.Cu")
		(net "M1_DQ_NODE1_DQ53")
	)
	(segment
		(start 83.77555 -45.738034)
		(end 83.77555 -46.032674)
		(width 0.2032)
		(layer "In7.Cu")
		(net "M1_DQ_NODE1_DQ53")
	)
	(segment
		(start 90.155522 -26.663396)
		(end 89.355422 -27.463496)
		(width 0.2032)
		(layer "In7.Cu")
		(net "M1_DQ_NODE1_DQ53")
	)
	(segment
		(start 84.27847 -45.529754)
		(end 83.98383 -45.529754)
		(width 0.2032)
		(layer "In7.Cu")
		(net "M1_DQ_NODE1_DQ53")
	)
	(segment
		(start 84.884768 -45.424852)
		(end 84.676488 -45.633132)
		(width 0.2032)
		(layer "In7.Cu")
		(net "M1_DQ_NODE1_DQ53")
	)
	(segment
		(start 85.78723 -44.020994)
		(end 86.099396 -44.33316)
		(width 0.2032)
		(layer "In7.Cu")
		(net "M1_DQ_NODE1_DQ53")
	)
	(segment
		(start 83.878928 -46.430692)
		(end 83.670648 -46.638972)
		(width 0.2032)
		(layer "In7.Cu")
		(net "M1_DQ_NODE1_DQ53")
	)
	(segment
		(start 89.355422 -28.308554)
		(end 89.53754 -28.490672)
		(width 0.2032)
		(layer "In7.Cu")
		(net "M1_DQ_NODE1_DQ53")
	)
	(segment
		(start 84.676488 -45.633132)
		(end 84.381848 -45.633132)
		(width 0.2032)
		(layer "In7.Cu")
		(net "M1_DQ_NODE1_DQ53")
	)
	(segment
		(start 87.712296 -42.6339)
		(end 87.417656 -42.6339)
		(width 0.2032)
		(layer "In7.Cu")
		(net "M1_DQ_NODE1_DQ53")
	)
	(segment
		(start 87.29599 -42.512234)
		(end 87.00135 -42.512234)
		(width 0.2032)
		(layer "In7.Cu")
		(net "M1_DQ_NODE1_DQ53")
	)
	(segment
		(start 83.27263 -46.535594)
		(end 82.97799 -46.535594)
		(width 0.2032)
		(layer "In7.Cu")
		(net "M1_DQ_NODE1_DQ53")
	)
	(segment
		(start 86.099396 -44.620688)
		(end 85.884004 -44.83608)
		(width 0.2032)
		(layer "In7.Cu")
		(net "M1_DQ_NODE1_DQ53")
	)
	(segment
		(start 84.78139 -45.026834)
		(end 84.884768 -45.130212)
		(width 0.2032)
		(layer "In7.Cu")
		(net "M1_DQ_NODE1_DQ53")
	)
	(segment
		(start 85.28431 -44.523914)
		(end 84.98967 -44.523914)
		(width 0.2032)
		(layer "In7.Cu")
		(net "M1_DQ_NODE1_DQ53")
	)
	(segment
		(start 82.664808 -47.644812)
		(end 82.370168 -47.644812)
		(width 0.2032)
		(layer "In7.Cu")
		(net "M1_DQ_NODE1_DQ53")
	)
	(segment
		(start 87.79891 -42.009314)
		(end 87.920576 -42.13098)
		(width 0.2032)
		(layer "In7.Cu")
		(net "M1_DQ_NODE1_DQ53")
	)
	(segment
		(start 83.878928 -46.136052)
		(end 83.878928 -46.430692)
		(width 0.2032)
		(layer "In7.Cu")
		(net "M1_DQ_NODE1_DQ53")
	)
	(segment
		(start 87.00135 -42.512234)
		(end 86.79307 -42.720514)
		(width 0.2032)
		(layer "In7.Cu")
		(net "M1_DQ_NODE1_DQ53")
	)
	(segment
		(start 89.88298 -34.89198)
		(end 89.63406 -35.1409)
		(width 0.2032)
		(layer "In7.Cu")
		(net "M1_DQ_NODE1_DQ53")
	)
	(segment
		(start 84.381848 -45.633132)
		(end 84.27847 -45.529754)
		(width 0.2032)
		(layer "In7.Cu")
		(net "M1_DQ_NODE1_DQ53")
	)
	(segment
		(start 76.15682 -58.924952)
		(end 76.05014 -59.031632)
		(width 0.1016)
		(layer "In7.Cu")
		(net "M1_DQ_NODE1_DQ53")
	)
	(segment
		(start 86.79307 -43.015154)
		(end 87.145876 -43.36796)
		(width 0.2032)
		(layer "In7.Cu")
		(net "M1_DQ_NODE1_DQ53")
	)
	(segment
		(start 85.99551 -43.518074)
		(end 85.78723 -43.726354)
		(width 0.2032)
		(layer "In7.Cu")
		(net "M1_DQ_NODE1_DQ53")
	)
	(segment
		(start 76.15682 -58.542428)
		(end 76.15682 -58.924952)
		(width 0.1016)
		(layer "In7.Cu")
		(net "M1_DQ_NODE1_DQ53")
	)
	(segment
		(start 84.78139 -44.732194)
		(end 84.78139 -45.026834)
		(width 0.2032)
		(layer "In7.Cu")
		(net "M1_DQ_NODE1_DQ53")
	)
	(segment
		(start 86.79307 -42.720514)
		(end 86.79307 -43.015154)
		(width 0.2032)
		(layer "In7.Cu")
		(net "M1_DQ_NODE1_DQ53")
	)
	(segment
		(start 85.596476 -44.83608)
		(end 85.28431 -44.523914)
		(width 0.2032)
		(layer "In7.Cu")
		(net "M1_DQ_NODE1_DQ53")
	)
	(segment
		(start 85.884004 -44.83608)
		(end 85.596476 -44.83608)
		(width 0.2032)
		(layer "In7.Cu")
		(net "M1_DQ_NODE1_DQ53")
	)
	(segment
		(start 83.670648 -46.638972)
		(end 83.376008 -46.638972)
		(width 0.2032)
		(layer "In7.Cu")
		(net "M1_DQ_NODE1_DQ53")
	)
	(segment
		(start 81.65338 -47.860204)
		(end 81.65338 -48.683672)
		(width 0.2032)
		(layer "In7.Cu")
		(net "M1_DQ_NODE1_DQ53")
	)
	(segment
		(start 84.884768 -45.130212)
		(end 84.884768 -45.424852)
		(width 0.2032)
		(layer "In7.Cu")
		(net "M1_DQ_NODE1_DQ53")
	)
	(segment
		(start 76.05014 -59.031632)
		(end 76.05014 -62.901576)
		(width 0.1016)
		(layer "In7.Cu")
		(net "M1_DQ_NODE1_DQ53")
	)
	(segment
		(start 88.91778 -39.31666)
		(end 88.91778 -40.595804)
		(width 0.2032)
		(layer "In7.Cu")
		(net "M1_DQ_NODE1_DQ53")
	)
	(segment
		(start 76.05014 -62.901576)
		(end 76.143104 -62.99454)
		(width 0.1016)
		(layer "In7.Cu")
		(net "M1_DQ_NODE1_DQ53")
	)
	(segment
		(start 87.79891 -41.714674)
		(end 87.79891 -42.009314)
		(width 0.2032)
		(layer "In7.Cu")
		(net "M1_DQ_NODE1_DQ53")
	)
	(segment
		(start 82.97799 -46.535594)
		(end 82.76971 -46.743874)
		(width 0.2032)
		(layer "In7.Cu")
		(net "M1_DQ_NODE1_DQ53")
	)
	(segment
		(start 90.155522 -26.464514)
		(end 90.155522 -26.663396)
		(width 0.2032)
		(layer "In7.Cu")
		(net "M1_DQ_NODE1_DQ53")
	)
	(segment
		(start 82.26679 -47.541434)
		(end 81.97215 -47.541434)
		(width 0.2032)
		(layer "In7.Cu")
		(net "M1_DQ_NODE1_DQ53")
	)
	(segment
		(start 81.97215 -47.541434)
		(end 81.65338 -47.860204)
		(width 0.2032)
		(layer "In7.Cu")
		(net "M1_DQ_NODE1_DQ53")
	)
	(segment
		(start 89.355422 -27.463496)
		(end 89.355422 -28.308554)
		(width 0.2032)
		(layer "In7.Cu")
		(net "M1_DQ_NODE1_DQ53")
	)
	(segment
		(start 89.883742 -33.922208)
		(end 89.88298 -33.922208)
		(width 0.2032)
		(layer "In7.Cu")
		(net "M1_DQ_NODE1_DQ53")
	)
	(segment
		(start 86.29015 -43.518074)
		(end 85.99551 -43.518074)
		(width 0.2032)
		(layer "In7.Cu")
		(net "M1_DQ_NODE1_DQ53")
	)
	(segment
		(start 76.15682 -54.180232)
		(end 76.15682 -58.542428)
		(width 0.2032)
		(layer "In7.Cu")
		(net "M1_DQ_NODE1_DQ53")
	)
	(segment
		(start 82.873088 -47.436532)
		(end 82.664808 -47.644812)
		(width 0.2032)
		(layer "In7.Cu")
		(net "M1_DQ_NODE1_DQ53")
	)
	(segment
		(start 89.88298 -33.922208)
		(end 89.88298 -34.89198)
		(width 0.2032)
		(layer "In7.Cu")
		(net "M1_DQ_NODE1_DQ53")
	)
	(segment
		(start 158.271972 -30.534864)
		(end 159.724852 -30.534864)
		(width 0.1016)
		(layer "F.Cu")
		(net "N21624894")
	)
	(segment
		(start 157.930342 -26.594816)
		(end 159.006286 -26.594816)
		(width 0.1016)
		(layer "F.Cu")
		(net "N21624894")
	)
	(segment
		(start 159.724852 -27.313382)
		(end 159.724852 -30.534864)
		(width 0.1016)
		(layer "F.Cu")
		(net "N21624894")
	)
	(segment
		(start 159.006286 -26.594816)
		(end 159.724852 -27.313382)
		(width 0.1016)
		(layer "F.Cu")
		(net "N21624894")
	)
	(via
		(at 159.724852 -30.534864)
		(size 0.508)
		(drill 0.254)
		(layers "F.Cu" "B.Cu")
		(net "N21624894")
	)
	(segment
		(start 40.34155 -60.104782)
		(end 40.34536 -60.103258)
		(width 0.127)
		(layer "F.Cu")
		(net "P2E_CPU_SATA_NODE1_RX_DP")
	)
	(segment
		(start 40.176958 -60.162948)
		(end 40.22598 -60.146438)
		(width 0.127)
		(layer "F.Cu")
		(net "P2E_CPU_SATA_NODE1_RX_DP")
	)
	(segment
		(start 46.095158 -63.158624)
		(end 46.383448 -63.158624)
		(width 0.1016)
		(layer "F.Cu")
		(net "P2E_CPU_SATA_NODE1_RX_DP")
	)
	(segment
		(start 45.775372 -60.898024)
		(end 45.775372 -62.290452)
		(width 0.127)
		(layer "F.Cu")
		(net "P2E_CPU_SATA_NODE1_RX_DP")
	)
	(segment
		(start 45.724572 -62.353952)
		(end 45.724572 -62.788038)
		(width 0.1016)
		(layer "F.Cu")
		(net "P2E_CPU_SATA_NODE1_RX_DP")
	)
	(segment
		(start 43.23207 -59.737244)
		(end 44.614592 -59.737244)
		(width 0.127)
		(layer "F.Cu")
		(net "P2E_CPU_SATA_NODE1_RX_DP")
	)
	(segment
		(start 40.34536 -60.103258)
		(end 40.347138 -60.098686)
		(width 0.127)
		(layer "F.Cu")
		(net "P2E_CPU_SATA_NODE1_RX_DP")
	)
	(segment
		(start 45.775372 -62.290452)
		(end 45.775372 -62.303152)
		(width 0.1016)
		(layer "F.Cu")
		(net "P2E_CPU_SATA_NODE1_RX_DP")
	)
	(segment
		(start 149.978618 -74.683112)
		(end 149.978618 -77.006196)
		(width 0.127)
		(layer "F.Cu")
		(net "P2E_CPU_SATA_NODE1_RX_DP")
	)
	(segment
		(start 149.978618 -77.006196)
		(end 149.506178 -77.478636)
		(width 0.127)
		(layer "F.Cu")
		(net "P2E_CPU_SATA_NODE1_RX_DP")
	)
	(segment
		(start 40.22598 -60.146438)
		(end 40.34155 -60.104782)
		(width 0.127)
		(layer "F.Cu")
		(net "P2E_CPU_SATA_NODE1_RX_DP")
	)
	(segment
		(start 37.794438 -62.283594)
		(end 38.227508 -61.735716)
		(width 0.127)
		(layer "F.Cu")
		(net "P2E_CPU_SATA_NODE1_RX_DP")
	)
	(segment
		(start 45.724572 -62.788038)
		(end 46.095158 -63.158624)
		(width 0.1016)
		(layer "F.Cu")
		(net "P2E_CPU_SATA_NODE1_RX_DP")
	)
	(segment
		(start 36.9697 -62.283594)
		(end 37.794438 -62.283594)
		(width 0.127)
		(layer "F.Cu")
		(net "P2E_CPU_SATA_NODE1_RX_DP")
	)
	(segment
		(start 45.775372 -62.303152)
		(end 45.724572 -62.353952)
		(width 0.1016)
		(layer "F.Cu")
		(net "P2E_CPU_SATA_NODE1_RX_DP")
	)
	(segment
		(start 38.227508 -61.735716)
		(end 40.176958 -60.162948)
		(width 0.127)
		(layer "F.Cu")
		(net "P2E_CPU_SATA_NODE1_RX_DP")
	)
	(segment
		(start 36.6776 -61.991494)
		(end 36.9697 -62.283594)
		(width 0.127)
		(layer "F.Cu")
		(net "P2E_CPU_SATA_NODE1_RX_DP")
	)
	(segment
		(start 149.633178 -74.337672)
		(end 149.978618 -74.683112)
		(width 0.127)
		(layer "F.Cu")
		(net "P2E_CPU_SATA_NODE1_RX_DP")
	)
	(segment
		(start 40.347138 -60.098686)
		(end 40.3479 -60.098432)
		(width 0.127)
		(layer "F.Cu")
		(net "P2E_CPU_SATA_NODE1_RX_DP")
	)
	(segment
		(start 40.3479 -60.098432)
		(end 43.23207 -59.737244)
		(width 0.127)
		(layer "F.Cu")
		(net "P2E_CPU_SATA_NODE1_RX_DP")
	)
	(segment
		(start 44.614592 -59.737244)
		(end 45.775372 -60.898024)
		(width 0.127)
		(layer "F.Cu")
		(net "P2E_CPU_SATA_NODE1_RX_DP")
	)
	(via
		(at 149.506178 -77.478636)
		(size 0.508)
		(drill 0.254)
		(layers "F.Cu" "B.Cu")
		(net "P2E_CPU_SATA_NODE1_RX_DP")
	)
	(via
		(at 36.6776 -61.991494)
		(size 0.508)
		(drill 0.254)
		(layers "F.Cu" "B.Cu")
		(net "P2E_CPU_SATA_NODE1_RX_DP")
	)
	(segment
		(start 120.764554 -58.492644)
		(end 122.303794 -61.17971)
		(width 0.127)
		(layer "B.Cu")
		(net "P2E_CPU_SATA_NODE1_RX_DP")
	)
	(segment
		(start 71.706486 -41.383712)
		(end 89.239852 -42.430954)
		(width 0.127)
		(layer "B.Cu")
		(net "P2E_CPU_SATA_NODE1_RX_DP")
	)
	(segment
		(start 134.23773 -72.911716)
		(end 135.73125 -73.851516)
		(width 0.127)
		(layer "B.Cu")
		(net "P2E_CPU_SATA_NODE1_RX_DP")
	)
	(segment
		(start 149.957028 -77.027786)
		(end 149.506178 -77.478636)
		(width 0.127)
		(layer "B.Cu")
		(net "P2E_CPU_SATA_NODE1_RX_DP")
	)
	(segment
		(start 54.434994 -37.298122)
		(end 58.44667 -37.99332)
		(width 0.127)
		(layer "B.Cu")
		(net "P2E_CPU_SATA_NODE1_RX_DP")
	)
	(segment
		(start 47.593504 -39.093648)
		(end 47.773336 -39.164006)
		(width 0.127)
		(layer "B.Cu")
		(net "P2E_CPU_SATA_NODE1_RX_DP")
	)
	(segment
		(start 47.773336 -39.164006)
		(end 48.122586 -39.010844)
		(width 0.127)
		(layer "B.Cu")
		(net "P2E_CPU_SATA_NODE1_RX_DP")
	)
	(segment
		(start 71.666608 -41.383712)
		(end 71.706486 -41.383712)
		(width 0.127)
		(layer "B.Cu")
		(net "P2E_CPU_SATA_NODE1_RX_DP")
	)
	(segment
		(start 58.44667 -37.99332)
		(end 58.462418 -37.99332)
		(width 0.127)
		(layer "B.Cu")
		(net "P2E_CPU_SATA_NODE1_RX_DP")
	)
	(segment
		(start 147.612862 -76.260198)
		(end 147.993862 -76.260198)
		(width 0.127)
		(layer "B.Cu")
		(net "P2E_CPU_SATA_NODE1_RX_DP")
	)
	(segment
		(start 148.503386 -76.131674)
		(end 148.63191 -76.260198)
		(width 0.127)
		(layer "B.Cu")
		(net "P2E_CPU_SATA_NODE1_RX_DP")
	)
	(segment
		(start 146.593814 -76.260198)
		(end 146.974814 -76.260198)
		(width 0.127)
		(layer "B.Cu")
		(net "P2E_CPU_SATA_NODE1_RX_DP")
	)
	(segment
		(start 37.544248 -55.3466)
		(end 40.129206 -47.371762)
		(width 0.127)
		(layer "B.Cu")
		(net "P2E_CPU_SATA_NODE1_RX_DP")
	)
	(segment
		(start 36.3855 -62.283594)
		(end 36.043108 -62.283594)
		(width 0.127)
		(layer "B.Cu")
		(net "P2E_CPU_SATA_NODE1_RX_DP")
	)
	(segment
		(start 36.997894 -57.444894)
		(end 36.915344 -57.284112)
		(width 0.127)
		(layer "B.Cu")
		(net "P2E_CPU_SATA_NODE1_RX_DP")
	)
	(segment
		(start 37.033454 -56.921146)
		(end 37.194236 -56.839104)
		(width 0.127)
		(layer "B.Cu")
		(net "P2E_CPU_SATA_NODE1_RX_DP")
	)
	(segment
		(start 48.19269 -38.831266)
		(end 48.54194 -38.678104)
		(width 0.127)
		(layer "B.Cu")
		(net "P2E_CPU_SATA_NODE1_RX_DP")
	)
	(segment
		(start 149.01291 -76.260198)
		(end 149.141434 -76.131674)
		(width 0.127)
		(layer "B.Cu")
		(net "P2E_CPU_SATA_NODE1_RX_DP")
	)
	(segment
		(start 36.28644 -59.221624)
		(end 36.40455 -58.858658)
		(width 0.127)
		(layer "B.Cu")
		(net "P2E_CPU_SATA_NODE1_RX_DP")
	)
	(segment
		(start 147.993862 -76.260198)
		(end 148.122386 -76.131674)
		(width 0.127)
		(layer "B.Cu")
		(net "P2E_CPU_SATA_NODE1_RX_DP")
	)
	(segment
		(start 48.54194 -38.678104)
		(end 48.721772 -38.748462)
		(width 0.127)
		(layer "B.Cu")
		(net "P2E_CPU_SATA_NODE1_RX_DP")
	)
	(segment
		(start 37.626798 -55.507382)
		(end 37.544248 -55.3466)
		(width 0.127)
		(layer "B.Cu")
		(net "P2E_CPU_SATA_NODE1_RX_DP")
	)
	(segment
		(start 37.194236 -56.839104)
		(end 37.312346 -56.476138)
		(width 0.127)
		(layer "B.Cu")
		(net "P2E_CPU_SATA_NODE1_RX_DP")
	)
	(segment
		(start 47.244254 -39.24681)
		(end 47.593504 -39.093648)
		(width 0.127)
		(layer "B.Cu")
		(net "P2E_CPU_SATA_NODE1_RX_DP")
	)
	(segment
		(start 35.936428 -60.714128)
		(end 36.054538 -60.351162)
		(width 0.127)
		(layer "B.Cu")
		(net "P2E_CPU_SATA_NODE1_RX_DP")
	)
	(segment
		(start 47.17415 -39.426388)
		(end 47.244254 -39.24681)
		(width 0.127)
		(layer "B.Cu")
		(net "P2E_CPU_SATA_NODE1_RX_DP")
	)
	(segment
		(start 35.775646 -60.79617)
		(end 35.936428 -60.714128)
		(width 0.127)
		(layer "B.Cu")
		(net "P2E_CPU_SATA_NODE1_RX_DP")
	)
	(segment
		(start 147.103338 -76.131674)
		(end 147.484338 -76.131674)
		(width 0.127)
		(layer "B.Cu")
		(net "P2E_CPU_SATA_NODE1_RX_DP")
	)
	(segment
		(start 36.40455 -58.858658)
		(end 36.565332 -58.776616)
		(width 0.127)
		(layer "B.Cu")
		(net "P2E_CPU_SATA_NODE1_RX_DP")
	)
	(segment
		(start 36.683442 -58.41365)
		(end 36.600892 -58.252868)
		(width 0.127)
		(layer "B.Cu")
		(net "P2E_CPU_SATA_NODE1_RX_DP")
	)
	(segment
		(start 36.879784 -57.80786)
		(end 36.997894 -57.444894)
		(width 0.127)
		(layer "B.Cu")
		(net "P2E_CPU_SATA_NODE1_RX_DP")
	)
	(segment
		(start 93.838776 -42.705528)
		(end 109.306106 -53.520848)
		(width 0.127)
		(layer "B.Cu")
		(net "P2E_CPU_SATA_NODE1_RX_DP")
	)
	(segment
		(start 36.36899 -59.382406)
		(end 36.28644 -59.221624)
		(width 0.127)
		(layer "B.Cu")
		(net "P2E_CPU_SATA_NODE1_RX_DP")
	)
	(segment
		(start 122.303794 -61.17971)
		(end 130.462528 -68.443094)
		(width 0.127)
		(layer "B.Cu")
		(net "P2E_CPU_SATA_NODE1_RX_DP")
	)
	(segment
		(start 140.483082 -74.80935)
		(end 143.501872 -75.080622)
		(width 0.127)
		(layer "B.Cu")
		(net "P2E_CPU_SATA_NODE1_RX_DP")
	)
	(segment
		(start 135.73125 -73.851516)
		(end 135.819642 -73.889362)
		(width 0.127)
		(layer "B.Cu")
		(net "P2E_CPU_SATA_NODE1_RX_DP")
	)
	(segment
		(start 49.141126 -38.415722)
		(end 49.490376 -38.26256)
		(width 0.127)
		(layer "B.Cu")
		(net "P2E_CPU_SATA_NODE1_RX_DP")
	)
	(segment
		(start 35.971988 -60.19038)
		(end 36.090098 -59.827414)
		(width 0.127)
		(layer "B.Cu")
		(net "P2E_CPU_SATA_NODE1_RX_DP")
	)
	(segment
		(start 51.401726 -37.424868)
		(end 53.53558 -37.298122)
		(width 0.127)
		(layer "B.Cu")
		(net "P2E_CPU_SATA_NODE1_RX_DP")
	)
	(segment
		(start 149.957028 -76.693268)
		(end 149.957028 -77.027786)
		(width 0.127)
		(layer "B.Cu")
		(net "P2E_CPU_SATA_NODE1_RX_DP")
	)
	(segment
		(start 36.719002 -57.889902)
		(end 36.879784 -57.80786)
		(width 0.127)
		(layer "B.Cu")
		(net "P2E_CPU_SATA_NODE1_RX_DP")
	)
	(segment
		(start 36.043108 -62.283594)
		(end 35.672776 -62.046104)
		(width 0.127)
		(layer "B.Cu")
		(net "P2E_CPU_SATA_NODE1_RX_DP")
	)
	(segment
		(start 149.141434 -76.131674)
		(end 149.395434 -76.131674)
		(width 0.127)
		(layer "B.Cu")
		(net "P2E_CPU_SATA_NODE1_RX_DP")
	)
	(segment
		(start 40.129206 -47.371762)
		(end 46.151546 -39.725346)
		(width 0.127)
		(layer "B.Cu")
		(net "P2E_CPU_SATA_NODE1_RX_DP")
	)
	(segment
		(start 149.395434 -76.131674)
		(end 149.957028 -76.693268)
		(width 0.127)
		(layer "B.Cu")
		(net "P2E_CPU_SATA_NODE1_RX_DP")
	)
	(segment
		(start 35.65017 -61.182504)
		(end 35.775646 -60.79617)
		(width 0.127)
		(layer "B.Cu")
		(net "P2E_CPU_SATA_NODE1_RX_DP")
	)
	(segment
		(start 147.484338 -76.131674)
		(end 147.612862 -76.260198)
		(width 0.127)
		(layer "B.Cu")
		(net "P2E_CPU_SATA_NODE1_RX_DP")
	)
	(segment
		(start 46.8249 -39.57955)
		(end 47.17415 -39.426388)
		(width 0.127)
		(layer "B.Cu")
		(net "P2E_CPU_SATA_NODE1_RX_DP")
	)
	(segment
		(start 36.915344 -57.284112)
		(end 37.033454 -56.921146)
		(width 0.127)
		(layer "B.Cu")
		(net "P2E_CPU_SATA_NODE1_RX_DP")
	)
	(segment
		(start 37.508688 -55.870348)
		(end 37.626798 -55.507382)
		(width 0.127)
		(layer "B.Cu")
		(net "P2E_CPU_SATA_NODE1_RX_DP")
	)
	(segment
		(start 36.090098 -59.827414)
		(end 36.25088 -59.745372)
		(width 0.127)
		(layer "B.Cu")
		(net "P2E_CPU_SATA_NODE1_RX_DP")
	)
	(segment
		(start 37.312346 -56.476138)
		(end 37.229796 -56.315356)
		(width 0.127)
		(layer "B.Cu")
		(net "P2E_CPU_SATA_NODE1_RX_DP")
	)
	(segment
		(start 49.670208 -38.332918)
		(end 50.019458 -38.179756)
		(width 0.127)
		(layer "B.Cu")
		(net "P2E_CPU_SATA_NODE1_RX_DP")
	)
	(segment
		(start 35.672776 -62.046104)
		(end 35.65017 -61.182504)
		(width 0.127)
		(layer "B.Cu")
		(net "P2E_CPU_SATA_NODE1_RX_DP")
	)
	(segment
		(start 49.490376 -38.26256)
		(end 49.670208 -38.332918)
		(width 0.127)
		(layer "B.Cu")
		(net "P2E_CPU_SATA_NODE1_RX_DP")
	)
	(segment
		(start 36.6776 -61.991494)
		(end 36.3855 -62.283594)
		(width 0.127)
		(layer "B.Cu")
		(net "P2E_CPU_SATA_NODE1_RX_DP")
	)
	(segment
		(start 53.53558 -37.298122)
		(end 54.434994 -37.298122)
		(width 0.127)
		(layer "B.Cu")
		(net "P2E_CPU_SATA_NODE1_RX_DP")
	)
	(segment
		(start 37.347906 -55.95239)
		(end 37.508688 -55.870348)
		(width 0.127)
		(layer "B.Cu")
		(net "P2E_CPU_SATA_NODE1_RX_DP")
	)
	(segment
		(start 145.360644 -76.005182)
		(end 145.562574 -76.005182)
		(width 0.127)
		(layer "B.Cu")
		(net "P2E_CPU_SATA_NODE1_RX_DP")
	)
	(segment
		(start 145.565622 -76.00823)
		(end 146.182842 -76.131674)
		(width 0.127)
		(layer "B.Cu")
		(net "P2E_CPU_SATA_NODE1_RX_DP")
	)
	(segment
		(start 37.229796 -56.315356)
		(end 37.347906 -55.95239)
		(width 0.127)
		(layer "B.Cu")
		(net "P2E_CPU_SATA_NODE1_RX_DP")
	)
	(segment
		(start 48.721772 -38.748462)
		(end 49.071022 -38.5953)
		(width 0.127)
		(layer "B.Cu")
		(net "P2E_CPU_SATA_NODE1_RX_DP")
	)
	(segment
		(start 110.099856 -54.075584)
		(end 116.451126 -55.439818)
		(width 0.127)
		(layer "B.Cu")
		(net "P2E_CPU_SATA_NODE1_RX_DP")
	)
	(segment
		(start 36.054538 -60.351162)
		(end 35.971988 -60.19038)
		(width 0.127)
		(layer "B.Cu")
		(net "P2E_CPU_SATA_NODE1_RX_DP")
	)
	(segment
		(start 146.182842 -76.131674)
		(end 146.46529 -76.131674)
		(width 0.127)
		(layer "B.Cu")
		(net "P2E_CPU_SATA_NODE1_RX_DP")
	)
	(segment
		(start 36.565332 -58.776616)
		(end 36.683442 -58.41365)
		(width 0.127)
		(layer "B.Cu")
		(net "P2E_CPU_SATA_NODE1_RX_DP")
	)
	(segment
		(start 49.071022 -38.5953)
		(end 49.141126 -38.415722)
		(width 0.127)
		(layer "B.Cu")
		(net "P2E_CPU_SATA_NODE1_RX_DP")
	)
	(segment
		(start 148.63191 -76.260198)
		(end 149.01291 -76.260198)
		(width 0.127)
		(layer "B.Cu")
		(net "P2E_CPU_SATA_NODE1_RX_DP")
	)
	(segment
		(start 109.306106 -53.520848)
		(end 110.099856 -54.075584)
		(width 0.127)
		(layer "B.Cu")
		(net "P2E_CPU_SATA_NODE1_RX_DP")
	)
	(segment
		(start 46.151546 -39.725346)
		(end 46.645068 -39.508938)
		(width 0.127)
		(layer "B.Cu")
		(net "P2E_CPU_SATA_NODE1_RX_DP")
	)
	(segment
		(start 132.84454 -71.623936)
		(end 134.23773 -72.911716)
		(width 0.127)
		(layer "B.Cu")
		(net "P2E_CPU_SATA_NODE1_RX_DP")
	)
	(segment
		(start 146.974814 -76.260198)
		(end 147.103338 -76.131674)
		(width 0.127)
		(layer "B.Cu")
		(net "P2E_CPU_SATA_NODE1_RX_DP")
	)
	(segment
		(start 36.600892 -58.252868)
		(end 36.719002 -57.889902)
		(width 0.127)
		(layer "B.Cu")
		(net "P2E_CPU_SATA_NODE1_RX_DP")
	)
	(segment
		(start 116.451126 -55.439818)
		(end 120.764554 -58.492644)
		(width 0.127)
		(layer "B.Cu")
		(net "P2E_CPU_SATA_NODE1_RX_DP")
	)
	(segment
		(start 50.019458 -38.179756)
		(end 50.089562 -38.000178)
		(width 0.127)
		(layer "B.Cu")
		(net "P2E_CPU_SATA_NODE1_RX_DP")
	)
	(segment
		(start 145.562574 -76.005182)
		(end 145.565622 -76.00823)
		(width 0.127)
		(layer "B.Cu")
		(net "P2E_CPU_SATA_NODE1_RX_DP")
	)
	(segment
		(start 148.122386 -76.131674)
		(end 148.503386 -76.131674)
		(width 0.127)
		(layer "B.Cu")
		(net "P2E_CPU_SATA_NODE1_RX_DP")
	)
	(segment
		(start 143.501872 -75.080622)
		(end 145.360644 -76.005182)
		(width 0.127)
		(layer "B.Cu")
		(net "P2E_CPU_SATA_NODE1_RX_DP")
	)
	(segment
		(start 89.239852 -42.430954)
		(end 93.838776 -42.705528)
		(width 0.127)
		(layer "B.Cu")
		(net "P2E_CPU_SATA_NODE1_RX_DP")
	)
	(segment
		(start 48.122586 -39.010844)
		(end 48.19269 -38.831266)
		(width 0.127)
		(layer "B.Cu")
		(net "P2E_CPU_SATA_NODE1_RX_DP")
	)
	(segment
		(start 135.819642 -73.889362)
		(end 140.483082 -74.80935)
		(width 0.127)
		(layer "B.Cu")
		(net "P2E_CPU_SATA_NODE1_RX_DP")
	)
	(segment
		(start 130.462528 -68.443094)
		(end 132.84454 -71.623936)
		(width 0.127)
		(layer "B.Cu")
		(net "P2E_CPU_SATA_NODE1_RX_DP")
	)
	(segment
		(start 46.645068 -39.508938)
		(end 46.8249 -39.57955)
		(width 0.127)
		(layer "B.Cu")
		(net "P2E_CPU_SATA_NODE1_RX_DP")
	)
	(segment
		(start 50.089562 -38.000178)
		(end 51.401726 -37.424868)
		(width 0.127)
		(layer "B.Cu")
		(net "P2E_CPU_SATA_NODE1_RX_DP")
	)
	(segment
		(start 146.46529 -76.131674)
		(end 146.593814 -76.260198)
		(width 0.127)
		(layer "B.Cu")
		(net "P2E_CPU_SATA_NODE1_RX_DP")
	)
	(segment
		(start 58.462418 -37.99332)
		(end 71.666608 -41.383712)
		(width 0.127)
		(layer "B.Cu")
		(net "P2E_CPU_SATA_NODE1_RX_DP")
	)
	(segment
		(start 36.25088 -59.745372)
		(end 36.36899 -59.382406)
		(width 0.127)
		(layer "B.Cu")
		(net "P2E_CPU_SATA_NODE1_RX_DP")
	)
	(segment
		(start 64.816736 -89.188798)
		(end 64.816736 -90.830654)
		(width 0.1016)
		(layer "F.Cu")
		(net "SPC_CPU_NODE1_RI_L")
	)
	(segment
		(start 65.114932 -88.890602)
		(end 64.816736 -89.188798)
		(width 0.1016)
		(layer "F.Cu")
		(net "SPC_CPU_NODE1_RI_L")
	)
	(segment
		(start 64.816736 -90.830654)
		(end 65.173352 -91.18727)
		(width 0.1016)
		(layer "F.Cu")
		(net "SPC_CPU_NODE1_RI_L")
	)
	(segment
		(start 65.114932 -88.44026)
		(end 65.114932 -88.890602)
		(width 0.1016)
		(layer "F.Cu")
		(net "SPC_CPU_NODE1_RI_L")
	)
	(via
		(at 65.108074 -94.235524)
		(size 0.6604)
		(drill 0.3302)
		(layers "F.Cu" "B.Cu")
		(net "SPC_CPU_NODE1_RI_L")
	)
	(via
		(at 65.173352 -91.18727)
		(size 0.508)
		(drill 0.254)
		(layers "F.Cu" "B.Cu")
		(net "SPC_CPU_NODE1_RI_L")
	)
	(segment
		(start 65.173352 -94.170246)
		(end 65.173352 -91.18727)
		(width 0.1016)
		(layer "B.Cu")
		(net "SPC_CPU_NODE1_RI_L")
	)
	(segment
		(start 65.108074 -95.34906)
		(end 65.108074 -94.235524)
		(width 0.1016)
		(layer "B.Cu")
		(net "SPC_CPU_NODE1_RI_L")
	)
	(segment
		(start 65.108074 -94.235524)
		(end 65.173352 -94.170246)
		(width 0.1016)
		(layer "B.Cu")
		(net "SPC_CPU_NODE1_RI_L")
	)
	(segment
		(start 65.706498 -95.947484)
		(end 65.108074 -95.34906)
		(width 0.1016)
		(layer "B.Cu")
		(net "SPC_CPU_NODE1_RI_L")
	)
	(segment
		(start 65.706498 -98.781108)
		(end 65.706498 -95.947484)
		(width 0.1016)
		(layer "B.Cu")
		(net "SPC_CPU_NODE1_RI_L")
	)
	(segment
		(start 88.301068 -32.706056)
		(end 88.63711 -33.042098)
		(width 0.1651)
		(layer "F.Cu")
		(net "M_DDR3_NODE1_DQS5N")
	)
	(segment
		(start 88.63711 -33.042098)
		(end 89.058242 -33.042098)
		(width 0.1651)
		(layer "F.Cu")
		(net "M_DDR3_NODE1_DQS5N")
	)
	(segment
		(start 88.650064 -29.149802)
		(end 88.650064 -30.350968)
		(width 0.1651)
		(layer "F.Cu")
		(net "M_DDR3_NODE1_DQS5N")
	)
	(segment
		(start 89.058242 -33.042098)
		(end 89.281762 -33.265618)
		(width 0.1651)
		(layer "F.Cu")
		(net "M_DDR3_NODE1_DQS5N")
	)
	(segment
		(start 72.063864 -66.386456)
		(end 72.063864 -66.388488)
		(width 0.1016)
		(layer "F.Cu")
		(net "M_DDR3_NODE1_DQS5N")
	)
	(segment
		(start 89.281762 -33.265618)
		(end 89.281762 -33.266888)
		(width 0.1651)
		(layer "F.Cu")
		(net "M_DDR3_NODE1_DQS5N")
	)
	(segment
		(start 88.301068 -31.468314)
		(end 88.301068 -32.706056)
		(width 0.1651)
		(layer "F.Cu")
		(net "M_DDR3_NODE1_DQS5N")
	)
	(segment
		(start 72.063864 -66.388488)
		(end 71.670164 -66.782188)
		(width 0.1016)
		(layer "F.Cu")
		(net "M_DDR3_NODE1_DQS5N")
	)
	(segment
		(start 88.803988 -30.965394)
		(end 88.301068 -31.468314)
		(width 0.1651)
		(layer "F.Cu")
		(net "M_DDR3_NODE1_DQS5N")
	)
	(segment
		(start 88.650064 -30.350968)
		(end 88.803988 -30.504892)
		(width 0.1651)
		(layer "F.Cu")
		(net "M_DDR3_NODE1_DQS5N")
	)
	(segment
		(start 88.803988 -30.504892)
		(end 88.803988 -30.965394)
		(width 0.1651)
		(layer "F.Cu")
		(net "M_DDR3_NODE1_DQS5N")
	)
	(via
		(at 89.281762 -33.266888)
		(size 0.508)
		(drill 0.254)
		(layers "F.Cu" "B.Cu")
		(net "M_DDR3_NODE1_DQS5N")
	)
	(via
		(at 71.670164 -66.782188)
		(size 0.508)
		(drill 0.254)
		(layers "F.Cu" "B.Cu")
		(net "M_DDR3_NODE1_DQS5N")
	)
	(segment
		(start 71.670164 -66.663062)
		(end 71.761858 -66.571368)
		(width 0.09906)
		(layer "In2.Cu")
		(net "M_DDR3_NODE1_DQS5N")
	)
	(segment
		(start 82.486246 -56.75376)
		(end 82.888582 -57.156096)
		(width 0.2032)
		(layer "In2.Cu")
		(net "M_DDR3_NODE1_DQS5N")
	)
	(segment
		(start 84.797646 -53.16093)
		(end 85.006434 -53.369464)
		(width 0.2032)
		(layer "In2.Cu")
		(net "M_DDR3_NODE1_DQS5N")
	)
	(segment
		(start 82.385154 -57.659778)
		(end 81.34223 -56.617362)
		(width 0.2032)
		(layer "In2.Cu")
		(net "M_DDR3_NODE1_DQS5N")
	)
	(segment
		(start 71.976996 -66.571368)
		(end 72.308466 -66.239898)
		(width 0.09906)
		(layer "In2.Cu")
		(net "M_DDR3_NODE1_DQS5N")
	)
	(segment
		(start 82.486246 -56.185816)
		(end 82.486246 -56.75376)
		(width 0.2032)
		(layer "In2.Cu")
		(net "M_DDR3_NODE1_DQS5N")
	)
	(segment
		(start 90.709496 -35.576256)
		(end 89.406476 -35.576256)
		(width 0.2032)
		(layer "In2.Cu")
		(net "M_DDR3_NODE1_DQS5N")
	)
	(segment
		(start 77.530452 -59.323478)
		(end 81.289906 -59.323478)
		(width 0.2032)
		(layer "In2.Cu")
		(net "M_DDR3_NODE1_DQS5N")
	)
	(segment
		(start 88.65108 -34.82086)
		(end 88.65108 -33.259776)
		(width 0.2032)
		(layer "In2.Cu")
		(net "M_DDR3_NODE1_DQS5N")
	)
	(segment
		(start 88.857836 -33.05302)
		(end 89.066116 -33.05302)
		(width 0.2032)
		(layer "In2.Cu")
		(net "M_DDR3_NODE1_DQS5N")
	)
	(segment
		(start 91.4019 -36.26866)
		(end 90.709496 -35.576256)
		(width 0.2032)
		(layer "In2.Cu")
		(net "M_DDR3_NODE1_DQS5N")
	)
	(segment
		(start 89.066116 -33.05302)
		(end 89.279984 -33.266888)
		(width 0.2032)
		(layer "In2.Cu")
		(net "M_DDR3_NODE1_DQS5N")
	)
	(segment
		(start 74.488294 -62.365636)
		(end 77.530452 -59.323478)
		(width 0.2032)
		(layer "In2.Cu")
		(net "M_DDR3_NODE1_DQS5N")
	)
	(segment
		(start 72.308466 -66.239898)
		(end 72.308466 -65.281048)
		(width 0.09906)
		(layer "In2.Cu")
		(net "M_DDR3_NODE1_DQS5N")
	)
	(segment
		(start 74.470006 -62.383924)
		(end 74.488294 -62.365636)
		(width 0.09906)
		(layer "In2.Cu")
		(net "M_DDR3_NODE1_DQS5N")
	)
	(segment
		(start 85.006434 -53.664104)
		(end 82.486246 -56.185816)
		(width 0.2032)
		(layer "In2.Cu")
		(net "M_DDR3_NODE1_DQS5N")
	)
	(segment
		(start 81.289906 -59.323478)
		(end 82.385154 -58.227722)
		(width 0.2032)
		(layer "In2.Cu")
		(net "M_DDR3_NODE1_DQS5N")
	)
	(segment
		(start 88.65108 -33.259776)
		(end 88.857836 -33.05302)
		(width 0.2032)
		(layer "In2.Cu")
		(net "M_DDR3_NODE1_DQS5N")
	)
	(segment
		(start 81.34223 -56.617362)
		(end 81.34223 -56.32323)
		(width 0.2032)
		(layer "In2.Cu")
		(net "M_DDR3_NODE1_DQS5N")
	)
	(segment
		(start 73.84542 -63.744094)
		(end 73.84542 -62.918594)
		(width 0.09906)
		(layer "In2.Cu")
		(net "M_DDR3_NODE1_DQS5N")
	)
	(segment
		(start 74.38009 -62.383924)
		(end 74.470006 -62.383924)
		(width 0.09906)
		(layer "In2.Cu")
		(net "M_DDR3_NODE1_DQS5N")
	)
	(segment
		(start 82.385154 -58.227722)
		(end 82.385154 -57.659778)
		(width 0.2032)
		(layer "In2.Cu")
		(net "M_DDR3_NODE1_DQS5N")
	)
	(segment
		(start 89.279984 -33.266888)
		(end 89.281762 -33.266888)
		(width 0.2032)
		(layer "In2.Cu")
		(net "M_DDR3_NODE1_DQS5N")
	)
	(segment
		(start 85.006434 -53.369464)
		(end 85.006434 -53.664104)
		(width 0.2032)
		(layer "In2.Cu")
		(net "M_DDR3_NODE1_DQS5N")
	)
	(segment
		(start 82.888582 -57.156096)
		(end 83.456526 -57.155588)
		(width 0.2032)
		(layer "In2.Cu")
		(net "M_DDR3_NODE1_DQS5N")
	)
	(segment
		(start 84.502752 -53.16093)
		(end 84.797646 -53.16093)
		(width 0.2032)
		(layer "In2.Cu")
		(net "M_DDR3_NODE1_DQS5N")
	)
	(segment
		(start 91.4019 -49.205896)
		(end 91.4019 -36.26866)
		(width 0.2032)
		(layer "In2.Cu")
		(net "M_DDR3_NODE1_DQS5N")
	)
	(segment
		(start 81.34223 -56.32323)
		(end 84.502752 -53.16093)
		(width 0.2032)
		(layer "In2.Cu")
		(net "M_DDR3_NODE1_DQS5N")
	)
	(segment
		(start 89.406476 -35.576256)
		(end 88.65108 -34.82086)
		(width 0.2032)
		(layer "In2.Cu")
		(net "M_DDR3_NODE1_DQS5N")
	)
	(segment
		(start 73.84542 -62.918594)
		(end 74.38009 -62.383924)
		(width 0.09906)
		(layer "In2.Cu")
		(net "M_DDR3_NODE1_DQS5N")
	)
	(segment
		(start 71.670164 -66.782188)
		(end 71.670164 -66.663062)
		(width 0.09906)
		(layer "In2.Cu")
		(net "M_DDR3_NODE1_DQS5N")
	)
	(segment
		(start 83.456526 -57.155588)
		(end 91.4019 -49.205896)
		(width 0.2032)
		(layer "In2.Cu")
		(net "M_DDR3_NODE1_DQS5N")
	)
	(segment
		(start 71.761858 -66.571368)
		(end 71.976996 -66.571368)
		(width 0.09906)
		(layer "In2.Cu")
		(net "M_DDR3_NODE1_DQS5N")
	)
	(segment
		(start 72.308466 -65.281048)
		(end 73.84542 -63.744094)
		(width 0.09906)
		(layer "In2.Cu")
		(net "M_DDR3_NODE1_DQS5N")
	)
	(segment
		(start 133.71576 -111.183674)
		(end 133.977634 -111.183674)
		(width 0.1016)
		(layer "F.Cu")
		(net "CLP_ITP_EN_NODE1")
	)
	(segment
		(start 133.977634 -111.183674)
		(end 134.2644 -110.896908)
		(width 0.1016)
		(layer "F.Cu")
		(net "CLP_ITP_EN_NODE1")
	)
	(segment
		(start 134.85876 -108.853478)
		(end 134.373112 -109.339126)
		(width 0.1016)
		(layer "F.Cu")
		(net "CLP_ITP_EN_NODE1")
	)
	(segment
		(start 133.562852 -112.908842)
		(end 133.562852 -111.336582)
		(width 0.1016)
		(layer "F.Cu")
		(net "CLP_ITP_EN_NODE1")
	)
	(segment
		(start 134.2644 -110.896908)
		(end 134.2644 -109.755178)
		(width 0.1016)
		(layer "F.Cu")
		(net "CLP_ITP_EN_NODE1")
	)
	(segment
		(start 134.2644 -109.755178)
		(end 134.373112 -109.646466)
		(width 0.1016)
		(layer "F.Cu")
		(net "CLP_ITP_EN_NODE1")
	)
	(segment
		(start 133.153658 -113.318036)
		(end 133.562852 -112.908842)
		(width 0.1016)
		(layer "F.Cu")
		(net "CLP_ITP_EN_NODE1")
	)
	(segment
		(start 133.153658 -113.96472)
		(end 133.153658 -113.318036)
		(width 0.1016)
		(layer "F.Cu")
		(net "CLP_ITP_EN_NODE1")
	)
	(segment
		(start 134.85876 -108.770674)
		(end 134.85876 -108.853478)
		(width 0.1016)
		(layer "F.Cu")
		(net "CLP_ITP_EN_NODE1")
	)
	(segment
		(start 133.562852 -111.336582)
		(end 133.71576 -111.183674)
		(width 0.1016)
		(layer "F.Cu")
		(net "CLP_ITP_EN_NODE1")
	)
	(segment
		(start 133.71576 -108.770674)
		(end 134.85876 -108.770674)
		(width 0.1016)
		(layer "F.Cu")
		(net "CLP_ITP_EN_NODE1")
	)
	(segment
		(start 134.373112 -109.646466)
		(end 134.373112 -109.339126)
		(width 0.1016)
		(layer "F.Cu")
		(net "CLP_ITP_EN_NODE1")
	)
	(via
		(at 134.373112 -109.339126)
		(size 0.508)
		(drill 0.254)
		(layers "F.Cu" "B.Cu")
		(net "CLP_ITP_EN_NODE1")
	)
	(segment
		(start 32.812736 -184.2135)
		(end 32.812736 -183.368696)
		(width 0.254)
		(layer "F.Cu")
		(net "AGND_HSC_NODE1")
	)
	(segment
		(start 33.639252 -179.002182)
		(end 33.13938 -179.502054)
		(width 0.254)
		(layer "F.Cu")
		(net "AGND_HSC_NODE1")
	)
	(segment
		(start 33.639252 -179.002182)
		(end 33.639252 -177.765202)
		(width 0.254)
		(layer "F.Cu")
		(net "AGND_HSC_NODE1")
	)
	(segment
		(start 32.812736 -183.368696)
		(end 33.13938 -183.042052)
		(width 0.254)
		(layer "F.Cu")
		(net "AGND_HSC_NODE1")
	)
	(segment
		(start 33.13938 -179.502054)
		(end 33.13938 -182.215282)
		(width 0.254)
		(layer "F.Cu")
		(net "AGND_HSC_NODE1")
	)
	(segment
		(start 33.13938 -183.042052)
		(end 33.13938 -182.215282)
		(width 0.254)
		(layer "F.Cu")
		(net "AGND_HSC_NODE1")
	)
	(via
		(at 33.639252 -179.002182)
		(size 0.508)
		(drill 0.254)
		(layers "F.Cu" "B.Cu")
		(net "AGND_HSC_NODE1")
	)
	(segment
		(start 158.271972 -29.234892)
		(end 157.203902 -29.234892)
		(width 0.1016)
		(layer "F.Cu")
		(net "N21624861")
	)
	(segment
		(start 155.878022 -27.909012)
		(end 156.95295 -28.98394)
		(width 0.1016)
		(layer "F.Cu")
		(net "N21624861")
	)
	(segment
		(start 155.878022 -26.601928)
		(end 155.878022 -27.909012)
		(width 0.1016)
		(layer "F.Cu")
		(net "N21624861")
	)
	(segment
		(start 157.203902 -29.234892)
		(end 156.95295 -28.98394)
		(width 0.1016)
		(layer "F.Cu")
		(net "N21624861")
	)
	(segment
		(start 156.95295 -28.972256)
		(end 156.95295 -28.98394)
		(width 0.1016)
		(layer "F.Cu")
		(net "N21624861")
	)
	(via
		(at 156.95295 -28.972256)
		(size 0.508)
		(drill 0.254)
		(layers "F.Cu" "B.Cu")
		(net "N21624861")
	)
	(segment
		(start 61.911992 -92.122752)
		(end 62.12713 -92.33789)
		(width 0.1016)
		(layer "F.Cu")
		(net "SPI_CPU_NODE1_MOSI_R")
	)
	(segment
		(start 62.40018 -87.52459)
		(end 61.97092 -87.95385)
		(width 0.1016)
		(layer "F.Cu")
		(net "SPI_CPU_NODE1_MOSI_R")
	)
	(segment
		(start 61.911992 -91.186)
		(end 61.911992 -92.122752)
		(width 0.1016)
		(layer "F.Cu")
		(net "SPI_CPU_NODE1_MOSI_R")
	)
	(segment
		(start 61.97092 -87.95385)
		(end 61.97092 -88.714834)
		(width 0.1016)
		(layer "F.Cu")
		(net "SPI_CPU_NODE1_MOSI_R")
	)
	(segment
		(start 64.193166 -95.897954)
		(end 62.27191 -93.976698)
		(width 0.1016)
		(layer "F.Cu")
		(net "SPI_CPU_NODE1_MOSI_R")
	)
	(segment
		(start 62.40018 -87.341964)
		(end 62.40018 -87.52459)
		(width 0.1016)
		(layer "F.Cu")
		(net "SPI_CPU_NODE1_MOSI_R")
	)
	(segment
		(start 61.97092 -88.714834)
		(end 61.89218 -88.793574)
		(width 0.1016)
		(layer "F.Cu")
		(net "SPI_CPU_NODE1_MOSI_R")
	)
	(segment
		(start 61.89218 -91.166188)
		(end 61.911992 -91.186)
		(width 0.1016)
		(layer "F.Cu")
		(net "SPI_CPU_NODE1_MOSI_R")
	)
	(segment
		(start 61.89218 -88.793574)
		(end 61.89218 -91.166188)
		(width 0.1016)
		(layer "F.Cu")
		(net "SPI_CPU_NODE1_MOSI_R")
	)
	(segment
		(start 64.193166 -96.309942)
		(end 64.193166 -95.897954)
		(width 0.1016)
		(layer "F.Cu")
		(net "SPI_CPU_NODE1_MOSI_R")
	)
	(segment
		(start 62.27191 -93.976698)
		(end 62.27191 -92.48267)
		(width 0.1016)
		(layer "F.Cu")
		(net "SPI_CPU_NODE1_MOSI_R")
	)
	(segment
		(start 62.27191 -92.48267)
		(end 62.12713 -92.33789)
		(width 0.1016)
		(layer "F.Cu")
		(net "SPI_CPU_NODE1_MOSI_R")
	)
	(via
		(at 62.12713 -92.33789)
		(size 0.508)
		(drill 0.254)
		(layers "F.Cu" "B.Cu")
		(net "SPI_CPU_NODE1_MOSI_R")
	)
	(segment
		(start 75.76058 -45.658532)
		(end 75.976226 -45.442886)
		(width 0.2286)
		(layer "F.Cu")
		(net "M_DDR3_NODE1_MA2")
	)
	(segment
		(start 61.1632 -60.128404)
		(end 62.0268 -59.264804)
		(width 0.1016)
		(layer "F.Cu")
		(net "M_DDR3_NODE1_MA2")
	)
	(segment
		(start 73.364598 -48.1457)
		(end 73.669398 -48.1457)
		(width 0.2286)
		(layer "F.Cu")
		(net "M_DDR3_NODE1_MA2")
	)
	(segment
		(start 74.503026 -45.874178)
		(end 74.718672 -45.658532)
		(width 0.2286)
		(layer "F.Cu")
		(net "M_DDR3_NODE1_MA2")
	)
	(segment
		(start 74.190352 -47.624746)
		(end 74.190352 -47.319946)
		(width 0.2286)
		(layer "F.Cu")
		(net "M_DDR3_NODE1_MA2")
	)
	(segment
		(start 73.885552 -48.666654)
		(end 72.032368 -50.519838)
		(width 0.2286)
		(layer "F.Cu")
		(net "M_DDR3_NODE1_MA2")
	)
	(segment
		(start 61.1632 -61.478414)
		(end 61.1632 -60.128404)
		(width 0.1016)
		(layer "F.Cu")
		(net "M_DDR3_NODE1_MA2")
	)
	(segment
		(start 74.250296 -29.149802)
		(end 74.250296 -30.849824)
		(width 0.2286)
		(layer "F.Cu")
		(net "M_DDR3_NODE1_MA2")
	)
	(segment
		(start 61.058552 -62.440312)
		(end 61.058552 -61.583062)
		(width 0.1016)
		(layer "F.Cu")
		(net "M_DDR3_NODE1_MA2")
	)
	(segment
		(start 68.136516 -53.373782)
		(end 73.364598 -48.1457)
		(width 0.2286)
		(layer "F.Cu")
		(net "M_DDR3_NODE1_MA2")
	)
	(segment
		(start 74.190352 -47.319946)
		(end 74.503026 -47.007272)
		(width 0.2286)
		(layer "F.Cu")
		(net "M_DDR3_NODE1_MA2")
	)
	(segment
		(start 75.757278 -39.909242)
		(end 75.757278 -36.423854)
		(width 0.2286)
		(layer "F.Cu")
		(net "M_DDR3_NODE1_MA2")
	)
	(segment
		(start 72.032368 -50.519838)
		(end 72.032368 -50.824638)
		(width 0.2286)
		(layer "F.Cu")
		(net "M_DDR3_NODE1_MA2")
	)
	(segment
		(start 62.0268 -59.217814)
		(end 62.0268 -55.71617)
		(width 0.2286)
		(layer "F.Cu")
		(net "M_DDR3_NODE1_MA2")
	)
	(segment
		(start 75.239626 -41.518332)
		(end 75.239626 -44.706286)
		(width 0.2286)
		(layer "F.Cu")
		(net "M_DDR3_NODE1_MA2")
	)
	(segment
		(start 74.92746 -48.666654)
		(end 74.92746 -48.361854)
		(width 0.2286)
		(layer "F.Cu")
		(net "M_DDR3_NODE1_MA2")
	)
	(segment
		(start 62.0268 -59.264804)
		(end 62.0268 -59.217814)
		(width 0.1016)
		(layer "F.Cu")
		(net "M_DDR3_NODE1_MA2")
	)
	(segment
		(start 74.250296 -30.849824)
		(end 74.064622 -31.035498)
		(width 0.2286)
		(layer "F.Cu")
		(net "M_DDR3_NODE1_MA2")
	)
	(segment
		(start 74.718672 -45.658532)
		(end 75.76058 -45.658532)
		(width 0.2286)
		(layer "F.Cu")
		(net "M_DDR3_NODE1_MA2")
	)
	(segment
		(start 61.16828 -62.55004)
		(end 61.058552 -62.440312)
		(width 0.1016)
		(layer "F.Cu")
		(net "M_DDR3_NODE1_MA2")
	)
	(segment
		(start 75.976226 -41.518332)
		(end 75.76058 -41.302686)
		(width 0.2286)
		(layer "F.Cu")
		(net "M_DDR3_NODE1_MA2")
	)
	(segment
		(start 74.503026 -44.706286)
		(end 74.503026 -41.163494)
		(width 0.2286)
		(layer "F.Cu")
		(net "M_DDR3_NODE1_MA2")
	)
	(segment
		(start 62.0268 -55.71617)
		(end 64.369188 -53.373782)
		(width 0.2286)
		(layer "F.Cu")
		(net "M_DDR3_NODE1_MA2")
	)
	(segment
		(start 74.503026 -47.007272)
		(end 74.503026 -45.874178)
		(width 0.2286)
		(layer "F.Cu")
		(net "M_DDR3_NODE1_MA2")
	)
	(segment
		(start 72.032368 -50.824638)
		(end 72.248522 -51.040792)
		(width 0.2286)
		(layer "F.Cu")
		(net "M_DDR3_NODE1_MA2")
	)
	(segment
		(start 73.669398 -48.1457)
		(end 73.885552 -48.361854)
		(width 0.2286)
		(layer "F.Cu")
		(net "M_DDR3_NODE1_MA2")
	)
	(segment
		(start 74.503026 -41.163494)
		(end 75.757278 -39.909242)
		(width 0.2286)
		(layer "F.Cu")
		(net "M_DDR3_NODE1_MA2")
	)
	(segment
		(start 75.02398 -44.921932)
		(end 74.718672 -44.921932)
		(width 0.2286)
		(layer "F.Cu")
		(net "M_DDR3_NODE1_MA2")
	)
	(segment
		(start 75.455272 -41.302686)
		(end 75.239626 -41.518332)
		(width 0.2286)
		(layer "F.Cu")
		(net "M_DDR3_NODE1_MA2")
	)
	(segment
		(start 64.369188 -53.373782)
		(end 68.136516 -53.373782)
		(width 0.2286)
		(layer "F.Cu")
		(net "M_DDR3_NODE1_MA2")
	)
	(segment
		(start 75.239626 -44.706286)
		(end 75.02398 -44.921932)
		(width 0.2286)
		(layer "F.Cu")
		(net "M_DDR3_NODE1_MA2")
	)
	(segment
		(start 75.757278 -36.423854)
		(end 75.027282 -35.693858)
		(width 0.2286)
		(layer "F.Cu")
		(net "M_DDR3_NODE1_MA2")
	)
	(segment
		(start 74.064622 -31.035498)
		(end 74.064622 -34.731198)
		(width 0.2286)
		(layer "F.Cu")
		(net "M_DDR3_NODE1_MA2")
	)
	(segment
		(start 61.058552 -61.583062)
		(end 61.1632 -61.478414)
		(width 0.1016)
		(layer "F.Cu")
		(net "M_DDR3_NODE1_MA2")
	)
	(segment
		(start 74.718672 -44.921932)
		(end 74.503026 -44.706286)
		(width 0.2286)
		(layer "F.Cu")
		(net "M_DDR3_NODE1_MA2")
	)
	(segment
		(start 74.92746 -48.361854)
		(end 74.190352 -47.624746)
		(width 0.2286)
		(layer "F.Cu")
		(net "M_DDR3_NODE1_MA2")
	)
	(segment
		(start 72.553322 -51.040792)
		(end 74.92746 -48.666654)
		(width 0.2286)
		(layer "F.Cu")
		(net "M_DDR3_NODE1_MA2")
	)
	(segment
		(start 74.064622 -34.731198)
		(end 75.027282 -35.693858)
		(width 0.2286)
		(layer "F.Cu")
		(net "M_DDR3_NODE1_MA2")
	)
	(segment
		(start 75.76058 -41.302686)
		(end 75.455272 -41.302686)
		(width 0.2286)
		(layer "F.Cu")
		(net "M_DDR3_NODE1_MA2")
	)
	(segment
		(start 72.248522 -51.040792)
		(end 72.553322 -51.040792)
		(width 0.2286)
		(layer "F.Cu")
		(net "M_DDR3_NODE1_MA2")
	)
	(segment
		(start 73.885552 -48.361854)
		(end 73.885552 -48.666654)
		(width 0.2286)
		(layer "F.Cu")
		(net "M_DDR3_NODE1_MA2")
	)
	(segment
		(start 75.976226 -45.442886)
		(end 75.976226 -41.518332)
		(width 0.2286)
		(layer "F.Cu")
		(net "M_DDR3_NODE1_MA2")
	)
	(via
		(at 75.027282 -35.693858)
		(size 0.762)
		(drill 0.381)
		(layers "F.Cu" "B.Cu")
		(net "M_DDR3_NODE1_MA2")
	)
	(segment
		(start 126.590298 -119.314722)
		(end 126.522226 -119.382794)
		(width 0.1016)
		(layer "F.Cu")
		(net "CPU_STP_NODE1")
	)
	(segment
		(start 129.403856 -119.314722)
		(end 126.590298 -119.314722)
		(width 0.1016)
		(layer "F.Cu")
		(net "CPU_STP_NODE1")
	)
	(via
		(at 126.522226 -119.382794)
		(size 0.508)
		(drill 0.254)
		(layers "F.Cu" "B.Cu")
		(net "CPU_STP_NODE1")
	)
	(segment
		(start 126.635002 -116.971064)
		(end 126.635002 -119.270018)
		(width 0.1016)
		(layer "B.Cu")
		(net "CPU_STP_NODE1")
	)
	(segment
		(start 126.635002 -119.270018)
		(end 126.522226 -119.382794)
		(width 0.1016)
		(layer "B.Cu")
		(net "CPU_STP_NODE1")
	)
	(segment
		(start 155.077922 -28.378912)
		(end 155.077922 -27.350212)
		(width 0.1016)
		(layer "F.Cu")
		(net "N21624866")
	)
	(segment
		(start 156.583888 -29.884878)
		(end 155.077922 -28.378912)
		(width 0.1016)
		(layer "F.Cu")
		(net "N21624866")
	)
	(segment
		(start 155.077922 -26.601928)
		(end 155.077922 -27.350212)
		(width 0.1016)
		(layer "F.Cu")
		(net "N21624866")
	)
	(segment
		(start 158.271972 -29.884878)
		(end 156.583888 -29.884878)
		(width 0.1016)
		(layer "F.Cu")
		(net "N21624866")
	)
	(via
		(at 155.077922 -27.350212)
		(size 0.508)
		(drill 0.254)
		(layers "F.Cu" "B.Cu")
		(net "N21624866")
	)
	(segment
		(start 56.71439 -88.04656)
		(end 56.71439 -88.317324)
		(width 0.1016)
		(layer "F.Cu")
		(net "PU_CPU_NODE1_DFX_GPIO_GRP1_6")
	)
	(segment
		(start 56.198516 -90.691208)
		(end 56.44515 -90.937842)
		(width 0.1016)
		(layer "F.Cu")
		(net "PU_CPU_NODE1_DFX_GPIO_GRP1_6")
	)
	(segment
		(start 58.097166 -95.754444)
		(end 56.672226 -94.329504)
		(width 0.1016)
		(layer "F.Cu")
		(net "PU_CPU_NODE1_DFX_GPIO_GRP1_6")
	)
	(segment
		(start 56.672226 -94.329504)
		(end 56.672226 -92.69095)
		(width 0.1016)
		(layer "F.Cu")
		(net "PU_CPU_NODE1_DFX_GPIO_GRP1_6")
	)
	(segment
		(start 56.153812 -88.877902)
		(end 56.153812 -89.776808)
		(width 0.1016)
		(layer "F.Cu")
		(net "PU_CPU_NODE1_DFX_GPIO_GRP1_6")
	)
	(segment
		(start 56.198516 -89.821512)
		(end 56.198516 -90.691208)
		(width 0.1016)
		(layer "F.Cu")
		(net "PU_CPU_NODE1_DFX_GPIO_GRP1_6")
	)
	(segment
		(start 56.71439 -88.317324)
		(end 56.153812 -88.877902)
		(width 0.1016)
		(layer "F.Cu")
		(net "PU_CPU_NODE1_DFX_GPIO_GRP1_6")
	)
	(segment
		(start 56.44515 -90.937842)
		(end 56.44515 -92.463874)
		(width 0.1016)
		(layer "F.Cu")
		(net "PU_CPU_NODE1_DFX_GPIO_GRP1_6")
	)
	(segment
		(start 58.097166 -96.309942)
		(end 58.097166 -95.754444)
		(width 0.1016)
		(layer "F.Cu")
		(net "PU_CPU_NODE1_DFX_GPIO_GRP1_6")
	)
	(segment
		(start 56.153812 -89.776808)
		(end 56.198516 -89.821512)
		(width 0.1016)
		(layer "F.Cu")
		(net "PU_CPU_NODE1_DFX_GPIO_GRP1_6")
	)
	(segment
		(start 56.672226 -92.69095)
		(end 56.44515 -92.463874)
		(width 0.1016)
		(layer "F.Cu")
		(net "PU_CPU_NODE1_DFX_GPIO_GRP1_6")
	)
	(via
		(at 56.44515 -92.463874)
		(size 0.508)
		(drill 0.254)
		(layers "F.Cu" "B.Cu")
		(net "PU_CPU_NODE1_DFX_GPIO_GRP1_6")
	)
	(segment
		(start 56.249062 -27.087576)
		(end 56.249062 -29.149802)
		(width 0.1651)
		(layer "F.Cu")
		(net "M1_DQ_NODE1_DQ28")
	)
	(segment
		(start 56.129682 -26.968196)
		(end 56.249062 -27.087576)
		(width 0.1651)
		(layer "F.Cu")
		(net "M1_DQ_NODE1_DQ28")
	)
	(segment
		(start 56.249062 -29.149802)
		(end 56.250078 -29.149802)
		(width 0.1651)
		(layer "F.Cu")
		(net "M1_DQ_NODE1_DQ28")
	)
	(segment
		(start 52.162456 -62.55004)
		(end 52.162456 -61.899546)
		(width 0.1016)
		(layer "F.Cu")
		(net "M1_DQ_NODE1_DQ28")
	)
	(segment
		(start 52.162456 -61.899546)
		(end 52.213764 -61.848238)
		(width 0.1016)
		(layer "F.Cu")
		(net "M1_DQ_NODE1_DQ28")
	)
	(via
		(at 52.213764 -61.848238)
		(size 0.508)
		(drill 0.254)
		(layers "F.Cu" "B.Cu")
		(net "M1_DQ_NODE1_DQ28")
	)
	(via
		(at 56.129682 -26.968196)
		(size 0.508)
		(drill 0.254)
		(layers "F.Cu" "B.Cu")
		(net "M1_DQ_NODE1_DQ28")
	)
	(segment
		(start 56.129682 -26.968196)
		(end 54.967886 -26.968196)
		(width 0.2032)
		(layer "In2.Cu")
		(net "M1_DQ_NODE1_DQ28")
	)
	(segment
		(start 42.34434 -47.071788)
		(end 42.0497 -47.071788)
		(width 0.2032)
		(layer "In2.Cu")
		(net "M1_DQ_NODE1_DQ28")
	)
	(segment
		(start 53.823362 -29.023818)
		(end 53.823362 -29.318458)
		(width 0.2032)
		(layer "In2.Cu")
		(net "M1_DQ_NODE1_DQ28")
	)
	(segment
		(start 41.63314 -42.595038)
		(end 41.3385 -42.595038)
		(width 0.2032)
		(layer "In2.Cu")
		(net "M1_DQ_NODE1_DQ28")
	)
	(segment
		(start 42.55262 -42.715942)
		(end 42.55262 -46.863508)
		(width 0.2032)
		(layer "In2.Cu")
		(net "M1_DQ_NODE1_DQ28")
	)
	(segment
		(start 54.323742 -29.526738)
		(end 54.532022 -29.735018)
		(width 0.2032)
		(layer "In2.Cu")
		(net "M1_DQ_NODE1_DQ28")
	)
	(segment
		(start 53.823362 -29.318458)
		(end 54.031642 -29.526738)
		(width 0.2032)
		(layer "In2.Cu")
		(net "M1_DQ_NODE1_DQ28")
	)
	(segment
		(start 54.532022 -32.749744)
		(end 46.76013 -40.521636)
		(width 0.2032)
		(layer "In2.Cu")
		(net "M1_DQ_NODE1_DQ28")
	)
	(segment
		(start 41.13022 -42.803318)
		(end 41.13022 -47.35195)
		(width 0.2032)
		(layer "In2.Cu")
		(net "M1_DQ_NODE1_DQ28")
	)
	(segment
		(start 50.00244 -56.22417)
		(end 50.00244 -57.053988)
		(width 0.2032)
		(layer "In2.Cu")
		(net "M1_DQ_NODE1_DQ28")
	)
	(segment
		(start 54.532022 -27.40406)
		(end 54.532022 -28.607258)
		(width 0.2032)
		(layer "In2.Cu")
		(net "M1_DQ_NODE1_DQ28")
	)
	(segment
		(start 54.323742 -28.815538)
		(end 54.031642 -28.815538)
		(width 0.2032)
		(layer "In2.Cu")
		(net "M1_DQ_NODE1_DQ28")
	)
	(segment
		(start 50.00244 -57.053988)
		(end 50.00244 -57.653428)
		(width 0.1016)
		(layer "In2.Cu")
		(net "M1_DQ_NODE1_DQ28")
	)
	(segment
		(start 41.84142 -42.803318)
		(end 41.63314 -42.595038)
		(width 0.2032)
		(layer "In2.Cu")
		(net "M1_DQ_NODE1_DQ28")
	)
	(segment
		(start 44.746926 -40.521636)
		(end 42.55262 -42.715942)
		(width 0.2032)
		(layer "In2.Cu")
		(net "M1_DQ_NODE1_DQ28")
	)
	(segment
		(start 42.55262 -46.863508)
		(end 42.34434 -47.071788)
		(width 0.2032)
		(layer "In2.Cu")
		(net "M1_DQ_NODE1_DQ28")
	)
	(segment
		(start 54.967886 -26.968196)
		(end 54.532022 -27.40406)
		(width 0.2032)
		(layer "In2.Cu")
		(net "M1_DQ_NODE1_DQ28")
	)
	(segment
		(start 41.3385 -42.595038)
		(end 41.13022 -42.803318)
		(width 0.2032)
		(layer "In2.Cu")
		(net "M1_DQ_NODE1_DQ28")
	)
	(segment
		(start 51.647852 -60.226956)
		(end 51.647852 -61.282326)
		(width 0.1016)
		(layer "In2.Cu")
		(net "M1_DQ_NODE1_DQ28")
	)
	(segment
		(start 54.031642 -29.526738)
		(end 54.323742 -29.526738)
		(width 0.2032)
		(layer "In2.Cu")
		(net "M1_DQ_NODE1_DQ28")
	)
	(segment
		(start 54.532022 -29.735018)
		(end 54.532022 -32.749744)
		(width 0.2032)
		(layer "In2.Cu")
		(net "M1_DQ_NODE1_DQ28")
	)
	(segment
		(start 41.84142 -46.863508)
		(end 41.84142 -42.803318)
		(width 0.2032)
		(layer "In2.Cu")
		(net "M1_DQ_NODE1_DQ28")
	)
	(segment
		(start 46.76013 -40.521636)
		(end 44.746926 -40.521636)
		(width 0.2032)
		(layer "In2.Cu")
		(net "M1_DQ_NODE1_DQ28")
	)
	(segment
		(start 51.34356 -59.922664)
		(end 51.647852 -60.226956)
		(width 0.1016)
		(layer "In2.Cu")
		(net "M1_DQ_NODE1_DQ28")
	)
	(segment
		(start 54.532022 -28.607258)
		(end 54.323742 -28.815538)
		(width 0.2032)
		(layer "In2.Cu")
		(net "M1_DQ_NODE1_DQ28")
	)
	(segment
		(start 51.34356 -58.994548)
		(end 51.34356 -59.922664)
		(width 0.1016)
		(layer "In2.Cu")
		(net "M1_DQ_NODE1_DQ28")
	)
	(segment
		(start 54.031642 -28.815538)
		(end 53.823362 -29.023818)
		(width 0.2032)
		(layer "In2.Cu")
		(net "M1_DQ_NODE1_DQ28")
	)
	(segment
		(start 51.647852 -61.282326)
		(end 52.213764 -61.848238)
		(width 0.1016)
		(layer "In2.Cu")
		(net "M1_DQ_NODE1_DQ28")
	)
	(segment
		(start 42.0497 -47.071788)
		(end 41.84142 -46.863508)
		(width 0.2032)
		(layer "In2.Cu")
		(net "M1_DQ_NODE1_DQ28")
	)
	(segment
		(start 50.00244 -57.653428)
		(end 51.34356 -58.994548)
		(width 0.1016)
		(layer "In2.Cu")
		(net "M1_DQ_NODE1_DQ28")
	)
	(segment
		(start 41.13022 -47.35195)
		(end 50.00244 -56.22417)
		(width 0.2032)
		(layer "In2.Cu")
		(net "M1_DQ_NODE1_DQ28")
	)
	(segment
		(start 136.12876 -108.770674)
		(end 135.546084 -109.35335)
		(width 0.1016)
		(layer "F.Cu")
		(net "CLK_FSLB_NODE1")
	)
	(segment
		(start 135.546084 -109.35335)
		(end 135.546084 -110.6297)
		(width 0.1016)
		(layer "F.Cu")
		(net "CLK_FSLB_NODE1")
	)
	(segment
		(start 133.842252 -112.28324)
		(end 134.310628 -111.814864)
		(width 0.1016)
		(layer "F.Cu")
		(net "CLK_FSLB_NODE1")
	)
	(segment
		(start 134.98576 -111.440976)
		(end 134.611872 -111.814864)
		(width 0.1016)
		(layer "F.Cu")
		(net "CLK_FSLB_NODE1")
	)
	(segment
		(start 133.553708 -113.298986)
		(end 133.842252 -113.010442)
		(width 0.1016)
		(layer "F.Cu")
		(net "CLK_FSLB_NODE1")
	)
	(segment
		(start 133.553708 -113.96472)
		(end 133.553708 -113.298986)
		(width 0.1016)
		(layer "F.Cu")
		(net "CLK_FSLB_NODE1")
	)
	(segment
		(start 133.842252 -113.010442)
		(end 133.842252 -112.28324)
		(width 0.1016)
		(layer "F.Cu")
		(net "CLK_FSLB_NODE1")
	)
	(segment
		(start 134.98576 -111.183674)
		(end 134.98576 -111.440976)
		(width 0.1016)
		(layer "F.Cu")
		(net "CLK_FSLB_NODE1")
	)
	(segment
		(start 134.310628 -111.814864)
		(end 134.611872 -111.814864)
		(width 0.1016)
		(layer "F.Cu")
		(net "CLK_FSLB_NODE1")
	)
	(segment
		(start 134.99211 -111.183674)
		(end 134.98576 -111.183674)
		(width 0.1016)
		(layer "F.Cu")
		(net "CLK_FSLB_NODE1")
	)
	(segment
		(start 135.546084 -110.6297)
		(end 134.99211 -111.183674)
		(width 0.1016)
		(layer "F.Cu")
		(net "CLK_FSLB_NODE1")
	)
	(via
		(at 134.611872 -111.814864)
		(size 0.508)
		(drill 0.254)
		(layers "F.Cu" "B.Cu")
		(net "CLK_FSLB_NODE1")
	)
	(segment
		(start 146.33067 -68.799202)
		(end 146.33067 -69.492622)
		(width 0.127)
		(layer "F.Cu")
		(net "CLK_100M_SATA_NODE1_DP")
	)
	(segment
		(start 135.391652 -124.034042)
		(end 135.629142 -124.034042)
		(width 0.127)
		(layer "F.Cu")
		(net "CLK_100M_SATA_NODE1_DP")
	)
	(segment
		(start 145.393918 -76.734162)
		(end 145.393918 -79.480664)
		(width 0.127)
		(layer "F.Cu")
		(net "CLK_100M_SATA_NODE1_DP")
	)
	(segment
		(start 149.65172 -81.928716)
		(end 149.827488 -82.104484)
		(width 0.127)
		(layer "F.Cu")
		(net "CLK_100M_SATA_NODE1_DP")
	)
	(segment
		(start 146.283172 -69.638418)
		(end 146.283172 -70.931786)
		(width 0.127)
		(layer "F.Cu")
		(net "CLK_100M_SATA_NODE1_DP")
	)
	(segment
		(start 146.491452 -80.578198)
		(end 148.879306 -80.578198)
		(width 0.127)
		(layer "F.Cu")
		(net "CLK_100M_SATA_NODE1_DP")
	)
	(segment
		(start 146.283172 -70.931786)
		(end 145.814796 -71.400162)
		(width 0.127)
		(layer "F.Cu")
		(net "CLK_100M_SATA_NODE1_DP")
	)
	(segment
		(start 148.879306 -80.578198)
		(end 149.65172 -81.350612)
		(width 0.127)
		(layer "F.Cu")
		(net "CLK_100M_SATA_NODE1_DP")
	)
	(segment
		(start 149.827488 -82.104484)
		(end 150.109936 -82.104484)
		(width 0.127)
		(layer "F.Cu")
		(net "CLK_100M_SATA_NODE1_DP")
	)
	(segment
		(start 135.874252 -123.788932)
		(end 135.874252 -122.992134)
		(width 0.127)
		(layer "F.Cu")
		(net "CLK_100M_SATA_NODE1_DP")
	)
	(segment
		(start 145.814796 -71.400162)
		(end 145.814796 -76.313284)
		(width 0.127)
		(layer "F.Cu")
		(net "CLK_100M_SATA_NODE1_DP")
	)
	(segment
		(start 134.807452 -121.514362)
		(end 134.753858 -121.460768)
		(width 0.127)
		(layer "F.Cu")
		(net "CLK_100M_SATA_NODE1_DP")
	)
	(segment
		(start 146.33067 -69.492622)
		(end 146.283172 -69.638418)
		(width 0.127)
		(layer "F.Cu")
		(net "CLK_100M_SATA_NODE1_DP")
	)
	(segment
		(start 135.629142 -124.034042)
		(end 135.874252 -123.788932)
		(width 0.127)
		(layer "F.Cu")
		(net "CLK_100M_SATA_NODE1_DP")
	)
	(segment
		(start 149.65172 -81.350612)
		(end 149.65172 -81.928716)
		(width 0.127)
		(layer "F.Cu")
		(net "CLK_100M_SATA_NODE1_DP")
	)
	(segment
		(start 134.807452 -121.925334)
		(end 134.807452 -121.514362)
		(width 0.127)
		(layer "F.Cu")
		(net "CLK_100M_SATA_NODE1_DP")
	)
	(segment
		(start 145.393918 -79.480664)
		(end 146.491452 -80.578198)
		(width 0.127)
		(layer "F.Cu")
		(net "CLK_100M_SATA_NODE1_DP")
	)
	(segment
		(start 145.814796 -76.313284)
		(end 145.393918 -76.734162)
		(width 0.127)
		(layer "F.Cu")
		(net "CLK_100M_SATA_NODE1_DP")
	)
	(segment
		(start 134.753858 -121.460768)
		(end 134.753858 -121.064528)
		(width 0.127)
		(layer "F.Cu")
		(net "CLK_100M_SATA_NODE1_DP")
	)
	(segment
		(start 135.874252 -122.992134)
		(end 134.807452 -121.925334)
		(width 0.127)
		(layer "F.Cu")
		(net "CLK_100M_SATA_NODE1_DP")
	)
	(via
		(at 135.391652 -124.034042)
		(size 0.508)
		(drill 0.254)
		(layers "F.Cu" "B.Cu")
		(net "CLK_100M_SATA_NODE1_DP")
	)
	(via
		(at 150.109936 -82.104484)
		(size 0.508)
		(drill 0.254)
		(layers "F.Cu" "B.Cu")
		(net "CLK_100M_SATA_NODE1_DP")
	)
	(segment
		(start 142.31366 -119.55145)
		(end 142.79372 -119.07139)
		(width 0.127)
		(layer "B.Cu")
		(net "CLK_100M_SATA_NODE1_DP")
	)
	(segment
		(start 142.79372 -119.07139)
		(end 142.79372 -97.919032)
		(width 0.127)
		(layer "B.Cu")
		(net "CLK_100M_SATA_NODE1_DP")
	)
	(segment
		(start 135.707374 -124.034042)
		(end 135.874252 -124.20092)
		(width 0.127)
		(layer "B.Cu")
		(net "CLK_100M_SATA_NODE1_DP")
	)
	(segment
		(start 135.874252 -124.846334)
		(end 136.527794 -125.499876)
		(width 0.127)
		(layer "B.Cu")
		(net "CLK_100M_SATA_NODE1_DP")
	)
	(segment
		(start 149.627336 -91.085416)
		(end 149.627336 -82.587084)
		(width 0.127)
		(layer "B.Cu")
		(net "CLK_100M_SATA_NODE1_DP")
	)
	(segment
		(start 142.79372 -97.919032)
		(end 149.627336 -91.085416)
		(width 0.127)
		(layer "B.Cu")
		(net "CLK_100M_SATA_NODE1_DP")
	)
	(segment
		(start 149.627336 -82.587084)
		(end 150.109936 -82.104484)
		(width 0.127)
		(layer "B.Cu")
		(net "CLK_100M_SATA_NODE1_DP")
	)
	(segment
		(start 135.391652 -124.034042)
		(end 135.707374 -124.034042)
		(width 0.127)
		(layer "B.Cu")
		(net "CLK_100M_SATA_NODE1_DP")
	)
	(segment
		(start 136.527794 -125.499876)
		(end 139.123166 -125.499876)
		(width 0.127)
		(layer "B.Cu")
		(net "CLK_100M_SATA_NODE1_DP")
	)
	(segment
		(start 142.31366 -122.309382)
		(end 142.31366 -119.55145)
		(width 0.127)
		(layer "B.Cu")
		(net "CLK_100M_SATA_NODE1_DP")
	)
	(segment
		(start 139.123166 -125.499876)
		(end 142.31366 -122.309382)
		(width 0.127)
		(layer "B.Cu")
		(net "CLK_100M_SATA_NODE1_DP")
	)
	(segment
		(start 135.874252 -124.20092)
		(end 135.874252 -124.846334)
		(width 0.127)
		(layer "B.Cu")
		(net "CLK_100M_SATA_NODE1_DP")
	)
	(segment
		(start 12.949174 -17.480788)
		(end 13.04036 -17.571974)
		(width 0.1016)
		(layer "F.Cu")
		(net "N54251487")
	)
	(segment
		(start 13.188188 -20.20316)
		(end 13.188188 -17.719802)
		(width 0.1016)
		(layer "F.Cu")
		(net "N54251487")
	)
	(segment
		(start 13.188188 -17.719802)
		(end 13.04036 -17.571974)
		(width 0.1016)
		(layer "F.Cu")
		(net "N54251487")
	)
	(segment
		(start 12.949174 -16.660622)
		(end 12.949174 -17.480788)
		(width 0.1016)
		(layer "F.Cu")
		(net "N54251487")
	)
	(via
		(at 13.04036 -17.571974)
		(size 0.508)
		(drill 0.254)
		(layers "F.Cu" "B.Cu")
		(net "N54251487")
	)
	(segment
		(start 152.179528 -69.060822)
		(end 151.097488 -69.060822)
		(width 0.1016)
		(layer "F.Cu")
		(net "SATA_NODE1_XTLOUT")
	)
	(segment
		(start 150.800308 -68.763642)
		(end 150.970996 -68.93433)
		(width 0.1016)
		(layer "F.Cu")
		(net "SATA_NODE1_XTLOUT")
	)
	(segment
		(start 149.573488 -67.15633)
		(end 150.081996 -67.15633)
		(width 0.1016)
		(layer "F.Cu")
		(net "SATA_NODE1_XTLOUT")
	)
	(segment
		(start 150.800308 -67.874642)
		(end 150.800308 -68.763642)
		(width 0.1016)
		(layer "F.Cu")
		(net "SATA_NODE1_XTLOUT")
	)
	(segment
		(start 150.081996 -67.15633)
		(end 150.800308 -67.874642)
		(width 0.1016)
		(layer "F.Cu")
		(net "SATA_NODE1_XTLOUT")
	)
	(segment
		(start 149.57171 -67.158108)
		(end 149.573488 -67.15633)
		(width 0.1016)
		(layer "F.Cu")
		(net "SATA_NODE1_XTLOUT")
	)
	(segment
		(start 151.097488 -69.060822)
		(end 150.970996 -68.93433)
		(width 0.1016)
		(layer "F.Cu")
		(net "SATA_NODE1_XTLOUT")
	)
	(via
		(at 150.970996 -68.93433)
		(size 0.508)
		(drill 0.254)
		(layers "F.Cu" "B.Cu")
		(net "SATA_NODE1_XTLOUT")
	)
	(segment
		(start 58.23077 -85.381846)
		(end 58.232802 -85.381846)
		(width 0.1016)
		(layer "F.Cu")
		(net "PU_CPU_NODE1_DFX_GPIO_GRP1_3")
	)
	(segment
		(start 58.60415 -85.010498)
		(end 58.60415 -84.974938)
		(width 0.1016)
		(layer "F.Cu")
		(net "PU_CPU_NODE1_DFX_GPIO_GRP1_3")
	)
	(segment
		(start 58.232802 -85.381846)
		(end 58.60415 -85.010498)
		(width 0.1016)
		(layer "F.Cu")
		(net "PU_CPU_NODE1_DFX_GPIO_GRP1_3")
	)
	(via
		(at 55.038498 -95.106236)
		(size 0.6604)
		(drill 0.3302)
		(layers "F.Cu" "B.Cu")
		(net "PU_CPU_NODE1_DFX_GPIO_GRP1_3")
	)
	(via
		(at 58.60415 -84.974938)
		(size 0.508)
		(drill 0.254)
		(layers "F.Cu" "B.Cu")
		(net "PU_CPU_NODE1_DFX_GPIO_GRP1_3")
	)
	(segment
		(start 58.332878 -89.452196)
		(end 58.332878 -90.237056)
		(width 0.1016)
		(layer "B.Cu")
		(net "PU_CPU_NODE1_DFX_GPIO_GRP1_3")
	)
	(segment
		(start 57.391554 -92.295726)
		(end 56.345074 -93.342206)
		(width 0.1016)
		(layer "B.Cu")
		(net "PU_CPU_NODE1_DFX_GPIO_GRP1_3")
	)
	(segment
		(start 58.526426 -90.822526)
		(end 57.391554 -91.957398)
		(width 0.1016)
		(layer "B.Cu")
		(net "PU_CPU_NODE1_DFX_GPIO_GRP1_3")
	)
	(segment
		(start 57.391554 -91.957398)
		(end 57.391554 -92.295726)
		(width 0.1016)
		(layer "B.Cu")
		(net "PU_CPU_NODE1_DFX_GPIO_GRP1_3")
	)
	(segment
		(start 58.27903 -89.398348)
		(end 58.332878 -89.452196)
		(width 0.1016)
		(layer "B.Cu")
		(net "PU_CPU_NODE1_DFX_GPIO_GRP1_3")
	)
	(segment
		(start 58.332878 -90.237056)
		(end 58.526426 -90.430604)
		(width 0.1016)
		(layer "B.Cu")
		(net "PU_CPU_NODE1_DFX_GPIO_GRP1_3")
	)
	(segment
		(start 58.526426 -90.430604)
		(end 58.526426 -90.822526)
		(width 0.1016)
		(layer "B.Cu")
		(net "PU_CPU_NODE1_DFX_GPIO_GRP1_3")
	)
	(segment
		(start 55.038498 -95.106236)
		(end 55.038498 -96.296734)
		(width 0.1016)
		(layer "B.Cu")
		(net "PU_CPU_NODE1_DFX_GPIO_GRP1_3")
	)
	(segment
		(start 55.038498 -93.87078)
		(end 55.038498 -95.106236)
		(width 0.1016)
		(layer "B.Cu")
		(net "PU_CPU_NODE1_DFX_GPIO_GRP1_3")
	)
	(segment
		(start 56.345074 -93.342206)
		(end 55.567072 -93.342206)
		(width 0.1016)
		(layer "B.Cu")
		(net "PU_CPU_NODE1_DFX_GPIO_GRP1_3")
	)
	(segment
		(start 55.567072 -93.342206)
		(end 55.038498 -93.87078)
		(width 0.1016)
		(layer "B.Cu")
		(net "PU_CPU_NODE1_DFX_GPIO_GRP1_3")
	)
	(segment
		(start 58.27903 -85.729064)
		(end 58.27903 -89.398348)
		(width 0.1016)
		(layer "B.Cu")
		(net "PU_CPU_NODE1_DFX_GPIO_GRP1_3")
	)
	(segment
		(start 58.60415 -84.974938)
		(end 58.60415 -85.403944)
		(width 0.1016)
		(layer "B.Cu")
		(net "PU_CPU_NODE1_DFX_GPIO_GRP1_3")
	)
	(segment
		(start 58.60415 -85.403944)
		(end 58.27903 -85.729064)
		(width 0.1016)
		(layer "B.Cu")
		(net "PU_CPU_NODE1_DFX_GPIO_GRP1_3")
	)
	(segment
		(start 54.282848 -62.31255)
		(end 54.282848 -60.998608)
		(width 0.09906)
		(layer "F.Cu")
		(net "M_DDR3_NODE1_DQS3N")
	)
	(segment
		(start 58.436002 -31.464758)
		(end 57.947052 -31.953708)
		(width 0.1651)
		(layer "F.Cu")
		(net "M_DDR3_NODE1_DQS3N")
	)
	(segment
		(start 53.83149 -60.99429)
		(end 53.83149 -61.15939)
		(width 0.09906)
		(layer "F.Cu")
		(net "M_DDR3_NODE1_DQS3N")
	)
	(segment
		(start 58.050176 -30.350968)
		(end 58.2041 -30.504892)
		(width 0.1651)
		(layer "F.Cu")
		(net "M_DDR3_NODE1_DQS3N")
	)
	(segment
		(start 54.282848 -60.998608)
		(end 54.175914 -60.891674)
		(width 0.09906)
		(layer "F.Cu")
		(net "M_DDR3_NODE1_DQS3N")
	)
	(segment
		(start 53.550312 -63.49492)
		(end 53.880258 -63.164974)
		(width 0.09906)
		(layer "F.Cu")
		(net "M_DDR3_NODE1_DQS3N")
	)
	(segment
		(start 58.436002 -31.134558)
		(end 58.436002 -31.464758)
		(width 0.1651)
		(layer "F.Cu")
		(net "M_DDR3_NODE1_DQS3N")
	)
	(segment
		(start 58.050176 -29.149802)
		(end 58.050176 -30.350968)
		(width 0.1651)
		(layer "F.Cu")
		(net "M_DDR3_NODE1_DQS3N")
	)
	(segment
		(start 58.2041 -30.902656)
		(end 58.436002 -31.134558)
		(width 0.1651)
		(layer "F.Cu")
		(net "M_DDR3_NODE1_DQS3N")
	)
	(segment
		(start 54.175914 -60.891674)
		(end 53.934106 -60.891674)
		(width 0.09906)
		(layer "F.Cu")
		(net "M_DDR3_NODE1_DQS3N")
	)
	(segment
		(start 53.934106 -60.891674)
		(end 53.83149 -60.99429)
		(width 0.09906)
		(layer "F.Cu")
		(net "M_DDR3_NODE1_DQS3N")
	)
	(segment
		(start 58.2041 -30.504892)
		(end 58.2041 -30.902656)
		(width 0.1651)
		(layer "F.Cu")
		(net "M_DDR3_NODE1_DQS3N")
	)
	(segment
		(start 53.880258 -63.164974)
		(end 53.880258 -62.71514)
		(width 0.09906)
		(layer "F.Cu")
		(net "M_DDR3_NODE1_DQS3N")
	)
	(segment
		(start 53.880258 -62.71514)
		(end 54.282848 -62.31255)
		(width 0.09906)
		(layer "F.Cu")
		(net "M_DDR3_NODE1_DQS3N")
	)
	(via
		(at 57.947052 -31.953708)
		(size 0.508)
		(drill 0.254)
		(layers "F.Cu" "B.Cu")
		(net "M_DDR3_NODE1_DQS3N")
	)
	(via
		(at 53.83149 -61.15939)
		(size 0.508)
		(drill 0.254)
		(layers "F.Cu" "B.Cu")
		(net "M_DDR3_NODE1_DQS3N")
	)
	(segment
		(start 52.7177 -60.357004)
		(end 53.189886 -60.82919)
		(width 0.09906)
		(layer "In2.Cu")
		(net "M_DDR3_NODE1_DQS3N")
	)
	(segment
		(start 49.444148 -48.642524)
		(end 50.012092 -48.642524)
		(width 0.2032)
		(layer "In2.Cu")
		(net "M_DDR3_NODE1_DQS3N")
	)
	(segment
		(start 52.396136 -52.53482)
		(end 49.689766 -49.82845)
		(width 0.2032)
		(layer "In2.Cu")
		(net "M_DDR3_NODE1_DQS3N")
	)
	(segment
		(start 51.12512 -43.788076)
		(end 51.12512 -50.257964)
		(width 0.2032)
		(layer "In2.Cu")
		(net "M_DDR3_NODE1_DQS3N")
	)
	(segment
		(start 52.7177 -57.814718)
		(end 52.7177 -60.357004)
		(width 0.09906)
		(layer "In2.Cu")
		(net "M_DDR3_NODE1_DQS3N")
	)
	(segment
		(start 51.12512 -50.257964)
		(end 52.899056 -52.0319)
		(width 0.2032)
		(layer "In2.Cu")
		(net "M_DDR3_NODE1_DQS3N")
	)
	(segment
		(start 49.04232 -42.375074)
		(end 49.04232 -48.240696)
		(width 0.2032)
		(layer "In2.Cu")
		(net "M_DDR3_NODE1_DQS3N")
	)
	(segment
		(start 53.50129 -60.82919)
		(end 53.83149 -61.15939)
		(width 0.09906)
		(layer "In2.Cu")
		(net "M_DDR3_NODE1_DQS3N")
	)
	(segment
		(start 50.91684 -43.579796)
		(end 51.12512 -43.788076)
		(width 0.2032)
		(layer "In2.Cu")
		(net "M_DDR3_NODE1_DQS3N")
	)
	(segment
		(start 49.04232 -48.240696)
		(end 49.444148 -48.642524)
		(width 0.2032)
		(layer "In2.Cu")
		(net "M_DDR3_NODE1_DQS3N")
	)
	(segment
		(start 48.718978 -50.79873)
		(end 52.89296 -54.972712)
		(width 0.2032)
		(layer "In2.Cu")
		(net "M_DDR3_NODE1_DQS3N")
	)
	(segment
		(start 49.689766 -49.82845)
		(end 49.121314 -49.82845)
		(width 0.2032)
		(layer "In2.Cu")
		(net "M_DDR3_NODE1_DQS3N")
	)
	(segment
		(start 50.41392 -48.240696)
		(end 50.41392 -43.788076)
		(width 0.2032)
		(layer "In2.Cu")
		(net "M_DDR3_NODE1_DQS3N")
	)
	(segment
		(start 49.121314 -49.82845)
		(end 48.718978 -50.230532)
		(width 0.2032)
		(layer "In2.Cu")
		(net "M_DDR3_NODE1_DQS3N")
	)
	(segment
		(start 58.43778 -32.979614)
		(end 49.04232 -42.375074)
		(width 0.2032)
		(layer "In2.Cu")
		(net "M_DDR3_NODE1_DQS3N")
	)
	(segment
		(start 52.899056 -52.32654)
		(end 52.690776 -52.53482)
		(width 0.2032)
		(layer "In2.Cu")
		(net "M_DDR3_NODE1_DQS3N")
	)
	(segment
		(start 52.899056 -52.0319)
		(end 52.899056 -52.32654)
		(width 0.2032)
		(layer "In2.Cu")
		(net "M_DDR3_NODE1_DQS3N")
	)
	(segment
		(start 53.189886 -60.82919)
		(end 53.50129 -60.82919)
		(width 0.09906)
		(layer "In2.Cu")
		(net "M_DDR3_NODE1_DQS3N")
	)
	(segment
		(start 50.41392 -43.788076)
		(end 50.6222 -43.579796)
		(width 0.2032)
		(layer "In2.Cu")
		(net "M_DDR3_NODE1_DQS3N")
	)
	(segment
		(start 48.718978 -50.230532)
		(end 48.718978 -50.79873)
		(width 0.2032)
		(layer "In2.Cu")
		(net "M_DDR3_NODE1_DQS3N")
	)
	(segment
		(start 57.947052 -31.953708)
		(end 58.43778 -32.444436)
		(width 0.2032)
		(layer "In2.Cu")
		(net "M_DDR3_NODE1_DQS3N")
	)
	(segment
		(start 50.012092 -48.642524)
		(end 50.41392 -48.240696)
		(width 0.2032)
		(layer "In2.Cu")
		(net "M_DDR3_NODE1_DQS3N")
	)
	(segment
		(start 50.6222 -43.579796)
		(end 50.91684 -43.579796)
		(width 0.2032)
		(layer "In2.Cu")
		(net "M_DDR3_NODE1_DQS3N")
	)
	(segment
		(start 52.690776 -52.53482)
		(end 52.396136 -52.53482)
		(width 0.2032)
		(layer "In2.Cu")
		(net "M_DDR3_NODE1_DQS3N")
	)
	(segment
		(start 52.89296 -56.844184)
		(end 52.89296 -56.870092)
		(width 0.09906)
		(layer "In2.Cu")
		(net "M_DDR3_NODE1_DQS3N")
	)
	(segment
		(start 52.95646 -57.575958)
		(end 52.7177 -57.814718)
		(width 0.09906)
		(layer "In2.Cu")
		(net "M_DDR3_NODE1_DQS3N")
	)
	(segment
		(start 52.89296 -56.870092)
		(end 52.95646 -56.933592)
		(width 0.09906)
		(layer "In2.Cu")
		(net "M_DDR3_NODE1_DQS3N")
	)
	(segment
		(start 58.43778 -32.444436)
		(end 58.43778 -32.979614)
		(width 0.2032)
		(layer "In2.Cu")
		(net "M_DDR3_NODE1_DQS3N")
	)
	(segment
		(start 52.89296 -54.972712)
		(end 52.89296 -56.844184)
		(width 0.2032)
		(layer "In2.Cu")
		(net "M_DDR3_NODE1_DQS3N")
	)
	(segment
		(start 52.95646 -56.933592)
		(end 52.95646 -57.575958)
		(width 0.09906)
		(layer "In2.Cu")
		(net "M_DDR3_NODE1_DQS3N")
	)
	(segment
		(start 153.172922 -27.849322)
		(end 153.172922 -26.601928)
		(width 0.1016)
		(layer "F.Cu")
		(net "N21624848")
	)
	(segment
		(start 152.429972 -28.592272)
		(end 153.172922 -27.849322)
		(width 0.1016)
		(layer "F.Cu")
		(net "N21624848")
	)
	(segment
		(start 152.429972 -29.234892)
		(end 152.429972 -28.592272)
		(width 0.1016)
		(layer "F.Cu")
		(net "N21624848")
	)
	(via
		(at 152.429972 -28.592272)
		(size 0.508)
		(drill 0.254)
		(layers "F.Cu" "B.Cu")
		(net "N21624848")
	)
	(segment
		(start 142.730474 -68.799202)
		(end 142.730474 -69.539866)
		(width 0.1016)
		(layer "F.Cu")
		(net "LED_SATA_NODE1_GPIO0")
	)
	(segment
		(start 142.730474 -69.539866)
		(end 141.530578 -70.739762)
		(width 0.1016)
		(layer "F.Cu")
		(net "LED_SATA_NODE1_GPIO0")
	)
	(segment
		(start 141.530578 -70.739762)
		(end 141.530578 -71.203312)
		(width 0.1016)
		(layer "F.Cu")
		(net "LED_SATA_NODE1_GPIO0")
	)
	(segment
		(start 141.479778 -71.254112)
		(end 141.530578 -71.203312)
		(width 0.1016)
		(layer "F.Cu")
		(net "LED_SATA_NODE1_GPIO0")
	)
	(segment
		(start 139.986766 -71.254112)
		(end 141.479778 -71.254112)
		(width 0.1016)
		(layer "F.Cu")
		(net "LED_SATA_NODE1_GPIO0")
	)
	(via
		(at 141.530578 -71.203312)
		(size 0.508)
		(drill 0.254)
		(layers "F.Cu" "B.Cu")
		(net "LED_SATA_NODE1_GPIO0")
	)
	(segment
		(start 57.530746 -85.37448)
		(end 57.148984 -84.992718)
		(width 0.1016)
		(layer "F.Cu")
		(net "PD_CPU_NODE1_DFX_GPIO_GRP0_4")
	)
	(segment
		(start 57.530746 -85.381846)
		(end 57.530746 -85.37448)
		(width 0.1016)
		(layer "F.Cu")
		(net "PD_CPU_NODE1_DFX_GPIO_GRP0_4")
	)
	(via
		(at 57.148984 -84.992718)
		(size 0.508)
		(drill 0.254)
		(layers "F.Cu" "B.Cu")
		(net "PD_CPU_NODE1_DFX_GPIO_GRP0_4")
	)
	(via
		(at 56.853074 -91.192858)
		(size 0.6604)
		(drill 0.3302)
		(layers "F.Cu" "B.Cu")
		(net "PD_CPU_NODE1_DFX_GPIO_GRP0_4")
	)
	(segment
		(start 57.426606 -90.619326)
		(end 57.426606 -86.138512)
		(width 0.1016)
		(layer "B.Cu")
		(net "PD_CPU_NODE1_DFX_GPIO_GRP0_4")
	)
	(segment
		(start 57.148984 -85.86089)
		(end 57.148984 -84.992718)
		(width 0.1016)
		(layer "B.Cu")
		(net "PD_CPU_NODE1_DFX_GPIO_GRP0_4")
	)
	(segment
		(start 54.022498 -94.023434)
		(end 56.853074 -91.192858)
		(width 0.1016)
		(layer "B.Cu")
		(net "PD_CPU_NODE1_DFX_GPIO_GRP0_4")
	)
	(segment
		(start 54.022498 -96.296734)
		(end 54.022498 -94.023434)
		(width 0.1016)
		(layer "B.Cu")
		(net "PD_CPU_NODE1_DFX_GPIO_GRP0_4")
	)
	(segment
		(start 56.853074 -91.192858)
		(end 57.426606 -90.619326)
		(width 0.1016)
		(layer "B.Cu")
		(net "PD_CPU_NODE1_DFX_GPIO_GRP0_4")
	)
	(segment
		(start 57.426606 -86.138512)
		(end 57.148984 -85.86089)
		(width 0.1016)
		(layer "B.Cu")
		(net "PD_CPU_NODE1_DFX_GPIO_GRP0_4")
	)
	(segment
		(start 55.395368 -63.898526)
		(end 55.395368 -63.663322)
		(width 0.1016)
		(layer "F.Cu")
		(net "M1_DQ_NODE1_DQ29")
	)
	(segment
		(start 56.85028 -28.087066)
		(end 56.85028 -29.149802)
		(width 0.1651)
		(layer "F.Cu")
		(net "M1_DQ_NODE1_DQ29")
	)
	(segment
		(start 55.96509 -63.0936)
		(end 55.96509 -60.396374)
		(width 0.1016)
		(layer "F.Cu")
		(net "M1_DQ_NODE1_DQ29")
	)
	(segment
		(start 55.395368 -63.663322)
		(end 55.96509 -63.0936)
		(width 0.1016)
		(layer "F.Cu")
		(net "M1_DQ_NODE1_DQ29")
	)
	(segment
		(start 55.15229 -59.583574)
		(end 55.15229 -58.56859)
		(width 0.1016)
		(layer "F.Cu")
		(net "M1_DQ_NODE1_DQ29")
	)
	(segment
		(start 55.96509 -60.396374)
		(end 55.15229 -59.583574)
		(width 0.1016)
		(layer "F.Cu")
		(net "M1_DQ_NODE1_DQ29")
	)
	(segment
		(start 59.497722 -25.439624)
		(end 56.85028 -28.087066)
		(width 0.1651)
		(layer "F.Cu")
		(net "M1_DQ_NODE1_DQ29")
	)
	(via
		(at 59.497722 -25.439624)
		(size 0.508)
		(drill 0.254)
		(layers "F.Cu" "B.Cu")
		(net "M1_DQ_NODE1_DQ29")
	)
	(via
		(at 55.15229 -58.56859)
		(size 0.508)
		(drill 0.254)
		(layers "F.Cu" "B.Cu")
		(net "M1_DQ_NODE1_DQ29")
	)
	(segment
		(start 64.81699 -26.16073)
		(end 65.09004 -26.43378)
		(width 0.2032)
		(layer "In2.Cu")
		(net "M1_DQ_NODE1_DQ29")
	)
	(segment
		(start 56.509412 -49.224946)
		(end 56.509412 -49.226978)
		(width 0.2032)
		(layer "In2.Cu")
		(net "M1_DQ_NODE1_DQ29")
	)
	(segment
		(start 56.804052 -49.224946)
		(end 56.509412 -49.224946)
		(width 0.2032)
		(layer "In2.Cu")
		(net "M1_DQ_NODE1_DQ29")
	)
	(segment
		(start 61.574426 -30.625542)
		(end 61.732414 -30.625542)
		(width 0.2032)
		(layer "In2.Cu")
		(net "M1_DQ_NODE1_DQ29")
	)
	(segment
		(start 55.73268 -50.51552)
		(end 55.5244 -50.7238)
		(width 0.2032)
		(layer "In2.Cu")
		(net "M1_DQ_NODE1_DQ29")
	)
	(segment
		(start 55.5244 -57.564274)
		(end 55.5244 -58.1025)
		(width 0.1016)
		(layer "In2.Cu")
		(net "M1_DQ_NODE1_DQ29")
	)
	(segment
		(start 61.94806 -28.200096)
		(end 61.732414 -28.415742)
		(width 0.2032)
		(layer "In2.Cu")
		(net "M1_DQ_NODE1_DQ29")
	)
	(segment
		(start 61.35878 -30.104588)
		(end 61.35878 -30.409896)
		(width 0.2032)
		(layer "In2.Cu")
		(net "M1_DQ_NODE1_DQ29")
	)
	(segment
		(start 62.18428 -27.622246)
		(end 61.94806 -27.858466)
		(width 0.2032)
		(layer "In2.Cu")
		(net "M1_DQ_NODE1_DQ29")
	)
	(segment
		(start 60.638944 -24.093932)
		(end 60.944252 -24.093932)
		(width 0.2032)
		(layer "In2.Cu")
		(net "M1_DQ_NODE1_DQ29")
	)
	(segment
		(start 55.5244 -58.1025)
		(end 55.15229 -58.47461)
		(width 0.1016)
		(layer "In2.Cu")
		(net "M1_DQ_NODE1_DQ29")
	)
	(segment
		(start 55.73268 -49.80432)
		(end 56.07812 -49.80432)
		(width 0.2032)
		(layer "In2.Cu")
		(net "M1_DQ_NODE1_DQ29")
	)
	(segment
		(start 55.5244 -49.59604)
		(end 55.73268 -49.80432)
		(width 0.2032)
		(layer "In2.Cu")
		(net "M1_DQ_NODE1_DQ29")
	)
	(segment
		(start 61.05906 -28.618942)
		(end 61.05906 -28.949142)
		(width 0.2032)
		(layer "In2.Cu")
		(net "M1_DQ_NODE1_DQ29")
	)
	(segment
		(start 56.6674 -48.379126)
		(end 57.012332 -48.724058)
		(width 0.2032)
		(layer "In2.Cu")
		(net "M1_DQ_NODE1_DQ29")
	)
	(segment
		(start 65.09004 -27.408124)
		(end 64.875918 -27.622246)
		(width 0.2032)
		(layer "In2.Cu")
		(net "M1_DQ_NODE1_DQ29")
	)
	(segment
		(start 56.509412 -49.226978)
		(end 56.137302 -48.854868)
		(width 0.2032)
		(layer "In2.Cu")
		(net "M1_DQ_NODE1_DQ29")
	)
	(segment
		(start 57.012332 -49.016666)
		(end 56.804052 -49.224946)
		(width 0.2032)
		(layer "In2.Cu")
		(net "M1_DQ_NODE1_DQ29")
	)
	(segment
		(start 61.159898 -24.309578)
		(end 61.159898 -25.10282)
		(width 0.2032)
		(layer "In2.Cu")
		(net "M1_DQ_NODE1_DQ29")
	)
	(segment
		(start 61.732414 -29.888942)
		(end 61.574426 -29.888942)
		(width 0.2032)
		(layer "In2.Cu")
		(net "M1_DQ_NODE1_DQ29")
	)
	(segment
		(start 56.2864 -50.0126)
		(end 56.2864 -50.30724)
		(width 0.2032)
		(layer "In2.Cu")
		(net "M1_DQ_NODE1_DQ29")
	)
	(segment
		(start 59.497722 -25.439624)
		(end 60.220098 -25.439624)
		(width 0.2032)
		(layer "In2.Cu")
		(net "M1_DQ_NODE1_DQ29")
	)
	(segment
		(start 61.375544 -25.318466)
		(end 62.158626 -25.318466)
		(width 0.2032)
		(layer "In2.Cu")
		(net "M1_DQ_NODE1_DQ29")
	)
	(segment
		(start 55.5244 -49.083468)
		(end 55.5244 -49.59604)
		(width 0.2032)
		(layer "In2.Cu")
		(net "M1_DQ_NODE1_DQ29")
	)
	(segment
		(start 57.012332 -48.724058)
		(end 57.012332 -49.016666)
		(width 0.2032)
		(layer "In2.Cu")
		(net "M1_DQ_NODE1_DQ29")
	)
	(segment
		(start 55.15229 -58.47461)
		(end 55.15229 -58.56859)
		(width 0.1016)
		(layer "In2.Cu")
		(net "M1_DQ_NODE1_DQ29")
	)
	(segment
		(start 61.26226 -28.415742)
		(end 61.05906 -28.618942)
		(width 0.2032)
		(layer "In2.Cu")
		(net "M1_DQ_NODE1_DQ29")
	)
	(segment
		(start 55.5244 -50.7238)
		(end 55.5244 -57.564274)
		(width 0.2032)
		(layer "In2.Cu")
		(net "M1_DQ_NODE1_DQ29")
	)
	(segment
		(start 60.423298 -24.309578)
		(end 60.638944 -24.093932)
		(width 0.2032)
		(layer "In2.Cu")
		(net "M1_DQ_NODE1_DQ29")
	)
	(segment
		(start 64.875918 -27.622246)
		(end 62.18428 -27.622246)
		(width 0.2032)
		(layer "In2.Cu")
		(net "M1_DQ_NODE1_DQ29")
	)
	(segment
		(start 61.05906 -28.949142)
		(end 61.26226 -29.152342)
		(width 0.2032)
		(layer "In2.Cu")
		(net "M1_DQ_NODE1_DQ29")
	)
	(segment
		(start 56.2864 -50.30724)
		(end 56.07812 -50.51552)
		(width 0.2032)
		(layer "In2.Cu")
		(net "M1_DQ_NODE1_DQ29")
	)
	(segment
		(start 61.94806 -33.453578)
		(end 56.6674 -38.734238)
		(width 0.2032)
		(layer "In2.Cu")
		(net "M1_DQ_NODE1_DQ29")
	)
	(segment
		(start 61.94806 -29.367988)
		(end 61.94806 -29.673296)
		(width 0.2032)
		(layer "In2.Cu")
		(net "M1_DQ_NODE1_DQ29")
	)
	(segment
		(start 61.732414 -28.415742)
		(end 61.26226 -28.415742)
		(width 0.2032)
		(layer "In2.Cu")
		(net "M1_DQ_NODE1_DQ29")
	)
	(segment
		(start 56.137302 -48.854868)
		(end 55.753 -48.854868)
		(width 0.2032)
		(layer "In2.Cu")
		(net "M1_DQ_NODE1_DQ29")
	)
	(segment
		(start 61.94806 -27.858466)
		(end 61.94806 -28.200096)
		(width 0.2032)
		(layer "In2.Cu")
		(net "M1_DQ_NODE1_DQ29")
	)
	(segment
		(start 61.94806 -30.841188)
		(end 61.94806 -33.453578)
		(width 0.2032)
		(layer "In2.Cu")
		(net "M1_DQ_NODE1_DQ29")
	)
	(segment
		(start 62.158626 -25.318466)
		(end 63.00089 -26.16073)
		(width 0.2032)
		(layer "In2.Cu")
		(net "M1_DQ_NODE1_DQ29")
	)
	(segment
		(start 61.94806 -29.673296)
		(end 61.732414 -29.888942)
		(width 0.2032)
		(layer "In2.Cu")
		(net "M1_DQ_NODE1_DQ29")
	)
	(segment
		(start 61.26226 -29.152342)
		(end 61.732414 -29.152342)
		(width 0.2032)
		(layer "In2.Cu")
		(net "M1_DQ_NODE1_DQ29")
	)
	(segment
		(start 60.220098 -25.439624)
		(end 60.423298 -25.236424)
		(width 0.2032)
		(layer "In2.Cu")
		(net "M1_DQ_NODE1_DQ29")
	)
	(segment
		(start 61.732414 -29.152342)
		(end 61.94806 -29.367988)
		(width 0.2032)
		(layer "In2.Cu")
		(net "M1_DQ_NODE1_DQ29")
	)
	(segment
		(start 61.159898 -25.10282)
		(end 61.375544 -25.318466)
		(width 0.2032)
		(layer "In2.Cu")
		(net "M1_DQ_NODE1_DQ29")
	)
	(segment
		(start 60.944252 -24.093932)
		(end 61.159898 -24.309578)
		(width 0.2032)
		(layer "In2.Cu")
		(net "M1_DQ_NODE1_DQ29")
	)
	(segment
		(start 61.574426 -29.888942)
		(end 61.35878 -30.104588)
		(width 0.2032)
		(layer "In2.Cu")
		(net "M1_DQ_NODE1_DQ29")
	)
	(segment
		(start 61.35878 -30.409896)
		(end 61.574426 -30.625542)
		(width 0.2032)
		(layer "In2.Cu")
		(net "M1_DQ_NODE1_DQ29")
	)
	(segment
		(start 61.732414 -30.625542)
		(end 61.94806 -30.841188)
		(width 0.2032)
		(layer "In2.Cu")
		(net "M1_DQ_NODE1_DQ29")
	)
	(segment
		(start 65.09004 -26.43378)
		(end 65.09004 -27.408124)
		(width 0.2032)
		(layer "In2.Cu")
		(net "M1_DQ_NODE1_DQ29")
	)
	(segment
		(start 56.6674 -38.734238)
		(end 56.6674 -48.379126)
		(width 0.2032)
		(layer "In2.Cu")
		(net "M1_DQ_NODE1_DQ29")
	)
	(segment
		(start 60.423298 -25.236424)
		(end 60.423298 -24.309578)
		(width 0.2032)
		(layer "In2.Cu")
		(net "M1_DQ_NODE1_DQ29")
	)
	(segment
		(start 63.00089 -26.16073)
		(end 64.81699 -26.16073)
		(width 0.2032)
		(layer "In2.Cu")
		(net "M1_DQ_NODE1_DQ29")
	)
	(segment
		(start 56.07812 -50.51552)
		(end 55.73268 -50.51552)
		(width 0.2032)
		(layer "In2.Cu")
		(net "M1_DQ_NODE1_DQ29")
	)
	(segment
		(start 56.07812 -49.80432)
		(end 56.2864 -50.0126)
		(width 0.2032)
		(layer "In2.Cu")
		(net "M1_DQ_NODE1_DQ29")
	)
	(segment
		(start 55.753 -48.854868)
		(end 55.5244 -49.083468)
		(width 0.2032)
		(layer "In2.Cu")
		(net "M1_DQ_NODE1_DQ29")
	)
	(segment
		(start 133.029452 -122.230642)
		(end 133.512052 -122.713242)
		(width 0.1016)
		(layer "F.Cu")
		(net "PCI_STP_NODE1")
	)
	(segment
		(start 133.029452 -121.748042)
		(end 133.029452 -122.230642)
		(width 0.1016)
		(layer "F.Cu")
		(net "PCI_STP_NODE1")
	)
	(segment
		(start 133.512052 -122.713242)
		(end 133.512052 -122.941842)
		(width 0.1016)
		(layer "F.Cu")
		(net "PCI_STP_NODE1")
	)
	(segment
		(start 133.153658 -121.623836)
		(end 133.029452 -121.748042)
		(width 0.1016)
		(layer "F.Cu")
		(net "PCI_STP_NODE1")
	)
	(segment
		(start 133.153658 -121.064528)
		(end 133.153658 -121.623836)
		(width 0.1016)
		(layer "F.Cu")
		(net "PCI_STP_NODE1")
	)
	(via
		(at 133.512052 -122.941842)
		(size 0.508)
		(drill 0.254)
		(layers "F.Cu" "B.Cu")
		(net "PCI_STP_NODE1")
	)
	(segment
		(start 134.279132 -122.840242)
		(end 134.177532 -122.941842)
		(width 0.1016)
		(layer "B.Cu")
		(net "PCI_STP_NODE1")
	)
	(segment
		(start 134.177532 -122.941842)
		(end 133.512052 -122.941842)
		(width 0.1016)
		(layer "B.Cu")
		(net "PCI_STP_NODE1")
	)
	(segment
		(start 135.007858 -122.841258)
		(end 135.007858 -122.840242)
		(width 0.1016)
		(layer "B.Cu")
		(net "PCI_STP_NODE1")
	)
	(segment
		(start 135.007858 -122.840242)
		(end 134.279132 -122.840242)
		(width 0.1016)
		(layer "B.Cu")
		(net "PCI_STP_NODE1")
	)
	(segment
		(start 152.429972 -31.834836)
		(end 153.346658 -31.834836)
		(width 0.1016)
		(layer "F.Cu")
		(net "N21624850")
	)
	(segment
		(start 153.973022 -31.208472)
		(end 153.68778 -31.493714)
		(width 0.1016)
		(layer "F.Cu")
		(net "N21624850")
	)
	(segment
		(start 153.346658 -31.834836)
		(end 153.68778 -31.493714)
		(width 0.1016)
		(layer "F.Cu")
		(net "N21624850")
	)
	(segment
		(start 153.973022 -26.601928)
		(end 153.973022 -31.208472)
		(width 0.1016)
		(layer "F.Cu")
		(net "N21624850")
	)
	(via
		(at 153.68778 -31.493714)
		(size 0.508)
		(drill 0.254)
		(layers "F.Cu" "B.Cu")
		(net "N21624850")
	)
	(segment
		(start 59.550808 -27.386534)
		(end 58.753502 -27.386534)
		(width 0.1651)
		(layer "F.Cu")
		(net "M1_DQ_NODE1_DQ30")
	)
	(segment
		(start 59.850274 -29.149802)
		(end 59.850274 -27.686)
		(width 0.1651)
		(layer "F.Cu")
		(net "M1_DQ_NODE1_DQ30")
	)
	(segment
		(start 53.215032 -63.72225)
		(end 53.215032 -59.09437)
		(width 0.1016)
		(layer "F.Cu")
		(net "M1_DQ_NODE1_DQ30")
	)
	(segment
		(start 59.850274 -27.686)
		(end 59.550808 -27.386534)
		(width 0.1651)
		(layer "F.Cu")
		(net "M1_DQ_NODE1_DQ30")
	)
	(segment
		(start 53.215032 -59.09437)
		(end 52.20589 -58.085228)
		(width 0.1016)
		(layer "F.Cu")
		(net "M1_DQ_NODE1_DQ30")
	)
	(segment
		(start 58.753502 -27.386534)
		(end 58.583322 -27.556714)
		(width 0.1651)
		(layer "F.Cu")
		(net "M1_DQ_NODE1_DQ30")
	)
	(segment
		(start 58.583322 -27.556714)
		(end 58.583322 -27.558238)
		(width 0.1651)
		(layer "F.Cu")
		(net "M1_DQ_NODE1_DQ30")
	)
	(segment
		(start 52.932584 -64.004698)
		(end 53.215032 -63.72225)
		(width 0.1016)
		(layer "F.Cu")
		(net "M1_DQ_NODE1_DQ30")
	)
	(via
		(at 58.583322 -27.558238)
		(size 0.508)
		(drill 0.254)
		(layers "F.Cu" "B.Cu")
		(net "M1_DQ_NODE1_DQ30")
	)
	(via
		(at 52.20589 -58.085228)
		(size 0.508)
		(drill 0.254)
		(layers "F.Cu" "B.Cu")
		(net "M1_DQ_NODE1_DQ30")
	)
	(segment
		(start 56.777382 -30.552898)
		(end 57.259982 -30.070298)
		(width 0.2032)
		(layer "In2.Cu")
		(net "M1_DQ_NODE1_DQ30")
	)
	(segment
		(start 46.99 -44.238164)
		(end 46.99 -49.476152)
		(width 0.2032)
		(layer "In2.Cu")
		(net "M1_DQ_NODE1_DQ30")
	)
	(segment
		(start 51.86426 -57.743598)
		(end 51.86426 -56.782208)
		(width 0.1016)
		(layer "In2.Cu")
		(net "M1_DQ_NODE1_DQ30")
	)
	(segment
		(start 56.777382 -32.357568)
		(end 56.777382 -30.552898)
		(width 0.2032)
		(layer "In2.Cu")
		(net "M1_DQ_NODE1_DQ30")
	)
	(segment
		(start 58.55462 -29.014928)
		(end 58.55462 -28.698444)
		(width 0.2032)
		(layer "In2.Cu")
		(net "M1_DQ_NODE1_DQ30")
	)
	(segment
		(start 46.2788 -44.238164)
		(end 46.48708 -44.029884)
		(width 0.2032)
		(layer "In2.Cu")
		(net "M1_DQ_NODE1_DQ30")
	)
	(segment
		(start 51.86426 -56.782208)
		(end 51.86426 -55.38216)
		(width 0.2032)
		(layer "In2.Cu")
		(net "M1_DQ_NODE1_DQ30")
	)
	(segment
		(start 58.916062 -27.890978)
		(end 58.583322 -27.558238)
		(width 0.2032)
		(layer "In2.Cu")
		(net "M1_DQ_NODE1_DQ30")
	)
	(segment
		(start 52.20589 -58.085228)
		(end 51.86426 -57.743598)
		(width 0.1016)
		(layer "In2.Cu")
		(net "M1_DQ_NODE1_DQ30")
	)
	(segment
		(start 58.55462 -28.698444)
		(end 58.916062 -28.337002)
		(width 0.2032)
		(layer "In2.Cu")
		(net "M1_DQ_NODE1_DQ30")
	)
	(segment
		(start 58.916062 -29.837126)
		(end 58.916062 -29.37637)
		(width 0.2032)
		(layer "In2.Cu")
		(net "M1_DQ_NODE1_DQ30")
	)
	(segment
		(start 46.78172 -44.029884)
		(end 46.99 -44.238164)
		(width 0.2032)
		(layer "In2.Cu")
		(net "M1_DQ_NODE1_DQ30")
	)
	(segment
		(start 46.48708 -44.029884)
		(end 46.78172 -44.029884)
		(width 0.2032)
		(layer "In2.Cu")
		(net "M1_DQ_NODE1_DQ30")
	)
	(segment
		(start 47.49292 -49.684432)
		(end 47.7012 -49.476152)
		(width 0.2032)
		(layer "In2.Cu")
		(net "M1_DQ_NODE1_DQ30")
	)
	(segment
		(start 58.68289 -30.070298)
		(end 58.916062 -29.837126)
		(width 0.2032)
		(layer "In2.Cu")
		(net "M1_DQ_NODE1_DQ30")
	)
	(segment
		(start 56.77662 -32.357568)
		(end 56.777382 -32.357568)
		(width 0.2032)
		(layer "In2.Cu")
		(net "M1_DQ_NODE1_DQ30")
	)
	(segment
		(start 51.86426 -55.38216)
		(end 46.2788 -49.7967)
		(width 0.2032)
		(layer "In2.Cu")
		(net "M1_DQ_NODE1_DQ30")
	)
	(segment
		(start 46.2788 -49.7967)
		(end 46.2788 -44.238164)
		(width 0.2032)
		(layer "In2.Cu")
		(net "M1_DQ_NODE1_DQ30")
	)
	(segment
		(start 57.259982 -30.070298)
		(end 58.68289 -30.070298)
		(width 0.2032)
		(layer "In2.Cu")
		(net "M1_DQ_NODE1_DQ30")
	)
	(segment
		(start 47.7012 -49.476152)
		(end 47.7012 -43.573446)
		(width 0.2032)
		(layer "In2.Cu")
		(net "M1_DQ_NODE1_DQ30")
	)
	(segment
		(start 58.916062 -28.337002)
		(end 58.916062 -27.890978)
		(width 0.2032)
		(layer "In2.Cu")
		(net "M1_DQ_NODE1_DQ30")
	)
	(segment
		(start 47.7012 -43.573446)
		(end 47.23638 -43.108626)
		(width 0.2032)
		(layer "In2.Cu")
		(net "M1_DQ_NODE1_DQ30")
	)
	(segment
		(start 58.916062 -29.37637)
		(end 58.55462 -29.014928)
		(width 0.2032)
		(layer "In2.Cu")
		(net "M1_DQ_NODE1_DQ30")
	)
	(segment
		(start 47.23638 -42.744136)
		(end 56.77662 -33.203896)
		(width 0.2032)
		(layer "In2.Cu")
		(net "M1_DQ_NODE1_DQ30")
	)
	(segment
		(start 47.23638 -43.108626)
		(end 47.23638 -42.744136)
		(width 0.2032)
		(layer "In2.Cu")
		(net "M1_DQ_NODE1_DQ30")
	)
	(segment
		(start 46.99 -49.476152)
		(end 47.19828 -49.684432)
		(width 0.2032)
		(layer "In2.Cu")
		(net "M1_DQ_NODE1_DQ30")
	)
	(segment
		(start 56.77662 -33.203896)
		(end 56.77662 -32.357568)
		(width 0.2032)
		(layer "In2.Cu")
		(net "M1_DQ_NODE1_DQ30")
	)
	(segment
		(start 47.19828 -49.684432)
		(end 47.49292 -49.684432)
		(width 0.2032)
		(layer "In2.Cu")
		(net "M1_DQ_NODE1_DQ30")
	)
	(segment
		(start 17.013174 -16.660622)
		(end 17.013174 -17.7927)
		(width 0.1016)
		(layer "F.Cu")
		(net "N54251539")
	)
	(segment
		(start 15.788132 -19.017742)
		(end 16.30426 -18.501614)
		(width 0.1016)
		(layer "F.Cu")
		(net "N54251539")
	)
	(segment
		(start 15.788132 -20.20316)
		(end 15.788132 -19.017742)
		(width 0.1016)
		(layer "F.Cu")
		(net "N54251539")
	)
	(segment
		(start 17.013174 -17.7927)
		(end 16.30426 -18.501614)
		(width 0.1016)
		(layer "F.Cu")
		(net "N54251539")
	)
	(via
		(at 16.30426 -18.501614)
		(size 0.508)
		(drill 0.254)
		(layers "F.Cu" "B.Cu")
		(net "N54251539")
	)
	(segment
		(start 131.57962 -63.648336)
		(end 131.48818 -63.556896)
		(width 0.1016)
		(layer "F.Cu")
		(net "SATA_SPI_CS_NODE1")
	)
	(segment
		(start 136.92251 -75.393296)
		(end 135.329676 -73.800462)
		(width 0.1016)
		(layer "F.Cu")
		(net "SATA_SPI_CS_NODE1")
	)
	(segment
		(start 132.737352 -63.648336)
		(end 131.57962 -63.648336)
		(width 0.1016)
		(layer "F.Cu")
		(net "SATA_SPI_CS_NODE1")
	)
	(segment
		(start 138.96213 -75.393296)
		(end 136.92251 -75.393296)
		(width 0.1016)
		(layer "F.Cu")
		(net "SATA_SPI_CS_NODE1")
	)
	(segment
		(start 135.329676 -73.800462)
		(end 135.329676 -71.645272)
		(width 0.1016)
		(layer "F.Cu")
		(net "SATA_SPI_CS_NODE1")
	)
	(segment
		(start 131.48818 -63.556896)
		(end 131.48818 -62.871858)
		(width 0.1016)
		(layer "F.Cu")
		(net "SATA_SPI_CS_NODE1")
	)
	(via
		(at 135.329676 -71.645272)
		(size 0.508)
		(drill 0.254)
		(layers "F.Cu" "B.Cu")
		(net "SATA_SPI_CS_NODE1")
	)
	(via
		(at 131.48818 -62.871858)
		(size 0.508)
		(drill 0.254)
		(layers "F.Cu" "B.Cu")
		(net "SATA_SPI_CS_NODE1")
	)
	(segment
		(start 133.90245 -65.797938)
		(end 133.90245 -66.050414)
		(width 0.1016)
		(layer "B.Cu")
		(net "SATA_SPI_CS_NODE1")
	)
	(segment
		(start 133.039866 -65.18783)
		(end 131.79298 -66.434716)
		(width 0.1016)
		(layer "B.Cu")
		(net "SATA_SPI_CS_NODE1")
	)
	(segment
		(start 133.471158 -65.619122)
		(end 133.723634 -65.619122)
		(width 0.1016)
		(layer "B.Cu")
		(net "SATA_SPI_CS_NODE1")
	)
	(segment
		(start 133.90245 -66.050414)
		(end 132.655564 -67.2973)
		(width 0.1016)
		(layer "B.Cu")
		(net "SATA_SPI_CS_NODE1")
	)
	(segment
		(start 132.177282 -64.325246)
		(end 130.930396 -65.572132)
		(width 0.1016)
		(layer "B.Cu")
		(net "SATA_SPI_CS_NODE1")
	)
	(segment
		(start 134.333742 -66.481706)
		(end 134.586218 -66.481706)
		(width 0.1016)
		(layer "B.Cu")
		(net "SATA_SPI_CS_NODE1")
	)
	(segment
		(start 132.655564 -67.2973)
		(end 132.655564 -67.549776)
		(width 0.1016)
		(layer "B.Cu")
		(net "SATA_SPI_CS_NODE1")
	)
	(segment
		(start 133.039866 -64.935354)
		(end 133.039866 -65.18783)
		(width 0.1016)
		(layer "B.Cu")
		(net "SATA_SPI_CS_NODE1")
	)
	(segment
		(start 132.224272 -66.866008)
		(end 133.471158 -65.619122)
		(width 0.1016)
		(layer "B.Cu")
		(net "SATA_SPI_CS_NODE1")
	)
	(segment
		(start 132.86105 -64.756538)
		(end 133.039866 -64.935354)
		(width 0.1016)
		(layer "B.Cu")
		(net "SATA_SPI_CS_NODE1")
	)
	(segment
		(start 131.79298 -66.434716)
		(end 131.79298 -66.687192)
		(width 0.1016)
		(layer "B.Cu")
		(net "SATA_SPI_CS_NODE1")
	)
	(segment
		(start 134.586218 -66.481706)
		(end 135.329676 -67.225164)
		(width 0.1016)
		(layer "B.Cu")
		(net "SATA_SPI_CS_NODE1")
	)
	(segment
		(start 130.930396 -65.572132)
		(end 130.930396 -65.824608)
		(width 0.1016)
		(layer "B.Cu")
		(net "SATA_SPI_CS_NODE1")
	)
	(segment
		(start 131.79298 -66.687192)
		(end 131.971796 -66.866008)
		(width 0.1016)
		(layer "B.Cu")
		(net "SATA_SPI_CS_NODE1")
	)
	(segment
		(start 131.48818 -62.871858)
		(end 132.177282 -63.56096)
		(width 0.1016)
		(layer "B.Cu")
		(net "SATA_SPI_CS_NODE1")
	)
	(segment
		(start 132.177282 -63.56096)
		(end 132.177282 -64.325246)
		(width 0.1016)
		(layer "B.Cu")
		(net "SATA_SPI_CS_NODE1")
	)
	(segment
		(start 133.723634 -65.619122)
		(end 133.90245 -65.797938)
		(width 0.1016)
		(layer "B.Cu")
		(net "SATA_SPI_CS_NODE1")
	)
	(segment
		(start 132.655564 -67.549776)
		(end 132.83438 -67.728592)
		(width 0.1016)
		(layer "B.Cu")
		(net "SATA_SPI_CS_NODE1")
	)
	(segment
		(start 132.608574 -64.756538)
		(end 132.86105 -64.756538)
		(width 0.1016)
		(layer "B.Cu")
		(net "SATA_SPI_CS_NODE1")
	)
	(segment
		(start 131.361688 -66.003424)
		(end 132.608574 -64.756538)
		(width 0.1016)
		(layer "B.Cu")
		(net "SATA_SPI_CS_NODE1")
	)
	(segment
		(start 130.930396 -65.824608)
		(end 131.109212 -66.003424)
		(width 0.1016)
		(layer "B.Cu")
		(net "SATA_SPI_CS_NODE1")
	)
	(segment
		(start 131.109212 -66.003424)
		(end 131.361688 -66.003424)
		(width 0.1016)
		(layer "B.Cu")
		(net "SATA_SPI_CS_NODE1")
	)
	(segment
		(start 131.971796 -66.866008)
		(end 132.224272 -66.866008)
		(width 0.1016)
		(layer "B.Cu")
		(net "SATA_SPI_CS_NODE1")
	)
	(segment
		(start 132.83438 -67.728592)
		(end 133.086856 -67.728592)
		(width 0.1016)
		(layer "B.Cu")
		(net "SATA_SPI_CS_NODE1")
	)
	(segment
		(start 133.086856 -67.728592)
		(end 134.333742 -66.481706)
		(width 0.1016)
		(layer "B.Cu")
		(net "SATA_SPI_CS_NODE1")
	)
	(segment
		(start 135.329676 -67.225164)
		(end 135.329676 -71.645272)
		(width 0.1016)
		(layer "B.Cu")
		(net "SATA_SPI_CS_NODE1")
	)
	(segment
		(start 56.109108 -88.559894)
		(end 55.944516 -88.724486)
		(width 0.1016)
		(layer "F.Cu")
		(net "PD_CPU_NODE1_DFX_GPIO_GRP0_3")
	)
	(segment
		(start 57.081166 -95.691706)
		(end 56.32958 -94.94012)
		(width 0.1016)
		(layer "F.Cu")
		(net "PD_CPU_NODE1_DFX_GPIO_GRP0_3")
	)
	(segment
		(start 56.109108 -88.44026)
		(end 56.109108 -88.559894)
		(width 0.1016)
		(layer "F.Cu")
		(net "PD_CPU_NODE1_DFX_GPIO_GRP0_3")
	)
	(segment
		(start 55.944516 -88.724486)
		(end 55.944516 -94.555056)
		(width 0.1016)
		(layer "F.Cu")
		(net "PD_CPU_NODE1_DFX_GPIO_GRP0_3")
	)
	(segment
		(start 57.081166 -96.309942)
		(end 57.081166 -95.691706)
		(width 0.1016)
		(layer "F.Cu")
		(net "PD_CPU_NODE1_DFX_GPIO_GRP0_3")
	)
	(segment
		(start 55.944516 -94.555056)
		(end 56.32958 -94.94012)
		(width 0.1016)
		(layer "F.Cu")
		(net "PD_CPU_NODE1_DFX_GPIO_GRP0_3")
	)
	(via
		(at 56.32958 -94.94012)
		(size 0.762)
		(drill 0.381)
		(layers "F.Cu" "B.Cu")
		(net "PD_CPU_NODE1_DFX_GPIO_GRP0_3")
	)
	(segment
		(start 70.252844 -48.14316)
		(end 70.557644 -48.143414)
		(width 0.2286)
		(layer "F.Cu")
		(net "M_DDR3_NODE1_MA4")
	)
	(segment
		(start 73.53427 -39.264844)
		(end 73.228962 -39.264844)
		(width 0.2286)
		(layer "F.Cu")
		(net "M_DDR3_NODE1_MA4")
	)
	(segment
		(start 75.014582 -38.790118)
		(end 75.014582 -37.051742)
		(width 0.2286)
		(layer "F.Cu")
		(net "M_DDR3_NODE1_MA4")
	)
	(segment
		(start 73.650094 -30.464506)
		(end 73.650094 -29.149802)
		(width 0.2286)
		(layer "F.Cu")
		(net "M_DDR3_NODE1_MA4")
	)
	(segment
		(start 73.348342 -34.972498)
		(end 73.348342 -30.766258)
		(width 0.2286)
		(layer "F.Cu")
		(net "M_DDR3_NODE1_MA4")
	)
	(segment
		(start 73.013316 -39.049198)
		(end 73.013316 -35.307524)
		(width 0.2286)
		(layer "F.Cu")
		(net "M_DDR3_NODE1_MA4")
	)
	(segment
		(start 73.749916 -39.049198)
		(end 73.53427 -39.264844)
		(width 0.2286)
		(layer "F.Cu")
		(net "M_DDR3_NODE1_MA4")
	)
	(segment
		(start 64.191134 -52.543456)
		(end 65.852548 -52.543456)
		(width 0.2286)
		(layer "F.Cu")
		(net "M_DDR3_NODE1_MA4")
	)
	(segment
		(start 60.77204 -61.275722)
		(end 60.77204 -59.983116)
		(width 0.1016)
		(layer "F.Cu")
		(net "M_DDR3_NODE1_MA4")
	)
	(segment
		(start 70.773544 -48.359314)
		(end 70.77329 -48.664622)
		(width 0.2286)
		(layer "F.Cu")
		(net "M_DDR3_NODE1_MA4")
	)
	(segment
		(start 73.71842 -46.7614)
		(end 73.71842 -40.79367)
		(width 0.2286)
		(layer "F.Cu")
		(net "M_DDR3_NODE1_MA4")
	)
	(segment
		(start 60.818522 -63.160402)
		(end 60.56757 -62.909704)
		(width 0.1016)
		(layer "F.Cu")
		(net "M_DDR3_NODE1_MA4")
	)
	(segment
		(start 60.56757 -62.909704)
		(end 60.56757 -61.480192)
		(width 0.1016)
		(layer "F.Cu")
		(net "M_DDR3_NODE1_MA4")
	)
	(segment
		(start 74.484738 -36.521898)
		(end 73.953116 -36.521898)
		(width 0.2286)
		(layer "F.Cu")
		(net "M_DDR3_NODE1_MA4")
	)
	(segment
		(start 73.953116 -36.521898)
		(end 73.749916 -36.725098)
		(width 0.2286)
		(layer "F.Cu")
		(net "M_DDR3_NODE1_MA4")
	)
	(segment
		(start 65.852548 -52.543456)
		(end 70.252844 -48.14316)
		(width 0.2286)
		(layer "F.Cu")
		(net "M_DDR3_NODE1_MA4")
	)
	(segment
		(start 70.77329 -48.664622)
		(end 67.331844 -52.106068)
		(width 0.2286)
		(layer "F.Cu")
		(net "M_DDR3_NODE1_MA4")
	)
	(segment
		(start 60.77204 -59.983116)
		(end 61.3156 -59.439556)
		(width 0.1016)
		(layer "F.Cu")
		(net "M_DDR3_NODE1_MA4")
	)
	(segment
		(start 75.014582 -37.051742)
		(end 74.484738 -36.521898)
		(width 0.2286)
		(layer "F.Cu")
		(net "M_DDR3_NODE1_MA4")
	)
	(segment
		(start 61.317632 -55.416958)
		(end 64.191134 -52.543456)
		(width 0.2286)
		(layer "F.Cu")
		(net "M_DDR3_NODE1_MA4")
	)
	(segment
		(start 73.71842 -40.79367)
		(end 74.435462 -40.076628)
		(width 0.2286)
		(layer "F.Cu")
		(net "M_DDR3_NODE1_MA4")
	)
	(segment
		(start 67.332098 -52.410868)
		(end 67.547998 -52.626768)
		(width 0.2286)
		(layer "F.Cu")
		(net "M_DDR3_NODE1_MA4")
	)
	(segment
		(start 74.435462 -39.369238)
		(end 75.014582 -38.790118)
		(width 0.2286)
		(layer "F.Cu")
		(net "M_DDR3_NODE1_MA4")
	)
	(segment
		(start 70.557644 -48.143414)
		(end 70.773544 -48.359314)
		(width 0.2286)
		(layer "F.Cu")
		(net "M_DDR3_NODE1_MA4")
	)
	(segment
		(start 73.348342 -30.766258)
		(end 73.650094 -30.464506)
		(width 0.2286)
		(layer "F.Cu")
		(net "M_DDR3_NODE1_MA4")
	)
	(segment
		(start 73.749916 -36.725098)
		(end 73.749916 -39.049198)
		(width 0.2286)
		(layer "F.Cu")
		(net "M_DDR3_NODE1_MA4")
	)
	(segment
		(start 67.331844 -52.106068)
		(end 67.332098 -52.410868)
		(width 0.2286)
		(layer "F.Cu")
		(net "M_DDR3_NODE1_MA4")
	)
	(segment
		(start 73.228962 -39.264844)
		(end 73.013316 -39.049198)
		(width 0.2286)
		(layer "F.Cu")
		(net "M_DDR3_NODE1_MA4")
	)
	(segment
		(start 61.31814 -55.416958)
		(end 61.317632 -55.416958)
		(width 0.2286)
		(layer "F.Cu")
		(net "M_DDR3_NODE1_MA4")
	)
	(segment
		(start 67.853306 -52.626514)
		(end 73.71842 -46.7614)
		(width 0.2286)
		(layer "F.Cu")
		(net "M_DDR3_NODE1_MA4")
	)
	(segment
		(start 73.013316 -35.307524)
		(end 73.348342 -34.972498)
		(width 0.2286)
		(layer "F.Cu")
		(net "M_DDR3_NODE1_MA4")
	)
	(segment
		(start 61.3156 -59.439556)
		(end 61.3156 -59.353704)
		(width 0.1016)
		(layer "F.Cu")
		(net "M_DDR3_NODE1_MA4")
	)
	(segment
		(start 60.818776 -63.160402)
		(end 60.818522 -63.160402)
		(width 0.1016)
		(layer "F.Cu")
		(net "M_DDR3_NODE1_MA4")
	)
	(segment
		(start 61.3156 -59.353704)
		(end 61.3156 -55.419498)
		(width 0.2286)
		(layer "F.Cu")
		(net "M_DDR3_NODE1_MA4")
	)
	(segment
		(start 74.435462 -40.076628)
		(end 74.435462 -39.369238)
		(width 0.2286)
		(layer "F.Cu")
		(net "M_DDR3_NODE1_MA4")
	)
	(segment
		(start 67.547998 -52.626768)
		(end 67.853306 -52.626514)
		(width 0.2286)
		(layer "F.Cu")
		(net "M_DDR3_NODE1_MA4")
	)
	(segment
		(start 61.3156 -55.419498)
		(end 61.31814 -55.416958)
		(width 0.2286)
		(layer "F.Cu")
		(net "M_DDR3_NODE1_MA4")
	)
	(segment
		(start 60.56757 -61.480192)
		(end 60.77204 -61.275722)
		(width 0.1016)
		(layer "F.Cu")
		(net "M_DDR3_NODE1_MA4")
	)
	(via
		(at 74.435462 -39.369238)
		(size 0.762)
		(drill 0.381)
		(layers "F.Cu" "B.Cu")
		(net "M_DDR3_NODE1_MA4")
	)
	(segment
		(start 13.89507 -28.713684)
		(end 14.02842 -28.580334)
		(width 0.1016)
		(layer "F.Cu")
		(net "N54251541")
	)
	(segment
		(start 13.894562 -29.254704)
		(end 13.89507 -29.254196)
		(width 0.1016)
		(layer "F.Cu")
		(net "N54251541")
	)
	(segment
		(start 13.89507 -29.254196)
		(end 13.89507 -28.713684)
		(width 0.1016)
		(layer "F.Cu")
		(net "N54251541")
	)
	(segment
		(start 15.138146 -26.04516)
		(end 15.138146 -27.470608)
		(width 0.1016)
		(layer "F.Cu")
		(net "N54251541")
	)
	(segment
		(start 15.138146 -27.470608)
		(end 14.02842 -28.580334)
		(width 0.1016)
		(layer "F.Cu")
		(net "N54251541")
	)
	(segment
		(start 13.894562 -29.450284)
		(end 13.894562 -29.254704)
		(width 0.1016)
		(layer "F.Cu")
		(net "N54251541")
	)
	(via
		(at 14.02842 -28.580334)
		(size 0.508)
		(drill 0.254)
		(layers "F.Cu" "B.Cu")
		(net "N54251541")
	)
	(segment
		(start 131.358894 -64.918336)
		(end 130.98145 -64.540892)
		(width 0.1016)
		(layer "F.Cu")
		(net "SATA_SPI_DI_NODE1_R")
	)
	(segment
		(start 130.98018 -64.540892)
		(end 130.98145 -64.540892)
		(width 0.1016)
		(layer "F.Cu")
		(net "SATA_SPI_DI_NODE1_R")
	)
	(segment
		(start 130.98145 -62.181994)
		(end 130.81254 -62.350904)
		(width 0.1016)
		(layer "F.Cu")
		(net "SATA_SPI_DI_NODE1_R")
	)
	(segment
		(start 132.737352 -64.918336)
		(end 131.358894 -64.918336)
		(width 0.1016)
		(layer "F.Cu")
		(net "SATA_SPI_DI_NODE1_R")
	)
	(segment
		(start 130.98145 -61.330332)
		(end 130.98145 -62.181994)
		(width 0.1016)
		(layer "F.Cu")
		(net "SATA_SPI_DI_NODE1_R")
	)
	(segment
		(start 130.81254 -62.350904)
		(end 130.81254 -64.373252)
		(width 0.1016)
		(layer "F.Cu")
		(net "SATA_SPI_DI_NODE1_R")
	)
	(segment
		(start 130.81254 -64.373252)
		(end 130.98018 -64.540892)
		(width 0.1016)
		(layer "F.Cu")
		(net "SATA_SPI_DI_NODE1_R")
	)
	(segment
		(start 131.99745 -61.330332)
		(end 130.98145 -61.330332)
		(width 0.1016)
		(layer "F.Cu")
		(net "SATA_SPI_DI_NODE1_R")
	)
	(via
		(at 130.98145 -64.540892)
		(size 0.508)
		(drill 0.254)
		(layers "F.Cu" "B.Cu")
		(net "SATA_SPI_DI_NODE1_R")
	)
	(segment
		(start 78.764638 -86.974172)
		(end 79.563468 -86.974172)
		(width 0.1016)
		(layer "F.Cu")
		(net "SPI_CPU_NODE1_WP_R_L")
	)
	(segment
		(start 72.181466 -84.093304)
		(end 72.662034 -83.612736)
		(width 0.1016)
		(layer "F.Cu")
		(net "SPI_CPU_NODE1_WP_R_L")
	)
	(segment
		(start 77.69352 -86.117684)
		(end 77.90815 -86.117684)
		(width 0.1016)
		(layer "F.Cu")
		(net "SPI_CPU_NODE1_WP_R_L")
	)
	(segment
		(start 71.816214 -84.214462)
		(end 71.937372 -84.093304)
		(width 0.1016)
		(layer "F.Cu")
		(net "SPI_CPU_NODE1_WP_R_L")
	)
	(segment
		(start 79.563468 -87.979504)
		(end 79.563468 -88.995504)
		(width 0.1016)
		(layer "F.Cu")
		(net "SPI_CPU_NODE1_WP_R_L")
	)
	(segment
		(start 79.563468 -86.974172)
		(end 79.563468 -87.979504)
		(width 0.1016)
		(layer "F.Cu")
		(net "SPI_CPU_NODE1_WP_R_L")
	)
	(segment
		(start 77.90815 -86.117684)
		(end 78.764638 -86.974172)
		(width 0.1016)
		(layer "F.Cu")
		(net "SPI_CPU_NODE1_WP_R_L")
	)
	(segment
		(start 71.937372 -84.093304)
		(end 72.181466 -84.093304)
		(width 0.1016)
		(layer "F.Cu")
		(net "SPI_CPU_NODE1_WP_R_L")
	)
	(segment
		(start 71.345044 -84.214462)
		(end 71.816214 -84.214462)
		(width 0.1016)
		(layer "F.Cu")
		(net "SPI_CPU_NODE1_WP_R_L")
	)
	(via
		(at 77.69352 -86.117684)
		(size 0.508)
		(drill 0.254)
		(layers "F.Cu" "B.Cu")
		(net "SPI_CPU_NODE1_WP_R_L")
	)
	(via
		(at 72.662034 -83.612736)
		(size 0.508)
		(drill 0.254)
		(layers "F.Cu" "B.Cu")
		(net "SPI_CPU_NODE1_WP_R_L")
	)
	(segment
		(start 74.312272 -83.612736)
		(end 76.81722 -86.117684)
		(width 0.1143)
		(layer "In2.Cu")
		(net "SPI_CPU_NODE1_WP_R_L")
	)
	(segment
		(start 76.81722 -86.117684)
		(end 77.69352 -86.117684)
		(width 0.1143)
		(layer "In2.Cu")
		(net "SPI_CPU_NODE1_WP_R_L")
	)
	(segment
		(start 72.662034 -83.612736)
		(end 74.312272 -83.612736)
		(width 0.1143)
		(layer "In2.Cu")
		(net "SPI_CPU_NODE1_WP_R_L")
	)
	(segment
		(start 75.917044 -27.363928)
		(end 76.200762 -27.647646)
		(width 0.1651)
		(layer "F.Cu")
		(net "M_DDR3_NODE1_CK1P")
	)
	(segment
		(start 74.646028 -26.656284)
		(end 74.646028 -27.075892)
		(width 0.1651)
		(layer "F.Cu")
		(net "M_DDR3_NODE1_CK1P")
	)
	(segment
		(start 76.200762 -27.916378)
		(end 76.05014 -28.067)
		(width 0.1651)
		(layer "F.Cu")
		(net "M_DDR3_NODE1_CK1P")
	)
	(segment
		(start 76.05014 -28.067)
		(end 76.05014 -29.149802)
		(width 0.1651)
		(layer "F.Cu")
		(net "M_DDR3_NODE1_CK1P")
	)
	(segment
		(start 76.200762 -27.647646)
		(end 76.200762 -27.916378)
		(width 0.1651)
		(layer "F.Cu")
		(net "M_DDR3_NODE1_CK1P")
	)
	(segment
		(start 74.934064 -27.363928)
		(end 75.917044 -27.363928)
		(width 0.1651)
		(layer "F.Cu")
		(net "M_DDR3_NODE1_CK1P")
	)
	(segment
		(start 74.149458 -26.159714)
		(end 74.646028 -26.656284)
		(width 0.1651)
		(layer "F.Cu")
		(net "M_DDR3_NODE1_CK1P")
	)
	(segment
		(start 74.646028 -27.075892)
		(end 74.934064 -27.363928)
		(width 0.1651)
		(layer "F.Cu")
		(net "M_DDR3_NODE1_CK1P")
	)
	(segment
		(start 61.743082 -66.217038)
		(end 61.369702 -66.590418)
		(width 0.09906)
		(layer "F.Cu")
		(net "M_DDR3_NODE1_CK1P")
	)
	(segment
		(start 61.369702 -66.590418)
		(end 61.369702 -66.598038)
		(width 0.09906)
		(layer "F.Cu")
		(net "M_DDR3_NODE1_CK1P")
	)
	(via
		(at 74.149458 -26.159714)
		(size 0.508)
		(drill 0.254)
		(layers "F.Cu" "B.Cu")
		(net "M_DDR3_NODE1_CK1P")
	)
	(via
		(at 61.369702 -66.598038)
		(size 0.508)
		(drill 0.254)
		(layers "F.Cu" "B.Cu")
		(net "M_DDR3_NODE1_CK1P")
	)
	(segment
		(start 70.206108 -45.473366)
		(end 70.786498 -46.053756)
		(width 0.2032)
		(layer "In2.Cu")
		(net "M_DDR3_NODE1_CK1P")
	)
	(segment
		(start 73.043796 -37.546788)
		(end 72.642222 -37.948362)
		(width 0.2032)
		(layer "In2.Cu")
		(net "M_DDR3_NODE1_CK1P")
	)
	(segment
		(start 72.642222 -35.865562)
		(end 72.642222 -36.434014)
		(width 0.2032)
		(layer "In2.Cu")
		(net "M_DDR3_NODE1_CK1P")
	)
	(segment
		(start 73.8378 -34.955988)
		(end 73.8378 -35.260788)
		(width 0.2032)
		(layer "In2.Cu")
		(net "M_DDR3_NODE1_CK1P")
	)
	(segment
		(start 73.75398 -29.495242)
		(end 73.75398 -31.534354)
		(width 0.2032)
		(layer "In2.Cu")
		(net "M_DDR3_NODE1_CK1P")
	)
	(segment
		(start 61.940948 -65.514474)
		(end 61.940948 -65.527682)
		(width 0.09906)
		(layer "In2.Cu")
		(net "M_DDR3_NODE1_CK1P")
	)
	(segment
		(start 73.336912 -41.358312)
		(end 72.115934 -41.358312)
		(width 0.2032)
		(layer "In2.Cu")
		(net "M_DDR3_NODE1_CK1P")
	)
	(segment
		(start 72.642222 -34.351214)
		(end 73.043796 -34.752788)
		(width 0.2032)
		(layer "In2.Cu")
		(net "M_DDR3_NODE1_CK1P")
	)
	(segment
		(start 62.004448 -66.484754)
		(end 61.891164 -66.598038)
		(width 0.09906)
		(layer "In2.Cu")
		(net "M_DDR3_NODE1_CK1P")
	)
	(segment
		(start 70.786498 -46.347888)
		(end 70.094094 -47.040292)
		(width 0.2032)
		(layer "In2.Cu")
		(net "M_DDR3_NODE1_CK1P")
	)
	(segment
		(start 74.149458 -26.159714)
		(end 74.62266 -26.632916)
		(width 0.2032)
		(layer "In2.Cu")
		(net "M_DDR3_NODE1_CK1P")
	)
	(segment
		(start 72.642222 -37.948362)
		(end 72.642222 -38.825424)
		(width 0.2032)
		(layer "In2.Cu")
		(net "M_DDR3_NODE1_CK1P")
	)
	(segment
		(start 61.434218 -65.199006)
		(end 61.775086 -65.199006)
		(width 0.2032)
		(layer "In2.Cu")
		(net "M_DDR3_NODE1_CK1P")
	)
	(segment
		(start 73.6346 -35.463988)
		(end 73.043796 -35.463988)
		(width 0.2032)
		(layer "In2.Cu")
		(net "M_DDR3_NODE1_CK1P")
	)
	(segment
		(start 74.8284 -28.420822)
		(end 73.75398 -29.495242)
		(width 0.2032)
		(layer "In2.Cu")
		(net "M_DDR3_NODE1_CK1P")
	)
	(segment
		(start 73.640696 -31.647638)
		(end 72.982836 -31.647638)
		(width 0.2032)
		(layer "In2.Cu")
		(net "M_DDR3_NODE1_CK1P")
	)
	(segment
		(start 73.043796 -34.752788)
		(end 73.6346 -34.752788)
		(width 0.2032)
		(layer "In2.Cu")
		(net "M_DDR3_NODE1_CK1P")
	)
	(segment
		(start 74.62266 -26.632916)
		(end 74.62266 -27.171142)
		(width 0.2032)
		(layer "In2.Cu")
		(net "M_DDR3_NODE1_CK1P")
	)
	(segment
		(start 73.6346 -34.752788)
		(end 73.8378 -34.955988)
		(width 0.2032)
		(layer "In2.Cu")
		(net "M_DDR3_NODE1_CK1P")
	)
	(segment
		(start 62.357 -62.779402)
		(end 61.073538 -64.062864)
		(width 0.2032)
		(layer "In2.Cu")
		(net "M_DDR3_NODE1_CK1P")
	)
	(segment
		(start 74.23658 -37.043868)
		(end 74.23658 -37.338508)
		(width 0.2032)
		(layer "In2.Cu")
		(net "M_DDR3_NODE1_CK1P")
	)
	(segment
		(start 72.642222 -31.988252)
		(end 72.642222 -34.351214)
		(width 0.2032)
		(layer "In2.Cu")
		(net "M_DDR3_NODE1_CK1P")
	)
	(segment
		(start 61.940948 -65.527682)
		(end 62.004448 -65.591182)
		(width 0.09906)
		(layer "In2.Cu")
		(net "M_DDR3_NODE1_CK1P")
	)
	(segment
		(start 74.8284 -27.376882)
		(end 74.8284 -28.420822)
		(width 0.2032)
		(layer "In2.Cu")
		(net "M_DDR3_NODE1_CK1P")
	)
	(segment
		(start 72.642222 -36.434014)
		(end 73.043796 -36.835588)
		(width 0.2032)
		(layer "In2.Cu")
		(net "M_DDR3_NODE1_CK1P")
	)
	(segment
		(start 74.0283 -36.835588)
		(end 74.23658 -37.043868)
		(width 0.2032)
		(layer "In2.Cu")
		(net "M_DDR3_NODE1_CK1P")
	)
	(segment
		(start 73.6854 -41.009824)
		(end 73.336912 -41.358312)
		(width 0.2032)
		(layer "In2.Cu")
		(net "M_DDR3_NODE1_CK1P")
	)
	(segment
		(start 74.0283 -37.546788)
		(end 73.043796 -37.546788)
		(width 0.2032)
		(layer "In2.Cu")
		(net "M_DDR3_NODE1_CK1P")
	)
	(segment
		(start 62.004448 -65.591182)
		(end 62.004448 -66.484754)
		(width 0.09906)
		(layer "In2.Cu")
		(net "M_DDR3_NODE1_CK1P")
	)
	(segment
		(start 73.37298 -43.761406)
		(end 72.050656 -45.08373)
		(width 0.2032)
		(layer "In2.Cu")
		(net "M_DDR3_NODE1_CK1P")
	)
	(segment
		(start 62.357 -54.777386)
		(end 62.357 -62.779402)
		(width 0.2032)
		(layer "In2.Cu")
		(net "M_DDR3_NODE1_CK1P")
	)
	(segment
		(start 73.37298 -42.938192)
		(end 73.37298 -43.761406)
		(width 0.2032)
		(layer "In2.Cu")
		(net "M_DDR3_NODE1_CK1P")
	)
	(segment
		(start 68.75018 -47.937928)
		(end 68.75018 -48.383952)
		(width 0.2032)
		(layer "In2.Cu")
		(net "M_DDR3_NODE1_CK1P")
	)
	(segment
		(start 73.1647 -42.729912)
		(end 73.37298 -42.938192)
		(width 0.2032)
		(layer "In2.Cu")
		(net "M_DDR3_NODE1_CK1P")
	)
	(segment
		(start 72.642222 -38.825424)
		(end 73.6854 -39.868602)
		(width 0.2032)
		(layer "In2.Cu")
		(net "M_DDR3_NODE1_CK1P")
	)
	(segment
		(start 70.786498 -46.053756)
		(end 70.786498 -46.347888)
		(width 0.2032)
		(layer "In2.Cu")
		(net "M_DDR3_NODE1_CK1P")
	)
	(segment
		(start 70.614794 -44.50334)
		(end 70.206108 -44.912026)
		(width 0.2032)
		(layer "In2.Cu")
		(net "M_DDR3_NODE1_CK1P")
	)
	(segment
		(start 69.647816 -47.040292)
		(end 68.75018 -47.937928)
		(width 0.2032)
		(layer "In2.Cu")
		(net "M_DDR3_NODE1_CK1P")
	)
	(segment
		(start 61.775086 -65.199006)
		(end 61.940948 -65.364868)
		(width 0.2032)
		(layer "In2.Cu")
		(net "M_DDR3_NODE1_CK1P")
	)
	(segment
		(start 61.073538 -64.838326)
		(end 61.434218 -65.199006)
		(width 0.2032)
		(layer "In2.Cu")
		(net "M_DDR3_NODE1_CK1P")
	)
	(segment
		(start 74.23658 -37.338508)
		(end 74.0283 -37.546788)
		(width 0.2032)
		(layer "In2.Cu")
		(net "M_DDR3_NODE1_CK1P")
	)
	(segment
		(start 73.043796 -36.835588)
		(end 74.0283 -36.835588)
		(width 0.2032)
		(layer "In2.Cu")
		(net "M_DDR3_NODE1_CK1P")
	)
	(segment
		(start 71.756524 -45.08373)
		(end 71.176134 -44.50334)
		(width 0.2032)
		(layer "In2.Cu")
		(net "M_DDR3_NODE1_CK1P")
	)
	(segment
		(start 72.050656 -45.08373)
		(end 71.756524 -45.08373)
		(width 0.2032)
		(layer "In2.Cu")
		(net "M_DDR3_NODE1_CK1P")
	)
	(segment
		(start 73.8378 -35.260788)
		(end 73.6346 -35.463988)
		(width 0.2032)
		(layer "In2.Cu")
		(net "M_DDR3_NODE1_CK1P")
	)
	(segment
		(start 70.094094 -47.040292)
		(end 69.647816 -47.040292)
		(width 0.2032)
		(layer "In2.Cu")
		(net "M_DDR3_NODE1_CK1P")
	)
	(segment
		(start 61.073538 -64.062864)
		(end 61.073538 -64.838326)
		(width 0.2032)
		(layer "In2.Cu")
		(net "M_DDR3_NODE1_CK1P")
	)
	(segment
		(start 61.940948 -65.364868)
		(end 61.940948 -65.514474)
		(width 0.2032)
		(layer "In2.Cu")
		(net "M_DDR3_NODE1_CK1P")
	)
	(segment
		(start 74.62266 -27.171142)
		(end 74.8284 -27.376882)
		(width 0.2032)
		(layer "In2.Cu")
		(net "M_DDR3_NODE1_CK1P")
	)
	(segment
		(start 72.115934 -41.358312)
		(end 71.71944 -41.754806)
		(width 0.2032)
		(layer "In2.Cu")
		(net "M_DDR3_NODE1_CK1P")
	)
	(segment
		(start 71.71944 -42.333418)
		(end 72.115934 -42.729912)
		(width 0.2032)
		(layer "In2.Cu")
		(net "M_DDR3_NODE1_CK1P")
	)
	(segment
		(start 61.891164 -66.598038)
		(end 61.369702 -66.598038)
		(width 0.09906)
		(layer "In2.Cu")
		(net "M_DDR3_NODE1_CK1P")
	)
	(segment
		(start 71.176134 -44.50334)
		(end 70.614794 -44.50334)
		(width 0.2032)
		(layer "In2.Cu")
		(net "M_DDR3_NODE1_CK1P")
	)
	(segment
		(start 72.115934 -42.729912)
		(end 73.1647 -42.729912)
		(width 0.2032)
		(layer "In2.Cu")
		(net "M_DDR3_NODE1_CK1P")
	)
	(segment
		(start 70.206108 -44.912026)
		(end 70.206108 -45.473366)
		(width 0.2032)
		(layer "In2.Cu")
		(net "M_DDR3_NODE1_CK1P")
	)
	(segment
		(start 71.71944 -41.754806)
		(end 71.71944 -42.333418)
		(width 0.2032)
		(layer "In2.Cu")
		(net "M_DDR3_NODE1_CK1P")
	)
	(segment
		(start 73.75398 -31.534354)
		(end 73.640696 -31.647638)
		(width 0.2032)
		(layer "In2.Cu")
		(net "M_DDR3_NODE1_CK1P")
	)
	(segment
		(start 73.043796 -35.463988)
		(end 72.642222 -35.865562)
		(width 0.2032)
		(layer "In2.Cu")
		(net "M_DDR3_NODE1_CK1P")
	)
	(segment
		(start 68.75018 -48.383952)
		(end 62.357 -54.777386)
		(width 0.2032)
		(layer "In2.Cu")
		(net "M_DDR3_NODE1_CK1P")
	)
	(segment
		(start 72.982836 -31.647638)
		(end 72.642222 -31.988252)
		(width 0.2032)
		(layer "In2.Cu")
		(net "M_DDR3_NODE1_CK1P")
	)
	(segment
		(start 73.6854 -39.868602)
		(end 73.6854 -41.009824)
		(width 0.2032)
		(layer "In2.Cu")
		(net "M_DDR3_NODE1_CK1P")
	)
	(segment
		(start 13.838174 -18.956528)
		(end 13.741654 -18.860008)
		(width 0.1016)
		(layer "F.Cu")
		(net "N54251519")
	)
	(segment
		(start 13.965174 -16.660622)
		(end 13.965174 -18.636488)
		(width 0.1016)
		(layer "F.Cu")
		(net "N54251519")
	)
	(segment
		(start 13.965174 -18.636488)
		(end 13.741654 -18.860008)
		(width 0.1016)
		(layer "F.Cu")
		(net "N54251519")
	)
	(segment
		(start 13.838174 -20.20316)
		(end 13.838174 -18.956528)
		(width 0.1016)
		(layer "F.Cu")
		(net "N54251519")
	)
	(via
		(at 13.741654 -18.860008)
		(size 0.508)
		(drill 0.254)
		(layers "F.Cu" "B.Cu")
		(net "N54251519")
	)
	(segment
		(start 150.310596 -73.19899)
		(end 150.310596 -72.387206)
		(width 0.127)
		(layer "F.Cu")
		(net "P2E_CPU_SATA_NODE1_RX_C_DN")
	)
	(segment
		(start 148.682964 -70.455282)
		(end 150.310596 -72.082914)
		(width 0.127)
		(layer "F.Cu")
		(net "P2E_CPU_SATA_NODE1_RX_C_DN")
	)
	(segment
		(start 150.310596 -72.082914)
		(end 150.310596 -72.387206)
		(width 0.127)
		(layer "F.Cu")
		(net "P2E_CPU_SATA_NODE1_RX_C_DN")
	)
	(segment
		(start 148.730462 -69.472048)
		(end 148.682964 -69.638418)
		(width 0.127)
		(layer "F.Cu")
		(net "P2E_CPU_SATA_NODE1_RX_C_DN")
	)
	(segment
		(start 148.730462 -68.799202)
		(end 148.730462 -69.472048)
		(width 0.127)
		(layer "F.Cu")
		(net "P2E_CPU_SATA_NODE1_RX_C_DN")
	)
	(segment
		(start 150.649178 -73.537572)
		(end 150.310596 -73.19899)
		(width 0.127)
		(layer "F.Cu")
		(net "P2E_CPU_SATA_NODE1_RX_C_DN")
	)
	(segment
		(start 148.682964 -69.638418)
		(end 148.682964 -70.455282)
		(width 0.127)
		(layer "F.Cu")
		(net "P2E_CPU_SATA_NODE1_RX_C_DN")
	)
	(via
		(at 150.310596 -72.387206)
		(size 0.4064)
		(drill 0.2032)
		(layers "F.Cu" "B.Cu")
		(net "P2E_CPU_SATA_NODE1_RX_C_DN")
	)
	(segment
		(start 64.786002 -93.715332)
		(end 64.897762 -93.827092)
		(width 0.1016)
		(layer "F.Cu")
		(net "LPC_CPU_NODE1_R_CLKOUT0")
	)
	(segment
		(start 66.176144 -94.843854)
		(end 66.176144 -95.050864)
		(width 0.1016)
		(layer "F.Cu")
		(net "LPC_CPU_NODE1_R_CLKOUT0")
	)
	(segment
		(start 63.317628 -90.113104)
		(end 63.317628 -92.772484)
		(width 0.1016)
		(layer "F.Cu")
		(net "LPC_CPU_NODE1_R_CLKOUT0")
	)
	(segment
		(start 67.241166 -96.244156)
		(end 66.176144 -95.179134)
		(width 0.1016)
		(layer "F.Cu")
		(net "LPC_CPU_NODE1_R_CLKOUT0")
	)
	(segment
		(start 64.897762 -93.827092)
		(end 65.159382 -93.827092)
		(width 0.1016)
		(layer "F.Cu")
		(net "LPC_CPU_NODE1_R_CLKOUT0")
	)
	(segment
		(start 67.241166 -96.309942)
		(end 67.241166 -96.244156)
		(width 0.1016)
		(layer "F.Cu")
		(net "LPC_CPU_NODE1_R_CLKOUT0")
	)
	(segment
		(start 66.176144 -95.179134)
		(end 66.176144 -95.050864)
		(width 0.1016)
		(layer "F.Cu")
		(net "LPC_CPU_NODE1_R_CLKOUT0")
	)
	(segment
		(start 63.12154 -88.551766)
		(end 63.12154 -89.917016)
		(width 0.1016)
		(layer "F.Cu")
		(net "LPC_CPU_NODE1_R_CLKOUT0")
	)
	(segment
		(start 63.317628 -92.772484)
		(end 64.260476 -93.715332)
		(width 0.1016)
		(layer "F.Cu")
		(net "LPC_CPU_NODE1_R_CLKOUT0")
	)
	(segment
		(start 65.159382 -93.827092)
		(end 66.176144 -94.843854)
		(width 0.1016)
		(layer "F.Cu")
		(net "LPC_CPU_NODE1_R_CLKOUT0")
	)
	(segment
		(start 63.12154 -89.917016)
		(end 63.317628 -90.113104)
		(width 0.1016)
		(layer "F.Cu")
		(net "LPC_CPU_NODE1_R_CLKOUT0")
	)
	(segment
		(start 64.260476 -93.715332)
		(end 64.786002 -93.715332)
		(width 0.1016)
		(layer "F.Cu")
		(net "LPC_CPU_NODE1_R_CLKOUT0")
	)
	(via
		(at 66.176144 -95.050864)
		(size 0.508)
		(drill 0.254)
		(layers "F.Cu" "B.Cu")
		(net "LPC_CPU_NODE1_R_CLKOUT0")
	)
	(segment
		(start 45.151802 -30.748478)
		(end 46.165262 -30.748478)
		(width 0.1651)
		(layer "F.Cu")
		(net "M1_DQ_NODE1_DQ12")
	)
	(segment
		(start 46.731174 -59.81446)
		(end 46.731174 -60.237878)
		(width 0.1016)
		(layer "F.Cu")
		(net "M1_DQ_NODE1_DQ12")
	)
	(segment
		(start 46.165262 -30.748478)
		(end 46.650148 -30.263592)
		(width 0.1651)
		(layer "F.Cu")
		(net "M1_DQ_NODE1_DQ12")
	)
	(segment
		(start 47.217584 -60.724288)
		(end 47.217584 -62.10808)
		(width 0.1016)
		(layer "F.Cu")
		(net "M1_DQ_NODE1_DQ12")
	)
	(segment
		(start 46.6217 -59.70524)
		(end 46.621954 -59.70524)
		(width 0.1016)
		(layer "F.Cu")
		(net "M1_DQ_NODE1_DQ12")
	)
	(segment
		(start 46.621954 -59.70524)
		(end 46.731174 -59.81446)
		(width 0.1016)
		(layer "F.Cu")
		(net "M1_DQ_NODE1_DQ12")
	)
	(segment
		(start 46.650148 -30.263592)
		(end 46.650148 -29.149802)
		(width 0.1651)
		(layer "F.Cu")
		(net "M1_DQ_NODE1_DQ12")
	)
	(segment
		(start 47.217584 -62.10808)
		(end 47.659544 -62.55004)
		(width 0.1016)
		(layer "F.Cu")
		(net "M1_DQ_NODE1_DQ12")
	)
	(segment
		(start 46.731174 -60.237878)
		(end 47.217584 -60.724288)
		(width 0.1016)
		(layer "F.Cu")
		(net "M1_DQ_NODE1_DQ12")
	)
	(via
		(at 45.151802 -30.748478)
		(size 0.508)
		(drill 0.254)
		(layers "F.Cu" "B.Cu")
		(net "M1_DQ_NODE1_DQ12")
	)
	(via
		(at 46.6217 -59.70524)
		(size 0.508)
		(drill 0.254)
		(layers "F.Cu" "B.Cu")
		(net "M1_DQ_NODE1_DQ12")
	)
	(segment
		(start 33.18764 -46.672246)
		(end 33.48482 -46.672246)
		(width 0.2032)
		(layer "In2.Cu")
		(net "M1_DQ_NODE1_DQ12")
	)
	(segment
		(start 33.48482 -48.805846)
		(end 33.18764 -48.805846)
		(width 0.2032)
		(layer "In2.Cu")
		(net "M1_DQ_NODE1_DQ12")
	)
	(segment
		(start 40.420036 -59.490864)
		(end 44.680124 -59.490864)
		(width 0.2032)
		(layer "In2.Cu")
		(net "M1_DQ_NODE1_DQ12")
	)
	(segment
		(start 40.009572 -31.158688)
		(end 39.25316 -31.9151)
		(width 0.2032)
		(layer "In2.Cu")
		(net "M1_DQ_NODE1_DQ12")
	)
	(segment
		(start 33.48482 -51.650646)
		(end 33.18764 -51.650646)
		(width 0.2032)
		(layer "In2.Cu")
		(net "M1_DQ_NODE1_DQ12")
	)
	(segment
		(start 32.97936 -53.281326)
		(end 32.97936 -53.575966)
		(width 0.2032)
		(layer "In2.Cu")
		(net "M1_DQ_NODE1_DQ12")
	)
	(segment
		(start 32.97936 -52.153566)
		(end 33.18764 -52.361846)
		(width 0.2032)
		(layer "In2.Cu")
		(net "M1_DQ_NODE1_DQ12")
	)
	(segment
		(start 36.094162 -58.485786)
		(end 36.669472 -59.061096)
		(width 0.2032)
		(layer "In2.Cu")
		(net "M1_DQ_NODE1_DQ12")
	)
	(segment
		(start 32.97936 -49.308766)
		(end 33.18764 -49.517046)
		(width 0.2032)
		(layer "In2.Cu")
		(net "M1_DQ_NODE1_DQ12")
	)
	(segment
		(start 32.97936 -43.619166)
		(end 33.18764 -43.827446)
		(width 0.2032)
		(layer "In2.Cu")
		(net "M1_DQ_NODE1_DQ12")
	)
	(segment
		(start 33.48482 -40.271446)
		(end 33.18764 -40.271446)
		(width 0.2032)
		(layer "In2.Cu")
		(net "M1_DQ_NODE1_DQ12")
	)
	(segment
		(start 33.6931 -48.302926)
		(end 33.6931 -48.597566)
		(width 0.2032)
		(layer "In2.Cu")
		(net "M1_DQ_NODE1_DQ12")
	)
	(segment
		(start 33.18764 -49.517046)
		(end 33.48482 -49.517046)
		(width 0.2032)
		(layer "In2.Cu")
		(net "M1_DQ_NODE1_DQ12")
	)
	(segment
		(start 32.97936 -47.886366)
		(end 33.18764 -48.094646)
		(width 0.2032)
		(layer "In2.Cu")
		(net "M1_DQ_NODE1_DQ12")
	)
	(segment
		(start 34.92754 -57.319164)
		(end 35.296602 -57.688226)
		(width 0.2032)
		(layer "In2.Cu")
		(net "M1_DQ_NODE1_DQ12")
	)
	(segment
		(start 33.16224 -55.4228)
		(end 33.48482 -55.4228)
		(width 0.2032)
		(layer "In2.Cu")
		(net "M1_DQ_NODE1_DQ12")
	)
	(segment
		(start 33.18764 -53.784246)
		(end 33.48482 -53.784246)
		(width 0.2032)
		(layer "In2.Cu")
		(net "M1_DQ_NODE1_DQ12")
	)
	(segment
		(start 32.97936 -45.041566)
		(end 33.18764 -45.249846)
		(width 0.2032)
		(layer "In2.Cu")
		(net "M1_DQ_NODE1_DQ12")
	)
	(segment
		(start 41.34612 -30.905958)
		(end 41.09339 -31.158688)
		(width 0.2032)
		(layer "In2.Cu")
		(net "M1_DQ_NODE1_DQ12")
	)
	(segment
		(start 33.48482 -42.405046)
		(end 33.6931 -42.613326)
		(width 0.2032)
		(layer "In2.Cu")
		(net "M1_DQ_NODE1_DQ12")
	)
	(segment
		(start 33.18764 -40.271446)
		(end 32.97936 -40.479726)
		(width 0.2032)
		(layer "In2.Cu")
		(net "M1_DQ_NODE1_DQ12")
	)
	(segment
		(start 32.97936 -53.575966)
		(end 33.18764 -53.784246)
		(width 0.2032)
		(layer "In2.Cu")
		(net "M1_DQ_NODE1_DQ12")
	)
	(segment
		(start 39.990268 -59.061096)
		(end 40.420036 -59.490864)
		(width 0.2032)
		(layer "In2.Cu")
		(net "M1_DQ_NODE1_DQ12")
	)
	(segment
		(start 33.6931 -41.190926)
		(end 33.6931 -41.485566)
		(width 0.2032)
		(layer "In2.Cu")
		(net "M1_DQ_NODE1_DQ12")
	)
	(segment
		(start 45.151802 -30.748478)
		(end 45.151802 -30.689296)
		(width 0.2032)
		(layer "In2.Cu")
		(net "M1_DQ_NODE1_DQ12")
	)
	(segment
		(start 33.18764 -43.827446)
		(end 33.48482 -43.827446)
		(width 0.2032)
		(layer "In2.Cu")
		(net "M1_DQ_NODE1_DQ12")
	)
	(segment
		(start 32.97936 -51.858926)
		(end 32.97936 -52.153566)
		(width 0.2032)
		(layer "In2.Cu")
		(net "M1_DQ_NODE1_DQ12")
	)
	(segment
		(start 33.48482 -44.538646)
		(end 33.18764 -44.538646)
		(width 0.2032)
		(layer "In2.Cu")
		(net "M1_DQ_NODE1_DQ12")
	)
	(segment
		(start 33.18764 -45.249846)
		(end 33.48482 -45.249846)
		(width 0.2032)
		(layer "In2.Cu")
		(net "M1_DQ_NODE1_DQ12")
	)
	(segment
		(start 32.97936 -40.479726)
		(end 32.97936 -40.774366)
		(width 0.2032)
		(layer "In2.Cu")
		(net "M1_DQ_NODE1_DQ12")
	)
	(segment
		(start 33.6931 -44.330366)
		(end 33.48482 -44.538646)
		(width 0.2032)
		(layer "In2.Cu")
		(net "M1_DQ_NODE1_DQ12")
	)
	(segment
		(start 33.48482 -53.073046)
		(end 33.18764 -53.073046)
		(width 0.2032)
		(layer "In2.Cu")
		(net "M1_DQ_NODE1_DQ12")
	)
	(segment
		(start 33.18764 -51.650646)
		(end 32.97936 -51.858926)
		(width 0.2032)
		(layer "In2.Cu")
		(net "M1_DQ_NODE1_DQ12")
	)
	(segment
		(start 33.48482 -40.982646)
		(end 33.6931 -41.190926)
		(width 0.2032)
		(layer "In2.Cu")
		(net "M1_DQ_NODE1_DQ12")
	)
	(segment
		(start 33.48482 -45.249846)
		(end 33.6931 -45.458126)
		(width 0.2032)
		(layer "In2.Cu")
		(net "M1_DQ_NODE1_DQ12")
	)
	(segment
		(start 33.18764 -48.805846)
		(end 32.97936 -49.014126)
		(width 0.2032)
		(layer "In2.Cu")
		(net "M1_DQ_NODE1_DQ12")
	)
	(segment
		(start 33.48482 -46.672246)
		(end 33.6931 -46.880526)
		(width 0.2032)
		(layer "In2.Cu")
		(net "M1_DQ_NODE1_DQ12")
	)
	(segment
		(start 33.6931 -51.147726)
		(end 33.6931 -51.442366)
		(width 0.2032)
		(layer "In2.Cu")
		(net "M1_DQ_NODE1_DQ12")
	)
	(segment
		(start 32.97936 -41.902126)
		(end 32.97936 -42.196766)
		(width 0.2032)
		(layer "In2.Cu")
		(net "M1_DQ_NODE1_DQ12")
	)
	(segment
		(start 33.18764 -47.383446)
		(end 32.97936 -47.591726)
		(width 0.2032)
		(layer "In2.Cu")
		(net "M1_DQ_NODE1_DQ12")
	)
	(segment
		(start 34.937954 -58.341514)
		(end 34.937954 -58.636154)
		(width 0.2032)
		(layer "In2.Cu")
		(net "M1_DQ_NODE1_DQ12")
	)
	(segment
		(start 33.6931 -48.597566)
		(end 33.48482 -48.805846)
		(width 0.2032)
		(layer "In2.Cu")
		(net "M1_DQ_NODE1_DQ12")
	)
	(segment
		(start 32.97936 -46.169326)
		(end 32.97936 -46.463966)
		(width 0.2032)
		(layer "In2.Cu")
		(net "M1_DQ_NODE1_DQ12")
	)
	(segment
		(start 32.97936 -49.014126)
		(end 32.97936 -49.308766)
		(width 0.2032)
		(layer "In2.Cu")
		(net "M1_DQ_NODE1_DQ12")
	)
	(segment
		(start 41.34612 -30.351984)
		(end 41.34612 -30.905958)
		(width 0.2032)
		(layer "In2.Cu")
		(net "M1_DQ_NODE1_DQ12")
	)
	(segment
		(start 45.151802 -30.689296)
		(end 44.584112 -30.121606)
		(width 0.2032)
		(layer "In2.Cu")
		(net "M1_DQ_NODE1_DQ12")
	)
	(segment
		(start 33.6931 -53.992526)
		(end 33.6931 -54.50332)
		(width 0.2032)
		(layer "In2.Cu")
		(net "M1_DQ_NODE1_DQ12")
	)
	(segment
		(start 33.16224 -54.7116)
		(end 32.95396 -54.91988)
		(width 0.2032)
		(layer "In2.Cu")
		(net "M1_DQ_NODE1_DQ12")
	)
	(segment
		(start 33.6931 -52.570126)
		(end 33.6931 -52.864766)
		(width 0.2032)
		(layer "In2.Cu")
		(net "M1_DQ_NODE1_DQ12")
	)
	(segment
		(start 32.97936 -43.324526)
		(end 32.97936 -43.619166)
		(width 0.2032)
		(layer "In2.Cu")
		(net "M1_DQ_NODE1_DQ12")
	)
	(segment
		(start 33.6931 -44.035726)
		(end 33.6931 -44.330366)
		(width 0.2032)
		(layer "In2.Cu")
		(net "M1_DQ_NODE1_DQ12")
	)
	(segment
		(start 33.48482 -49.517046)
		(end 33.6931 -49.725326)
		(width 0.2032)
		(layer "In2.Cu")
		(net "M1_DQ_NODE1_DQ12")
	)
	(segment
		(start 32.97936 -50.731166)
		(end 33.18764 -50.939446)
		(width 0.2032)
		(layer "In2.Cu")
		(net "M1_DQ_NODE1_DQ12")
	)
	(segment
		(start 36.669472 -59.061096)
		(end 39.990268 -59.061096)
		(width 0.2032)
		(layer "In2.Cu")
		(net "M1_DQ_NODE1_DQ12")
	)
	(segment
		(start 34.401252 -56.633872)
		(end 34.695892 -56.633872)
		(width 0.2032)
		(layer "In2.Cu")
		(net "M1_DQ_NODE1_DQ12")
	)
	(segment
		(start 33.48482 -50.939446)
		(end 33.6931 -51.147726)
		(width 0.2032)
		(layer "In2.Cu")
		(net "M1_DQ_NODE1_DQ12")
	)
	(segment
		(start 33.6931 -54.50332)
		(end 33.48482 -54.7116)
		(width 0.2032)
		(layer "In2.Cu")
		(net "M1_DQ_NODE1_DQ12")
	)
	(segment
		(start 44.680124 -59.490864)
		(end 44.888404 -59.699144)
		(width 0.2032)
		(layer "In2.Cu")
		(net "M1_DQ_NODE1_DQ12")
	)
	(segment
		(start 39.25316 -33.121854)
		(end 33.6931 -38.681914)
		(width 0.2032)
		(layer "In2.Cu")
		(net "M1_DQ_NODE1_DQ12")
	)
	(segment
		(start 33.6931 -42.613326)
		(end 33.6931 -42.907966)
		(width 0.2032)
		(layer "In2.Cu")
		(net "M1_DQ_NODE1_DQ12")
	)
	(segment
		(start 33.6931 -51.442366)
		(end 33.48482 -51.650646)
		(width 0.2032)
		(layer "In2.Cu")
		(net "M1_DQ_NODE1_DQ12")
	)
	(segment
		(start 33.48482 -43.116246)
		(end 33.18764 -43.116246)
		(width 0.2032)
		(layer "In2.Cu")
		(net "M1_DQ_NODE1_DQ12")
	)
	(segment
		(start 45.901864 -59.943238)
		(end 46.383702 -59.943238)
		(width 0.2032)
		(layer "In2.Cu")
		(net "M1_DQ_NODE1_DQ12")
	)
	(segment
		(start 34.695892 -56.633872)
		(end 34.92754 -56.86552)
		(width 0.2032)
		(layer "In2.Cu")
		(net "M1_DQ_NODE1_DQ12")
	)
	(segment
		(start 32.97936 -46.463966)
		(end 33.18764 -46.672246)
		(width 0.2032)
		(layer "In2.Cu")
		(net "M1_DQ_NODE1_DQ12")
	)
	(segment
		(start 33.18764 -41.693846)
		(end 32.97936 -41.902126)
		(width 0.2032)
		(layer "In2.Cu")
		(net "M1_DQ_NODE1_DQ12")
	)
	(segment
		(start 33.18764 -43.116246)
		(end 32.97936 -43.324526)
		(width 0.2032)
		(layer "In2.Cu")
		(net "M1_DQ_NODE1_DQ12")
	)
	(segment
		(start 35.146234 -58.844434)
		(end 35.440874 -58.844434)
		(width 0.2032)
		(layer "In2.Cu")
		(net "M1_DQ_NODE1_DQ12")
	)
	(segment
		(start 33.48482 -55.4228)
		(end 33.898332 -55.836312)
		(width 0.2032)
		(layer "In2.Cu")
		(net "M1_DQ_NODE1_DQ12")
	)
	(segment
		(start 33.18764 -48.094646)
		(end 33.48482 -48.094646)
		(width 0.2032)
		(layer "In2.Cu")
		(net "M1_DQ_NODE1_DQ12")
	)
	(segment
		(start 33.18764 -45.961046)
		(end 32.97936 -46.169326)
		(width 0.2032)
		(layer "In2.Cu")
		(net "M1_DQ_NODE1_DQ12")
	)
	(segment
		(start 45.599604 -60.247784)
		(end 45.599604 -60.245498)
		(width 0.2032)
		(layer "In2.Cu")
		(net "M1_DQ_NODE1_DQ12")
	)
	(segment
		(start 41.576498 -30.121606)
		(end 41.34612 -30.351984)
		(width 0.2032)
		(layer "In2.Cu")
		(net "M1_DQ_NODE1_DQ12")
	)
	(segment
		(start 41.09339 -31.158688)
		(end 40.009572 -31.158688)
		(width 0.2032)
		(layer "In2.Cu")
		(net "M1_DQ_NODE1_DQ12")
	)
	(segment
		(start 33.48482 -52.361846)
		(end 33.6931 -52.570126)
		(width 0.2032)
		(layer "In2.Cu")
		(net "M1_DQ_NODE1_DQ12")
	)
	(segment
		(start 33.18764 -44.538646)
		(end 32.97936 -44.746926)
		(width 0.2032)
		(layer "In2.Cu")
		(net "M1_DQ_NODE1_DQ12")
	)
	(segment
		(start 33.6931 -38.681914)
		(end 33.6931 -40.063166)
		(width 0.2032)
		(layer "In2.Cu")
		(net "M1_DQ_NODE1_DQ12")
	)
	(segment
		(start 33.6931 -40.063166)
		(end 33.48482 -40.271446)
		(width 0.2032)
		(layer "In2.Cu")
		(net "M1_DQ_NODE1_DQ12")
	)
	(segment
		(start 33.6931 -50.019966)
		(end 33.48482 -50.228246)
		(width 0.2032)
		(layer "In2.Cu")
		(net "M1_DQ_NODE1_DQ12")
	)
	(segment
		(start 33.6931 -45.458126)
		(end 33.6931 -45.752766)
		(width 0.2032)
		(layer "In2.Cu")
		(net "M1_DQ_NODE1_DQ12")
	)
	(segment
		(start 33.6931 -45.752766)
		(end 33.48482 -45.961046)
		(width 0.2032)
		(layer "In2.Cu")
		(net "M1_DQ_NODE1_DQ12")
	)
	(segment
		(start 45.096684 -60.456064)
		(end 45.391324 -60.456064)
		(width 0.2032)
		(layer "In2.Cu")
		(net "M1_DQ_NODE1_DQ12")
	)
	(segment
		(start 32.97936 -50.436526)
		(end 32.97936 -50.731166)
		(width 0.2032)
		(layer "In2.Cu")
		(net "M1_DQ_NODE1_DQ12")
	)
	(segment
		(start 32.97936 -42.196766)
		(end 33.18764 -42.405046)
		(width 0.2032)
		(layer "In2.Cu")
		(net "M1_DQ_NODE1_DQ12")
	)
	(segment
		(start 33.6931 -41.485566)
		(end 33.48482 -41.693846)
		(width 0.2032)
		(layer "In2.Cu")
		(net "M1_DQ_NODE1_DQ12")
	)
	(segment
		(start 33.6931 -42.907966)
		(end 33.48482 -43.116246)
		(width 0.2032)
		(layer "In2.Cu")
		(net "M1_DQ_NODE1_DQ12")
	)
	(segment
		(start 33.48482 -45.961046)
		(end 33.18764 -45.961046)
		(width 0.2032)
		(layer "In2.Cu")
		(net "M1_DQ_NODE1_DQ12")
	)
	(segment
		(start 33.898332 -55.836312)
		(end 33.898332 -56.130952)
		(width 0.2032)
		(layer "In2.Cu")
		(net "M1_DQ_NODE1_DQ12")
	)
	(segment
		(start 45.599604 -60.245498)
		(end 45.901864 -59.943238)
		(width 0.2032)
		(layer "In2.Cu")
		(net "M1_DQ_NODE1_DQ12")
	)
	(segment
		(start 33.6931 -49.725326)
		(end 33.6931 -50.019966)
		(width 0.2032)
		(layer "In2.Cu")
		(net "M1_DQ_NODE1_DQ12")
	)
	(segment
		(start 32.95396 -54.91988)
		(end 32.95396 -55.21452)
		(width 0.2032)
		(layer "In2.Cu")
		(net "M1_DQ_NODE1_DQ12")
	)
	(segment
		(start 34.140902 -56.894222)
		(end 34.401252 -56.633872)
		(width 0.2032)
		(layer "In2.Cu")
		(net "M1_DQ_NODE1_DQ12")
	)
	(segment
		(start 39.25316 -31.9151)
		(end 39.25316 -33.121854)
		(width 0.2032)
		(layer "In2.Cu")
		(net "M1_DQ_NODE1_DQ12")
	)
	(segment
		(start 33.18764 -53.073046)
		(end 32.97936 -53.281326)
		(width 0.2032)
		(layer "In2.Cu")
		(net "M1_DQ_NODE1_DQ12")
	)
	(segment
		(start 33.6931 -52.864766)
		(end 33.48482 -53.073046)
		(width 0.2032)
		(layer "In2.Cu")
		(net "M1_DQ_NODE1_DQ12")
	)
	(segment
		(start 44.888404 -60.247784)
		(end 45.096684 -60.456064)
		(width 0.2032)
		(layer "In2.Cu")
		(net "M1_DQ_NODE1_DQ12")
	)
	(segment
		(start 33.637982 -56.391302)
		(end 33.637982 -56.685942)
		(width 0.2032)
		(layer "In2.Cu")
		(net "M1_DQ_NODE1_DQ12")
	)
	(segment
		(start 32.97936 -40.774366)
		(end 33.18764 -40.982646)
		(width 0.2032)
		(layer "In2.Cu")
		(net "M1_DQ_NODE1_DQ12")
	)
	(segment
		(start 35.296602 -57.982866)
		(end 34.937954 -58.341514)
		(width 0.2032)
		(layer "In2.Cu")
		(net "M1_DQ_NODE1_DQ12")
	)
	(segment
		(start 33.48482 -43.827446)
		(end 33.6931 -44.035726)
		(width 0.2032)
		(layer "In2.Cu")
		(net "M1_DQ_NODE1_DQ12")
	)
	(segment
		(start 35.799522 -58.485786)
		(end 36.094162 -58.485786)
		(width 0.2032)
		(layer "In2.Cu")
		(net "M1_DQ_NODE1_DQ12")
	)
	(segment
		(start 33.48482 -50.228246)
		(end 33.18764 -50.228246)
		(width 0.2032)
		(layer "In2.Cu")
		(net "M1_DQ_NODE1_DQ12")
	)
	(segment
		(start 33.48482 -41.693846)
		(end 33.18764 -41.693846)
		(width 0.2032)
		(layer "In2.Cu")
		(net "M1_DQ_NODE1_DQ12")
	)
	(segment
		(start 33.48482 -53.784246)
		(end 33.6931 -53.992526)
		(width 0.2032)
		(layer "In2.Cu")
		(net "M1_DQ_NODE1_DQ12")
	)
	(segment
		(start 44.584112 -30.121606)
		(end 41.576498 -30.121606)
		(width 0.2032)
		(layer "In2.Cu")
		(net "M1_DQ_NODE1_DQ12")
	)
	(segment
		(start 33.18764 -50.939446)
		(end 33.48482 -50.939446)
		(width 0.2032)
		(layer "In2.Cu")
		(net "M1_DQ_NODE1_DQ12")
	)
	(segment
		(start 33.6931 -47.175166)
		(end 33.48482 -47.383446)
		(width 0.2032)
		(layer "In2.Cu")
		(net "M1_DQ_NODE1_DQ12")
	)
	(segment
		(start 33.6931 -46.880526)
		(end 33.6931 -47.175166)
		(width 0.2032)
		(layer "In2.Cu")
		(net "M1_DQ_NODE1_DQ12")
	)
	(segment
		(start 33.18764 -42.405046)
		(end 33.48482 -42.405046)
		(width 0.2032)
		(layer "In2.Cu")
		(net "M1_DQ_NODE1_DQ12")
	)
	(segment
		(start 33.18764 -50.228246)
		(end 32.97936 -50.436526)
		(width 0.2032)
		(layer "In2.Cu")
		(net "M1_DQ_NODE1_DQ12")
	)
	(segment
		(start 34.937954 -58.636154)
		(end 35.146234 -58.844434)
		(width 0.2032)
		(layer "In2.Cu")
		(net "M1_DQ_NODE1_DQ12")
	)
	(segment
		(start 32.97936 -44.746926)
		(end 32.97936 -45.041566)
		(width 0.2032)
		(layer "In2.Cu")
		(net "M1_DQ_NODE1_DQ12")
	)
	(segment
		(start 33.18764 -40.982646)
		(end 33.48482 -40.982646)
		(width 0.2032)
		(layer "In2.Cu")
		(net "M1_DQ_NODE1_DQ12")
	)
	(segment
		(start 33.898332 -56.130952)
		(end 33.637982 -56.391302)
		(width 0.2032)
		(layer "In2.Cu")
		(net "M1_DQ_NODE1_DQ12")
	)
	(segment
		(start 33.48482 -54.7116)
		(end 33.16224 -54.7116)
		(width 0.2032)
		(layer "In2.Cu")
		(net "M1_DQ_NODE1_DQ12")
	)
	(segment
		(start 33.637982 -56.685942)
		(end 33.846262 -56.894222)
		(width 0.2032)
		(layer "In2.Cu")
		(net "M1_DQ_NODE1_DQ12")
	)
	(segment
		(start 33.48482 -47.383446)
		(end 33.18764 -47.383446)
		(width 0.2032)
		(layer "In2.Cu")
		(net "M1_DQ_NODE1_DQ12")
	)
	(segment
		(start 33.846262 -56.894222)
		(end 34.140902 -56.894222)
		(width 0.2032)
		(layer "In2.Cu")
		(net "M1_DQ_NODE1_DQ12")
	)
	(segment
		(start 46.383702 -59.943238)
		(end 46.6217 -59.70524)
		(width 0.2032)
		(layer "In2.Cu")
		(net "M1_DQ_NODE1_DQ12")
	)
	(segment
		(start 44.888404 -59.699144)
		(end 44.888404 -60.247784)
		(width 0.2032)
		(layer "In2.Cu")
		(net "M1_DQ_NODE1_DQ12")
	)
	(segment
		(start 45.391324 -60.456064)
		(end 45.599604 -60.247784)
		(width 0.2032)
		(layer "In2.Cu")
		(net "M1_DQ_NODE1_DQ12")
	)
	(segment
		(start 32.97936 -47.591726)
		(end 32.97936 -47.886366)
		(width 0.2032)
		(layer "In2.Cu")
		(net "M1_DQ_NODE1_DQ12")
	)
	(segment
		(start 35.440874 -58.844434)
		(end 35.799522 -58.485786)
		(width 0.2032)
		(layer "In2.Cu")
		(net "M1_DQ_NODE1_DQ12")
	)
	(segment
		(start 32.95396 -55.21452)
		(end 33.16224 -55.4228)
		(width 0.2032)
		(layer "In2.Cu")
		(net "M1_DQ_NODE1_DQ12")
	)
	(segment
		(start 33.48482 -48.094646)
		(end 33.6931 -48.302926)
		(width 0.2032)
		(layer "In2.Cu")
		(net "M1_DQ_NODE1_DQ12")
	)
	(segment
		(start 35.296602 -57.688226)
		(end 35.296602 -57.982866)
		(width 0.2032)
		(layer "In2.Cu")
		(net "M1_DQ_NODE1_DQ12")
	)
	(segment
		(start 33.18764 -52.361846)
		(end 33.48482 -52.361846)
		(width 0.2032)
		(layer "In2.Cu")
		(net "M1_DQ_NODE1_DQ12")
	)
	(segment
		(start 34.92754 -56.86552)
		(end 34.92754 -57.319164)
		(width 0.2032)
		(layer "In2.Cu")
		(net "M1_DQ_NODE1_DQ12")
	)
	(segment
		(start 151.312372 -33.134808)
		(end 150.606252 -33.840928)
		(width 0.1016)
		(layer "F.Cu")
		(net "N21624806")
	)
	(segment
		(start 152.429972 -33.134808)
		(end 151.312372 -33.134808)
		(width 0.1016)
		(layer "F.Cu")
		(net "N21624806")
	)
	(segment
		(start 149.909022 -33.586928)
		(end 150.352252 -33.586928)
		(width 0.1016)
		(layer "F.Cu")
		(net "N21624806")
	)
	(segment
		(start 150.352252 -33.586928)
		(end 150.606252 -33.840928)
		(width 0.1016)
		(layer "F.Cu")
		(net "N21624806")
	)
	(via
		(at 150.606252 -33.840928)
		(size 0.508)
		(drill 0.254)
		(layers "F.Cu" "B.Cu")
		(net "N21624806")
	)
	(segment
		(start 144.519396 -69.77253)
		(end 144.519396 -70.07733)
		(width 0.1016)
		(layer "F.Cu")
		(net "SATA_SPI_CLK_NODE1_R")
	)
	(segment
		(start 140.236194 -74.301096)
		(end 140.988288 -73.549002)
		(width 0.1016)
		(layer "F.Cu")
		(net "SATA_SPI_CLK_NODE1_R")
	)
	(segment
		(start 139.83843 -74.301096)
		(end 140.236194 -74.301096)
		(width 0.1016)
		(layer "F.Cu")
		(net "SATA_SPI_CLK_NODE1_R")
	)
	(segment
		(start 144.519396 -70.07733)
		(end 143.960596 -70.63613)
		(width 0.1016)
		(layer "F.Cu")
		(net "SATA_SPI_CLK_NODE1_R")
	)
	(segment
		(start 143.960596 -73.046844)
		(end 143.458438 -73.549002)
		(width 0.1016)
		(layer "F.Cu")
		(net "SATA_SPI_CLK_NODE1_R")
	)
	(segment
		(start 144.330674 -69.583808)
		(end 144.519396 -69.77253)
		(width 0.1016)
		(layer "F.Cu")
		(net "SATA_SPI_CLK_NODE1_R")
	)
	(segment
		(start 143.960596 -70.63613)
		(end 143.960596 -73.046844)
		(width 0.1016)
		(layer "F.Cu")
		(net "SATA_SPI_CLK_NODE1_R")
	)
	(segment
		(start 144.330674 -68.799202)
		(end 144.330674 -69.583808)
		(width 0.1016)
		(layer "F.Cu")
		(net "SATA_SPI_CLK_NODE1_R")
	)
	(segment
		(start 143.458438 -73.549002)
		(end 140.988288 -73.549002)
		(width 0.1016)
		(layer "F.Cu")
		(net "SATA_SPI_CLK_NODE1_R")
	)
	(via
		(at 140.988288 -73.549002)
		(size 0.508)
		(drill 0.254)
		(layers "F.Cu" "B.Cu")
		(net "SATA_SPI_CLK_NODE1_R")
	)
	(segment
		(start 55.049166 -96.309942)
		(end 55.049166 -95.640906)
		(width 0.1016)
		(layer "F.Cu")
		(net "PD_CPU_NODE1_DFX_GPIO_GRP0_6")
	)
	(segment
		(start 55.06974 -91.414092)
		(end 54.357778 -92.126054)
		(width 0.1016)
		(layer "F.Cu")
		(net "PD_CPU_NODE1_DFX_GPIO_GRP0_6")
	)
	(segment
		(start 55.544212 -87.563452)
		(end 55.544212 -87.899748)
		(width 0.1016)
		(layer "F.Cu")
		(net "PD_CPU_NODE1_DFX_GPIO_GRP0_6")
	)
	(segment
		(start 55.30596 -87.3252)
		(end 55.544212 -87.563452)
		(width 0.1016)
		(layer "F.Cu")
		(net "PD_CPU_NODE1_DFX_GPIO_GRP0_6")
	)
	(segment
		(start 55.06974 -90.330274)
		(end 55.06974 -91.414092)
		(width 0.1016)
		(layer "F.Cu")
		(net "PD_CPU_NODE1_DFX_GPIO_GRP0_6")
	)
	(segment
		(start 55.512716 -87.931244)
		(end 55.512716 -88.579706)
		(width 0.1016)
		(layer "F.Cu")
		(net "PD_CPU_NODE1_DFX_GPIO_GRP0_6")
	)
	(segment
		(start 55.30596 -87.00389)
		(end 55.30596 -87.3252)
		(width 0.1016)
		(layer "F.Cu")
		(net "PD_CPU_NODE1_DFX_GPIO_GRP0_6")
	)
	(segment
		(start 55.512716 -88.579706)
		(end 55.385716 -88.706706)
		(width 0.1016)
		(layer "F.Cu")
		(net "PD_CPU_NODE1_DFX_GPIO_GRP0_6")
	)
	(segment
		(start 55.385716 -88.706706)
		(end 55.385716 -90.014298)
		(width 0.1016)
		(layer "F.Cu")
		(net "PD_CPU_NODE1_DFX_GPIO_GRP0_6")
	)
	(segment
		(start 55.049166 -95.640906)
		(end 54.357778 -94.949518)
		(width 0.1016)
		(layer "F.Cu")
		(net "PD_CPU_NODE1_DFX_GPIO_GRP0_6")
	)
	(segment
		(start 54.357778 -94.949518)
		(end 54.357778 -92.126054)
		(width 0.1016)
		(layer "F.Cu")
		(net "PD_CPU_NODE1_DFX_GPIO_GRP0_6")
	)
	(segment
		(start 55.544212 -87.899748)
		(end 55.512716 -87.931244)
		(width 0.1016)
		(layer "F.Cu")
		(net "PD_CPU_NODE1_DFX_GPIO_GRP0_6")
	)
	(segment
		(start 55.385716 -90.014298)
		(end 55.06974 -90.330274)
		(width 0.1016)
		(layer "F.Cu")
		(net "PD_CPU_NODE1_DFX_GPIO_GRP0_6")
	)
	(via
		(at 54.357778 -92.126054)
		(size 0.508)
		(drill 0.254)
		(layers "F.Cu" "B.Cu")
		(net "PD_CPU_NODE1_DFX_GPIO_GRP0_6")
	)
	(segment
		(start 54.497986 -67.741038)
		(end 54.497986 -67.734688)
		(width 0.09906)
		(layer "F.Cu")
		(net "M_DDR3_NODE1_DQS2N")
	)
	(segment
		(start 53.551582 -24.1427)
		(end 53.062632 -24.63165)
		(width 0.1651)
		(layer "F.Cu")
		(net "M_DDR3_NODE1_DQS2N")
	)
	(segment
		(start 54.497986 -67.734688)
		(end 54.887368 -67.345306)
		(width 0.09906)
		(layer "F.Cu")
		(net "M_DDR3_NODE1_DQS2N")
	)
	(segment
		(start 52.95011 -20.94992)
		(end 52.95011 -22.151086)
		(width 0.1651)
		(layer "F.Cu")
		(net "M_DDR3_NODE1_DQS2N")
	)
	(segment
		(start 53.104034 -22.30501)
		(end 53.104034 -23.363428)
		(width 0.1651)
		(layer "F.Cu")
		(net "M_DDR3_NODE1_DQS2N")
	)
	(segment
		(start 53.551582 -23.810976)
		(end 53.551582 -24.1427)
		(width 0.1651)
		(layer "F.Cu")
		(net "M_DDR3_NODE1_DQS2N")
	)
	(segment
		(start 54.887368 -67.345306)
		(end 54.891686 -67.345306)
		(width 0.09906)
		(layer "F.Cu")
		(net "M_DDR3_NODE1_DQS2N")
	)
	(segment
		(start 52.95011 -22.151086)
		(end 53.104034 -22.30501)
		(width 0.1651)
		(layer "F.Cu")
		(net "M_DDR3_NODE1_DQS2N")
	)
	(segment
		(start 53.104034 -23.363428)
		(end 53.551582 -23.810976)
		(width 0.1651)
		(layer "F.Cu")
		(net "M_DDR3_NODE1_DQS2N")
	)
	(via
		(at 54.891686 -67.345306)
		(size 0.508)
		(drill 0.254)
		(layers "F.Cu" "B.Cu")
		(net "M_DDR3_NODE1_DQS2N")
	)
	(via
		(at 53.062632 -24.63165)
		(size 0.508)
		(drill 0.254)
		(layers "F.Cu" "B.Cu")
		(net "M_DDR3_NODE1_DQS2N")
	)
	(segment
		(start 44.568872 -49.033176)
		(end 44.9707 -48.631348)
		(width 0.2032)
		(layer "In7.Cu")
		(net "M_DDR3_NODE1_DQS2N")
	)
	(segment
		(start 45.6819 -50.78222)
		(end 52.29352 -57.39384)
		(width 0.2032)
		(layer "In7.Cu")
		(net "M_DDR3_NODE1_DQS2N")
	)
	(segment
		(start 52.96916 -59.282076)
		(end 52.96916 -62.689994)
		(width 0.09906)
		(layer "In7.Cu")
		(net "M_DDR3_NODE1_DQS2N")
	)
	(segment
		(start 43.5991 -48.631348)
		(end 44.000928 -49.033176)
		(width 0.2032)
		(layer "In7.Cu")
		(net "M_DDR3_NODE1_DQS2N")
	)
	(segment
		(start 45.6819 -46.256194)
		(end 45.6819 -50.78222)
		(width 0.2032)
		(layer "In7.Cu")
		(net "M_DDR3_NODE1_DQS2N")
	)
	(segment
		(start 44.000928 -49.033176)
		(end 44.568872 -49.033176)
		(width 0.2032)
		(layer "In7.Cu")
		(net "M_DDR3_NODE1_DQS2N")
	)
	(segment
		(start 43.5991 -42.895266)
		(end 43.5991 -48.631348)
		(width 0.2032)
		(layer "In7.Cu")
		(net "M_DDR3_NODE1_DQS2N")
	)
	(segment
		(start 52.31257 -57.412128)
		(end 52.4002 -57.412128)
		(width 0.09906)
		(layer "In7.Cu")
		(net "M_DDR3_NODE1_DQS2N")
	)
	(segment
		(start 52.29352 -57.39384)
		(end 52.294282 -57.39384)
		(width 0.2032)
		(layer "In7.Cu")
		(net "M_DDR3_NODE1_DQS2N")
	)
	(segment
		(start 52.294282 -57.39384)
		(end 52.31257 -57.412128)
		(width 0.09906)
		(layer "In7.Cu")
		(net "M_DDR3_NODE1_DQS2N")
	)
	(segment
		(start 52.13858 -26.80716)
		(end 52.13858 -34.355786)
		(width 0.2032)
		(layer "In7.Cu")
		(net "M_DDR3_NODE1_DQS2N")
	)
	(segment
		(start 53.1114 -59.139836)
		(end 52.96916 -59.282076)
		(width 0.09906)
		(layer "In7.Cu")
		(net "M_DDR3_NODE1_DQS2N")
	)
	(segment
		(start 54.39664 -64.683132)
		(end 54.39664 -65.3034)
		(width 0.09906)
		(layer "In7.Cu")
		(net "M_DDR3_NODE1_DQS2N")
	)
	(segment
		(start 52.96916 -62.689994)
		(end 53.877464 -63.598298)
		(width 0.09906)
		(layer "In7.Cu")
		(net "M_DDR3_NODE1_DQS2N")
	)
	(segment
		(start 53.062632 -24.63165)
		(end 53.465222 -25.03424)
		(width 0.2032)
		(layer "In7.Cu")
		(net "M_DDR3_NODE1_DQS2N")
	)
	(segment
		(start 44.9707 -46.256194)
		(end 45.179234 -46.04766)
		(width 0.2032)
		(layer "In7.Cu")
		(net "M_DDR3_NODE1_DQS2N")
	)
	(segment
		(start 53.465222 -25.480518)
		(end 52.13858 -26.80716)
		(width 0.2032)
		(layer "In7.Cu")
		(net "M_DDR3_NODE1_DQS2N")
	)
	(segment
		(start 45.473366 -46.04766)
		(end 45.6819 -46.256194)
		(width 0.2032)
		(layer "In7.Cu")
		(net "M_DDR3_NODE1_DQS2N")
	)
	(segment
		(start 53.877464 -63.598298)
		(end 53.877464 -64.163956)
		(width 0.09906)
		(layer "In7.Cu")
		(net "M_DDR3_NODE1_DQS2N")
	)
	(segment
		(start 52.13858 -34.355786)
		(end 43.5991 -42.895266)
		(width 0.2032)
		(layer "In7.Cu")
		(net "M_DDR3_NODE1_DQS2N")
	)
	(segment
		(start 54.371748 -67.127882)
		(end 54.674262 -67.127882)
		(width 0.09906)
		(layer "In7.Cu")
		(net "M_DDR3_NODE1_DQS2N")
	)
	(segment
		(start 52.4002 -57.412128)
		(end 53.1114 -58.123328)
		(width 0.09906)
		(layer "In7.Cu")
		(net "M_DDR3_NODE1_DQS2N")
	)
	(segment
		(start 45.179234 -46.04766)
		(end 45.473366 -46.04766)
		(width 0.2032)
		(layer "In7.Cu")
		(net "M_DDR3_NODE1_DQS2N")
	)
	(segment
		(start 54.080664 -65.619376)
		(end 54.080664 -66.836798)
		(width 0.09906)
		(layer "In7.Cu")
		(net "M_DDR3_NODE1_DQS2N")
	)
	(segment
		(start 53.465222 -25.03424)
		(end 53.465222 -25.480518)
		(width 0.2032)
		(layer "In7.Cu")
		(net "M_DDR3_NODE1_DQS2N")
	)
	(segment
		(start 54.674262 -67.127882)
		(end 54.891686 -67.345306)
		(width 0.09906)
		(layer "In7.Cu")
		(net "M_DDR3_NODE1_DQS2N")
	)
	(segment
		(start 53.877464 -64.163956)
		(end 54.39664 -64.683132)
		(width 0.09906)
		(layer "In7.Cu")
		(net "M_DDR3_NODE1_DQS2N")
	)
	(segment
		(start 54.39664 -65.3034)
		(end 54.080664 -65.619376)
		(width 0.09906)
		(layer "In7.Cu")
		(net "M_DDR3_NODE1_DQS2N")
	)
	(segment
		(start 44.9707 -48.631348)
		(end 44.9707 -46.256194)
		(width 0.2032)
		(layer "In7.Cu")
		(net "M_DDR3_NODE1_DQS2N")
	)
	(segment
		(start 54.080664 -66.836798)
		(end 54.371748 -67.127882)
		(width 0.09906)
		(layer "In7.Cu")
		(net "M_DDR3_NODE1_DQS2N")
	)
	(segment
		(start 53.1114 -58.123328)
		(end 53.1114 -59.139836)
		(width 0.09906)
		(layer "In7.Cu")
		(net "M_DDR3_NODE1_DQS2N")
	)
	(segment
		(start 14.898116 -28.774898)
		(end 15.68704 -27.985974)
		(width 0.1016)
		(layer "F.Cu")
		(net "N54251529")
	)
	(segment
		(start 14.898116 -29.250132)
		(end 14.898116 -28.774898)
		(width 0.1016)
		(layer "F.Cu")
		(net "N54251529")
	)
	(segment
		(start 15.68704 -27.985974)
		(end 15.68704 -27.259534)
		(width 0.1016)
		(layer "F.Cu")
		(net "N54251529")
	)
	(segment
		(start 15.788132 -27.158442)
		(end 15.68704 -27.259534)
		(width 0.1016)
		(layer "F.Cu")
		(net "N54251529")
	)
	(segment
		(start 15.788132 -26.04516)
		(end 15.788132 -27.158442)
		(width 0.1016)
		(layer "F.Cu")
		(net "N54251529")
	)
	(via
		(at 15.68704 -27.259534)
		(size 0.508)
		(drill 0.254)
		(layers "F.Cu" "B.Cu")
		(net "N54251529")
	)
	(via
		(at 136.973818 -67.843908)
		(size 0.508)
		(drill 0.254)
		(layers "F.Cu" "B.Cu")
		(net "SATA_VCONT_NODE1")
	)
	(via
		(at 150.081996 -69.89953)
		(size 0.508)
		(drill 0.254)
		(layers "F.Cu" "B.Cu")
		(net "SATA_VCONT_NODE1")
	)
	(segment
		(start 144.337532 -71.613522)
		(end 143.048482 -71.613522)
		(width 0.4572)
		(layer "In2.Cu")
		(net "SATA_VCONT_NODE1")
	)
	(segment
		(start 142.916402 -71.481442)
		(end 142.910052 -71.481442)
		(width 0.4572)
		(layer "In2.Cu")
		(net "SATA_VCONT_NODE1")
	)
	(segment
		(start 148.929344 -71.052182)
		(end 144.898872 -71.052182)
		(width 0.4572)
		(layer "In2.Cu")
		(net "SATA_VCONT_NODE1")
	)
	(segment
		(start 150.081996 -69.89953)
		(end 148.929344 -71.052182)
		(width 0.4572)
		(layer "In2.Cu")
		(net "SATA_VCONT_NODE1")
	)
	(segment
		(start 139.723622 -70.593712)
		(end 136.973818 -67.843908)
		(width 0.4572)
		(layer "In2.Cu")
		(net "SATA_VCONT_NODE1")
	)
	(segment
		(start 144.898872 -71.052182)
		(end 144.337532 -71.613522)
		(width 0.4572)
		(layer "In2.Cu")
		(net "SATA_VCONT_NODE1")
	)
	(segment
		(start 143.048482 -71.613522)
		(end 142.916402 -71.481442)
		(width 0.4572)
		(layer "In2.Cu")
		(net "SATA_VCONT_NODE1")
	)
	(segment
		(start 142.910052 -71.481442)
		(end 142.022322 -70.593712)
		(width 0.4572)
		(layer "In2.Cu")
		(net "SATA_VCONT_NODE1")
	)
	(segment
		(start 142.022322 -70.593712)
		(end 139.723622 -70.593712)
		(width 0.4572)
		(layer "In2.Cu")
		(net "SATA_VCONT_NODE1")
	)
	(segment
		(start 62.20333 -86.143338)
		(end 62.65799 -85.688678)
		(width 0.1016)
		(layer "F.Cu")
		(net "LPC_CPU_NODE1_LAD0_R")
	)
	(segment
		(start 62.20333 -86.143846)
		(end 62.20333 -86.143338)
		(width 0.1016)
		(layer "F.Cu")
		(net "LPC_CPU_NODE1_LAD0_R")
	)
	(via
		(at 62.65799 -85.688678)
		(size 0.508)
		(drill 0.254)
		(layers "F.Cu" "B.Cu")
		(net "LPC_CPU_NODE1_LAD0_R")
	)
	(via
		(at 63.35014 -93.605858)
		(size 0.6604)
		(drill 0.3302)
		(layers "F.Cu" "B.Cu")
		(net "LPC_CPU_NODE1_LAD0_R")
	)
	(segment
		(start 62.55004 -96.440244)
		(end 62.55004 -95.66148)
		(width 0.1016)
		(layer "B.Cu")
		(net "LPC_CPU_NODE1_LAD0_R")
	)
	(segment
		(start 62.902338 -94.882462)
		(end 63.36284 -94.42196)
		(width 0.1016)
		(layer "B.Cu")
		(net "LPC_CPU_NODE1_LAD0_R")
	)
	(segment
		(start 62.920372 -86.544912)
		(end 62.65799 -86.28253)
		(width 0.1016)
		(layer "B.Cu")
		(net "LPC_CPU_NODE1_LAD0_R")
	)
	(segment
		(start 62.888876 -94.882462)
		(end 62.902338 -94.882462)
		(width 0.1016)
		(layer "B.Cu")
		(net "LPC_CPU_NODE1_LAD0_R")
	)
	(segment
		(start 63.342266 -87.892128)
		(end 62.920372 -87.470234)
		(width 0.1016)
		(layer "B.Cu")
		(net "LPC_CPU_NODE1_LAD0_R")
	)
	(segment
		(start 63.36284 -94.42196)
		(end 63.36284 -93.605858)
		(width 0.1016)
		(layer "B.Cu")
		(net "LPC_CPU_NODE1_LAD0_R")
	)
	(segment
		(start 63.342266 -93.62567)
		(end 63.342266 -87.892128)
		(width 0.1016)
		(layer "B.Cu")
		(net "LPC_CPU_NODE1_LAD0_R")
	)
	(segment
		(start 63.362078 -93.605858)
		(end 63.342266 -93.62567)
		(width 0.1016)
		(layer "B.Cu")
		(net "LPC_CPU_NODE1_LAD0_R")
	)
	(segment
		(start 62.55004 -95.66148)
		(end 62.888876 -94.882462)
		(width 0.1016)
		(layer "B.Cu")
		(net "LPC_CPU_NODE1_LAD0_R")
	)
	(segment
		(start 62.65799 -86.28253)
		(end 62.65799 -85.688678)
		(width 0.1016)
		(layer "B.Cu")
		(net "LPC_CPU_NODE1_LAD0_R")
	)
	(segment
		(start 63.362078 -93.605858)
		(end 63.35014 -93.605858)
		(width 0.1016)
		(layer "B.Cu")
		(net "LPC_CPU_NODE1_LAD0_R")
	)
	(segment
		(start 62.920372 -87.470234)
		(end 62.920372 -86.544912)
		(width 0.1016)
		(layer "B.Cu")
		(net "LPC_CPU_NODE1_LAD0_R")
	)
	(segment
		(start 62.166246 -96.824038)
		(end 62.55004 -96.440244)
		(width 0.1016)
		(layer "B.Cu")
		(net "LPC_CPU_NODE1_LAD0_R")
	)
	(segment
		(start 63.36284 -93.605858)
		(end 63.362078 -93.605858)
		(width 0.1016)
		(layer "B.Cu")
		(net "LPC_CPU_NODE1_LAD0_R")
	)
	(segment
		(start 74.084434 -66.569336)
		(end 74.405236 -66.569336)
		(width 0.1016)
		(layer "F.Cu")
		(net "M1_DQ_NODE1_DQ54")
	)
	(segment
		(start 94.650306 -28.02763)
		(end 94.650306 -29.149802)
		(width 0.1651)
		(layer "F.Cu")
		(net "M1_DQ_NODE1_DQ54")
	)
	(segment
		(start 74.405236 -66.569336)
		(end 74.81697 -66.157602)
		(width 0.1016)
		(layer "F.Cu")
		(net "M1_DQ_NODE1_DQ54")
	)
	(segment
		(start 74.81697 -63.806324)
		(end 75.228704 -63.39459)
		(width 0.1016)
		(layer "F.Cu")
		(net "M1_DQ_NODE1_DQ54")
	)
	(segment
		(start 72.752204 -67.576954)
		(end 73.076816 -67.576954)
		(width 0.1016)
		(layer "F.Cu")
		(net "M1_DQ_NODE1_DQ54")
	)
	(segment
		(start 73.076816 -67.576954)
		(end 74.084434 -66.569336)
		(width 0.1016)
		(layer "F.Cu")
		(net "M1_DQ_NODE1_DQ54")
	)
	(segment
		(start 74.81697 -66.157602)
		(end 74.81697 -63.806324)
		(width 0.1016)
		(layer "F.Cu")
		(net "M1_DQ_NODE1_DQ54")
	)
	(segment
		(start 92.468954 -25.846278)
		(end 94.650306 -28.02763)
		(width 0.1651)
		(layer "F.Cu")
		(net "M1_DQ_NODE1_DQ54")
	)
	(segment
		(start 91.81338 -25.846278)
		(end 92.468954 -25.846278)
		(width 0.1651)
		(layer "F.Cu")
		(net "M1_DQ_NODE1_DQ54")
	)
	(via
		(at 75.228704 -63.39459)
		(size 0.508)
		(drill 0.254)
		(layers "F.Cu" "B.Cu")
		(net "M1_DQ_NODE1_DQ54")
	)
	(via
		(at 91.81338 -25.846278)
		(size 0.508)
		(drill 0.254)
		(layers "F.Cu" "B.Cu")
		(net "M1_DQ_NODE1_DQ54")
	)
	(segment
		(start 89.831672 -24.366728)
		(end 89.526872 -24.366728)
		(width 0.2032)
		(layer "In7.Cu")
		(net "M1_DQ_NODE1_DQ54")
	)
	(segment
		(start 87.925402 -40.073834)
		(end 87.925402 -40.426386)
		(width 0.2032)
		(layer "In7.Cu")
		(net "M1_DQ_NODE1_DQ54")
	)
	(segment
		(start 85.913722 -42.085514)
		(end 85.913722 -42.438066)
		(width 0.2032)
		(layer "In7.Cu")
		(net "M1_DQ_NODE1_DQ54")
	)
	(segment
		(start 88.1634 -36.079684)
		(end 88.37168 -36.287964)
		(width 0.2032)
		(layer "In7.Cu")
		(net "M1_DQ_NODE1_DQ54")
	)
	(segment
		(start 86.919562 -41.432226)
		(end 86.592918 -41.75887)
		(width 0.2032)
		(layer "In7.Cu")
		(net "M1_DQ_NODE1_DQ54")
	)
	(segment
		(start 84.581238 -43.77055)
		(end 84.228686 -43.77055)
		(width 0.2032)
		(layer "In7.Cu")
		(net "M1_DQ_NODE1_DQ54")
	)
	(segment
		(start 88.933782 -38.213284)
		(end 88.725502 -38.421564)
		(width 0.2032)
		(layer "In7.Cu")
		(net "M1_DQ_NODE1_DQ54")
	)
	(segment
		(start 75.52182 -63.101474)
		(end 75.228704 -63.39459)
		(width 0.1016)
		(layer "In7.Cu")
		(net "M1_DQ_NODE1_DQ54")
	)
	(segment
		(start 88.717882 -30.918658)
		(end 88.71712 -30.91942)
		(width 0.2032)
		(layer "In7.Cu")
		(net "M1_DQ_NODE1_DQ54")
	)
	(segment
		(start 91.457272 -25.49017)
		(end 91.457272 -24.45512)
		(width 0.2032)
		(layer "In7.Cu")
		(net "M1_DQ_NODE1_DQ54")
	)
	(segment
		(start 88.725502 -36.999164)
		(end 88.37168 -36.999164)
		(width 0.2032)
		(layer "In7.Cu")
		(net "M1_DQ_NODE1_DQ54")
	)
	(segment
		(start 88.71712 -32.66186)
		(end 88.1634 -33.21558)
		(width 0.2032)
		(layer "In7.Cu")
		(net "M1_DQ_NODE1_DQ54")
	)
	(segment
		(start 84.228686 -43.77055)
		(end 83.72856 -44.270676)
		(width 0.2032)
		(layer "In7.Cu")
		(net "M1_DQ_NODE1_DQ54")
	)
	(segment
		(start 81.01838 -48.419766)
		(end 75.52182 -53.916326)
		(width 0.2032)
		(layer "In7.Cu")
		(net "M1_DQ_NODE1_DQ54")
	)
	(segment
		(start 90.746072 -25.465024)
		(end 90.542872 -25.668224)
		(width 0.2032)
		(layer "In7.Cu")
		(net "M1_DQ_NODE1_DQ54")
	)
	(segment
		(start 88.933782 -36.496244)
		(end 88.933782 -36.790884)
		(width 0.2032)
		(layer "In7.Cu")
		(net "M1_DQ_NODE1_DQ54")
	)
	(segment
		(start 75.52182 -53.916326)
		(end 75.52182 -58.781442)
		(width 0.2032)
		(layer "In7.Cu")
		(net "M1_DQ_NODE1_DQ54")
	)
	(segment
		(start 88.725502 -36.287964)
		(end 88.933782 -36.496244)
		(width 0.2032)
		(layer "In7.Cu")
		(net "M1_DQ_NODE1_DQ54")
	)
	(segment
		(start 88.1634 -37.502084)
		(end 88.37168 -37.710364)
		(width 0.2032)
		(layer "In7.Cu")
		(net "M1_DQ_NODE1_DQ54")
	)
	(segment
		(start 85.234526 -42.76471)
		(end 84.907882 -43.091354)
		(width 0.2032)
		(layer "In7.Cu")
		(net "M1_DQ_NODE1_DQ54")
	)
	(segment
		(start 83.72856 -44.270676)
		(end 83.72856 -44.884594)
		(width 0.2032)
		(layer "In7.Cu")
		(net "M1_DQ_NODE1_DQ54")
	)
	(segment
		(start 88.37168 -36.999164)
		(end 88.1634 -37.207444)
		(width 0.2032)
		(layer "In7.Cu")
		(net "M1_DQ_NODE1_DQ54")
	)
	(segment
		(start 88.1634 -33.21558)
		(end 88.1634 -36.079684)
		(width 0.2032)
		(layer "In7.Cu")
		(net "M1_DQ_NODE1_DQ54")
	)
	(segment
		(start 87.246206 -40.75303)
		(end 86.919562 -41.079674)
		(width 0.2032)
		(layer "In7.Cu")
		(net "M1_DQ_NODE1_DQ54")
	)
	(segment
		(start 85.587078 -42.76471)
		(end 85.234526 -42.76471)
		(width 0.2032)
		(layer "In7.Cu")
		(net "M1_DQ_NODE1_DQ54")
	)
	(segment
		(start 88.71712 -30.91942)
		(end 88.71712 -32.66186)
		(width 0.2032)
		(layer "In7.Cu")
		(net "M1_DQ_NODE1_DQ54")
	)
	(segment
		(start 88.933782 -37.918644)
		(end 88.933782 -38.213284)
		(width 0.2032)
		(layer "In7.Cu")
		(net "M1_DQ_NODE1_DQ54")
	)
	(segment
		(start 86.919562 -41.079674)
		(end 86.919562 -41.432226)
		(width 0.2032)
		(layer "In7.Cu")
		(net "M1_DQ_NODE1_DQ54")
	)
	(segment
		(start 88.37168 -36.287964)
		(end 88.725502 -36.287964)
		(width 0.2032)
		(layer "In7.Cu")
		(net "M1_DQ_NODE1_DQ54")
	)
	(segment
		(start 81.01838 -47.594774)
		(end 81.01838 -48.419766)
		(width 0.2032)
		(layer "In7.Cu")
		(net "M1_DQ_NODE1_DQ54")
	)
	(segment
		(start 84.907882 -43.091354)
		(end 84.907882 -43.443906)
		(width 0.2032)
		(layer "In7.Cu")
		(net "M1_DQ_NODE1_DQ54")
	)
	(segment
		(start 88.933782 -36.790884)
		(end 88.725502 -36.999164)
		(width 0.2032)
		(layer "In7.Cu")
		(net "M1_DQ_NODE1_DQ54")
	)
	(segment
		(start 88.1634 -38.629844)
		(end 88.1634 -39.835836)
		(width 0.2032)
		(layer "In7.Cu")
		(net "M1_DQ_NODE1_DQ54")
	)
	(segment
		(start 83.72856 -44.884594)
		(end 81.01838 -47.594774)
		(width 0.2032)
		(layer "In7.Cu")
		(net "M1_DQ_NODE1_DQ54")
	)
	(segment
		(start 87.598758 -40.75303)
		(end 87.246206 -40.75303)
		(width 0.2032)
		(layer "In7.Cu")
		(net "M1_DQ_NODE1_DQ54")
	)
	(segment
		(start 88.37168 -38.421564)
		(end 88.1634 -38.629844)
		(width 0.2032)
		(layer "In7.Cu")
		(net "M1_DQ_NODE1_DQ54")
	)
	(segment
		(start 91.457272 -24.45512)
		(end 91.25966 -24.257508)
		(width 0.2032)
		(layer "In7.Cu")
		(net "M1_DQ_NODE1_DQ54")
	)
	(segment
		(start 85.913722 -42.438066)
		(end 85.587078 -42.76471)
		(width 0.2032)
		(layer "In7.Cu")
		(net "M1_DQ_NODE1_DQ54")
	)
	(segment
		(start 90.956638 -24.25573)
		(end 90.746072 -24.466296)
		(width 0.2032)
		(layer "In7.Cu")
		(net "M1_DQ_NODE1_DQ54")
	)
	(segment
		(start 90.034872 -25.465024)
		(end 90.034872 -24.569928)
		(width 0.2032)
		(layer "In7.Cu")
		(net "M1_DQ_NODE1_DQ54")
	)
	(segment
		(start 86.240366 -41.75887)
		(end 85.913722 -42.085514)
		(width 0.2032)
		(layer "In7.Cu")
		(net "M1_DQ_NODE1_DQ54")
	)
	(segment
		(start 88.725502 -37.710364)
		(end 88.933782 -37.918644)
		(width 0.2032)
		(layer "In7.Cu")
		(net "M1_DQ_NODE1_DQ54")
	)
	(segment
		(start 90.034872 -24.569928)
		(end 89.831672 -24.366728)
		(width 0.2032)
		(layer "In7.Cu")
		(net "M1_DQ_NODE1_DQ54")
	)
	(segment
		(start 88.1634 -39.835836)
		(end 87.925402 -40.073834)
		(width 0.2032)
		(layer "In7.Cu")
		(net "M1_DQ_NODE1_DQ54")
	)
	(segment
		(start 89.323672 -24.569928)
		(end 89.323672 -25.88895)
		(width 0.2032)
		(layer "In7.Cu")
		(net "M1_DQ_NODE1_DQ54")
	)
	(segment
		(start 86.592918 -41.75887)
		(end 86.240366 -41.75887)
		(width 0.2032)
		(layer "In7.Cu")
		(net "M1_DQ_NODE1_DQ54")
	)
	(segment
		(start 91.25966 -24.257508)
		(end 90.956892 -24.257508)
		(width 0.2032)
		(layer "In7.Cu")
		(net "M1_DQ_NODE1_DQ54")
	)
	(segment
		(start 87.925402 -40.426386)
		(end 87.598758 -40.75303)
		(width 0.2032)
		(layer "In7.Cu")
		(net "M1_DQ_NODE1_DQ54")
	)
	(segment
		(start 89.526872 -24.366728)
		(end 89.323672 -24.569928)
		(width 0.2032)
		(layer "In7.Cu")
		(net "M1_DQ_NODE1_DQ54")
	)
	(segment
		(start 84.907882 -43.443906)
		(end 84.581238 -43.77055)
		(width 0.2032)
		(layer "In7.Cu")
		(net "M1_DQ_NODE1_DQ54")
	)
	(segment
		(start 88.725502 -38.421564)
		(end 88.37168 -38.421564)
		(width 0.2032)
		(layer "In7.Cu")
		(net "M1_DQ_NODE1_DQ54")
	)
	(segment
		(start 90.956892 -24.257508)
		(end 90.956638 -24.25573)
		(width 0.2032)
		(layer "In7.Cu")
		(net "M1_DQ_NODE1_DQ54")
	)
	(segment
		(start 91.81338 -25.846278)
		(end 91.457272 -25.49017)
		(width 0.2032)
		(layer "In7.Cu")
		(net "M1_DQ_NODE1_DQ54")
	)
	(segment
		(start 88.717882 -26.49474)
		(end 88.717882 -30.918658)
		(width 0.2032)
		(layer "In7.Cu")
		(net "M1_DQ_NODE1_DQ54")
	)
	(segment
		(start 88.1634 -37.207444)
		(end 88.1634 -37.502084)
		(width 0.2032)
		(layer "In7.Cu")
		(net "M1_DQ_NODE1_DQ54")
	)
	(segment
		(start 89.323672 -25.88895)
		(end 88.717882 -26.49474)
		(width 0.2032)
		(layer "In7.Cu")
		(net "M1_DQ_NODE1_DQ54")
	)
	(segment
		(start 90.746072 -24.466296)
		(end 90.746072 -25.465024)
		(width 0.2032)
		(layer "In7.Cu")
		(net "M1_DQ_NODE1_DQ54")
	)
	(segment
		(start 88.37168 -37.710364)
		(end 88.725502 -37.710364)
		(width 0.2032)
		(layer "In7.Cu")
		(net "M1_DQ_NODE1_DQ54")
	)
	(segment
		(start 75.52182 -58.781442)
		(end 75.52182 -63.101474)
		(width 0.1016)
		(layer "In7.Cu")
		(net "M1_DQ_NODE1_DQ54")
	)
	(segment
		(start 90.542872 -25.668224)
		(end 90.238072 -25.668224)
		(width 0.2032)
		(layer "In7.Cu")
		(net "M1_DQ_NODE1_DQ54")
	)
	(segment
		(start 90.238072 -25.668224)
		(end 90.034872 -25.465024)
		(width 0.2032)
		(layer "In7.Cu")
		(net "M1_DQ_NODE1_DQ54")
	)
	(segment
		(start 147.930616 -59.916822)
		(end 147.930616 -59.31535)
		(width 0.1016)
		(layer "F.Cu")
		(net "SATA_NODE1_GPIO3")
	)
	(segment
		(start 147.930616 -59.31535)
		(end 147.245578 -58.630312)
		(width 0.1016)
		(layer "F.Cu")
		(net "SATA_NODE1_GPIO3")
	)
	(segment
		(start 147.245578 -58.630312)
		(end 147.245578 -58.26633)
		(width 0.1016)
		(layer "F.Cu")
		(net "SATA_NODE1_GPIO3")
	)
	(segment
		(start 147.245578 -58.26633)
		(end 147.245578 -57.649872)
		(width 0.1016)
		(layer "F.Cu")
		(net "SATA_NODE1_GPIO3")
	)
	(segment
		(start 147.245578 -57.649872)
		(end 148.261578 -57.649872)
		(width 0.1016)
		(layer "F.Cu")
		(net "SATA_NODE1_GPIO3")
	)
	(via
		(at 147.245578 -58.26633)
		(size 0.508)
		(drill 0.254)
		(layers "F.Cu" "B.Cu")
		(net "SATA_NODE1_GPIO3")
	)
	(segment
		(start 68.257166 -96.309942)
		(end 67.659758 -95.712534)
		(width 0.1016)
		(layer "F.Cu")
		(net "LPC_CPU_NODE1_R_CLKOUT1")
	)
	(segment
		(start 63.766954 -90.600276)
		(end 63.878714 -90.712036)
		(width 0.1016)
		(layer "F.Cu")
		(net "LPC_CPU_NODE1_R_CLKOUT1")
	)
	(segment
		(start 64.961262 -93.245432)
		(end 63.766954 -92.051124)
		(width 0.1016)
		(layer "F.Cu")
		(net "LPC_CPU_NODE1_R_CLKOUT1")
	)
	(segment
		(start 63.432436 -88.745568)
		(end 63.432436 -89.796366)
		(width 0.1016)
		(layer "F.Cu")
		(net "LPC_CPU_NODE1_R_CLKOUT1")
	)
	(segment
		(start 63.766954 -92.051124)
		(end 63.766954 -90.823796)
		(width 0.1016)
		(layer "F.Cu")
		(net "LPC_CPU_NODE1_R_CLKOUT1")
	)
	(segment
		(start 63.766954 -90.130884)
		(end 63.766954 -90.600276)
		(width 0.1016)
		(layer "F.Cu")
		(net "LPC_CPU_NODE1_R_CLKOUT1")
	)
	(segment
		(start 63.608458 -88.570054)
		(end 63.432436 -88.745568)
		(width 0.1016)
		(layer "F.Cu")
		(net "LPC_CPU_NODE1_R_CLKOUT1")
	)
	(segment
		(start 63.432436 -89.796366)
		(end 63.766954 -90.130884)
		(width 0.1016)
		(layer "F.Cu")
		(net "LPC_CPU_NODE1_R_CLKOUT1")
	)
	(segment
		(start 63.766954 -90.823796)
		(end 63.878714 -90.712036)
		(width 0.1016)
		(layer "F.Cu")
		(net "LPC_CPU_NODE1_R_CLKOUT1")
	)
	(segment
		(start 67.659758 -95.504762)
		(end 65.400428 -93.245432)
		(width 0.1016)
		(layer "F.Cu")
		(net "LPC_CPU_NODE1_R_CLKOUT1")
	)
	(segment
		(start 63.608458 -88.042242)
		(end 63.608458 -88.570054)
		(width 0.1016)
		(layer "F.Cu")
		(net "LPC_CPU_NODE1_R_CLKOUT1")
	)
	(segment
		(start 65.400428 -93.245432)
		(end 64.961262 -93.245432)
		(width 0.1016)
		(layer "F.Cu")
		(net "LPC_CPU_NODE1_R_CLKOUT1")
	)
	(segment
		(start 67.659758 -95.712534)
		(end 67.659758 -95.504762)
		(width 0.1016)
		(layer "F.Cu")
		(net "LPC_CPU_NODE1_R_CLKOUT1")
	)
	(via
		(at 63.878714 -90.712036)
		(size 0.508)
		(drill 0.254)
		(layers "F.Cu" "B.Cu")
		(net "LPC_CPU_NODE1_R_CLKOUT1")
	)
	(segment
		(start 80.02905 -22.912578)
		(end 80.031082 -22.912578)
		(width 0.2286)
		(layer "F.Cu")
		(net "M_DDR3_NODE1_CAS_L")
	)
	(segment
		(start 64.774572 -62.779148)
		(end 64.774572 -62.631574)
		(width 0.1016)
		(layer "F.Cu")
		(net "M_DDR3_NODE1_CAS_L")
	)
	(segment
		(start 79.95031 -20.94992)
		(end 79.95031 -22.833838)
		(width 0.2286)
		(layer "F.Cu")
		(net "M_DDR3_NODE1_CAS_L")
	)
	(segment
		(start 64.774572 -62.631574)
		(end 66.067432 -61.338714)
		(width 0.1016)
		(layer "F.Cu")
		(net "M_DDR3_NODE1_CAS_L")
	)
	(segment
		(start 66.067432 -61.338714)
		(end 66.067432 -61.055504)
		(width 0.1016)
		(layer "F.Cu")
		(net "M_DDR3_NODE1_CAS_L")
	)
	(segment
		(start 79.95031 -22.833838)
		(end 80.02905 -22.912578)
		(width 0.2286)
		(layer "F.Cu")
		(net "M_DDR3_NODE1_CAS_L")
	)
	(segment
		(start 64.395096 -63.158624)
		(end 64.774572 -62.779148)
		(width 0.1016)
		(layer "F.Cu")
		(net "M_DDR3_NODE1_CAS_L")
	)
	(via
		(at 80.031082 -22.912578)
		(size 0.508)
		(drill 0.254)
		(layers "F.Cu" "B.Cu")
		(net "M_DDR3_NODE1_CAS_L")
	)
	(via
		(at 66.067432 -61.055504)
		(size 0.508)
		(drill 0.254)
		(layers "F.Cu" "B.Cu")
		(net "M_DDR3_NODE1_CAS_L")
	)
	(segment
		(start 83.648296 -38.30193)
		(end 83.131406 -38.30193)
		(width 0.2286)
		(layer "In2.Cu")
		(net "M_DDR3_NODE1_CAS_L")
	)
	(segment
		(start 82.86242 -36.307776)
		(end 83.078066 -36.09213)
		(width 0.2286)
		(layer "In2.Cu")
		(net "M_DDR3_NODE1_CAS_L")
	)
	(segment
		(start 66.067432 -61.055504)
		(end 67.44462 -59.678316)
		(width 0.1016)
		(layer "In2.Cu")
		(net "M_DDR3_NODE1_CAS_L")
	)
	(segment
		(start 83.078066 -36.09213)
		(end 83.648296 -36.09213)
		(width 0.2286)
		(layer "In2.Cu")
		(net "M_DDR3_NODE1_CAS_L")
	)
	(segment
		(start 68.449444 -58.527696)
		(end 70.117716 -58.527696)
		(width 0.2286)
		(layer "In2.Cu")
		(net "M_DDR3_NODE1_CAS_L")
	)
	(segment
		(start 82.17408 -26.517854)
		(end 82.17408 -24.831548)
		(width 0.2286)
		(layer "In2.Cu")
		(net "M_DDR3_NODE1_CAS_L")
	)
	(segment
		(start 83.078066 -34.61893)
		(end 83.648296 -34.61893)
		(width 0.2286)
		(layer "In2.Cu")
		(net "M_DDR3_NODE1_CAS_L")
	)
	(segment
		(start 83.178396 -32.292036)
		(end 83.51774 -31.952692)
		(width 0.2286)
		(layer "In2.Cu")
		(net "M_DDR3_NODE1_CAS_L")
	)
	(segment
		(start 83.131406 -37.56533)
		(end 83.648296 -37.56533)
		(width 0.2286)
		(layer "In2.Cu")
		(net "M_DDR3_NODE1_CAS_L")
	)
	(segment
		(start 83.863942 -38.517576)
		(end 83.648296 -38.30193)
		(width 0.2286)
		(layer "In2.Cu")
		(net "M_DDR3_NODE1_CAS_L")
	)
	(segment
		(start 82.86242 -36.613084)
		(end 82.86242 -36.307776)
		(width 0.2286)
		(layer "In2.Cu")
		(net "M_DDR3_NODE1_CAS_L")
	)
	(segment
		(start 67.44462 -59.422792)
		(end 68.339716 -58.527696)
		(width 0.1016)
		(layer "In2.Cu")
		(net "M_DDR3_NODE1_CAS_L")
	)
	(segment
		(start 74.011028 -55.215028)
		(end 75.569318 -53.656738)
		(width 0.2286)
		(layer "In2.Cu")
		(net "M_DDR3_NODE1_CAS_L")
	)
	(segment
		(start 83.86318 -46.387258)
		(end 83.86318 -38.862508)
		(width 0.2286)
		(layer "In2.Cu")
		(net "M_DDR3_NODE1_CAS_L")
	)
	(segment
		(start 83.648296 -37.56533)
		(end 83.863942 -37.349684)
		(width 0.2286)
		(layer "In2.Cu")
		(net "M_DDR3_NODE1_CAS_L")
	)
	(segment
		(start 76.5937 -53.656738)
		(end 83.86318 -46.387258)
		(width 0.2286)
		(layer "In2.Cu")
		(net "M_DDR3_NODE1_CAS_L")
	)
	(segment
		(start 80.8736 -23.214584)
		(end 80.571594 -22.912578)
		(width 0.2286)
		(layer "In2.Cu")
		(net "M_DDR3_NODE1_CAS_L")
	)
	(segment
		(start 68.339716 -58.527696)
		(end 68.449444 -58.527696)
		(width 0.1016)
		(layer "In2.Cu")
		(net "M_DDR3_NODE1_CAS_L")
	)
	(segment
		(start 83.863942 -37.349684)
		(end 83.863942 -37.044376)
		(width 0.2286)
		(layer "In2.Cu")
		(net "M_DDR3_NODE1_CAS_L")
	)
	(segment
		(start 82.453226 -29.886148)
		(end 81.79562 -29.228542)
		(width 0.2286)
		(layer "In2.Cu")
		(net "M_DDR3_NODE1_CAS_L")
	)
	(segment
		(start 83.078066 -36.82873)
		(end 82.86242 -36.613084)
		(width 0.2286)
		(layer "In2.Cu")
		(net "M_DDR3_NODE1_CAS_L")
	)
	(segment
		(start 83.863942 -34.403284)
		(end 83.863942 -33.842198)
		(width 0.2286)
		(layer "In2.Cu")
		(net "M_DDR3_NODE1_CAS_L")
	)
	(segment
		(start 81.79562 -29.228542)
		(end 81.79562 -26.896314)
		(width 0.2286)
		(layer "In2.Cu")
		(net "M_DDR3_NODE1_CAS_L")
	)
	(segment
		(start 82.91576 -38.086284)
		(end 82.91576 -37.780976)
		(width 0.2286)
		(layer "In2.Cu")
		(net "M_DDR3_NODE1_CAS_L")
	)
	(segment
		(start 83.131406 -38.30193)
		(end 82.91576 -38.086284)
		(width 0.2286)
		(layer "In2.Cu")
		(net "M_DDR3_NODE1_CAS_L")
	)
	(segment
		(start 83.648296 -36.82873)
		(end 83.078066 -36.82873)
		(width 0.2286)
		(layer "In2.Cu")
		(net "M_DDR3_NODE1_CAS_L")
	)
	(segment
		(start 70.117716 -58.527696)
		(end 73.430384 -55.215028)
		(width 0.2286)
		(layer "In2.Cu")
		(net "M_DDR3_NODE1_CAS_L")
	)
	(segment
		(start 82.17408 -24.831548)
		(end 80.8736 -23.531068)
		(width 0.2286)
		(layer "In2.Cu")
		(net "M_DDR3_NODE1_CAS_L")
	)
	(segment
		(start 83.078066 -35.35553)
		(end 82.86242 -35.139884)
		(width 0.2286)
		(layer "In2.Cu")
		(net "M_DDR3_NODE1_CAS_L")
	)
	(segment
		(start 82.86242 -35.139884)
		(end 82.86242 -34.834576)
		(width 0.2286)
		(layer "In2.Cu")
		(net "M_DDR3_NODE1_CAS_L")
	)
	(segment
		(start 83.863942 -38.861746)
		(end 83.863942 -38.517576)
		(width 0.2286)
		(layer "In2.Cu")
		(net "M_DDR3_NODE1_CAS_L")
	)
	(segment
		(start 83.51774 -30.754828)
		(end 82.64906 -29.886148)
		(width 0.2286)
		(layer "In2.Cu")
		(net "M_DDR3_NODE1_CAS_L")
	)
	(segment
		(start 82.64906 -29.886148)
		(end 82.453226 -29.886148)
		(width 0.2286)
		(layer "In2.Cu")
		(net "M_DDR3_NODE1_CAS_L")
	)
	(segment
		(start 83.863942 -35.876484)
		(end 83.863942 -35.571176)
		(width 0.2286)
		(layer "In2.Cu")
		(net "M_DDR3_NODE1_CAS_L")
	)
	(segment
		(start 82.86242 -34.834576)
		(end 83.078066 -34.61893)
		(width 0.2286)
		(layer "In2.Cu")
		(net "M_DDR3_NODE1_CAS_L")
	)
	(segment
		(start 67.44462 -59.678316)
		(end 67.44462 -59.422792)
		(width 0.1016)
		(layer "In2.Cu")
		(net "M_DDR3_NODE1_CAS_L")
	)
	(segment
		(start 80.8736 -23.531068)
		(end 80.8736 -23.214584)
		(width 0.2286)
		(layer "In2.Cu")
		(net "M_DDR3_NODE1_CAS_L")
	)
	(segment
		(start 83.648296 -34.61893)
		(end 83.863942 -34.403284)
		(width 0.2286)
		(layer "In2.Cu")
		(net "M_DDR3_NODE1_CAS_L")
	)
	(segment
		(start 83.863942 -37.044376)
		(end 83.648296 -36.82873)
		(width 0.2286)
		(layer "In2.Cu")
		(net "M_DDR3_NODE1_CAS_L")
	)
	(segment
		(start 75.569318 -53.656738)
		(end 76.5937 -53.656738)
		(width 0.2286)
		(layer "In2.Cu")
		(net "M_DDR3_NODE1_CAS_L")
	)
	(segment
		(start 83.51774 -31.952692)
		(end 83.51774 -30.754828)
		(width 0.2286)
		(layer "In2.Cu")
		(net "M_DDR3_NODE1_CAS_L")
	)
	(segment
		(start 80.571594 -22.912578)
		(end 80.031082 -22.912578)
		(width 0.2286)
		(layer "In2.Cu")
		(net "M_DDR3_NODE1_CAS_L")
	)
	(segment
		(start 83.178396 -33.156652)
		(end 83.178396 -32.292036)
		(width 0.2286)
		(layer "In2.Cu")
		(net "M_DDR3_NODE1_CAS_L")
	)
	(segment
		(start 83.648296 -35.35553)
		(end 83.078066 -35.35553)
		(width 0.2286)
		(layer "In2.Cu")
		(net "M_DDR3_NODE1_CAS_L")
	)
	(segment
		(start 83.863942 -35.571176)
		(end 83.648296 -35.35553)
		(width 0.2286)
		(layer "In2.Cu")
		(net "M_DDR3_NODE1_CAS_L")
	)
	(segment
		(start 82.91576 -37.780976)
		(end 83.131406 -37.56533)
		(width 0.2286)
		(layer "In2.Cu")
		(net "M_DDR3_NODE1_CAS_L")
	)
	(segment
		(start 83.863942 -33.842198)
		(end 83.178396 -33.156652)
		(width 0.2286)
		(layer "In2.Cu")
		(net "M_DDR3_NODE1_CAS_L")
	)
	(segment
		(start 83.86318 -38.862508)
		(end 83.863942 -38.861746)
		(width 0.2286)
		(layer "In2.Cu")
		(net "M_DDR3_NODE1_CAS_L")
	)
	(segment
		(start 73.430384 -55.215028)
		(end 74.011028 -55.215028)
		(width 0.2286)
		(layer "In2.Cu")
		(net "M_DDR3_NODE1_CAS_L")
	)
	(segment
		(start 81.79562 -26.896314)
		(end 82.17408 -26.517854)
		(width 0.2286)
		(layer "In2.Cu")
		(net "M_DDR3_NODE1_CAS_L")
	)
	(segment
		(start 83.648296 -36.09213)
		(end 83.863942 -35.876484)
		(width 0.2286)
		(layer "In2.Cu")
		(net "M_DDR3_NODE1_CAS_L")
	)
	(segment
		(start 137.039096 -118.514622)
		(end 137.082276 -118.471442)
		(width 0.127)
		(layer "F.Cu")
		(net "CLK_100M_PCIE_SW_NODE1_DN")
	)
	(segment
		(start 137.082276 -118.471442)
		(end 137.601452 -118.471442)
		(width 0.127)
		(layer "F.Cu")
		(net "CLK_100M_PCIE_SW_NODE1_DN")
	)
	(segment
		(start 144.904714 -118.712996)
		(end 145.39976 -119.208042)
		(width 0.127)
		(layer "F.Cu")
		(net "CLK_100M_PCIE_SW_NODE1_DN")
	)
	(segment
		(start 136.503664 -118.514622)
		(end 137.039096 -118.514622)
		(width 0.127)
		(layer "F.Cu")
		(net "CLK_100M_PCIE_SW_NODE1_DN")
	)
	(segment
		(start 137.843006 -118.712996)
		(end 144.904714 -118.712996)
		(width 0.127)
		(layer "F.Cu")
		(net "CLK_100M_PCIE_SW_NODE1_DN")
	)
	(segment
		(start 137.601452 -118.471442)
		(end 137.843006 -118.712996)
		(width 0.127)
		(layer "F.Cu")
		(net "CLK_100M_PCIE_SW_NODE1_DN")
	)
	(via
		(at 145.39976 -119.208042)
		(size 0.508)
		(drill 0.254)
		(layers "F.Cu" "B.Cu")
		(net "CLK_100M_PCIE_SW_NODE1_DN")
	)
	(segment
		(start 146.07667 -121.616216)
		(end 146.338798 -121.616216)
		(width 0.127)
		(layer "B.Cu")
		(net "CLK_100M_PCIE_SW_NODE1_DN")
	)
	(segment
		(start 145.88236 -118.725442)
		(end 145.39976 -119.208042)
		(width 0.127)
		(layer "B.Cu")
		(net "CLK_100M_PCIE_SW_NODE1_DN")
	)
	(segment
		(start 145.196306 -122.49658)
		(end 143.667734 -120.968008)
		(width 0.127)
		(layer "B.Cu")
		(net "CLK_100M_PCIE_SW_NODE1_DN")
	)
	(segment
		(start 143.667734 -120.968008)
		(end 143.667734 -120.45188)
		(width 0.127)
		(layer "B.Cu")
		(net "CLK_100M_PCIE_SW_NODE1_DN")
	)
	(segment
		(start 128.86436 -129.345182)
		(end 128.99898 -129.210562)
		(width 0.127)
		(layer "B.Cu")
		(net "CLK_100M_PCIE_SW_NODE1_DN")
	)
	(segment
		(start 128.86436 -131.407662)
		(end 128.99898 -131.273042)
		(width 0.127)
		(layer "B.Cu")
		(net "CLK_100M_PCIE_SW_NODE1_DN")
	)
	(segment
		(start 128.99898 -131.273042)
		(end 128.99898 -130.892042)
		(width 0.127)
		(layer "B.Cu")
		(net "CLK_100M_PCIE_SW_NODE1_DN")
	)
	(segment
		(start 146.765518 -118.725442)
		(end 145.88236 -118.725442)
		(width 0.127)
		(layer "B.Cu")
		(net "CLK_100M_PCIE_SW_NODE1_DN")
	)
	(segment
		(start 145.196306 -122.758708)
		(end 145.196306 -122.49658)
		(width 0.127)
		(layer "B.Cu")
		(net "CLK_100M_PCIE_SW_NODE1_DN")
	)
	(segment
		(start 128.99898 -130.241802)
		(end 128.99898 -129.860802)
		(width 0.127)
		(layer "B.Cu")
		(net "CLK_100M_PCIE_SW_NODE1_DN")
	)
	(segment
		(start 141.555216 -123.995434)
		(end 143.95958 -123.995434)
		(width 0.127)
		(layer "B.Cu")
		(net "CLK_100M_PCIE_SW_NODE1_DN")
	)
	(segment
		(start 134.68858 -126.11862)
		(end 139.43203 -126.11862)
		(width 0.127)
		(layer "B.Cu")
		(net "CLK_100M_PCIE_SW_NODE1_DN")
	)
	(segment
		(start 139.43203 -126.11862)
		(end 141.555216 -123.995434)
		(width 0.127)
		(layer "B.Cu")
		(net "CLK_100M_PCIE_SW_NODE1_DN")
	)
	(segment
		(start 128.99898 -129.860802)
		(end 128.86436 -129.726182)
		(width 0.127)
		(layer "B.Cu")
		(net "CLK_100M_PCIE_SW_NODE1_DN")
	)
	(segment
		(start 130.875278 -126.917958)
		(end 133.889242 -126.917958)
		(width 0.127)
		(layer "B.Cu")
		(net "CLK_100M_PCIE_SW_NODE1_DN")
	)
	(segment
		(start 128.99898 -132.304282)
		(end 128.99898 -131.923282)
		(width 0.127)
		(layer "B.Cu")
		(net "CLK_100M_PCIE_SW_NODE1_DN")
	)
	(segment
		(start 128.86436 -132.819902)
		(end 128.86436 -132.438902)
		(width 0.127)
		(layer "B.Cu")
		(net "CLK_100M_PCIE_SW_NODE1_DN")
	)
	(segment
		(start 143.667734 -120.45188)
		(end 144.03197 -120.087644)
		(width 0.127)
		(layer "B.Cu")
		(net "CLK_100M_PCIE_SW_NODE1_DN")
	)
	(segment
		(start 146.338798 -121.616216)
		(end 147.47748 -120.477534)
		(width 0.127)
		(layer "B.Cu")
		(net "CLK_100M_PCIE_SW_NODE1_DN")
	)
	(segment
		(start 129.102612 -135.161782)
		(end 128.99898 -135.05815)
		(width 0.127)
		(layer "B.Cu")
		(net "CLK_100M_PCIE_SW_NODE1_DN")
	)
	(segment
		(start 147.47748 -119.437404)
		(end 146.765518 -118.725442)
		(width 0.127)
		(layer "B.Cu")
		(net "CLK_100M_PCIE_SW_NODE1_DN")
	)
	(segment
		(start 147.47748 -120.477534)
		(end 147.47748 -119.437404)
		(width 0.127)
		(layer "B.Cu")
		(net "CLK_100M_PCIE_SW_NODE1_DN")
	)
	(segment
		(start 128.86436 -132.438902)
		(end 128.99898 -132.304282)
		(width 0.127)
		(layer "B.Cu")
		(net "CLK_100M_PCIE_SW_NODE1_DN")
	)
	(segment
		(start 128.99898 -129.210562)
		(end 128.99898 -128.794256)
		(width 0.127)
		(layer "B.Cu")
		(net "CLK_100M_PCIE_SW_NODE1_DN")
	)
	(segment
		(start 143.95958 -123.995434)
		(end 145.196306 -122.758708)
		(width 0.127)
		(layer "B.Cu")
		(net "CLK_100M_PCIE_SW_NODE1_DN")
	)
	(segment
		(start 128.86436 -129.726182)
		(end 128.86436 -129.345182)
		(width 0.127)
		(layer "B.Cu")
		(net "CLK_100M_PCIE_SW_NODE1_DN")
	)
	(segment
		(start 144.548098 -120.087644)
		(end 146.07667 -121.616216)
		(width 0.127)
		(layer "B.Cu")
		(net "CLK_100M_PCIE_SW_NODE1_DN")
	)
	(segment
		(start 128.99898 -131.923282)
		(end 128.86436 -131.788662)
		(width 0.127)
		(layer "B.Cu")
		(net "CLK_100M_PCIE_SW_NODE1_DN")
	)
	(segment
		(start 128.86436 -131.788662)
		(end 128.86436 -131.407662)
		(width 0.127)
		(layer "B.Cu")
		(net "CLK_100M_PCIE_SW_NODE1_DN")
	)
	(segment
		(start 129.102612 -136.0043)
		(end 129.102612 -135.161782)
		(width 0.127)
		(layer "B.Cu")
		(net "CLK_100M_PCIE_SW_NODE1_DN")
	)
	(segment
		(start 128.99898 -130.892042)
		(end 128.86436 -130.757422)
		(width 0.127)
		(layer "B.Cu")
		(net "CLK_100M_PCIE_SW_NODE1_DN")
	)
	(segment
		(start 128.762252 -136.34466)
		(end 129.102612 -136.0043)
		(width 0.127)
		(layer "B.Cu")
		(net "CLK_100M_PCIE_SW_NODE1_DN")
	)
	(segment
		(start 133.889242 -126.917958)
		(end 134.68858 -126.11862)
		(width 0.127)
		(layer "B.Cu")
		(net "CLK_100M_PCIE_SW_NODE1_DN")
	)
	(segment
		(start 128.86436 -130.376422)
		(end 128.99898 -130.241802)
		(width 0.127)
		(layer "B.Cu")
		(net "CLK_100M_PCIE_SW_NODE1_DN")
	)
	(segment
		(start 128.99898 -128.794256)
		(end 130.875278 -126.917958)
		(width 0.127)
		(layer "B.Cu")
		(net "CLK_100M_PCIE_SW_NODE1_DN")
	)
	(segment
		(start 128.86436 -130.757422)
		(end 128.86436 -130.376422)
		(width 0.127)
		(layer "B.Cu")
		(net "CLK_100M_PCIE_SW_NODE1_DN")
	)
	(segment
		(start 128.99898 -132.954522)
		(end 128.86436 -132.819902)
		(width 0.127)
		(layer "B.Cu")
		(net "CLK_100M_PCIE_SW_NODE1_DN")
	)
	(segment
		(start 128.99898 -135.05815)
		(end 128.99898 -132.954522)
		(width 0.127)
		(layer "B.Cu")
		(net "CLK_100M_PCIE_SW_NODE1_DN")
	)
	(segment
		(start 144.03197 -120.087644)
		(end 144.548098 -120.087644)
		(width 0.127)
		(layer "B.Cu")
		(net "CLK_100M_PCIE_SW_NODE1_DN")
	)
	(segment
		(start 100.387658 -162.71621)
		(end 100.387658 -163.205668)
		(width 0.1016)
		(layer "F.Cu")
		(net "N52411069")
	)
	(segment
		(start 99.182428 -162.930586)
		(end 99.672648 -163.420806)
		(width 0.1016)
		(layer "F.Cu")
		(net "N52411069")
	)
	(segment
		(start 100.387658 -163.205668)
		(end 100.17252 -163.420806)
		(width 0.1016)
		(layer "F.Cu")
		(net "N52411069")
	)
	(segment
		(start 99.672648 -163.420806)
		(end 100.17252 -163.420806)
		(width 0.1016)
		(layer "F.Cu")
		(net "N52411069")
	)
	(segment
		(start 99.182428 -162.627818)
		(end 99.182428 -162.930586)
		(width 0.1016)
		(layer "F.Cu")
		(net "N52411069")
	)
	(via
		(at 100.17252 -163.420806)
		(size 0.508)
		(drill 0.254)
		(layers "F.Cu" "B.Cu")
		(net "N52411069")
	)
	(segment
		(start 57.245504 -58.829194)
		(end 57.728358 -58.829194)
		(width 0.1016)
		(layer "F.Cu")
		(net "M_DDR3_NODE1_MA14")
	)
	(segment
		(start 60.8457 -43.230038)
		(end 62.011814 -43.230038)
		(width 0.2286)
		(layer "F.Cu")
		(net "M_DDR3_NODE1_MA14")
	)
	(segment
		(start 62.47638 -48.024542)
		(end 62.260734 -47.808896)
		(width 0.2286)
		(layer "F.Cu")
		(net "M_DDR3_NODE1_MA14")
	)
	(segment
		(start 63.403988 -38.586664)
		(end 63.403988 -38.281864)
		(width 0.2286)
		(layer "F.Cu")
		(net "M_DDR3_NODE1_MA14")
	)
	(segment
		(start 62.45606 -44.660058)
		(end 62.240414 -44.444412)
		(width 0.2286)
		(layer "F.Cu")
		(net "M_DDR3_NODE1_MA14")
	)
	(segment
		(start 60.4901 -43.585638)
		(end 60.8457 -43.230038)
		(width 0.2286)
		(layer "F.Cu")
		(net "M_DDR3_NODE1_MA14")
	)
	(segment
		(start 63.403988 -38.281864)
		(end 66.363088 -35.322764)
		(width 0.2286)
		(layer "F.Cu")
		(net "M_DDR3_NODE1_MA14")
	)
	(segment
		(start 67.10426 -34.25698)
		(end 67.10426 -35.6235)
		(width 0.2286)
		(layer "F.Cu")
		(net "M_DDR3_NODE1_MA14")
	)
	(segment
		(start 62.47638 -46.551342)
		(end 62.260734 -46.335696)
		(width 0.2286)
		(layer "F.Cu")
		(net "M_DDR3_NODE1_MA14")
	)
	(segment
		(start 63.099188 -39.628572)
		(end 62.78372 -39.94404)
		(width 0.2286)
		(layer "F.Cu")
		(net "M_DDR3_NODE1_MA14")
	)
	(segment
		(start 62.60846 -38.035484)
		(end 62.60846 -38.833044)
		(width 0.2286)
		(layer "F.Cu")
		(net "M_DDR3_NODE1_MA14")
	)
	(segment
		(start 63.620142 -38.802818)
		(end 63.403988 -38.586664)
		(width 0.2286)
		(layer "F.Cu")
		(net "M_DDR3_NODE1_MA14")
	)
	(segment
		(start 62.60846 -38.833044)
		(end 63.099188 -39.323772)
		(width 0.2286)
		(layer "F.Cu")
		(net "M_DDR3_NODE1_MA14")
	)
	(segment
		(start 60.609734 -46.335696)
		(end 60.27166 -45.997622)
		(width 0.2286)
		(layer "F.Cu")
		(net "M_DDR3_NODE1_MA14")
	)
	(segment
		(start 62.47638 -46.85665)
		(end 62.47638 -46.551342)
		(width 0.2286)
		(layer "F.Cu")
		(net "M_DDR3_NODE1_MA14")
	)
	(segment
		(start 63.099188 -39.323772)
		(end 63.099188 -39.628572)
		(width 0.2286)
		(layer "F.Cu")
		(net "M_DDR3_NODE1_MA14")
	)
	(segment
		(start 57.728358 -58.829194)
		(end 57.96788 -58.589672)
		(width 0.1016)
		(layer "F.Cu")
		(net "M_DDR3_NODE1_MA14")
	)
	(segment
		(start 56.9722 -63.480188)
		(end 56.9722 -59.102498)
		(width 0.1016)
		(layer "F.Cu")
		(net "M_DDR3_NODE1_MA14")
	)
	(segment
		(start 62.784482 -41.913556)
		(end 62.784482 -41.429178)
		(width 0.2286)
		(layer "F.Cu")
		(net "M_DDR3_NODE1_MA14")
	)
	(segment
		(start 65.842134 -34.80181)
		(end 62.60846 -38.035484)
		(width 0.2286)
		(layer "F.Cu")
		(net "M_DDR3_NODE1_MA14")
	)
	(segment
		(start 62.260734 -47.072296)
		(end 62.47638 -46.85665)
		(width 0.2286)
		(layer "F.Cu")
		(net "M_DDR3_NODE1_MA14")
	)
	(segment
		(start 62.784482 -39.944802)
		(end 62.784482 -41.429178)
		(width 0.2286)
		(layer "F.Cu")
		(net "M_DDR3_NODE1_MA14")
	)
	(segment
		(start 60.715906 -47.808896)
		(end 60.50026 -47.59325)
		(width 0.2286)
		(layer "F.Cu")
		(net "M_DDR3_NODE1_MA14")
	)
	(segment
		(start 60.609734 -45.181012)
		(end 62.240414 -45.181012)
		(width 0.2286)
		(layer "F.Cu")
		(net "M_DDR3_NODE1_MA14")
	)
	(segment
		(start 60.8457 -44.444412)
		(end 60.4901 -44.088812)
		(width 0.2286)
		(layer "F.Cu")
		(net "M_DDR3_NODE1_MA14")
	)
	(segment
		(start 66.146934 -34.80181)
		(end 65.842134 -34.80181)
		(width 0.2286)
		(layer "F.Cu")
		(net "M_DDR3_NODE1_MA14")
	)
	(segment
		(start 60.27166 -45.519086)
		(end 60.609734 -45.181012)
		(width 0.2286)
		(layer "F.Cu")
		(net "M_DDR3_NODE1_MA14")
	)
	(segment
		(start 57.96788 -53.70703)
		(end 61.00318 -50.67173)
		(width 0.2286)
		(layer "F.Cu")
		(net "M_DDR3_NODE1_MA14")
	)
	(segment
		(start 60.715906 -47.072296)
		(end 62.260734 -47.072296)
		(width 0.2286)
		(layer "F.Cu")
		(net "M_DDR3_NODE1_MA14")
	)
	(segment
		(start 63.924942 -38.802818)
		(end 63.620142 -38.802818)
		(width 0.2286)
		(layer "F.Cu")
		(net "M_DDR3_NODE1_MA14")
	)
	(segment
		(start 62.22746 -43.014392)
		(end 62.22746 -42.470578)
		(width 0.2286)
		(layer "F.Cu")
		(net "M_DDR3_NODE1_MA14")
	)
	(segment
		(start 60.50026 -47.287942)
		(end 60.715906 -47.072296)
		(width 0.2286)
		(layer "F.Cu")
		(net "M_DDR3_NODE1_MA14")
	)
	(segment
		(start 60.27166 -45.997622)
		(end 60.27166 -45.519086)
		(width 0.2286)
		(layer "F.Cu")
		(net "M_DDR3_NODE1_MA14")
	)
	(segment
		(start 62.78372 -39.94404)
		(end 62.784482 -39.944802)
		(width 0.2286)
		(layer "F.Cu")
		(net "M_DDR3_NODE1_MA14")
	)
	(segment
		(start 61.758068 -48.545496)
		(end 62.260734 -48.545496)
		(width 0.2286)
		(layer "F.Cu")
		(net "M_DDR3_NODE1_MA14")
	)
	(segment
		(start 61.00318 -49.300384)
		(end 61.758068 -48.545496)
		(width 0.2286)
		(layer "F.Cu")
		(net "M_DDR3_NODE1_MA14")
	)
	(segment
		(start 60.50026 -47.59325)
		(end 60.50026 -47.287942)
		(width 0.2286)
		(layer "F.Cu")
		(net "M_DDR3_NODE1_MA14")
	)
	(segment
		(start 66.363088 -35.322764)
		(end 66.363088 -35.017964)
		(width 0.2286)
		(layer "F.Cu")
		(net "M_DDR3_NODE1_MA14")
	)
	(segment
		(start 62.45606 -44.965366)
		(end 62.45606 -44.660058)
		(width 0.2286)
		(layer "F.Cu")
		(net "M_DDR3_NODE1_MA14")
	)
	(segment
		(start 62.260734 -46.335696)
		(end 60.609734 -46.335696)
		(width 0.2286)
		(layer "F.Cu")
		(net "M_DDR3_NODE1_MA14")
	)
	(segment
		(start 66.363088 -35.017964)
		(end 66.146934 -34.80181)
		(width 0.2286)
		(layer "F.Cu")
		(net "M_DDR3_NODE1_MA14")
	)
	(segment
		(start 62.011814 -43.230038)
		(end 62.22746 -43.014392)
		(width 0.2286)
		(layer "F.Cu")
		(net "M_DDR3_NODE1_MA14")
	)
	(segment
		(start 62.22746 -42.470578)
		(end 62.784482 -41.913556)
		(width 0.2286)
		(layer "F.Cu")
		(net "M_DDR3_NODE1_MA14")
	)
	(segment
		(start 56.9722 -59.102498)
		(end 57.245504 -58.829194)
		(width 0.1016)
		(layer "F.Cu")
		(net "M_DDR3_NODE1_MA14")
	)
	(segment
		(start 60.4901 -44.088812)
		(end 60.4901 -43.585638)
		(width 0.2286)
		(layer "F.Cu")
		(net "M_DDR3_NODE1_MA14")
	)
	(segment
		(start 62.260734 -48.545496)
		(end 62.47638 -48.32985)
		(width 0.2286)
		(layer "F.Cu")
		(net "M_DDR3_NODE1_MA14")
	)
	(segment
		(start 62.240414 -44.444412)
		(end 60.8457 -44.444412)
		(width 0.2286)
		(layer "F.Cu")
		(net "M_DDR3_NODE1_MA14")
	)
	(segment
		(start 69.450204 -29.149802)
		(end 69.450204 -31.911036)
		(width 0.2286)
		(layer "F.Cu")
		(net "M_DDR3_NODE1_MA14")
	)
	(segment
		(start 62.260734 -47.808896)
		(end 60.715906 -47.808896)
		(width 0.2286)
		(layer "F.Cu")
		(net "M_DDR3_NODE1_MA14")
	)
	(segment
		(start 57.96788 -58.589672)
		(end 57.96788 -53.70703)
		(width 0.2286)
		(layer "F.Cu")
		(net "M_DDR3_NODE1_MA14")
	)
	(segment
		(start 67.10426 -35.6235)
		(end 63.924942 -38.802818)
		(width 0.2286)
		(layer "F.Cu")
		(net "M_DDR3_NODE1_MA14")
	)
	(segment
		(start 69.450204 -31.911036)
		(end 67.10426 -34.25698)
		(width 0.2286)
		(layer "F.Cu")
		(net "M_DDR3_NODE1_MA14")
	)
	(segment
		(start 62.240414 -45.181012)
		(end 62.45606 -44.965366)
		(width 0.2286)
		(layer "F.Cu")
		(net "M_DDR3_NODE1_MA14")
	)
	(segment
		(start 62.47638 -48.32985)
		(end 62.47638 -48.024542)
		(width 0.2286)
		(layer "F.Cu")
		(net "M_DDR3_NODE1_MA14")
	)
	(segment
		(start 61.00318 -50.67173)
		(end 61.00318 -49.300384)
		(width 0.2286)
		(layer "F.Cu")
		(net "M_DDR3_NODE1_MA14")
	)
	(segment
		(start 56.895746 -63.556642)
		(end 56.9722 -63.480188)
		(width 0.1016)
		(layer "F.Cu")
		(net "M_DDR3_NODE1_MA14")
	)
	(via
		(at 62.784482 -41.429178)
		(size 0.762)
		(drill 0.381)
		(layers "F.Cu" "B.Cu")
		(net "M_DDR3_NODE1_MA14")
	)
	(segment
		(start 137.091166 -118.166642)
		(end 137.727944 -118.166642)
		(width 0.127)
		(layer "F.Cu")
		(net "CLK_100M_PCIE_SW_NODE1_DP")
	)
	(segment
		(start 144.929606 -118.408196)
		(end 145.39976 -117.938042)
		(width 0.127)
		(layer "F.Cu")
		(net "CLK_100M_PCIE_SW_NODE1_DP")
	)
	(segment
		(start 136.503664 -118.114572)
		(end 137.039096 -118.114572)
		(width 0.127)
		(layer "F.Cu")
		(net "CLK_100M_PCIE_SW_NODE1_DP")
	)
	(segment
		(start 137.969498 -118.408196)
		(end 144.929606 -118.408196)
		(width 0.127)
		(layer "F.Cu")
		(net "CLK_100M_PCIE_SW_NODE1_DP")
	)
	(segment
		(start 137.727944 -118.166642)
		(end 137.969498 -118.408196)
		(width 0.127)
		(layer "F.Cu")
		(net "CLK_100M_PCIE_SW_NODE1_DP")
	)
	(segment
		(start 137.039096 -118.114572)
		(end 137.091166 -118.166642)
		(width 0.127)
		(layer "F.Cu")
		(net "CLK_100M_PCIE_SW_NODE1_DP")
	)
	(via
		(at 145.39976 -117.938042)
		(size 0.508)
		(drill 0.254)
		(layers "F.Cu" "B.Cu")
		(net "CLK_100M_PCIE_SW_NODE1_DP")
	)
	(segment
		(start 129.407412 -135.03529)
		(end 129.305812 -134.93369)
		(width 0.127)
		(layer "B.Cu")
		(net "CLK_100M_PCIE_SW_NODE1_DP")
	)
	(segment
		(start 141.681708 -124.300234)
		(end 144.086072 -124.300234)
		(width 0.127)
		(layer "B.Cu")
		(net "CLK_100M_PCIE_SW_NODE1_DP")
	)
	(segment
		(start 146.46529 -121.921016)
		(end 147.78228 -120.604026)
		(width 0.127)
		(layer "B.Cu")
		(net "CLK_100M_PCIE_SW_NODE1_DP")
	)
	(segment
		(start 129.305812 -132.838698)
		(end 129.30378 -132.838698)
		(width 0.127)
		(layer "B.Cu")
		(net "CLK_100M_PCIE_SW_NODE1_DP")
	)
	(segment
		(start 144.158462 -120.392444)
		(end 144.421606 -120.392444)
		(width 0.127)
		(layer "B.Cu")
		(net "CLK_100M_PCIE_SW_NODE1_DP")
	)
	(segment
		(start 144.086072 -124.300234)
		(end 145.501106 -122.8852)
		(width 0.127)
		(layer "B.Cu")
		(net "CLK_100M_PCIE_SW_NODE1_DP")
	)
	(segment
		(start 146.89201 -118.420642)
		(end 146.009106 -118.420642)
		(width 0.127)
		(layer "B.Cu")
		(net "CLK_100M_PCIE_SW_NODE1_DP")
	)
	(segment
		(start 131.00177 -127.222758)
		(end 134.015734 -127.222758)
		(width 0.127)
		(layer "B.Cu")
		(net "CLK_100M_PCIE_SW_NODE1_DP")
	)
	(segment
		(start 129.30378 -132.838698)
		(end 129.30378 -128.920748)
		(width 0.127)
		(layer "B.Cu")
		(net "CLK_100M_PCIE_SW_NODE1_DP")
	)
	(segment
		(start 147.78228 -120.604026)
		(end 147.78228 -119.310912)
		(width 0.127)
		(layer "B.Cu")
		(net "CLK_100M_PCIE_SW_NODE1_DP")
	)
	(segment
		(start 129.30378 -128.920748)
		(end 131.00177 -127.222758)
		(width 0.127)
		(layer "B.Cu")
		(net "CLK_100M_PCIE_SW_NODE1_DP")
	)
	(segment
		(start 134.015734 -127.222758)
		(end 134.815072 -126.42342)
		(width 0.127)
		(layer "B.Cu")
		(net "CLK_100M_PCIE_SW_NODE1_DP")
	)
	(segment
		(start 143.972534 -120.841516)
		(end 143.972534 -120.578372)
		(width 0.127)
		(layer "B.Cu")
		(net "CLK_100M_PCIE_SW_NODE1_DP")
	)
	(segment
		(start 146.009106 -118.420642)
		(end 146.008598 -118.420134)
		(width 0.127)
		(layer "B.Cu")
		(net "CLK_100M_PCIE_SW_NODE1_DP")
	)
	(segment
		(start 144.421606 -120.392444)
		(end 145.950178 -121.921016)
		(width 0.127)
		(layer "B.Cu")
		(net "CLK_100M_PCIE_SW_NODE1_DP")
	)
	(segment
		(start 134.815072 -126.42342)
		(end 139.558522 -126.42342)
		(width 0.127)
		(layer "B.Cu")
		(net "CLK_100M_PCIE_SW_NODE1_DP")
	)
	(segment
		(start 143.972534 -120.578372)
		(end 144.158462 -120.392444)
		(width 0.127)
		(layer "B.Cu")
		(net "CLK_100M_PCIE_SW_NODE1_DP")
	)
	(segment
		(start 146.008598 -118.420134)
		(end 145.882106 -118.420388)
		(width 0.127)
		(layer "B.Cu")
		(net "CLK_100M_PCIE_SW_NODE1_DP")
	)
	(segment
		(start 129.407412 -135.97382)
		(end 129.407412 -135.03529)
		(width 0.127)
		(layer "B.Cu")
		(net "CLK_100M_PCIE_SW_NODE1_DP")
	)
	(segment
		(start 145.882106 -118.420388)
		(end 145.39976 -117.938042)
		(width 0.127)
		(layer "B.Cu")
		(net "CLK_100M_PCIE_SW_NODE1_DP")
	)
	(segment
		(start 145.950178 -121.921016)
		(end 146.46529 -121.921016)
		(width 0.127)
		(layer "B.Cu")
		(net "CLK_100M_PCIE_SW_NODE1_DP")
	)
	(segment
		(start 129.305812 -134.93369)
		(end 129.305812 -132.838698)
		(width 0.127)
		(layer "B.Cu")
		(net "CLK_100M_PCIE_SW_NODE1_DP")
	)
	(segment
		(start 145.501106 -122.8852)
		(end 145.501106 -122.370088)
		(width 0.127)
		(layer "B.Cu")
		(net "CLK_100M_PCIE_SW_NODE1_DP")
	)
	(segment
		(start 129.778252 -136.34466)
		(end 129.407412 -135.97382)
		(width 0.127)
		(layer "B.Cu")
		(net "CLK_100M_PCIE_SW_NODE1_DP")
	)
	(segment
		(start 145.501106 -122.370088)
		(end 143.972534 -120.841516)
		(width 0.127)
		(layer "B.Cu")
		(net "CLK_100M_PCIE_SW_NODE1_DP")
	)
	(segment
		(start 139.558522 -126.42342)
		(end 141.681708 -124.300234)
		(width 0.127)
		(layer "B.Cu")
		(net "CLK_100M_PCIE_SW_NODE1_DP")
	)
	(segment
		(start 147.78228 -119.310912)
		(end 146.89201 -118.420642)
		(width 0.127)
		(layer "B.Cu")
		(net "CLK_100M_PCIE_SW_NODE1_DP")
	)
	(segment
		(start 138.480038 -69.662548)
		(end 138.480038 -70.324726)
		(width 0.254)
		(layer "F.Cu")
		(net "LED_SATA_NODE1_R")
	)
	(segment
		(start 138.486642 -70.33133)
		(end 138.486642 -71.254112)
		(width 0.254)
		(layer "F.Cu")
		(net "LED_SATA_NODE1_R")
	)
	(segment
		(start 138.480038 -70.324726)
		(end 138.486642 -70.33133)
		(width 0.254)
		(layer "F.Cu")
		(net "LED_SATA_NODE1_R")
	)
	(via
		(at 138.486642 -70.33133)
		(size 0.508)
		(drill 0.254)
		(layers "F.Cu" "B.Cu")
		(net "LED_SATA_NODE1_R")
	)
	(segment
		(start 67.073018 -93.348048)
		(end 67.59702 -93.348048)
		(width 0.1016)
		(layer "F.Cu")
		(net "SPC_CPU_NODE1_DTR_L")
	)
	(segment
		(start 69.273166 -97.110042)
		(end 70.289166 -97.110042)
		(width 0.1016)
		(layer "F.Cu")
		(net "SPC_CPU_NODE1_DTR_L")
	)
	(segment
		(start 66.41338 -92.68841)
		(end 67.073018 -93.348048)
		(width 0.1016)
		(layer "F.Cu")
		(net "SPC_CPU_NODE1_DTR_L")
	)
	(segment
		(start 70.800976 -95.980504)
		(end 70.36816 -95.547688)
		(width 0.1016)
		(layer "F.Cu")
		(net "SPC_CPU_NODE1_DTR_L")
	)
	(segment
		(start 65.138046 -90.532204)
		(end 66.41338 -91.807538)
		(width 0.1016)
		(layer "F.Cu")
		(net "SPC_CPU_NODE1_DTR_L")
	)
	(segment
		(start 65.138046 -89.375234)
		(end 65.138046 -90.532204)
		(width 0.1016)
		(layer "F.Cu")
		(net "SPC_CPU_NODE1_DTR_L")
	)
	(segment
		(start 67.59702 -93.348048)
		(end 68.461128 -94.212156)
		(width 0.1016)
		(layer "F.Cu")
		(net "SPC_CPU_NODE1_DTR_L")
	)
	(segment
		(start 70.289166 -97.110042)
		(end 70.800976 -96.598232)
		(width 0.1016)
		(layer "F.Cu")
		(net "SPC_CPU_NODE1_DTR_L")
	)
	(segment
		(start 66.41338 -91.807538)
		(end 66.41338 -92.68841)
		(width 0.1016)
		(layer "F.Cu")
		(net "SPC_CPU_NODE1_DTR_L")
	)
	(segment
		(start 65.464436 -89.048844)
		(end 65.138046 -89.375234)
		(width 0.1016)
		(layer "F.Cu")
		(net "SPC_CPU_NODE1_DTR_L")
	)
	(segment
		(start 68.461128 -94.212156)
		(end 69.032628 -94.212156)
		(width 0.1016)
		(layer "F.Cu")
		(net "SPC_CPU_NODE1_DTR_L")
	)
	(segment
		(start 70.800976 -96.598232)
		(end 70.800976 -95.980504)
		(width 0.1016)
		(layer "F.Cu")
		(net "SPC_CPU_NODE1_DTR_L")
	)
	(segment
		(start 69.032628 -94.212156)
		(end 70.36816 -95.547688)
		(width 0.1016)
		(layer "F.Cu")
		(net "SPC_CPU_NODE1_DTR_L")
	)
	(via
		(at 70.36816 -95.547688)
		(size 0.508)
		(drill 0.254)
		(layers "F.Cu" "B.Cu")
		(net "SPC_CPU_NODE1_DTR_L")
	)
	(segment
		(start 101.283262 -26.582878)
		(end 101.501702 -26.582878)
		(width 0.1651)
		(layer "F.Cu")
		(net "M1_DQ_NODE1_DQ63")
	)
	(segment
		(start 100.650294 -27.215846)
		(end 101.283262 -26.582878)
		(width 0.1651)
		(layer "F.Cu")
		(net "M1_DQ_NODE1_DQ63")
	)
	(segment
		(start 73.63968 -74.114914)
		(end 73.678542 -74.076052)
		(width 0.1016)
		(layer "F.Cu")
		(net "M1_DQ_NODE1_DQ63")
	)
	(segment
		(start 74.689716 -74.076052)
		(end 74.773028 -74.159364)
		(width 0.1016)
		(layer "F.Cu")
		(net "M1_DQ_NODE1_DQ63")
	)
	(segment
		(start 100.650294 -29.149802)
		(end 100.650294 -27.215846)
		(width 0.1651)
		(layer "F.Cu")
		(net "M1_DQ_NODE1_DQ63")
	)
	(segment
		(start 73.678542 -74.076052)
		(end 74.689716 -74.076052)
		(width 0.1016)
		(layer "F.Cu")
		(net "M1_DQ_NODE1_DQ63")
	)
	(via
		(at 101.501702 -26.582878)
		(size 0.508)
		(drill 0.254)
		(layers "F.Cu" "B.Cu")
		(net "M1_DQ_NODE1_DQ63")
	)
	(via
		(at 74.773028 -74.159364)
		(size 0.508)
		(drill 0.254)
		(layers "F.Cu" "B.Cu")
		(net "M1_DQ_NODE1_DQ63")
	)
	(segment
		(start 98.960686 -55.748428)
		(end 98.752406 -55.956708)
		(width 0.2032)
		(layer "In7.Cu")
		(net "M1_DQ_NODE1_DQ63")
	)
	(segment
		(start 101.769926 -52.939188)
		(end 101.475286 -52.939188)
		(width 0.2032)
		(layer "In7.Cu")
		(net "M1_DQ_NODE1_DQ63")
	)
	(segment
		(start 99.783646 -54.265068)
		(end 99.966526 -54.447948)
		(width 0.2032)
		(layer "In7.Cu")
		(net "M1_DQ_NODE1_DQ63")
	)
	(segment
		(start 102.403402 -26.275538)
		(end 102.403402 -28.119578)
		(width 0.2032)
		(layer "In7.Cu")
		(net "M1_DQ_NODE1_DQ63")
	)
	(segment
		(start 96.59112 -63.401702)
		(end 90.041222 -69.9516)
		(width 0.2032)
		(layer "In7.Cu")
		(net "M1_DQ_NODE1_DQ63")
	)
	(segment
		(start 100.997766 -52.756308)
		(end 100.789486 -52.964588)
		(width 0.2032)
		(layer "In7.Cu")
		(net "M1_DQ_NODE1_DQ63")
	)
	(segment
		(start 98.960686 -55.453788)
		(end 98.960686 -55.748428)
		(width 0.2032)
		(layer "In7.Cu")
		(net "M1_DQ_NODE1_DQ63")
	)
	(segment
		(start 97.954846 -56.754268)
		(end 97.746566 -56.962548)
		(width 0.2032)
		(layer "In7.Cu")
		(net "M1_DQ_NODE1_DQ63")
	)
	(segment
		(start 101.501702 -26.582878)
		(end 101.501702 -26.275538)
		(width 0.2032)
		(layer "In7.Cu")
		(net "M1_DQ_NODE1_DQ63")
	)
	(segment
		(start 98.457766 -55.956708)
		(end 98.274886 -55.773828)
		(width 0.2032)
		(layer "In7.Cu")
		(net "M1_DQ_NODE1_DQ63")
	)
	(segment
		(start 77.879448 -73.752964)
		(end 75.179428 -73.752964)
		(width 0.1016)
		(layer "In7.Cu")
		(net "M1_DQ_NODE1_DQ63")
	)
	(segment
		(start 104.350058 -29.771594)
		(end 104.350058 -30.066234)
		(width 0.2032)
		(layer "In7.Cu")
		(net "M1_DQ_NODE1_DQ63")
	)
	(segment
		(start 83.467956 -73.385172)
		(end 78.818994 -73.385172)
		(width 0.2032)
		(layer "In7.Cu")
		(net "M1_DQ_NODE1_DQ63")
	)
	(segment
		(start 99.463606 -54.950868)
		(end 99.280726 -54.767988)
		(width 0.2032)
		(layer "In7.Cu")
		(net "M1_DQ_NODE1_DQ63")
	)
	(segment
		(start 98.274886 -55.773828)
		(end 97.980246 -55.773828)
		(width 0.2032)
		(layer "In7.Cu")
		(net "M1_DQ_NODE1_DQ63")
	)
	(segment
		(start 96.974406 -56.779668)
		(end 96.59112 -57.162954)
		(width 0.2032)
		(layer "In7.Cu")
		(net "M1_DQ_NODE1_DQ63")
	)
	(segment
		(start 99.991926 -53.762148)
		(end 99.783646 -53.970428)
		(width 0.2032)
		(layer "In7.Cu")
		(net "M1_DQ_NODE1_DQ63")
	)
	(segment
		(start 97.980246 -55.773828)
		(end 97.771966 -55.982108)
		(width 0.2032)
		(layer "In7.Cu")
		(net "M1_DQ_NODE1_DQ63")
	)
	(segment
		(start 103.552498 -29.268674)
		(end 103.847138 -29.268674)
		(width 0.2032)
		(layer "In7.Cu")
		(net "M1_DQ_NODE1_DQ63")
	)
	(segment
		(start 99.758246 -54.950868)
		(end 99.463606 -54.950868)
		(width 0.2032)
		(layer "In7.Cu")
		(net "M1_DQ_NODE1_DQ63")
	)
	(segment
		(start 103.124 -50.630074)
		(end 101.795326 -51.958748)
		(width 0.2032)
		(layer "In7.Cu")
		(net "M1_DQ_NODE1_DQ63")
	)
	(segment
		(start 101.475286 -52.939188)
		(end 101.292406 -52.756308)
		(width 0.2032)
		(layer "In7.Cu")
		(net "M1_DQ_NODE1_DQ63")
	)
	(segment
		(start 97.269046 -56.779668)
		(end 96.974406 -56.779668)
		(width 0.2032)
		(layer "In7.Cu")
		(net "M1_DQ_NODE1_DQ63")
	)
	(segment
		(start 97.771966 -56.276748)
		(end 97.954846 -56.459628)
		(width 0.2032)
		(layer "In7.Cu")
		(net "M1_DQ_NODE1_DQ63")
	)
	(segment
		(start 97.954846 -56.459628)
		(end 97.954846 -56.754268)
		(width 0.2032)
		(layer "In7.Cu")
		(net "M1_DQ_NODE1_DQ63")
	)
	(segment
		(start 100.764086 -53.945028)
		(end 100.469446 -53.945028)
		(width 0.2032)
		(layer "In7.Cu")
		(net "M1_DQ_NODE1_DQ63")
	)
	(segment
		(start 101.795326 -51.958748)
		(end 101.795326 -52.253388)
		(width 0.2032)
		(layer "In7.Cu")
		(net "M1_DQ_NODE1_DQ63")
	)
	(segment
		(start 97.746566 -56.962548)
		(end 97.451926 -56.962548)
		(width 0.2032)
		(layer "In7.Cu")
		(net "M1_DQ_NODE1_DQ63")
	)
	(segment
		(start 99.280726 -54.767988)
		(end 98.986086 -54.767988)
		(width 0.2032)
		(layer "In7.Cu")
		(net "M1_DQ_NODE1_DQ63")
	)
	(segment
		(start 105.087674 -29.033978)
		(end 104.350058 -29.771594)
		(width 0.2032)
		(layer "In7.Cu")
		(net "M1_DQ_NODE1_DQ63")
	)
	(segment
		(start 104.350058 -30.066234)
		(end 105.29316 -31.009336)
		(width 0.2032)
		(layer "In7.Cu")
		(net "M1_DQ_NODE1_DQ63")
	)
	(segment
		(start 96.59112 -57.162954)
		(end 96.59112 -63.401702)
		(width 0.2032)
		(layer "In7.Cu")
		(net "M1_DQ_NODE1_DQ63")
	)
	(segment
		(start 101.978206 -52.436268)
		(end 101.978206 -52.730908)
		(width 0.2032)
		(layer "In7.Cu")
		(net "M1_DQ_NODE1_DQ63")
	)
	(segment
		(start 78.24724 -73.385172)
		(end 77.879448 -73.752964)
		(width 0.1016)
		(layer "In7.Cu")
		(net "M1_DQ_NODE1_DQ63")
	)
	(segment
		(start 103.124 -40.272208)
		(end 103.124 -50.630074)
		(width 0.2032)
		(layer "In7.Cu")
		(net "M1_DQ_NODE1_DQ63")
	)
	(segment
		(start 99.783646 -53.970428)
		(end 99.783646 -54.265068)
		(width 0.2032)
		(layer "In7.Cu")
		(net "M1_DQ_NODE1_DQ63")
	)
	(segment
		(start 101.501702 -26.275538)
		(end 101.704902 -26.072338)
		(width 0.2032)
		(layer "In7.Cu")
		(net "M1_DQ_NODE1_DQ63")
	)
	(segment
		(start 104.872282 -28.531058)
		(end 105.087674 -28.74645)
		(width 0.2032)
		(layer "In7.Cu")
		(net "M1_DQ_NODE1_DQ63")
	)
	(segment
		(start 103.847138 -29.268674)
		(end 104.584754 -28.531058)
		(width 0.2032)
		(layer "In7.Cu")
		(net "M1_DQ_NODE1_DQ63")
	)
	(segment
		(start 98.986086 -54.767988)
		(end 98.777806 -54.976268)
		(width 0.2032)
		(layer "In7.Cu")
		(net "M1_DQ_NODE1_DQ63")
	)
	(segment
		(start 99.966526 -54.742588)
		(end 99.758246 -54.950868)
		(width 0.2032)
		(layer "In7.Cu")
		(net "M1_DQ_NODE1_DQ63")
	)
	(segment
		(start 100.972366 -53.736748)
		(end 100.764086 -53.945028)
		(width 0.2032)
		(layer "In7.Cu")
		(net "M1_DQ_NODE1_DQ63")
	)
	(segment
		(start 97.451926 -56.962548)
		(end 97.269046 -56.779668)
		(width 0.2032)
		(layer "In7.Cu")
		(net "M1_DQ_NODE1_DQ63")
	)
	(segment
		(start 86.901528 -69.9516)
		(end 83.467956 -73.385172)
		(width 0.2032)
		(layer "In7.Cu")
		(net "M1_DQ_NODE1_DQ63")
	)
	(segment
		(start 102.403402 -28.119578)
		(end 103.552498 -29.268674)
		(width 0.2032)
		(layer "In7.Cu")
		(net "M1_DQ_NODE1_DQ63")
	)
	(segment
		(start 78.818994 -73.385172)
		(end 78.24724 -73.385172)
		(width 0.1016)
		(layer "In7.Cu")
		(net "M1_DQ_NODE1_DQ63")
	)
	(segment
		(start 75.179428 -73.752964)
		(end 74.773028 -74.159364)
		(width 0.1016)
		(layer "In7.Cu")
		(net "M1_DQ_NODE1_DQ63")
	)
	(segment
		(start 98.777806 -54.976268)
		(end 98.777806 -55.270908)
		(width 0.2032)
		(layer "In7.Cu")
		(net "M1_DQ_NODE1_DQ63")
	)
	(segment
		(start 90.041222 -69.9516)
		(end 86.901528 -69.9516)
		(width 0.2032)
		(layer "In7.Cu")
		(net "M1_DQ_NODE1_DQ63")
	)
	(segment
		(start 101.704902 -26.072338)
		(end 102.200202 -26.072338)
		(width 0.2032)
		(layer "In7.Cu")
		(net "M1_DQ_NODE1_DQ63")
	)
	(segment
		(start 97.771966 -55.982108)
		(end 97.771966 -56.276748)
		(width 0.2032)
		(layer "In7.Cu")
		(net "M1_DQ_NODE1_DQ63")
	)
	(segment
		(start 98.777806 -55.270908)
		(end 98.960686 -55.453788)
		(width 0.2032)
		(layer "In7.Cu")
		(net "M1_DQ_NODE1_DQ63")
	)
	(segment
		(start 100.286566 -53.762148)
		(end 99.991926 -53.762148)
		(width 0.2032)
		(layer "In7.Cu")
		(net "M1_DQ_NODE1_DQ63")
	)
	(segment
		(start 101.292406 -52.756308)
		(end 100.997766 -52.756308)
		(width 0.2032)
		(layer "In7.Cu")
		(net "M1_DQ_NODE1_DQ63")
	)
	(segment
		(start 105.29316 -38.103048)
		(end 103.124 -40.272208)
		(width 0.2032)
		(layer "In7.Cu")
		(net "M1_DQ_NODE1_DQ63")
	)
	(segment
		(start 101.795326 -52.253388)
		(end 101.978206 -52.436268)
		(width 0.2032)
		(layer "In7.Cu")
		(net "M1_DQ_NODE1_DQ63")
	)
	(segment
		(start 99.966526 -54.447948)
		(end 99.966526 -54.742588)
		(width 0.2032)
		(layer "In7.Cu")
		(net "M1_DQ_NODE1_DQ63")
	)
	(segment
		(start 101.978206 -52.730908)
		(end 101.769926 -52.939188)
		(width 0.2032)
		(layer "In7.Cu")
		(net "M1_DQ_NODE1_DQ63")
	)
	(segment
		(start 98.752406 -55.956708)
		(end 98.457766 -55.956708)
		(width 0.2032)
		(layer "In7.Cu")
		(net "M1_DQ_NODE1_DQ63")
	)
	(segment
		(start 102.200202 -26.072338)
		(end 102.403402 -26.275538)
		(width 0.2032)
		(layer "In7.Cu")
		(net "M1_DQ_NODE1_DQ63")
	)
	(segment
		(start 105.29316 -31.009336)
		(end 105.29316 -38.103048)
		(width 0.2032)
		(layer "In7.Cu")
		(net "M1_DQ_NODE1_DQ63")
	)
	(segment
		(start 100.972366 -53.442108)
		(end 100.972366 -53.736748)
		(width 0.2032)
		(layer "In7.Cu")
		(net "M1_DQ_NODE1_DQ63")
	)
	(segment
		(start 100.789486 -52.964588)
		(end 100.789486 -53.259228)
		(width 0.2032)
		(layer "In7.Cu")
		(net "M1_DQ_NODE1_DQ63")
	)
	(segment
		(start 105.087674 -28.74645)
		(end 105.087674 -29.033978)
		(width 0.2032)
		(layer "In7.Cu")
		(net "M1_DQ_NODE1_DQ63")
	)
	(segment
		(start 100.789486 -53.259228)
		(end 100.972366 -53.442108)
		(width 0.2032)
		(layer "In7.Cu")
		(net "M1_DQ_NODE1_DQ63")
	)
	(segment
		(start 104.584754 -28.531058)
		(end 104.872282 -28.531058)
		(width 0.2032)
		(layer "In7.Cu")
		(net "M1_DQ_NODE1_DQ63")
	)
	(segment
		(start 100.469446 -53.945028)
		(end 100.286566 -53.762148)
		(width 0.2032)
		(layer "In7.Cu")
		(net "M1_DQ_NODE1_DQ63")
	)
	(segment
		(start 51.048666 -63.898526)
		(end 51.444652 -63.50254)
		(width 0.1016)
		(layer "F.Cu")
		(net "M1_DQ_NODE1_DQ9")
	)
	(segment
		(start 51.444652 -63.50254)
		(end 51.444652 -61.966602)
		(width 0.1016)
		(layer "F.Cu")
		(net "M1_DQ_NODE1_DQ9")
	)
	(segment
		(start 50.574702 -58.455306)
		(end 46.7487 -58.455306)
		(width 0.1651)
		(layer "F.Cu")
		(net "M1_DQ_NODE1_DQ9")
	)
	(segment
		(start 50.892456 -63.898526)
		(end 51.048666 -63.898526)
		(width 0.1016)
		(layer "F.Cu")
		(net "M1_DQ_NODE1_DQ9")
	)
	(segment
		(start 51.44262 -60.867544)
		(end 51.44262 -59.323224)
		(width 0.1651)
		(layer "F.Cu")
		(net "M1_DQ_NODE1_DQ9")
	)
	(segment
		(start 51.444652 -61.966602)
		(end 51.44262 -61.96457)
		(width 0.1016)
		(layer "F.Cu")
		(net "M1_DQ_NODE1_DQ9")
	)
	(segment
		(start 51.44262 -59.323224)
		(end 50.574702 -58.455306)
		(width 0.1651)
		(layer "F.Cu")
		(net "M1_DQ_NODE1_DQ9")
	)
	(segment
		(start 51.44262 -61.96457)
		(end 51.44262 -60.867544)
		(width 0.1016)
		(layer "F.Cu")
		(net "M1_DQ_NODE1_DQ9")
	)
	(segment
		(start 46.350174 -23.134066)
		(end 46.350174 -20.94992)
		(width 0.1651)
		(layer "F.Cu")
		(net "M1_DQ_NODE1_DQ9")
	)
	(segment
		(start 46.485302 -25.098502)
		(end 46.12894 -24.74214)
		(width 0.1651)
		(layer "F.Cu")
		(net "M1_DQ_NODE1_DQ9")
	)
	(segment
		(start 46.12894 -24.74214)
		(end 46.12894 -23.3553)
		(width 0.1651)
		(layer "F.Cu")
		(net "M1_DQ_NODE1_DQ9")
	)
	(segment
		(start 46.12894 -23.3553)
		(end 46.350174 -23.134066)
		(width 0.1651)
		(layer "F.Cu")
		(net "M1_DQ_NODE1_DQ9")
	)
	(via
		(at 46.7487 -58.455306)
		(size 0.508)
		(drill 0.254)
		(layers "F.Cu" "B.Cu")
		(net "M1_DQ_NODE1_DQ9")
	)
	(via
		(at 46.485302 -25.098502)
		(size 0.508)
		(drill 0.254)
		(layers "F.Cu" "B.Cu")
		(net "M1_DQ_NODE1_DQ9")
	)
	(segment
		(start 35.72256 -57.214516)
		(end 36.849304 -58.34126)
		(width 0.2032)
		(layer "In2.Cu")
		(net "M1_DQ_NODE1_DQ9")
	)
	(segment
		(start 42.702734 -33.369504)
		(end 42.271188 -33.805114)
		(width 0.2032)
		(layer "In2.Cu")
		(net "M1_DQ_NODE1_DQ9")
	)
	(segment
		(start 40.557196 -58.34126)
		(end 41.000172 -58.784236)
		(width 0.2032)
		(layer "In2.Cu")
		(net "M1_DQ_NODE1_DQ9")
	)
	(segment
		(start 46.68266 -27.518614)
		(end 46.68266 -28.07843)
		(width 0.2032)
		(layer "In2.Cu")
		(net "M1_DQ_NODE1_DQ9")
	)
	(segment
		(start 41.000172 -58.784236)
		(end 46.41977 -58.784236)
		(width 0.2032)
		(layer "In2.Cu")
		(net "M1_DQ_NODE1_DQ9")
	)
	(segment
		(start 34.3281 -55.108856)
		(end 35.72256 -56.503316)
		(width 0.2032)
		(layer "In2.Cu")
		(net "M1_DQ_NODE1_DQ9")
	)
	(segment
		(start 46.41977 -58.784236)
		(end 46.7487 -58.455306)
		(width 0.2032)
		(layer "In2.Cu")
		(net "M1_DQ_NODE1_DQ9")
	)
	(segment
		(start 39.571676 -33.805114)
		(end 34.3281 -39.04869)
		(width 0.2032)
		(layer "In2.Cu")
		(net "M1_DQ_NODE1_DQ9")
	)
	(segment
		(start 45.92828 -28.83281)
		(end 45.92828 -32.811974)
		(width 0.2032)
		(layer "In2.Cu")
		(net "M1_DQ_NODE1_DQ9")
	)
	(segment
		(start 44.93514 -33.805114)
		(end 44.071032 -33.805114)
		(width 0.2032)
		(layer "In2.Cu")
		(net "M1_DQ_NODE1_DQ9")
	)
	(segment
		(start 46.485302 -25.098502)
		(end 46.485302 -27.321256)
		(width 0.2032)
		(layer "In2.Cu")
		(net "M1_DQ_NODE1_DQ9")
	)
	(segment
		(start 44.071032 -33.805114)
		(end 43.639486 -33.369504)
		(width 0.2032)
		(layer "In2.Cu")
		(net "M1_DQ_NODE1_DQ9")
	)
	(segment
		(start 34.3281 -39.04869)
		(end 34.3281 -55.108856)
		(width 0.2032)
		(layer "In2.Cu")
		(net "M1_DQ_NODE1_DQ9")
	)
	(segment
		(start 46.485302 -27.321256)
		(end 46.68266 -27.518614)
		(width 0.2032)
		(layer "In2.Cu")
		(net "M1_DQ_NODE1_DQ9")
	)
	(segment
		(start 45.92828 -32.811974)
		(end 44.93514 -33.805114)
		(width 0.2032)
		(layer "In2.Cu")
		(net "M1_DQ_NODE1_DQ9")
	)
	(segment
		(start 43.639486 -33.369504)
		(end 42.702734 -33.369504)
		(width 0.2032)
		(layer "In2.Cu")
		(net "M1_DQ_NODE1_DQ9")
	)
	(segment
		(start 46.68266 -28.07843)
		(end 45.92828 -28.83281)
		(width 0.2032)
		(layer "In2.Cu")
		(net "M1_DQ_NODE1_DQ9")
	)
	(segment
		(start 35.72256 -56.503316)
		(end 35.72256 -57.214516)
		(width 0.2032)
		(layer "In2.Cu")
		(net "M1_DQ_NODE1_DQ9")
	)
	(segment
		(start 36.849304 -58.34126)
		(end 40.557196 -58.34126)
		(width 0.2032)
		(layer "In2.Cu")
		(net "M1_DQ_NODE1_DQ9")
	)
	(segment
		(start 42.271188 -33.805114)
		(end 39.571676 -33.805114)
		(width 0.2032)
		(layer "In2.Cu")
		(net "M1_DQ_NODE1_DQ9")
	)
	(segment
		(start 149.124416 -82.104484)
		(end 148.839936 -82.104484)
		(width 0.127)
		(layer "F.Cu")
		(net "CLK_100M_SATA_NODE1_DN")
	)
	(segment
		(start 145.93062 -69.46392)
		(end 145.978372 -69.638418)
		(width 0.127)
		(layer "F.Cu")
		(net "CLK_100M_SATA_NODE1_DN")
	)
	(segment
		(start 145.509996 -71.27367)
		(end 145.509996 -76.186792)
		(width 0.127)
		(layer "F.Cu")
		(net "CLK_100M_SATA_NODE1_DN")
	)
	(segment
		(start 145.509996 -76.186792)
		(end 145.089118 -76.60767)
		(width 0.127)
		(layer "F.Cu")
		(net "CLK_100M_SATA_NODE1_DN")
	)
	(segment
		(start 149.34692 -81.88198)
		(end 149.124416 -82.104484)
		(width 0.127)
		(layer "F.Cu")
		(net "CLK_100M_SATA_NODE1_DN")
	)
	(segment
		(start 149.34692 -81.477104)
		(end 149.34692 -81.88198)
		(width 0.127)
		(layer "F.Cu")
		(net "CLK_100M_SATA_NODE1_DN")
	)
	(segment
		(start 145.089118 -79.607156)
		(end 146.36496 -80.882998)
		(width 0.127)
		(layer "F.Cu")
		(net "CLK_100M_SATA_NODE1_DN")
	)
	(segment
		(start 136.179052 -122.865642)
		(end 135.112252 -121.798842)
		(width 0.127)
		(layer "F.Cu")
		(net "CLK_100M_SATA_NODE1_DN")
	)
	(segment
		(start 136.427718 -124.034042)
		(end 136.179052 -123.785376)
		(width 0.127)
		(layer "F.Cu")
		(net "CLK_100M_SATA_NODE1_DN")
	)
	(segment
		(start 145.089118 -76.60767)
		(end 145.089118 -79.607156)
		(width 0.127)
		(layer "F.Cu")
		(net "CLK_100M_SATA_NODE1_DN")
	)
	(segment
		(start 135.153654 -121.523252)
		(end 135.153654 -121.064528)
		(width 0.127)
		(layer "F.Cu")
		(net "CLK_100M_SATA_NODE1_DN")
	)
	(segment
		(start 148.752814 -80.882998)
		(end 149.34692 -81.477104)
		(width 0.127)
		(layer "F.Cu")
		(net "CLK_100M_SATA_NODE1_DN")
	)
	(segment
		(start 145.978372 -70.805294)
		(end 145.509996 -71.27367)
		(width 0.127)
		(layer "F.Cu")
		(net "CLK_100M_SATA_NODE1_DN")
	)
	(segment
		(start 145.93062 -68.799202)
		(end 145.93062 -69.46392)
		(width 0.127)
		(layer "F.Cu")
		(net "CLK_100M_SATA_NODE1_DN")
	)
	(segment
		(start 135.112252 -121.798842)
		(end 135.112252 -121.564654)
		(width 0.127)
		(layer "F.Cu")
		(net "CLK_100M_SATA_NODE1_DN")
	)
	(segment
		(start 145.978372 -69.638418)
		(end 145.978372 -70.805294)
		(width 0.127)
		(layer "F.Cu")
		(net "CLK_100M_SATA_NODE1_DN")
	)
	(segment
		(start 146.36496 -80.882998)
		(end 148.752814 -80.882998)
		(width 0.127)
		(layer "F.Cu")
		(net "CLK_100M_SATA_NODE1_DN")
	)
	(segment
		(start 135.112252 -121.564654)
		(end 135.153654 -121.523252)
		(width 0.127)
		(layer "F.Cu")
		(net "CLK_100M_SATA_NODE1_DN")
	)
	(segment
		(start 136.661652 -124.034042)
		(end 136.427718 -124.034042)
		(width 0.127)
		(layer "F.Cu")
		(net "CLK_100M_SATA_NODE1_DN")
	)
	(segment
		(start 136.179052 -123.785376)
		(end 136.179052 -122.865642)
		(width 0.127)
		(layer "F.Cu")
		(net "CLK_100M_SATA_NODE1_DN")
	)
	(via
		(at 148.839936 -82.104484)
		(size 0.508)
		(drill 0.254)
		(layers "F.Cu" "B.Cu")
		(net "CLK_100M_SATA_NODE1_DN")
	)
	(via
		(at 136.661652 -124.034042)
		(size 0.508)
		(drill 0.254)
		(layers "F.Cu" "B.Cu")
		(net "CLK_100M_SATA_NODE1_DN")
	)
	(segment
		(start 142.48892 -97.79254)
		(end 149.322536 -90.958924)
		(width 0.127)
		(layer "B.Cu")
		(net "CLK_100M_SATA_NODE1_DN")
	)
	(segment
		(start 149.322536 -82.231484)
		(end 149.195536 -82.104484)
		(width 0.127)
		(layer "B.Cu")
		(net "CLK_100M_SATA_NODE1_DN")
	)
	(segment
		(start 149.322536 -87.783162)
		(end 149.11578 -87.576406)
		(width 0.127)
		(layer "B.Cu")
		(net "CLK_100M_SATA_NODE1_DN")
	)
	(segment
		(start 149.11578 -87.195406)
		(end 149.322536 -86.98865)
		(width 0.127)
		(layer "B.Cu")
		(net "CLK_100M_SATA_NODE1_DN")
	)
	(segment
		(start 149.322536 -86.60765)
		(end 149.11578 -86.400894)
		(width 0.127)
		(layer "B.Cu")
		(net "CLK_100M_SATA_NODE1_DN")
	)
	(segment
		(start 149.322536 -85.432138)
		(end 149.11578 -85.225382)
		(width 0.127)
		(layer "B.Cu")
		(net "CLK_100M_SATA_NODE1_DN")
	)
	(segment
		(start 149.11578 -87.576406)
		(end 149.11578 -87.195406)
		(width 0.127)
		(layer "B.Cu")
		(net "CLK_100M_SATA_NODE1_DN")
	)
	(segment
		(start 149.322536 -88.164162)
		(end 149.322536 -87.783162)
		(width 0.127)
		(layer "B.Cu")
		(net "CLK_100M_SATA_NODE1_DN")
	)
	(segment
		(start 136.380474 -124.034042)
		(end 136.179052 -124.235464)
		(width 0.127)
		(layer "B.Cu")
		(net "CLK_100M_SATA_NODE1_DN")
	)
	(segment
		(start 149.322536 -84.637626)
		(end 149.322536 -82.231484)
		(width 0.127)
		(layer "B.Cu")
		(net "CLK_100M_SATA_NODE1_DN")
	)
	(segment
		(start 142.00886 -122.18289)
		(end 142.00886 -119.424958)
		(width 0.127)
		(layer "B.Cu")
		(net "CLK_100M_SATA_NODE1_DN")
	)
	(segment
		(start 142.48892 -118.944898)
		(end 142.48892 -97.79254)
		(width 0.127)
		(layer "B.Cu")
		(net "CLK_100M_SATA_NODE1_DN")
	)
	(segment
		(start 149.322536 -88.958674)
		(end 149.11578 -88.751918)
		(width 0.127)
		(layer "B.Cu")
		(net "CLK_100M_SATA_NODE1_DN")
	)
	(segment
		(start 149.322536 -86.98865)
		(end 149.322536 -86.60765)
		(width 0.127)
		(layer "B.Cu")
		(net "CLK_100M_SATA_NODE1_DN")
	)
	(segment
		(start 136.179052 -124.719842)
		(end 136.654286 -125.195076)
		(width 0.127)
		(layer "B.Cu")
		(net "CLK_100M_SATA_NODE1_DN")
	)
	(segment
		(start 149.11578 -86.019894)
		(end 149.322536 -85.813138)
		(width 0.127)
		(layer "B.Cu")
		(net "CLK_100M_SATA_NODE1_DN")
	)
	(segment
		(start 142.00886 -119.424958)
		(end 142.48892 -118.944898)
		(width 0.127)
		(layer "B.Cu")
		(net "CLK_100M_SATA_NODE1_DN")
	)
	(segment
		(start 138.996674 -125.195076)
		(end 142.00886 -122.18289)
		(width 0.127)
		(layer "B.Cu")
		(net "CLK_100M_SATA_NODE1_DN")
	)
	(segment
		(start 149.11578 -85.225382)
		(end 149.11578 -84.844382)
		(width 0.127)
		(layer "B.Cu")
		(net "CLK_100M_SATA_NODE1_DN")
	)
	(segment
		(start 149.11578 -86.400894)
		(end 149.11578 -86.019894)
		(width 0.127)
		(layer "B.Cu")
		(net "CLK_100M_SATA_NODE1_DN")
	)
	(segment
		(start 136.661652 -124.034042)
		(end 136.380474 -124.034042)
		(width 0.127)
		(layer "B.Cu")
		(net "CLK_100M_SATA_NODE1_DN")
	)
	(segment
		(start 149.11578 -88.370918)
		(end 149.322536 -88.164162)
		(width 0.127)
		(layer "B.Cu")
		(net "CLK_100M_SATA_NODE1_DN")
	)
	(segment
		(start 149.11578 -89.54643)
		(end 149.322536 -89.339674)
		(width 0.127)
		(layer "B.Cu")
		(net "CLK_100M_SATA_NODE1_DN")
	)
	(segment
		(start 149.11578 -84.844382)
		(end 149.322536 -84.637626)
		(width 0.127)
		(layer "B.Cu")
		(net "CLK_100M_SATA_NODE1_DN")
	)
	(segment
		(start 149.195536 -82.104484)
		(end 148.839936 -82.104484)
		(width 0.127)
		(layer "B.Cu")
		(net "CLK_100M_SATA_NODE1_DN")
	)
	(segment
		(start 136.179052 -124.235464)
		(end 136.179052 -124.719842)
		(width 0.127)
		(layer "B.Cu")
		(net "CLK_100M_SATA_NODE1_DN")
	)
	(segment
		(start 149.322536 -90.134186)
		(end 149.11578 -89.92743)
		(width 0.127)
		(layer "B.Cu")
		(net "CLK_100M_SATA_NODE1_DN")
	)
	(segment
		(start 149.322536 -85.813138)
		(end 149.322536 -85.432138)
		(width 0.127)
		(layer "B.Cu")
		(net "CLK_100M_SATA_NODE1_DN")
	)
	(segment
		(start 149.11578 -88.751918)
		(end 149.11578 -88.370918)
		(width 0.127)
		(layer "B.Cu")
		(net "CLK_100M_SATA_NODE1_DN")
	)
	(segment
		(start 149.11578 -89.92743)
		(end 149.11578 -89.54643)
		(width 0.127)
		(layer "B.Cu")
		(net "CLK_100M_SATA_NODE1_DN")
	)
	(segment
		(start 149.322536 -89.339674)
		(end 149.322536 -88.958674)
		(width 0.127)
		(layer "B.Cu")
		(net "CLK_100M_SATA_NODE1_DN")
	)
	(segment
		(start 149.322536 -90.958924)
		(end 149.322536 -90.134186)
		(width 0.127)
		(layer "B.Cu")
		(net "CLK_100M_SATA_NODE1_DN")
	)
	(segment
		(start 136.654286 -125.195076)
		(end 138.996674 -125.195076)
		(width 0.127)
		(layer "B.Cu")
		(net "CLK_100M_SATA_NODE1_DN")
	)
	(segment
		(start 70.936358 -97.110042)
		(end 70.748652 -97.297748)
		(width 0.1016)
		(layer "F.Cu")
		(net "SPC_CPU_NODE1_RTS_L")
	)
	(segment
		(start 66.17589 -85.381846)
		(end 67.059302 -85.381846)
		(width 0.1016)
		(layer "F.Cu")
		(net "SPC_CPU_NODE1_RTS_L")
	)
	(segment
		(start 71.305166 -97.110042)
		(end 70.936358 -97.110042)
		(width 0.1016)
		(layer "F.Cu")
		(net "SPC_CPU_NODE1_RTS_L")
	)
	(segment
		(start 70.554088 -98.384106)
		(end 68.958968 -98.384106)
		(width 0.1016)
		(layer "F.Cu")
		(net "SPC_CPU_NODE1_RTS_L")
	)
	(segment
		(start 70.748652 -97.297748)
		(end 70.748652 -98.189542)
		(width 0.1016)
		(layer "F.Cu")
		(net "SPC_CPU_NODE1_RTS_L")
	)
	(segment
		(start 67.059302 -85.381846)
		(end 67.05981 -85.382354)
		(width 0.1016)
		(layer "F.Cu")
		(net "SPC_CPU_NODE1_RTS_L")
	)
	(segment
		(start 70.748652 -98.189542)
		(end 70.554088 -98.384106)
		(width 0.1016)
		(layer "F.Cu")
		(net "SPC_CPU_NODE1_RTS_L")
	)
	(segment
		(start 68.958968 -98.384106)
		(end 68.782184 -98.207322)
		(width 0.1016)
		(layer "F.Cu")
		(net "SPC_CPU_NODE1_RTS_L")
	)
	(via
		(at 68.782184 -98.207322)
		(size 0.508)
		(drill 0.254)
		(layers "F.Cu" "B.Cu")
		(net "SPC_CPU_NODE1_RTS_L")
	)
	(via
		(at 67.05981 -85.382354)
		(size 0.508)
		(drill 0.254)
		(layers "F.Cu" "B.Cu")
		(net "SPC_CPU_NODE1_RTS_L")
	)
	(segment
		(start 67.723766 -90.765376)
		(end 67.692778 -90.466926)
		(width 0.1016)
		(layer "B.Cu")
		(net "SPC_CPU_NODE1_RTS_L")
	)
	(segment
		(start 67.386708 -87.879936)
		(end 67.386708 -85.709252)
		(width 0.1016)
		(layer "B.Cu")
		(net "SPC_CPU_NODE1_RTS_L")
	)
	(segment
		(start 68.782184 -98.207322)
		(end 68.739766 -98.164904)
		(width 0.1016)
		(layer "B.Cu")
		(net "SPC_CPU_NODE1_RTS_L")
	)
	(segment
		(start 67.72402 -93.600016)
		(end 67.72402 -90.767916)
		(width 0.1016)
		(layer "B.Cu")
		(net "SPC_CPU_NODE1_RTS_L")
	)
	(segment
		(start 68.739766 -94.615762)
		(end 67.72402 -93.600016)
		(width 0.1016)
		(layer "B.Cu")
		(net "SPC_CPU_NODE1_RTS_L")
	)
	(segment
		(start 67.386708 -85.709252)
		(end 67.05981 -85.382354)
		(width 0.1016)
		(layer "B.Cu")
		(net "SPC_CPU_NODE1_RTS_L")
	)
	(segment
		(start 67.692778 -90.433398)
		(end 67.68846 -90.38717)
		(width 0.1016)
		(layer "B.Cu")
		(net "SPC_CPU_NODE1_RTS_L")
	)
	(segment
		(start 68.739766 -98.164904)
		(end 68.739766 -94.615762)
		(width 0.1016)
		(layer "B.Cu")
		(net "SPC_CPU_NODE1_RTS_L")
	)
	(segment
		(start 67.72402 -90.767916)
		(end 67.723766 -90.765376)
		(width 0.1016)
		(layer "B.Cu")
		(net "SPC_CPU_NODE1_RTS_L")
	)
	(segment
		(start 67.68846 -88.181688)
		(end 67.386708 -87.879936)
		(width 0.1016)
		(layer "B.Cu")
		(net "SPC_CPU_NODE1_RTS_L")
	)
	(segment
		(start 67.68846 -90.38717)
		(end 67.68846 -88.181688)
		(width 0.1016)
		(layer "B.Cu")
		(net "SPC_CPU_NODE1_RTS_L")
	)
	(segment
		(start 67.692778 -90.466926)
		(end 67.692778 -90.433398)
		(width 0.1016)
		(layer "B.Cu")
		(net "SPC_CPU_NODE1_RTS_L")
	)
	(segment
		(start 65.715642 -68.503038)
		(end 65.715642 -68.510658)
		(width 0.1016)
		(layer "F.Cu")
		(net "M_DDR3_NODE1_ECC1")
	)
	(segment
		(start 61.350144 -22.06498)
		(end 61.626242 -22.341078)
		(width 0.1651)
		(layer "F.Cu")
		(net "M_DDR3_NODE1_ECC1")
	)
	(segment
		(start 61.626242 -22.341078)
		(end 61.626242 -22.356318)
		(width 0.1651)
		(layer "F.Cu")
		(net "M_DDR3_NODE1_ECC1")
	)
	(segment
		(start 61.350144 -20.94992)
		(end 61.350144 -22.06498)
		(width 0.1651)
		(layer "F.Cu")
		(net "M_DDR3_NODE1_ECC1")
	)
	(segment
		(start 61.626242 -22.356318)
		(end 61.816742 -22.546818)
		(width 0.1651)
		(layer "F.Cu")
		(net "M_DDR3_NODE1_ECC1")
	)
	(segment
		(start 65.715642 -68.510658)
		(end 65.342262 -68.884038)
		(width 0.1016)
		(layer "F.Cu")
		(net "M_DDR3_NODE1_ECC1")
	)
	(via
		(at 65.342262 -68.884038)
		(size 0.508)
		(drill 0.254)
		(layers "F.Cu" "B.Cu")
		(net "M_DDR3_NODE1_ECC1")
	)
	(via
		(at 61.816742 -22.546818)
		(size 0.508)
		(drill 0.254)
		(layers "F.Cu" "B.Cu")
		(net "M_DDR3_NODE1_ECC1")
	)
	(segment
		(start 61.704982 -23.956518)
		(end 62.197742 -24.449278)
		(width 0.2032)
		(layer "In7.Cu")
		(net "M_DDR3_NODE1_ECC1")
	)
	(segment
		(start 61.816742 -22.546818)
		(end 61.704982 -22.658578)
		(width 0.2032)
		(layer "In7.Cu")
		(net "M_DDR3_NODE1_ECC1")
	)
	(segment
		(start 63.905638 -66.659252)
		(end 64.4398 -67.193414)
		(width 0.1016)
		(layer "In7.Cu")
		(net "M_DDR3_NODE1_ECC1")
	)
	(segment
		(start 59.772042 -30.531562)
		(end 60.419742 -31.179262)
		(width 0.2032)
		(layer "In7.Cu")
		(net "M_DDR3_NODE1_ECC1")
	)
	(segment
		(start 57.26176 -58.355484)
		(end 57.904634 -58.998358)
		(width 0.2032)
		(layer "In7.Cu")
		(net "M_DDR3_NODE1_ECC1")
	)
	(segment
		(start 59.56554 -26.218896)
		(end 59.56554 -28.25623)
		(width 0.2032)
		(layer "In7.Cu")
		(net "M_DDR3_NODE1_ECC1")
	)
	(segment
		(start 56.63692 -36.376102)
		(end 53.17998 -39.833042)
		(width 0.2032)
		(layer "In7.Cu")
		(net "M_DDR3_NODE1_ECC1")
	)
	(segment
		(start 62.530482 -64.356996)
		(end 62.85738 -64.356996)
		(width 0.1016)
		(layer "In7.Cu")
		(net "M_DDR3_NODE1_ECC1")
	)
	(segment
		(start 62.197742 -24.449278)
		(end 62.197742 -24.772366)
		(width 0.2032)
		(layer "In7.Cu")
		(net "M_DDR3_NODE1_ECC1")
	)
	(segment
		(start 57.26176 -53.687472)
		(end 57.26176 -58.355484)
		(width 0.2032)
		(layer "In7.Cu")
		(net "M_DDR3_NODE1_ECC1")
	)
	(segment
		(start 53.17998 -49.605692)
		(end 57.26176 -53.687472)
		(width 0.2032)
		(layer "In7.Cu")
		(net "M_DDR3_NODE1_ECC1")
	)
	(segment
		(start 59.700922 -33.209738)
		(end 57.985406 -33.209738)
		(width 0.2032)
		(layer "In7.Cu")
		(net "M_DDR3_NODE1_ECC1")
	)
	(segment
		(start 63.905638 -65.405254)
		(end 63.905638 -66.659252)
		(width 0.1016)
		(layer "In7.Cu")
		(net "M_DDR3_NODE1_ECC1")
	)
	(segment
		(start 60.604146 -24.33066)
		(end 60.31992 -24.614886)
		(width 0.2032)
		(layer "In7.Cu")
		(net "M_DDR3_NODE1_ECC1")
	)
	(segment
		(start 65.341754 -68.884038)
		(end 65.342262 -68.884038)
		(width 0.1016)
		(layer "In7.Cu")
		(net "M_DDR3_NODE1_ECC1")
	)
	(segment
		(start 61.704982 -22.658578)
		(end 61.704982 -23.956518)
		(width 0.2032)
		(layer "In7.Cu")
		(net "M_DDR3_NODE1_ECC1")
	)
	(segment
		(start 62.85738 -64.356996)
		(end 63.905638 -65.405254)
		(width 0.1016)
		(layer "In7.Cu")
		(net "M_DDR3_NODE1_ECC1")
	)
	(segment
		(start 60.753244 -61.788548)
		(end 60.753244 -62.579758)
		(width 0.1016)
		(layer "In7.Cu")
		(net "M_DDR3_NODE1_ECC1")
	)
	(segment
		(start 60.31992 -25.464516)
		(end 59.56554 -26.218896)
		(width 0.2032)
		(layer "In7.Cu")
		(net "M_DDR3_NODE1_ECC1")
	)
	(segment
		(start 64.4398 -67.193414)
		(end 64.4398 -67.982084)
		(width 0.1016)
		(layer "In7.Cu")
		(net "M_DDR3_NODE1_ECC1")
	)
	(segment
		(start 59.522614 -60.557156)
		(end 59.744864 -60.779406)
		(width 0.2032)
		(layer "In7.Cu")
		(net "M_DDR3_NODE1_ECC1")
	)
	(segment
		(start 59.772042 -28.462732)
		(end 59.772042 -30.531562)
		(width 0.2032)
		(layer "In7.Cu")
		(net "M_DDR3_NODE1_ECC1")
	)
	(segment
		(start 60.419742 -31.179262)
		(end 60.419742 -32.490918)
		(width 0.2032)
		(layer "In7.Cu")
		(net "M_DDR3_NODE1_ECC1")
	)
	(segment
		(start 60.419742 -32.490918)
		(end 59.700922 -33.209738)
		(width 0.2032)
		(layer "In7.Cu")
		(net "M_DDR3_NODE1_ECC1")
	)
	(segment
		(start 60.976764 -24.33066)
		(end 60.604146 -24.33066)
		(width 0.2032)
		(layer "In7.Cu")
		(net "M_DDR3_NODE1_ECC1")
	)
	(segment
		(start 60.753244 -62.579758)
		(end 62.530482 -64.356996)
		(width 0.1016)
		(layer "In7.Cu")
		(net "M_DDR3_NODE1_ECC1")
	)
	(segment
		(start 57.985406 -33.209738)
		(end 56.63692 -34.558224)
		(width 0.2032)
		(layer "In7.Cu")
		(net "M_DDR3_NODE1_ECC1")
	)
	(segment
		(start 59.56554 -28.25623)
		(end 59.772042 -28.462732)
		(width 0.2032)
		(layer "In7.Cu")
		(net "M_DDR3_NODE1_ECC1")
	)
	(segment
		(start 57.904634 -58.998358)
		(end 57.904634 -59.72556)
		(width 0.2032)
		(layer "In7.Cu")
		(net "M_DDR3_NODE1_ECC1")
	)
	(segment
		(start 64.4398 -67.982084)
		(end 65.341754 -68.884038)
		(width 0.1016)
		(layer "In7.Cu")
		(net "M_DDR3_NODE1_ECC1")
	)
	(segment
		(start 58.73623 -60.557156)
		(end 59.522614 -60.557156)
		(width 0.2032)
		(layer "In7.Cu")
		(net "M_DDR3_NODE1_ECC1")
	)
	(segment
		(start 59.744864 -60.780168)
		(end 60.753244 -61.788548)
		(width 0.1016)
		(layer "In7.Cu")
		(net "M_DDR3_NODE1_ECC1")
	)
	(segment
		(start 59.744864 -60.779406)
		(end 59.744864 -60.780168)
		(width 0.2032)
		(layer "In7.Cu")
		(net "M_DDR3_NODE1_ECC1")
	)
	(segment
		(start 62.197742 -24.772366)
		(end 61.96965 -25.000458)
		(width 0.2032)
		(layer "In7.Cu")
		(net "M_DDR3_NODE1_ECC1")
	)
	(segment
		(start 57.904634 -59.72556)
		(end 58.73623 -60.557156)
		(width 0.2032)
		(layer "In7.Cu")
		(net "M_DDR3_NODE1_ECC1")
	)
	(segment
		(start 60.31992 -24.614886)
		(end 60.31992 -25.464516)
		(width 0.2032)
		(layer "In7.Cu")
		(net "M_DDR3_NODE1_ECC1")
	)
	(segment
		(start 56.63692 -34.558224)
		(end 56.63692 -36.376102)
		(width 0.2032)
		(layer "In7.Cu")
		(net "M_DDR3_NODE1_ECC1")
	)
	(segment
		(start 61.646562 -25.000458)
		(end 60.976764 -24.33066)
		(width 0.2032)
		(layer "In7.Cu")
		(net "M_DDR3_NODE1_ECC1")
	)
	(segment
		(start 61.96965 -25.000458)
		(end 61.646562 -25.000458)
		(width 0.2032)
		(layer "In7.Cu")
		(net "M_DDR3_NODE1_ECC1")
	)
	(segment
		(start 53.17998 -39.833042)
		(end 53.17998 -49.605692)
		(width 0.2032)
		(layer "In7.Cu")
		(net "M_DDR3_NODE1_ECC1")
	)
	(segment
		(start 19.99996 -7.799832)
		(end 20.15744 -7.957312)
		(width 0.1016)
		(layer "F.Cu")
		(net "N53608934")
	)
	(segment
		(start 20.15744 -7.957312)
		(end 20.15744 -10.141204)
		(width 0.1016)
		(layer "F.Cu")
		(net "N53608934")
	)
	(segment
		(start 56.24449 -84.996274)
		(end 56.619394 -84.62137)
		(width 0.1016)
		(layer "F.Cu")
		(net "PD_CPU_NODE1_DFX_GPIO_GRP0_7")
	)
	(segment
		(start 56.24449 -85.000846)
		(end 56.24449 -84.996274)
		(width 0.1016)
		(layer "F.Cu")
		(net "PD_CPU_NODE1_DFX_GPIO_GRP0_7")
	)
	(via
		(at 50.974498 -95.12808)
		(size 0.6604)
		(drill 0.3302)
		(layers "F.Cu" "B.Cu")
		(net "PD_CPU_NODE1_DFX_GPIO_GRP0_7")
	)
	(via
		(at 56.619394 -84.62137)
		(size 0.508)
		(drill 0.254)
		(layers "F.Cu" "B.Cu")
		(net "PD_CPU_NODE1_DFX_GPIO_GRP0_7")
	)
	(segment
		(start 50.974498 -94.346776)
		(end 50.974498 -95.12808)
		(width 0.1016)
		(layer "B.Cu")
		(net "PD_CPU_NODE1_DFX_GPIO_GRP0_7")
	)
	(segment
		(start 56.619394 -84.62137)
		(end 55.571898 -85.668866)
		(width 0.1016)
		(layer "B.Cu")
		(net "PD_CPU_NODE1_DFX_GPIO_GRP0_7")
	)
	(segment
		(start 55.199026 -88.854026)
		(end 55.199026 -90.575384)
		(width 0.1016)
		(layer "B.Cu")
		(net "PD_CPU_NODE1_DFX_GPIO_GRP0_7")
	)
	(segment
		(start 55.571898 -85.668866)
		(end 55.571898 -88.481154)
		(width 0.1016)
		(layer "B.Cu")
		(net "PD_CPU_NODE1_DFX_GPIO_GRP0_7")
	)
	(segment
		(start 50.974498 -95.12808)
		(end 50.974498 -96.296734)
		(width 0.1016)
		(layer "B.Cu")
		(net "PD_CPU_NODE1_DFX_GPIO_GRP0_7")
	)
	(segment
		(start 55.199026 -90.575384)
		(end 54.57063 -91.20378)
		(width 0.1016)
		(layer "B.Cu")
		(net "PD_CPU_NODE1_DFX_GPIO_GRP0_7")
	)
	(segment
		(start 54.117494 -91.20378)
		(end 50.974498 -94.346776)
		(width 0.1016)
		(layer "B.Cu")
		(net "PD_CPU_NODE1_DFX_GPIO_GRP0_7")
	)
	(segment
		(start 55.571898 -88.481154)
		(end 55.199026 -88.854026)
		(width 0.1016)
		(layer "B.Cu")
		(net "PD_CPU_NODE1_DFX_GPIO_GRP0_7")
	)
	(segment
		(start 54.57063 -91.20378)
		(end 54.117494 -91.20378)
		(width 0.1016)
		(layer "B.Cu")
		(net "PD_CPU_NODE1_DFX_GPIO_GRP0_7")
	)
	(segment
		(start 83.876134 -34.54781)
		(end 84.09178 -34.332164)
		(width 0.2286)
		(layer "F.Cu")
		(net "M_DDR3_NODE1_MA13")
	)
	(segment
		(start 67.7545 -60.840112)
		(end 67.12331 -61.471302)
		(width 0.1016)
		(layer "F.Cu")
		(net "M_DDR3_NODE1_MA13")
	)
	(segment
		(start 83.559142 -37.74694)
		(end 83.6803 -37.868098)
		(width 0.2286)
		(layer "F.Cu")
		(net "M_DDR3_NODE1_MA13")
	)
	(segment
		(start 73.418192 -57.35066)
		(end 73.113392 -57.35066)
		(width 0.2286)
		(layer "F.Cu")
		(net "M_DDR3_NODE1_MA13")
	)
	(segment
		(start 74.4601 -56.308752)
		(end 74.1553 -56.308752)
		(width 0.2286)
		(layer "F.Cu")
		(net "M_DDR3_NODE1_MA13")
	)
	(segment
		(start 78.612746 -52.883308)
		(end 78.307946 -52.883308)
		(width 0.2286)
		(layer "F.Cu")
		(net "M_DDR3_NODE1_MA13")
	)
	(segment
		(start 81.45018 -31.173674)
		(end 81.45018 -29.149802)
		(width 0.2286)
		(layer "F.Cu")
		(net "M_DDR3_NODE1_MA13")
	)
	(segment
		(start 83.6803 -43.1546)
		(end 83.6803 -43.59402)
		(width 0.2286)
		(layer "F.Cu")
		(net "M_DDR3_NODE1_MA13")
	)
	(segment
		(start 76.72324 -53.382418)
		(end 76.41844 -53.382418)
		(width 0.2286)
		(layer "F.Cu")
		(net "M_DDR3_NODE1_MA13")
	)
	(segment
		(start 83.6803 -43.59402)
		(end 83.97748 -43.8912)
		(width 0.2286)
		(layer "F.Cu")
		(net "M_DDR3_NODE1_MA13")
	)
	(segment
		(start 79.848964 -50.256694)
		(end 79.544164 -50.256694)
		(width 0.2286)
		(layer "F.Cu")
		(net "M_DDR3_NODE1_MA13")
	)
	(segment
		(start 83.6803 -46.101)
		(end 83.6803 -47.815754)
		(width 0.2286)
		(layer "F.Cu")
		(net "M_DDR3_NODE1_MA13")
	)
	(segment
		(start 68.17741 -58.786268)
		(end 67.7545 -59.209178)
		(width 0.2286)
		(layer "F.Cu")
		(net "M_DDR3_NODE1_MA13")
	)
	(segment
		(start 73.686416 -56.144668)
		(end 73.470262 -56.360822)
		(width 0.2286)
		(layer "F.Cu")
		(net "M_DDR3_NODE1_MA13")
	)
	(segment
		(start 79.32801 -50.472848)
		(end 79.32801 -50.777648)
		(width 0.2286)
		(layer "F.Cu")
		(net "M_DDR3_NODE1_MA13")
	)
	(segment
		(start 66.058796 -62.363096)
		(end 66.058796 -62.98184)
		(width 0.1016)
		(layer "F.Cu")
		(net "M_DDR3_NODE1_MA13")
	)
	(segment
		(start 83.97748 -45.80382)
		(end 83.6803 -46.101)
		(width 0.2286)
		(layer "F.Cu")
		(net "M_DDR3_NODE1_MA13")
	)
	(segment
		(start 79.349854 -51.8414)
		(end 78.807056 -51.298602)
		(width 0.2286)
		(layer "F.Cu")
		(net "M_DDR3_NODE1_MA13")
	)
	(segment
		(start 84.09178 -34.026856)
		(end 83.876134 -33.81121)
		(width 0.2286)
		(layer "F.Cu")
		(net "M_DDR3_NODE1_MA13")
	)
	(segment
		(start 73.470262 -56.665622)
		(end 73.634346 -56.829706)
		(width 0.2286)
		(layer "F.Cu")
		(net "M_DDR3_NODE1_MA13")
	)
	(segment
		(start 83.876134 -33.81121)
		(end 83.400646 -33.81121)
		(width 0.2286)
		(layer "F.Cu")
		(net "M_DDR3_NODE1_MA13")
	)
	(segment
		(start 83.185 -34.763456)
		(end 83.400646 -34.54781)
		(width 0.2286)
		(layer "F.Cu")
		(net "M_DDR3_NODE1_MA13")
	)
	(segment
		(start 76.202286 -53.903372)
		(end 76.745084 -54.44617)
		(width 0.2286)
		(layer "F.Cu")
		(net "M_DDR3_NODE1_MA13")
	)
	(segment
		(start 72.428354 -58.036968)
		(end 71.679054 -58.786268)
		(width 0.2286)
		(layer "F.Cu")
		(net "M_DDR3_NODE1_MA13")
	)
	(segment
		(start 77.244194 -52.556664)
		(end 77.244194 -52.861464)
		(width 0.2286)
		(layer "F.Cu")
		(net "M_DDR3_NODE1_MA13")
	)
	(segment
		(start 84.09178 -34.332164)
		(end 84.09178 -34.026856)
		(width 0.2286)
		(layer "F.Cu")
		(net "M_DDR3_NODE1_MA13")
	)
	(segment
		(start 76.745084 -54.75097)
		(end 76.432664 -55.06339)
		(width 0.2286)
		(layer "F.Cu")
		(net "M_DDR3_NODE1_MA13")
	)
	(segment
		(start 79.544164 -50.256694)
		(end 79.32801 -50.472848)
		(width 0.2286)
		(layer "F.Cu")
		(net "M_DDR3_NODE1_MA13")
	)
	(segment
		(start 78.286102 -51.819556)
		(end 78.8289 -52.362354)
		(width 0.2286)
		(layer "F.Cu")
		(net "M_DDR3_NODE1_MA13")
	)
	(segment
		(start 72.949308 -57.186576)
		(end 72.644508 -57.186576)
		(width 0.2286)
		(layer "F.Cu")
		(net "M_DDR3_NODE1_MA13")
	)
	(segment
		(start 74.1553 -56.308752)
		(end 73.991216 -56.144668)
		(width 0.2286)
		(layer "F.Cu")
		(net "M_DDR3_NODE1_MA13")
	)
	(segment
		(start 67.12331 -61.471302)
		(end 66.95059 -61.471302)
		(width 0.1016)
		(layer "F.Cu")
		(net "M_DDR3_NODE1_MA13")
	)
	(segment
		(start 78.807056 -51.298602)
		(end 78.502256 -51.298602)
		(width 0.2286)
		(layer "F.Cu")
		(net "M_DDR3_NODE1_MA13")
	)
	(segment
		(start 77.786992 -53.709062)
		(end 77.570838 -53.925216)
		(width 0.2286)
		(layer "F.Cu")
		(net "M_DDR3_NODE1_MA13")
	)
	(segment
		(start 83.97748 -43.8912)
		(end 83.97748 -44.33062)
		(width 0.2286)
		(layer "F.Cu")
		(net "M_DDR3_NODE1_MA13")
	)
	(segment
		(start 78.307946 -52.883308)
		(end 77.765148 -52.34051)
		(width 0.2286)
		(layer "F.Cu")
		(net "M_DDR3_NODE1_MA13")
	)
	(segment
		(start 65.774062 -63.266574)
		(end 65.42786 -63.266574)
		(width 0.1016)
		(layer "F.Cu")
		(net "M_DDR3_NODE1_MA13")
	)
	(segment
		(start 74.676254 -56.092598)
		(end 74.4601 -56.308752)
		(width 0.2286)
		(layer "F.Cu")
		(net "M_DDR3_NODE1_MA13")
	)
	(segment
		(start 80.391762 -50.799492)
		(end 79.848964 -50.256694)
		(width 0.2286)
		(layer "F.Cu")
		(net "M_DDR3_NODE1_MA13")
	)
	(segment
		(start 83.6803 -37.868098)
		(end 83.6803 -42.12082)
		(width 0.2286)
		(layer "F.Cu")
		(net "M_DDR3_NODE1_MA13")
	)
	(segment
		(start 83.97748 -42.85742)
		(end 83.6803 -43.1546)
		(width 0.2286)
		(layer "F.Cu")
		(net "M_DDR3_NODE1_MA13")
	)
	(segment
		(start 77.765148 -52.34051)
		(end 77.460348 -52.34051)
		(width 0.2286)
		(layer "F.Cu")
		(net "M_DDR3_NODE1_MA13")
	)
	(segment
		(start 66.058796 -62.98184)
		(end 65.774062 -63.266574)
		(width 0.1016)
		(layer "F.Cu")
		(net "M_DDR3_NODE1_MA13")
	)
	(segment
		(start 83.185 -33.595564)
		(end 83.185 -31.992824)
		(width 0.2286)
		(layer "F.Cu")
		(net "M_DDR3_NODE1_MA13")
	)
	(segment
		(start 74.676254 -55.787798)
		(end 74.676254 -56.092598)
		(width 0.2286)
		(layer "F.Cu")
		(net "M_DDR3_NODE1_MA13")
	)
	(segment
		(start 77.266038 -53.925216)
		(end 76.72324 -53.382418)
		(width 0.2286)
		(layer "F.Cu")
		(net "M_DDR3_NODE1_MA13")
	)
	(segment
		(start 83.559142 -35.953192)
		(end 83.185 -35.57905)
		(width 0.2286)
		(layer "F.Cu")
		(net "M_DDR3_NODE1_MA13")
	)
	(segment
		(start 77.244194 -52.861464)
		(end 77.786992 -53.404262)
		(width 0.2286)
		(layer "F.Cu")
		(net "M_DDR3_NODE1_MA13")
	)
	(segment
		(start 81.930748 -31.654242)
		(end 81.45018 -31.173674)
		(width 0.2286)
		(layer "F.Cu")
		(net "M_DDR3_NODE1_MA13")
	)
	(segment
		(start 78.286102 -51.514756)
		(end 78.286102 -51.819556)
		(width 0.2286)
		(layer "F.Cu")
		(net "M_DDR3_NODE1_MA13")
	)
	(segment
		(start 73.634346 -56.829706)
		(end 73.634346 -57.134506)
		(width 0.2286)
		(layer "F.Cu")
		(net "M_DDR3_NODE1_MA13")
	)
	(segment
		(start 73.634346 -57.134506)
		(end 73.418192 -57.35066)
		(width 0.2286)
		(layer "F.Cu")
		(net "M_DDR3_NODE1_MA13")
	)
	(segment
		(start 72.428354 -57.40273)
		(end 72.428354 -58.036968)
		(width 0.2286)
		(layer "F.Cu")
		(net "M_DDR3_NODE1_MA13")
	)
	(segment
		(start 83.400646 -33.81121)
		(end 83.185 -33.595564)
		(width 0.2286)
		(layer "F.Cu")
		(net "M_DDR3_NODE1_MA13")
	)
	(segment
		(start 67.7545 -59.209178)
		(end 67.7545 -60.840112)
		(width 0.2286)
		(layer "F.Cu")
		(net "M_DDR3_NODE1_MA13")
	)
	(segment
		(start 75.145646 -54.685438)
		(end 74.51217 -55.318914)
		(width 0.2286)
		(layer "F.Cu")
		(net "M_DDR3_NODE1_MA13")
	)
	(segment
		(start 73.470262 -56.360822)
		(end 73.470262 -56.665622)
		(width 0.2286)
		(layer "F.Cu")
		(net "M_DDR3_NODE1_MA13")
	)
	(segment
		(start 83.6803 -42.12082)
		(end 83.97748 -42.418)
		(width 0.2286)
		(layer "F.Cu")
		(net "M_DDR3_NODE1_MA13")
	)
	(segment
		(start 76.41844 -53.382418)
		(end 76.202286 -53.598572)
		(width 0.2286)
		(layer "F.Cu")
		(net "M_DDR3_NODE1_MA13")
	)
	(segment
		(start 80.696562 -50.799492)
		(end 80.391762 -50.799492)
		(width 0.2286)
		(layer "F.Cu")
		(net "M_DDR3_NODE1_MA13")
	)
	(segment
		(start 73.991216 -56.144668)
		(end 73.686416 -56.144668)
		(width 0.2286)
		(layer "F.Cu")
		(net "M_DDR3_NODE1_MA13")
	)
	(segment
		(start 73.113392 -57.35066)
		(end 72.949308 -57.186576)
		(width 0.2286)
		(layer "F.Cu")
		(net "M_DDR3_NODE1_MA13")
	)
	(segment
		(start 66.95059 -61.471302)
		(end 66.058796 -62.363096)
		(width 0.1016)
		(layer "F.Cu")
		(net "M_DDR3_NODE1_MA13")
	)
	(segment
		(start 65.42786 -63.266574)
		(end 65.321688 -63.160402)
		(width 0.1016)
		(layer "F.Cu")
		(net "M_DDR3_NODE1_MA13")
	)
	(segment
		(start 83.185 -35.57905)
		(end 83.185 -34.763456)
		(width 0.2286)
		(layer "F.Cu")
		(net "M_DDR3_NODE1_MA13")
	)
	(segment
		(start 77.460348 -52.34051)
		(end 77.244194 -52.556664)
		(width 0.2286)
		(layer "F.Cu")
		(net "M_DDR3_NODE1_MA13")
	)
	(segment
		(start 71.679054 -58.786268)
		(end 68.17741 -58.786268)
		(width 0.2286)
		(layer "F.Cu")
		(net "M_DDR3_NODE1_MA13")
	)
	(segment
		(start 83.97748 -45.3644)
		(end 83.97748 -45.80382)
		(width 0.2286)
		(layer "F.Cu")
		(net "M_DDR3_NODE1_MA13")
	)
	(segment
		(start 79.870808 -51.320446)
		(end 79.870808 -51.625246)
		(width 0.2286)
		(layer "F.Cu")
		(net "M_DDR3_NODE1_MA13")
	)
	(segment
		(start 83.6803 -47.815754)
		(end 80.696562 -50.799492)
		(width 0.2286)
		(layer "F.Cu")
		(net "M_DDR3_NODE1_MA13")
	)
	(segment
		(start 77.786992 -53.404262)
		(end 77.786992 -53.709062)
		(width 0.2286)
		(layer "F.Cu")
		(net "M_DDR3_NODE1_MA13")
	)
	(segment
		(start 79.870808 -51.625246)
		(end 79.654654 -51.8414)
		(width 0.2286)
		(layer "F.Cu")
		(net "M_DDR3_NODE1_MA13")
	)
	(segment
		(start 78.8289 -52.362354)
		(end 78.8289 -52.667154)
		(width 0.2286)
		(layer "F.Cu")
		(net "M_DDR3_NODE1_MA13")
	)
	(segment
		(start 79.654654 -51.8414)
		(end 79.349854 -51.8414)
		(width 0.2286)
		(layer "F.Cu")
		(net "M_DDR3_NODE1_MA13")
	)
	(segment
		(start 78.502256 -51.298602)
		(end 78.286102 -51.514756)
		(width 0.2286)
		(layer "F.Cu")
		(net "M_DDR3_NODE1_MA13")
	)
	(segment
		(start 83.6803 -44.6278)
		(end 83.6803 -45.06722)
		(width 0.2286)
		(layer "F.Cu")
		(net "M_DDR3_NODE1_MA13")
	)
	(segment
		(start 83.6803 -45.06722)
		(end 83.97748 -45.3644)
		(width 0.2286)
		(layer "F.Cu")
		(net "M_DDR3_NODE1_MA13")
	)
	(segment
		(start 76.745084 -54.44617)
		(end 76.745084 -54.75097)
		(width 0.2286)
		(layer "F.Cu")
		(net "M_DDR3_NODE1_MA13")
	)
	(segment
		(start 75.59548 -54.685438)
		(end 75.145646 -54.685438)
		(width 0.2286)
		(layer "F.Cu")
		(net "M_DDR3_NODE1_MA13")
	)
	(segment
		(start 74.51217 -55.318914)
		(end 74.51217 -55.623714)
		(width 0.2286)
		(layer "F.Cu")
		(net "M_DDR3_NODE1_MA13")
	)
	(segment
		(start 79.32801 -50.777648)
		(end 79.870808 -51.320446)
		(width 0.2286)
		(layer "F.Cu")
		(net "M_DDR3_NODE1_MA13")
	)
	(segment
		(start 76.202286 -53.598572)
		(end 76.202286 -53.903372)
		(width 0.2286)
		(layer "F.Cu")
		(net "M_DDR3_NODE1_MA13")
	)
	(segment
		(start 74.51217 -55.623714)
		(end 74.676254 -55.787798)
		(width 0.2286)
		(layer "F.Cu")
		(net "M_DDR3_NODE1_MA13")
	)
	(segment
		(start 83.400646 -34.54781)
		(end 83.876134 -34.54781)
		(width 0.2286)
		(layer "F.Cu")
		(net "M_DDR3_NODE1_MA13")
	)
	(segment
		(start 75.973432 -55.06339)
		(end 75.59548 -54.685438)
		(width 0.2286)
		(layer "F.Cu")
		(net "M_DDR3_NODE1_MA13")
	)
	(segment
		(start 83.97748 -42.418)
		(end 83.97748 -42.85742)
		(width 0.2286)
		(layer "F.Cu")
		(net "M_DDR3_NODE1_MA13")
	)
	(segment
		(start 82.846418 -31.654242)
		(end 81.930748 -31.654242)
		(width 0.2286)
		(layer "F.Cu")
		(net "M_DDR3_NODE1_MA13")
	)
	(segment
		(start 78.8289 -52.667154)
		(end 78.612746 -52.883308)
		(width 0.2286)
		(layer "F.Cu")
		(net "M_DDR3_NODE1_MA13")
	)
	(segment
		(start 76.432664 -55.06339)
		(end 75.973432 -55.06339)
		(width 0.2286)
		(layer "F.Cu")
		(net "M_DDR3_NODE1_MA13")
	)
	(segment
		(start 77.570838 -53.925216)
		(end 77.266038 -53.925216)
		(width 0.2286)
		(layer "F.Cu")
		(net "M_DDR3_NODE1_MA13")
	)
	(segment
		(start 83.559142 -36.305998)
		(end 83.559142 -37.74694)
		(width 0.2286)
		(layer "F.Cu")
		(net "M_DDR3_NODE1_MA13")
	)
	(segment
		(start 72.644508 -57.186576)
		(end 72.428354 -57.40273)
		(width 0.2286)
		(layer "F.Cu")
		(net "M_DDR3_NODE1_MA13")
	)
	(segment
		(start 83.97748 -44.33062)
		(end 83.6803 -44.6278)
		(width 0.2286)
		(layer "F.Cu")
		(net "M_DDR3_NODE1_MA13")
	)
	(segment
		(start 83.559142 -36.305998)
		(end 83.559142 -35.953192)
		(width 0.2286)
		(layer "F.Cu")
		(net "M_DDR3_NODE1_MA13")
	)
	(segment
		(start 83.185 -31.992824)
		(end 82.846418 -31.654242)
		(width 0.2286)
		(layer "F.Cu")
		(net "M_DDR3_NODE1_MA13")
	)
	(via
		(at 83.559142 -36.305998)
		(size 0.762)
		(drill 0.381)
		(layers "F.Cu" "B.Cu")
		(net "M_DDR3_NODE1_MA13")
	)
	(segment
		(start 64.862202 -23.212298)
		(end 64.145922 -23.212298)
		(width 0.1651)
		(layer "F.Cu")
		(net "M_DDR3_NODE1_DQSECCP")
	)
	(segment
		(start 64.145922 -23.212298)
		(end 63.917322 -23.440898)
		(width 0.1651)
		(layer "F.Cu")
		(net "M_DDR3_NODE1_DQSECCP")
	)
	(segment
		(start 65.533016 -66.979038)
		(end 65.256664 -66.702686)
		(width 0.09906)
		(layer "F.Cu")
		(net "M_DDR3_NODE1_DQSECCP")
	)
	(segment
		(start 65.39611 -22.30501)
		(end 65.39611 -22.67839)
		(width 0.1651)
		(layer "F.Cu")
		(net "M_DDR3_NODE1_DQSECCP")
	)
	(segment
		(start 65.550288 -22.150832)
		(end 65.39611 -22.30501)
		(width 0.1651)
		(layer "F.Cu")
		(net "M_DDR3_NODE1_DQSECCP")
	)
	(segment
		(start 63.917322 -23.653242)
		(end 64.403732 -24.139652)
		(width 0.1651)
		(layer "F.Cu")
		(net "M_DDR3_NODE1_DQSECCP")
	)
	(segment
		(start 63.917322 -23.440898)
		(end 63.917322 -23.653242)
		(width 0.1651)
		(layer "F.Cu")
		(net "M_DDR3_NODE1_DQSECCP")
	)
	(segment
		(start 65.39611 -22.67839)
		(end 64.862202 -23.212298)
		(width 0.1651)
		(layer "F.Cu")
		(net "M_DDR3_NODE1_DQSECCP")
	)
	(segment
		(start 65.550288 -20.94992)
		(end 65.550288 -22.150832)
		(width 0.1651)
		(layer "F.Cu")
		(net "M_DDR3_NODE1_DQSECCP")
	)
	(segment
		(start 65.715642 -66.979038)
		(end 65.533016 -66.979038)
		(width 0.09906)
		(layer "F.Cu")
		(net "M_DDR3_NODE1_DQSECCP")
	)
	(via
		(at 65.256664 -66.702686)
		(size 0.508)
		(drill 0.254)
		(layers "F.Cu" "B.Cu")
		(net "M_DDR3_NODE1_DQSECCP")
	)
	(via
		(at 64.403732 -24.139652)
		(size 0.508)
		(drill 0.254)
		(layers "F.Cu" "B.Cu")
		(net "M_DDR3_NODE1_DQSECCP")
	)
	(segment
		(start 65.685162 -66.393568)
		(end 65.459864 -66.393568)
		(width 0.09906)
		(layer "In7.Cu")
		(net "M_DDR3_NODE1_DQSECCP")
	)
	(segment
		(start 61.95822 -58.618628)
		(end 61.89472 -58.682128)
		(width 0.09906)
		(layer "In7.Cu")
		(net "M_DDR3_NODE1_DQSECCP")
	)
	(segment
		(start 64.87414 -63.905384)
		(end 64.87414 -64.079374)
		(width 0.09906)
		(layer "In7.Cu")
		(net "M_DDR3_NODE1_DQSECCP")
	)
	(segment
		(start 65.507362 -30.098238)
		(end 64.407542 -31.198058)
		(width 0.2032)
		(layer "In7.Cu")
		(net "M_DDR3_NODE1_DQSECCP")
	)
	(segment
		(start 61.89472 -58.682128)
		(end 61.89472 -59.297316)
		(width 0.09906)
		(layer "In7.Cu")
		(net "M_DDR3_NODE1_DQSECCP")
	)
	(segment
		(start 63.933832 -25.121362)
		(end 65.507362 -26.694892)
		(width 0.2032)
		(layer "In7.Cu")
		(net "M_DDR3_NODE1_DQSECCP")
	)
	(segment
		(start 61.09716 -45.042582)
		(end 60.88888 -45.250862)
		(width 0.2032)
		(layer "In7.Cu")
		(net "M_DDR3_NODE1_DQSECCP")
	)
	(segment
		(start 62.7761 -61.807344)
		(end 64.87414 -63.905384)
		(width 0.09906)
		(layer "In7.Cu")
		(net "M_DDR3_NODE1_DQSECCP")
	)
	(segment
		(start 64.407542 -36.09721)
		(end 63.00851 -37.496242)
		(width 0.2032)
		(layer "In7.Cu")
		(net "M_DDR3_NODE1_DQSECCP")
	)
	(segment
		(start 64.403732 -24.139652)
		(end 63.933832 -24.609552)
		(width 0.2032)
		(layer "In7.Cu")
		(net "M_DDR3_NODE1_DQSECCP")
	)
	(segment
		(start 60.88888 -39.277798)
		(end 60.88888 -43.462702)
		(width 0.2032)
		(layer "In7.Cu")
		(net "M_DDR3_NODE1_DQSECCP")
	)
	(segment
		(start 62.001908 -40.375078)
		(end 62.569852 -40.375078)
		(width 0.2032)
		(layer "In7.Cu")
		(net "M_DDR3_NODE1_DQSECCP")
	)
	(segment
		(start 64.87414 -64.079374)
		(end 65.990216 -65.19545)
		(width 0.09906)
		(layer "In7.Cu")
		(net "M_DDR3_NODE1_DQSECCP")
	)
	(segment
		(start 65.990216 -66.088514)
		(end 65.685162 -66.393568)
		(width 0.09906)
		(layer "In7.Cu")
		(net "M_DDR3_NODE1_DQSECCP")
	)
	(segment
		(start 62.570106 -45.042582)
		(end 61.09716 -45.042582)
		(width 0.2032)
		(layer "In7.Cu")
		(net "M_DDR3_NODE1_DQSECCP")
	)
	(segment
		(start 61.60008 -43.462702)
		(end 61.60008 -40.776906)
		(width 0.2032)
		(layer "In7.Cu")
		(net "M_DDR3_NODE1_DQSECCP")
	)
	(segment
		(start 65.459864 -66.393568)
		(end 65.256664 -66.596768)
		(width 0.09906)
		(layer "In7.Cu")
		(net "M_DDR3_NODE1_DQSECCP")
	)
	(segment
		(start 60.88888 -45.250862)
		(end 60.88888 -57.120282)
		(width 0.2032)
		(layer "In7.Cu")
		(net "M_DDR3_NODE1_DQSECCP")
	)
	(segment
		(start 60.88888 -57.120282)
		(end 61.95822 -58.189622)
		(width 0.2032)
		(layer "In7.Cu")
		(net "M_DDR3_NODE1_DQSECCP")
	)
	(segment
		(start 64.407542 -31.198058)
		(end 64.407542 -36.09721)
		(width 0.2032)
		(layer "In7.Cu")
		(net "M_DDR3_NODE1_DQSECCP")
	)
	(segment
		(start 63.933832 -24.609552)
		(end 63.933832 -25.121362)
		(width 0.2032)
		(layer "In7.Cu")
		(net "M_DDR3_NODE1_DQSECCP")
	)
	(segment
		(start 62.670436 -37.496242)
		(end 60.88888 -39.277798)
		(width 0.2032)
		(layer "In7.Cu")
		(net "M_DDR3_NODE1_DQSECCP")
	)
	(segment
		(start 62.97168 -44.641008)
		(end 62.570106 -45.042582)
		(width 0.2032)
		(layer "In7.Cu")
		(net "M_DDR3_NODE1_DQSECCP")
	)
	(segment
		(start 61.3918 -43.670982)
		(end 61.60008 -43.462702)
		(width 0.2032)
		(layer "In7.Cu")
		(net "M_DDR3_NODE1_DQSECCP")
	)
	(segment
		(start 62.97168 -40.776906)
		(end 62.97168 -44.641008)
		(width 0.2032)
		(layer "In7.Cu")
		(net "M_DDR3_NODE1_DQSECCP")
	)
	(segment
		(start 61.09716 -43.670982)
		(end 61.3918 -43.670982)
		(width 0.2032)
		(layer "In7.Cu")
		(net "M_DDR3_NODE1_DQSECCP")
	)
	(segment
		(start 61.95822 -58.59272)
		(end 61.95822 -58.618628)
		(width 0.09906)
		(layer "In7.Cu")
		(net "M_DDR3_NODE1_DQSECCP")
	)
	(segment
		(start 61.60008 -40.776906)
		(end 62.001908 -40.375078)
		(width 0.2032)
		(layer "In7.Cu")
		(net "M_DDR3_NODE1_DQSECCP")
	)
	(segment
		(start 60.88888 -43.462702)
		(end 61.09716 -43.670982)
		(width 0.2032)
		(layer "In7.Cu")
		(net "M_DDR3_NODE1_DQSECCP")
	)
	(segment
		(start 61.89472 -59.297316)
		(end 62.7761 -60.178696)
		(width 0.09906)
		(layer "In7.Cu")
		(net "M_DDR3_NODE1_DQSECCP")
	)
	(segment
		(start 62.569852 -40.375078)
		(end 62.97168 -40.776906)
		(width 0.2032)
		(layer "In7.Cu")
		(net "M_DDR3_NODE1_DQSECCP")
	)
	(segment
		(start 63.00851 -37.496242)
		(end 62.670436 -37.496242)
		(width 0.2032)
		(layer "In7.Cu")
		(net "M_DDR3_NODE1_DQSECCP")
	)
	(segment
		(start 61.95822 -58.189622)
		(end 61.95822 -58.59272)
		(width 0.2032)
		(layer "In7.Cu")
		(net "M_DDR3_NODE1_DQSECCP")
	)
	(segment
		(start 62.7761 -60.178696)
		(end 62.7761 -61.807344)
		(width 0.09906)
		(layer "In7.Cu")
		(net "M_DDR3_NODE1_DQSECCP")
	)
	(segment
		(start 65.256664 -66.596768)
		(end 65.256664 -66.702686)
		(width 0.09906)
		(layer "In7.Cu")
		(net "M_DDR3_NODE1_DQSECCP")
	)
	(segment
		(start 65.507362 -26.694892)
		(end 65.507362 -30.098238)
		(width 0.2032)
		(layer "In7.Cu")
		(net "M_DDR3_NODE1_DQSECCP")
	)
	(segment
		(start 65.990216 -65.19545)
		(end 65.990216 -66.088514)
		(width 0.09906)
		(layer "In7.Cu")
		(net "M_DDR3_NODE1_DQSECCP")
	)
	(segment
		(start 130.353816 -121.741692)
		(end 130.401568 -121.789444)
		(width 0.127)
		(layer "F.Cu")
		(net "CLK_100M_PCIE_RP0_NODE1_DP")
	)
	(segment
		(start 44.02074 -67.117468)
		(end 44.187618 -67.117468)
		(width 0.1143)
		(layer "F.Cu")
		(net "CLK_100M_PCIE_RP0_NODE1_DP")
	)
	(segment
		(start 129.06248 -123.777502)
		(end 129.06248 -126.533402)
		(width 0.127)
		(layer "F.Cu")
		(net "CLK_100M_PCIE_RP0_NODE1_DP")
	)
	(segment
		(start 129.3749 -123.467114)
		(end 129.372868 -123.467114)
		(width 0.127)
		(layer "F.Cu")
		(net "CLK_100M_PCIE_RP0_NODE1_DP")
	)
	(segment
		(start 129.64922 -123.192794)
		(end 129.3749 -123.467114)
		(width 0.127)
		(layer "F.Cu")
		(net "CLK_100M_PCIE_RP0_NODE1_DP")
	)
	(segment
		(start 130.353816 -121.064528)
		(end 130.353816 -121.741692)
		(width 0.127)
		(layer "F.Cu")
		(net "CLK_100M_PCIE_RP0_NODE1_DP")
	)
	(segment
		(start 43.937428 -67.20078)
		(end 44.02074 -67.117468)
		(width 0.1143)
		(layer "F.Cu")
		(net "CLK_100M_PCIE_RP0_NODE1_DP")
	)
	(segment
		(start 44.59859 -66.706496)
		(end 44.780454 -66.706496)
		(width 0.1143)
		(layer "F.Cu")
		(net "CLK_100M_PCIE_RP0_NODE1_DP")
	)
	(segment
		(start 129.372868 -123.467114)
		(end 129.06248 -123.777502)
		(width 0.127)
		(layer "F.Cu")
		(net "CLK_100M_PCIE_RP0_NODE1_DP")
	)
	(segment
		(start 130.401568 -122.438922)
		(end 129.64922 -123.19127)
		(width 0.127)
		(layer "F.Cu")
		(net "CLK_100M_PCIE_RP0_NODE1_DP")
	)
	(segment
		(start 130.401568 -121.789444)
		(end 130.401568 -122.438922)
		(width 0.127)
		(layer "F.Cu")
		(net "CLK_100M_PCIE_RP0_NODE1_DP")
	)
	(segment
		(start 129.64922 -123.19127)
		(end 129.64922 -123.192794)
		(width 0.127)
		(layer "F.Cu")
		(net "CLK_100M_PCIE_RP0_NODE1_DP")
	)
	(segment
		(start 44.187618 -67.117468)
		(end 44.59859 -66.706496)
		(width 0.1143)
		(layer "F.Cu")
		(net "CLK_100M_PCIE_RP0_NODE1_DP")
	)
	(segment
		(start 129.06248 -126.533402)
		(end 128.834896 -126.760986)
		(width 0.127)
		(layer "F.Cu")
		(net "CLK_100M_PCIE_RP0_NODE1_DP")
	)
	(segment
		(start 128.834896 -126.760986)
		(end 128.58242 -126.760986)
		(width 0.127)
		(layer "F.Cu")
		(net "CLK_100M_PCIE_RP0_NODE1_DP")
	)
	(via
		(at 44.780454 -66.706496)
		(size 0.508)
		(drill 0.254)
		(layers "F.Cu" "B.Cu")
		(net "CLK_100M_PCIE_RP0_NODE1_DP")
	)
	(via
		(at 128.58242 -126.760986)
		(size 0.508)
		(drill 0.254)
		(layers "F.Cu" "B.Cu")
		(net "CLK_100M_PCIE_RP0_NODE1_DP")
	)
	(segment
		(start 90.8304 -93.532452)
		(end 91.080082 -93.28277)
		(width 0.127)
		(layer "In7.Cu")
		(net "CLK_100M_PCIE_RP0_NODE1_DP")
	)
	(segment
		(start 42.9641 -84.870798)
		(end 43.85818 -85.764878)
		(width 0.127)
		(layer "In7.Cu")
		(net "CLK_100M_PCIE_RP0_NODE1_DP")
	)
	(segment
		(start 51.084226 -91.575128)
		(end 53.519832 -94.010734)
		(width 0.127)
		(layer "In7.Cu")
		(net "CLK_100M_PCIE_RP0_NODE1_DP")
	)
	(segment
		(start 43.621452 -71.902574)
		(end 42.9641 -72.559926)
		(width 0.127)
		(layer "In7.Cu")
		(net "CLK_100M_PCIE_RP0_NODE1_DP")
	)
	(segment
		(start 121.71934 -104.892094)
		(end 121.40946 -105.201974)
		(width 0.127)
		(layer "In7.Cu")
		(net "CLK_100M_PCIE_RP0_NODE1_DP")
	)
	(segment
		(start 97.641664 -93.28277)
		(end 100.948236 -89.976198)
		(width 0.127)
		(layer "In7.Cu")
		(net "CLK_100M_PCIE_RP0_NODE1_DP")
	)
	(segment
		(start 46.299628 -67.807078)
		(end 47.671736 -67.807078)
		(width 0.127)
		(layer "In7.Cu")
		(net "CLK_100M_PCIE_RP0_NODE1_DP")
	)
	(segment
		(start 91.080082 -93.28277)
		(end 97.641664 -93.28277)
		(width 0.127)
		(layer "In7.Cu")
		(net "CLK_100M_PCIE_RP0_NODE1_DP")
	)
	(segment
		(start 130.378962 -127.978916)
		(end 129.553462 -127.978916)
		(width 0.127)
		(layer "In7.Cu")
		(net "CLK_100M_PCIE_RP0_NODE1_DP")
	)
	(segment
		(start 129.07137 -127.496824)
		(end 129.07137 -126.959106)
		(width 0.127)
		(layer "In7.Cu")
		(net "CLK_100M_PCIE_RP0_NODE1_DP")
	)
	(segment
		(start 129.40792 -122.244866)
		(end 131.2164 -124.053346)
		(width 0.127)
		(layer "In7.Cu")
		(net "CLK_100M_PCIE_RP0_NODE1_DP")
	)
	(segment
		(start 129.07137 -126.959106)
		(end 128.87325 -126.760986)
		(width 0.127)
		(layer "In7.Cu")
		(net "CLK_100M_PCIE_RP0_NODE1_DP")
	)
	(segment
		(start 121.40946 -107.521756)
		(end 125.1204 -111.232696)
		(width 0.127)
		(layer "In7.Cu")
		(net "CLK_100M_PCIE_RP0_NODE1_DP")
	)
	(segment
		(start 49.502568 -71.063358)
		(end 48.663352 -71.902574)
		(width 0.127)
		(layer "In7.Cu")
		(net "CLK_100M_PCIE_RP0_NODE1_DP")
	)
	(segment
		(start 86.717632 -92.638626)
		(end 87.611458 -93.532452)
		(width 0.127)
		(layer "In7.Cu")
		(net "CLK_100M_PCIE_RP0_NODE1_DP")
	)
	(segment
		(start 59.761628 -94.511368)
		(end 62.051438 -94.511368)
		(width 0.127)
		(layer "In7.Cu")
		(net "CLK_100M_PCIE_RP0_NODE1_DP")
	)
	(segment
		(start 43.85818 -90.752422)
		(end 44.680886 -91.575128)
		(width 0.127)
		(layer "In7.Cu")
		(net "CLK_100M_PCIE_RP0_NODE1_DP")
	)
	(segment
		(start 53.519832 -94.010734)
		(end 59.260994 -94.010734)
		(width 0.127)
		(layer "In7.Cu")
		(net "CLK_100M_PCIE_RP0_NODE1_DP")
	)
	(segment
		(start 126.98476 -115.782598)
		(end 126.98476 -118.552976)
		(width 0.127)
		(layer "In7.Cu")
		(net "CLK_100M_PCIE_RP0_NODE1_DP")
	)
	(segment
		(start 131.2164 -124.053346)
		(end 131.2164 -127.141478)
		(width 0.127)
		(layer "In7.Cu")
		(net "CLK_100M_PCIE_RP0_NODE1_DP")
	)
	(segment
		(start 43.85818 -85.764878)
		(end 43.85818 -90.752422)
		(width 0.127)
		(layer "In7.Cu")
		(net "CLK_100M_PCIE_RP0_NODE1_DP")
	)
	(segment
		(start 45.89653 -67.40398)
		(end 46.299628 -67.807078)
		(width 0.127)
		(layer "In7.Cu")
		(net "CLK_100M_PCIE_RP0_NODE1_DP")
	)
	(segment
		(start 48.257714 -68.968366)
		(end 49.502568 -70.21322)
		(width 0.127)
		(layer "In7.Cu")
		(net "CLK_100M_PCIE_RP0_NODE1_DP")
	)
	(segment
		(start 79.576168 -92.638626)
		(end 86.717632 -92.638626)
		(width 0.127)
		(layer "In7.Cu")
		(net "CLK_100M_PCIE_RP0_NODE1_DP")
	)
	(segment
		(start 48.663352 -71.902574)
		(end 43.621452 -71.902574)
		(width 0.127)
		(layer "In7.Cu")
		(net "CLK_100M_PCIE_RP0_NODE1_DP")
	)
	(segment
		(start 44.56811 -66.914014)
		(end 44.56811 -67.175126)
		(width 0.127)
		(layer "In7.Cu")
		(net "CLK_100M_PCIE_RP0_NODE1_DP")
	)
	(segment
		(start 125.1204 -111.232696)
		(end 125.1204 -113.918238)
		(width 0.127)
		(layer "In7.Cu")
		(net "CLK_100M_PCIE_RP0_NODE1_DP")
	)
	(segment
		(start 49.502568 -70.21322)
		(end 49.502568 -71.063358)
		(width 0.127)
		(layer "In7.Cu")
		(net "CLK_100M_PCIE_RP0_NODE1_DP")
	)
	(segment
		(start 87.611458 -93.532452)
		(end 90.8304 -93.532452)
		(width 0.127)
		(layer "In7.Cu")
		(net "CLK_100M_PCIE_RP0_NODE1_DP")
	)
	(segment
		(start 121.71934 -103.49992)
		(end 121.71934 -104.892094)
		(width 0.127)
		(layer "In7.Cu")
		(net "CLK_100M_PCIE_RP0_NODE1_DP")
	)
	(segment
		(start 44.796964 -67.40398)
		(end 45.89653 -67.40398)
		(width 0.127)
		(layer "In7.Cu")
		(net "CLK_100M_PCIE_RP0_NODE1_DP")
	)
	(segment
		(start 125.1204 -113.918238)
		(end 126.98476 -115.782598)
		(width 0.127)
		(layer "In7.Cu")
		(net "CLK_100M_PCIE_RP0_NODE1_DP")
	)
	(segment
		(start 44.780454 -66.706496)
		(end 44.56811 -66.914014)
		(width 0.127)
		(layer "In7.Cu")
		(net "CLK_100M_PCIE_RP0_NODE1_DP")
	)
	(segment
		(start 62.051438 -94.511368)
		(end 62.627764 -93.935042)
		(width 0.127)
		(layer "In7.Cu")
		(net "CLK_100M_PCIE_RP0_NODE1_DP")
	)
	(segment
		(start 48.257714 -68.393056)
		(end 48.257714 -68.968366)
		(width 0.127)
		(layer "In7.Cu")
		(net "CLK_100M_PCIE_RP0_NODE1_DP")
	)
	(segment
		(start 47.671736 -67.807078)
		(end 48.257714 -68.393056)
		(width 0.127)
		(layer "In7.Cu")
		(net "CLK_100M_PCIE_RP0_NODE1_DP")
	)
	(segment
		(start 44.680886 -91.575128)
		(end 51.084226 -91.575128)
		(width 0.127)
		(layer "In7.Cu")
		(net "CLK_100M_PCIE_RP0_NODE1_DP")
	)
	(segment
		(start 42.9641 -72.559926)
		(end 42.9641 -84.870798)
		(width 0.127)
		(layer "In7.Cu")
		(net "CLK_100M_PCIE_RP0_NODE1_DP")
	)
	(segment
		(start 121.40946 -105.201974)
		(end 121.40946 -107.521756)
		(width 0.127)
		(layer "In7.Cu")
		(net "CLK_100M_PCIE_RP0_NODE1_DP")
	)
	(segment
		(start 100.948236 -89.976198)
		(end 108.195618 -89.976198)
		(width 0.127)
		(layer "In7.Cu")
		(net "CLK_100M_PCIE_RP0_NODE1_DP")
	)
	(segment
		(start 129.40792 -120.976136)
		(end 129.40792 -122.244866)
		(width 0.127)
		(layer "In7.Cu")
		(net "CLK_100M_PCIE_RP0_NODE1_DP")
	)
	(segment
		(start 126.98476 -118.552976)
		(end 129.40792 -120.976136)
		(width 0.127)
		(layer "In7.Cu")
		(net "CLK_100M_PCIE_RP0_NODE1_DP")
	)
	(segment
		(start 44.56811 -67.175126)
		(end 44.796964 -67.40398)
		(width 0.127)
		(layer "In7.Cu")
		(net "CLK_100M_PCIE_RP0_NODE1_DP")
	)
	(segment
		(start 128.87325 -126.760986)
		(end 128.58242 -126.760986)
		(width 0.127)
		(layer "In7.Cu")
		(net "CLK_100M_PCIE_RP0_NODE1_DP")
	)
	(segment
		(start 129.553462 -127.978916)
		(end 129.07137 -127.496824)
		(width 0.127)
		(layer "In7.Cu")
		(net "CLK_100M_PCIE_RP0_NODE1_DP")
	)
	(segment
		(start 131.2164 -127.141478)
		(end 130.378962 -127.978916)
		(width 0.127)
		(layer "In7.Cu")
		(net "CLK_100M_PCIE_RP0_NODE1_DP")
	)
	(segment
		(start 59.260994 -94.010734)
		(end 59.761628 -94.511368)
		(width 0.127)
		(layer "In7.Cu")
		(net "CLK_100M_PCIE_RP0_NODE1_DP")
	)
	(segment
		(start 62.627764 -93.935042)
		(end 78.279752 -93.935042)
		(width 0.127)
		(layer "In7.Cu")
		(net "CLK_100M_PCIE_RP0_NODE1_DP")
	)
	(segment
		(start 108.195618 -89.976198)
		(end 121.71934 -103.49992)
		(width 0.127)
		(layer "In7.Cu")
		(net "CLK_100M_PCIE_RP0_NODE1_DP")
	)
	(segment
		(start 78.279752 -93.935042)
		(end 79.576168 -92.638626)
		(width 0.127)
		(layer "In7.Cu")
		(net "CLK_100M_PCIE_RP0_NODE1_DP")
	)
	(via
		(at 112.9157 -46.750478)
		(size 0.508)
		(drill 0.254)
		(layers "F.Cu" "B.Cu")
		(net "N21550241")
	)
	(segment
		(start 81.56194 -84.038694)
		(end 80.074262 -84.038694)
		(width 0.1016)
		(layer "F.Cu")
		(net "XTAL_CPU_NODE1_X1PAD")
	)
	(segment
		(start 82.7278 -84.041234)
		(end 81.56448 -84.041234)
		(width 0.1016)
		(layer "F.Cu")
		(net "XTAL_CPU_NODE1_X1PAD")
	)
	(segment
		(start 81.56448 -84.041234)
		(end 81.56194 -84.038694)
		(width 0.1016)
		(layer "F.Cu")
		(net "XTAL_CPU_NODE1_X1PAD")
	)
	(segment
		(start 76.00188 -82.415126)
		(end 76.239878 -82.653124)
		(width 0.1016)
		(layer "F.Cu")
		(net "XTAL_CPU_NODE1_X1PAD")
	)
	(segment
		(start 73.641458 -82.194146)
		(end 73.862438 -82.415126)
		(width 0.1016)
		(layer "F.Cu")
		(net "XTAL_CPU_NODE1_X1PAD")
	)
	(segment
		(start 79.717138 -84.038694)
		(end 79.8957 -84.217256)
		(width 0.1016)
		(layer "F.Cu")
		(net "XTAL_CPU_NODE1_X1PAD")
	)
	(segment
		(start 83.68792 -83.44027)
		(end 84.45246 -83.44027)
		(width 0.1016)
		(layer "F.Cu")
		(net "XTAL_CPU_NODE1_X1PAD")
	)
	(segment
		(start 78.81239 -84.038694)
		(end 79.717138 -84.038694)
		(width 0.1016)
		(layer "F.Cu")
		(net "XTAL_CPU_NODE1_X1PAD")
	)
	(segment
		(start 76.239878 -82.653124)
		(end 77.42682 -82.653124)
		(width 0.1016)
		(layer "F.Cu")
		(net "XTAL_CPU_NODE1_X1PAD")
	)
	(segment
		(start 80.074262 -84.038694)
		(end 79.8957 -84.217256)
		(width 0.1016)
		(layer "F.Cu")
		(net "XTAL_CPU_NODE1_X1PAD")
	)
	(segment
		(start 83.086956 -84.041234)
		(end 83.68792 -83.44027)
		(width 0.1016)
		(layer "F.Cu")
		(net "XTAL_CPU_NODE1_X1PAD")
	)
	(segment
		(start 82.7278 -84.041234)
		(end 83.086956 -84.041234)
		(width 0.1016)
		(layer "F.Cu")
		(net "XTAL_CPU_NODE1_X1PAD")
	)
	(segment
		(start 77.42682 -82.653124)
		(end 78.81239 -84.038694)
		(width 0.1016)
		(layer "F.Cu")
		(net "XTAL_CPU_NODE1_X1PAD")
	)
	(segment
		(start 73.862438 -82.415126)
		(end 76.00188 -82.415126)
		(width 0.1016)
		(layer "F.Cu")
		(net "XTAL_CPU_NODE1_X1PAD")
	)
	(via
		(at 79.8957 -84.217256)
		(size 0.508)
		(drill 0.254)
		(layers "F.Cu" "B.Cu")
		(net "XTAL_CPU_NODE1_X1PAD")
	)
	(segment
		(start 41.85031 -32.21609)
		(end 41.85031 -29.149802)
		(width 0.1651)
		(layer "F.Cu")
		(net "M1_DQ_NODE1_DQ5")
	)
	(segment
		(start 51.634644 -66.013076)
		(end 51.634644 -66.024506)
		(width 0.1016)
		(layer "F.Cu")
		(net "M1_DQ_NODE1_DQ5")
	)
	(segment
		(start 41.78046 -32.28594)
		(end 41.85031 -32.21609)
		(width 0.1651)
		(layer "F.Cu")
		(net "M1_DQ_NODE1_DQ5")
	)
	(segment
		(start 51.302158 -66.356992)
		(end 51.306476 -66.356992)
		(width 0.1016)
		(layer "F.Cu")
		(net "M1_DQ_NODE1_DQ5")
	)
	(segment
		(start 51.634644 -66.024506)
		(end 51.302158 -66.356992)
		(width 0.1016)
		(layer "F.Cu")
		(net "M1_DQ_NODE1_DQ5")
	)
	(segment
		(start 51.811682 -65.836038)
		(end 51.634644 -66.013076)
		(width 0.1016)
		(layer "F.Cu")
		(net "M1_DQ_NODE1_DQ5")
	)
	(via
		(at 41.78046 -32.28594)
		(size 0.508)
		(drill 0.254)
		(layers "F.Cu" "B.Cu")
		(net "M1_DQ_NODE1_DQ5")
	)
	(via
		(at 51.306476 -66.356992)
		(size 0.508)
		(drill 0.254)
		(layers "F.Cu" "B.Cu")
		(net "M1_DQ_NODE1_DQ5")
	)
	(segment
		(start 37.394388 -32.309816)
		(end 37.178742 -32.09417)
		(width 0.2032)
		(layer "In7.Cu")
		(net "M1_DQ_NODE1_DQ5")
	)
	(segment
		(start 46.157896 -62.665356)
		(end 45.5422 -62.04966)
		(width 0.2032)
		(layer "In7.Cu")
		(net "M1_DQ_NODE1_DQ5")
	)
	(segment
		(start 35.45078 -34.054542)
		(end 35.45078 -31.78683)
		(width 0.2032)
		(layer "In7.Cu")
		(net "M1_DQ_NODE1_DQ5")
	)
	(segment
		(start 49.857914 -68.070984)
		(end 49.060608 -68.070984)
		(width 0.1016)
		(layer "In7.Cu")
		(net "M1_DQ_NODE1_DQ5")
	)
	(segment
		(start 50.771298 -67.1576)
		(end 49.857914 -68.070984)
		(width 0.1016)
		(layer "In7.Cu")
		(net "M1_DQ_NODE1_DQ5")
	)
	(segment
		(start 37.394388 -31.573216)
		(end 41.067736 -31.573216)
		(width 0.2032)
		(layer "In7.Cu")
		(net "M1_DQ_NODE1_DQ5")
	)
	(segment
		(start 36.238942 -31.58363)
		(end 36.442142 -31.78683)
		(width 0.2032)
		(layer "In7.Cu")
		(net "M1_DQ_NODE1_DQ5")
	)
	(segment
		(start 37.178742 -32.09417)
		(end 37.178742 -31.788862)
		(width 0.2032)
		(layer "In7.Cu")
		(net "M1_DQ_NODE1_DQ5")
	)
	(segment
		(start 32.84728 -53.6194)
		(end 32.84728 -36.658042)
		(width 0.2032)
		(layer "In7.Cu")
		(net "M1_DQ_NODE1_DQ5")
	)
	(segment
		(start 33.3502 -35.850322)
		(end 32.951674 -35.451796)
		(width 0.2032)
		(layer "In7.Cu")
		(net "M1_DQ_NODE1_DQ5")
	)
	(segment
		(start 38.94328 -32.83077)
		(end 38.94328 -32.525462)
		(width 0.2032)
		(layer "In7.Cu")
		(net "M1_DQ_NODE1_DQ5")
	)
	(segment
		(start 42.899584 -59.622944)
		(end 42.318686 -59.622944)
		(width 0.2032)
		(layer "In7.Cu")
		(net "M1_DQ_NODE1_DQ5")
	)
	(segment
		(start 35.65398 -31.58363)
		(end 36.238942 -31.58363)
		(width 0.2032)
		(layer "In7.Cu")
		(net "M1_DQ_NODE1_DQ5")
	)
	(segment
		(start 34.175954 -35.329368)
		(end 35.45078 -34.054542)
		(width 0.2032)
		(layer "In7.Cu")
		(net "M1_DQ_NODE1_DQ5")
	)
	(segment
		(start 51.306476 -66.356992)
		(end 50.771298 -66.89217)
		(width 0.1016)
		(layer "In7.Cu")
		(net "M1_DQ_NODE1_DQ5")
	)
	(segment
		(start 38.94328 -32.525462)
		(end 38.727634 -32.309816)
		(width 0.2032)
		(layer "In7.Cu")
		(net "M1_DQ_NODE1_DQ5")
	)
	(segment
		(start 37.178742 -31.788862)
		(end 37.394388 -31.573216)
		(width 0.2032)
		(layer "In7.Cu")
		(net "M1_DQ_NODE1_DQ5")
	)
	(segment
		(start 32.951674 -35.451796)
		(end 32.951674 -35.146996)
		(width 0.2032)
		(layer "In7.Cu")
		(net "M1_DQ_NODE1_DQ5")
	)
	(segment
		(start 43.922442 -60.645802)
		(end 42.899584 -59.622944)
		(width 0.2032)
		(layer "In7.Cu")
		(net "M1_DQ_NODE1_DQ5")
	)
	(segment
		(start 45.5422 -61.699394)
		(end 44.488608 -60.645802)
		(width 0.2032)
		(layer "In7.Cu")
		(net "M1_DQ_NODE1_DQ5")
	)
	(segment
		(start 32.951674 -35.146996)
		(end 33.167828 -34.930842)
		(width 0.2032)
		(layer "In7.Cu")
		(net "M1_DQ_NODE1_DQ5")
	)
	(segment
		(start 33.472628 -34.930842)
		(end 33.871154 -35.329368)
		(width 0.2032)
		(layer "In7.Cu")
		(net "M1_DQ_NODE1_DQ5")
	)
	(segment
		(start 35.45078 -31.78683)
		(end 35.65398 -31.58363)
		(width 0.2032)
		(layer "In7.Cu")
		(net "M1_DQ_NODE1_DQ5")
	)
	(segment
		(start 33.167828 -34.930842)
		(end 33.472628 -34.930842)
		(width 0.2032)
		(layer "In7.Cu")
		(net "M1_DQ_NODE1_DQ5")
	)
	(segment
		(start 42.318686 -59.622944)
		(end 40.86225 -58.166508)
		(width 0.2032)
		(layer "In7.Cu")
		(net "M1_DQ_NODE1_DQ5")
	)
	(segment
		(start 46.157896 -62.809374)
		(end 46.157896 -62.665356)
		(width 0.2032)
		(layer "In7.Cu")
		(net "M1_DQ_NODE1_DQ5")
	)
	(segment
		(start 36.657788 -33.046416)
		(end 38.727634 -33.046416)
		(width 0.2032)
		(layer "In7.Cu")
		(net "M1_DQ_NODE1_DQ5")
	)
	(segment
		(start 33.871154 -35.329368)
		(end 34.175954 -35.329368)
		(width 0.2032)
		(layer "In7.Cu")
		(net "M1_DQ_NODE1_DQ5")
	)
	(segment
		(start 36.442142 -31.78683)
		(end 36.442142 -32.83077)
		(width 0.2032)
		(layer "In7.Cu")
		(net "M1_DQ_NODE1_DQ5")
	)
	(segment
		(start 47.63643 -63.345568)
		(end 46.69409 -63.345568)
		(width 0.1016)
		(layer "In7.Cu")
		(net "M1_DQ_NODE1_DQ5")
	)
	(segment
		(start 48.566324 -64.275462)
		(end 47.63643 -63.345568)
		(width 0.1016)
		(layer "In7.Cu")
		(net "M1_DQ_NODE1_DQ5")
	)
	(segment
		(start 32.84728 -36.658042)
		(end 33.3502 -36.155122)
		(width 0.2032)
		(layer "In7.Cu")
		(net "M1_DQ_NODE1_DQ5")
	)
	(segment
		(start 48.566324 -67.5767)
		(end 48.566324 -64.275462)
		(width 0.1016)
		(layer "In7.Cu")
		(net "M1_DQ_NODE1_DQ5")
	)
	(segment
		(start 40.86225 -58.166508)
		(end 37.394388 -58.166508)
		(width 0.2032)
		(layer "In7.Cu")
		(net "M1_DQ_NODE1_DQ5")
	)
	(segment
		(start 36.442142 -32.83077)
		(end 36.657788 -33.046416)
		(width 0.2032)
		(layer "In7.Cu")
		(net "M1_DQ_NODE1_DQ5")
	)
	(segment
		(start 50.771298 -66.89217)
		(end 50.771298 -67.1576)
		(width 0.1016)
		(layer "In7.Cu")
		(net "M1_DQ_NODE1_DQ5")
	)
	(segment
		(start 38.727634 -33.046416)
		(end 38.94328 -32.83077)
		(width 0.2032)
		(layer "In7.Cu")
		(net "M1_DQ_NODE1_DQ5")
	)
	(segment
		(start 38.727634 -32.309816)
		(end 37.394388 -32.309816)
		(width 0.2032)
		(layer "In7.Cu")
		(net "M1_DQ_NODE1_DQ5")
	)
	(segment
		(start 49.060608 -68.070984)
		(end 48.566324 -67.5767)
		(width 0.1016)
		(layer "In7.Cu")
		(net "M1_DQ_NODE1_DQ5")
	)
	(segment
		(start 37.394388 -58.166508)
		(end 32.84728 -53.6194)
		(width 0.2032)
		(layer "In7.Cu")
		(net "M1_DQ_NODE1_DQ5")
	)
	(segment
		(start 41.067736 -31.573216)
		(end 41.78046 -32.28594)
		(width 0.2032)
		(layer "In7.Cu")
		(net "M1_DQ_NODE1_DQ5")
	)
	(segment
		(start 44.488608 -60.645802)
		(end 43.922442 -60.645802)
		(width 0.2032)
		(layer "In7.Cu")
		(net "M1_DQ_NODE1_DQ5")
	)
	(segment
		(start 45.5422 -62.04966)
		(end 45.5422 -61.699394)
		(width 0.2032)
		(layer "In7.Cu")
		(net "M1_DQ_NODE1_DQ5")
	)
	(segment
		(start 33.3502 -36.155122)
		(end 33.3502 -35.850322)
		(width 0.2032)
		(layer "In7.Cu")
		(net "M1_DQ_NODE1_DQ5")
	)
	(segment
		(start 46.69409 -63.345568)
		(end 46.157896 -62.809374)
		(width 0.1016)
		(layer "In7.Cu")
		(net "M1_DQ_NODE1_DQ5")
	)
	(segment
		(start 55.182516 -88.438482)
		(end 55.182516 -89.816432)
		(width 0.1016)
		(layer "F.Cu")
		(net "PD_CPU_NODE1_DFX_GPIO_GRP0_2")
	)
	(segment
		(start 54.033166 -96.309942)
		(end 54.033166 -95.727774)
		(width 0.1016)
		(layer "F.Cu")
		(net "PD_CPU_NODE1_DFX_GPIO_GRP0_2")
	)
	(segment
		(start 55.182516 -89.816432)
		(end 54.522878 -90.47607)
		(width 0.1016)
		(layer "F.Cu")
		(net "PD_CPU_NODE1_DFX_GPIO_GRP0_2")
	)
	(segment
		(start 54.033166 -95.727774)
		(end 53.700426 -95.395034)
		(width 0.1016)
		(layer "F.Cu")
		(net "PD_CPU_NODE1_DFX_GPIO_GRP0_2")
	)
	(segment
		(start 53.700426 -95.395034)
		(end 53.700426 -91.965018)
		(width 0.1016)
		(layer "F.Cu")
		(net "PD_CPU_NODE1_DFX_GPIO_GRP0_2")
	)
	(segment
		(start 54.3433 -91.322144)
		(end 54.3433 -90.655648)
		(width 0.1016)
		(layer "F.Cu")
		(net "PD_CPU_NODE1_DFX_GPIO_GRP0_2")
	)
	(segment
		(start 54.3433 -90.655648)
		(end 54.522878 -90.47607)
		(width 0.1016)
		(layer "F.Cu")
		(net "PD_CPU_NODE1_DFX_GPIO_GRP0_2")
	)
	(segment
		(start 53.700426 -91.965018)
		(end 54.3433 -91.322144)
		(width 0.1016)
		(layer "F.Cu")
		(net "PD_CPU_NODE1_DFX_GPIO_GRP0_2")
	)
	(via
		(at 54.522878 -90.47607)
		(size 0.508)
		(drill 0.254)
		(layers "F.Cu" "B.Cu")
		(net "PD_CPU_NODE1_DFX_GPIO_GRP0_2")
	)
	(segment
		(start 54.750208 -22.841458)
		(end 54.806088 -22.897338)
		(width 0.1651)
		(layer "F.Cu")
		(net "M1_DQ_NODE1_DQ18")
	)
	(segment
		(start 53.797962 -66.240914)
		(end 53.41747 -66.621406)
		(width 0.1016)
		(layer "F.Cu")
		(net "M1_DQ_NODE1_DQ18")
	)
	(segment
		(start 53.797962 -66.217038)
		(end 53.797962 -66.240914)
		(width 0.1016)
		(layer "F.Cu")
		(net "M1_DQ_NODE1_DQ18")
	)
	(segment
		(start 54.806088 -22.897338)
		(end 54.806342 -22.897338)
		(width 0.1651)
		(layer "F.Cu")
		(net "M1_DQ_NODE1_DQ18")
	)
	(segment
		(start 54.750208 -20.94992)
		(end 54.750208 -22.841458)
		(width 0.1651)
		(layer "F.Cu")
		(net "M1_DQ_NODE1_DQ18")
	)
	(via
		(at 54.806342 -22.897338)
		(size 0.508)
		(drill 0.254)
		(layers "F.Cu" "B.Cu")
		(net "M1_DQ_NODE1_DQ18")
	)
	(via
		(at 53.41747 -66.621406)
		(size 0.508)
		(drill 0.254)
		(layers "F.Cu" "B.Cu")
		(net "M1_DQ_NODE1_DQ18")
	)
	(segment
		(start 42.52214 -45.745654)
		(end 42.31386 -45.537374)
		(width 0.2032)
		(layer "In7.Cu")
		(net "M1_DQ_NODE1_DQ18")
	)
	(segment
		(start 41.00576 -45.329094)
		(end 41.00576 -45.034454)
		(width 0.2032)
		(layer "In7.Cu")
		(net "M1_DQ_NODE1_DQ18")
	)
	(segment
		(start 41.00576 -45.034454)
		(end 41.21404 -44.826174)
		(width 0.2032)
		(layer "In7.Cu")
		(net "M1_DQ_NODE1_DQ18")
	)
	(segment
		(start 51.76012 -59.385962)
		(end 51.76012 -58.34253)
		(width 0.2032)
		(layer "In7.Cu")
		(net "M1_DQ_NODE1_DQ18")
	)
	(segment
		(start 54.709822 -22.993858)
		(end 54.806342 -22.897338)
		(width 0.2032)
		(layer "In7.Cu")
		(net "M1_DQ_NODE1_DQ18")
	)
	(segment
		(start 42.52214 -42.490898)
		(end 51.03622 -33.976818)
		(width 0.2032)
		(layer "In7.Cu")
		(net "M1_DQ_NODE1_DQ18")
	)
	(segment
		(start 51.036982 -28.264358)
		(end 50.780442 -28.007818)
		(width 0.2032)
		(layer "In7.Cu")
		(net "M1_DQ_NODE1_DQ18")
	)
	(segment
		(start 42.31386 -44.114974)
		(end 41.40708 -44.114974)
		(width 0.2032)
		(layer "In7.Cu")
		(net "M1_DQ_NODE1_DQ18")
	)
	(segment
		(start 51.590702 -25.371298)
		(end 51.590702 -24.357076)
		(width 0.2032)
		(layer "In7.Cu")
		(net "M1_DQ_NODE1_DQ18")
	)
	(segment
		(start 41.21404 -44.826174)
		(end 42.31386 -44.826174)
		(width 0.2032)
		(layer "In7.Cu")
		(net "M1_DQ_NODE1_DQ18")
	)
	(segment
		(start 42.31386 -43.403774)
		(end 42.52214 -43.195494)
		(width 0.2032)
		(layer "In7.Cu")
		(net "M1_DQ_NODE1_DQ18")
	)
	(segment
		(start 51.03622 -33.976818)
		(end 51.03622 -32.57042)
		(width 0.2032)
		(layer "In7.Cu")
		(net "M1_DQ_NODE1_DQ18")
	)
	(segment
		(start 53.826664 -65.470786)
		(end 54.029864 -65.267586)
		(width 0.1016)
		(layer "In7.Cu")
		(net "M1_DQ_NODE1_DQ18")
	)
	(segment
		(start 41.21404 -45.537374)
		(end 41.00576 -45.329094)
		(width 0.2032)
		(layer "In7.Cu")
		(net "M1_DQ_NODE1_DQ18")
	)
	(segment
		(start 52.703984 -60.670948)
		(end 51.76012 -59.727084)
		(width 0.1016)
		(layer "In7.Cu")
		(net "M1_DQ_NODE1_DQ18")
	)
	(segment
		(start 51.590702 -24.357076)
		(end 52.95392 -22.993858)
		(width 0.2032)
		(layer "In7.Cu")
		(net "M1_DQ_NODE1_DQ18")
	)
	(segment
		(start 51.417982 -26.552398)
		(end 51.417982 -25.544018)
		(width 0.2032)
		(layer "In7.Cu")
		(net "M1_DQ_NODE1_DQ18")
	)
	(segment
		(start 51.03622 -32.57042)
		(end 51.036982 -32.569658)
		(width 0.2032)
		(layer "In7.Cu")
		(net "M1_DQ_NODE1_DQ18")
	)
	(segment
		(start 53.36032 -63.607696)
		(end 52.703984 -62.95136)
		(width 0.1016)
		(layer "In7.Cu")
		(net "M1_DQ_NODE1_DQ18")
	)
	(segment
		(start 51.036982 -32.569658)
		(end 51.036982 -28.264358)
		(width 0.2032)
		(layer "In7.Cu")
		(net "M1_DQ_NODE1_DQ18")
	)
	(segment
		(start 41.1988 -43.612054)
		(end 41.40708 -43.403774)
		(width 0.2032)
		(layer "In7.Cu")
		(net "M1_DQ_NODE1_DQ18")
	)
	(segment
		(start 52.95392 -22.993858)
		(end 54.709822 -22.993858)
		(width 0.2032)
		(layer "In7.Cu")
		(net "M1_DQ_NODE1_DQ18")
	)
	(segment
		(start 42.52214 -49.10455)
		(end 42.52214 -45.745654)
		(width 0.2032)
		(layer "In7.Cu")
		(net "M1_DQ_NODE1_DQ18")
	)
	(segment
		(start 53.36032 -64.071754)
		(end 53.36032 -63.607696)
		(width 0.1016)
		(layer "In7.Cu")
		(net "M1_DQ_NODE1_DQ18")
	)
	(segment
		(start 51.76012 -59.727084)
		(end 51.76012 -59.385962)
		(width 0.1016)
		(layer "In7.Cu")
		(net "M1_DQ_NODE1_DQ18")
	)
	(segment
		(start 54.029864 -65.267586)
		(end 54.029864 -64.741298)
		(width 0.1016)
		(layer "In7.Cu")
		(net "M1_DQ_NODE1_DQ18")
	)
	(segment
		(start 53.41747 -66.621406)
		(end 53.826664 -66.212212)
		(width 0.1016)
		(layer "In7.Cu")
		(net "M1_DQ_NODE1_DQ18")
	)
	(segment
		(start 42.52214 -43.195494)
		(end 42.52214 -42.490898)
		(width 0.2032)
		(layer "In7.Cu")
		(net "M1_DQ_NODE1_DQ18")
	)
	(segment
		(start 41.40708 -44.114974)
		(end 41.1988 -43.906694)
		(width 0.2032)
		(layer "In7.Cu")
		(net "M1_DQ_NODE1_DQ18")
	)
	(segment
		(start 51.76012 -58.34253)
		(end 42.52214 -49.10455)
		(width 0.2032)
		(layer "In7.Cu")
		(net "M1_DQ_NODE1_DQ18")
	)
	(segment
		(start 54.029864 -64.741298)
		(end 53.36032 -64.071754)
		(width 0.1016)
		(layer "In7.Cu")
		(net "M1_DQ_NODE1_DQ18")
	)
	(segment
		(start 42.31386 -45.537374)
		(end 41.21404 -45.537374)
		(width 0.2032)
		(layer "In7.Cu")
		(net "M1_DQ_NODE1_DQ18")
	)
	(segment
		(start 50.780442 -28.007818)
		(end 50.780442 -27.189938)
		(width 0.2032)
		(layer "In7.Cu")
		(net "M1_DQ_NODE1_DQ18")
	)
	(segment
		(start 42.52214 -44.323254)
		(end 42.31386 -44.114974)
		(width 0.2032)
		(layer "In7.Cu")
		(net "M1_DQ_NODE1_DQ18")
	)
	(segment
		(start 52.703984 -62.95136)
		(end 52.703984 -60.670948)
		(width 0.1016)
		(layer "In7.Cu")
		(net "M1_DQ_NODE1_DQ18")
	)
	(segment
		(start 53.826664 -66.212212)
		(end 53.826664 -65.470786)
		(width 0.1016)
		(layer "In7.Cu")
		(net "M1_DQ_NODE1_DQ18")
	)
	(segment
		(start 42.52214 -44.617894)
		(end 42.52214 -44.323254)
		(width 0.2032)
		(layer "In7.Cu")
		(net "M1_DQ_NODE1_DQ18")
	)
	(segment
		(start 51.417982 -25.544018)
		(end 51.590702 -25.371298)
		(width 0.2032)
		(layer "In7.Cu")
		(net "M1_DQ_NODE1_DQ18")
	)
	(segment
		(start 41.40708 -43.403774)
		(end 42.31386 -43.403774)
		(width 0.2032)
		(layer "In7.Cu")
		(net "M1_DQ_NODE1_DQ18")
	)
	(segment
		(start 41.1988 -43.906694)
		(end 41.1988 -43.612054)
		(width 0.2032)
		(layer "In7.Cu")
		(net "M1_DQ_NODE1_DQ18")
	)
	(segment
		(start 42.31386 -44.826174)
		(end 42.52214 -44.617894)
		(width 0.2032)
		(layer "In7.Cu")
		(net "M1_DQ_NODE1_DQ18")
	)
	(segment
		(start 50.780442 -27.189938)
		(end 51.417982 -26.552398)
		(width 0.2032)
		(layer "In7.Cu")
		(net "M1_DQ_NODE1_DQ18")
	)
	(via
		(at 135.613902 -102.146354)
		(size 0.6604)
		(drill 0.3302)
		(layers "F.Cu" "B.Cu")
		(net "P3V3_CLK_NODE1_R")
	)
	(segment
		(start 179.622704 -9.114536)
		(end 179.622704 -11.13663)
		(width 0.1016)
		(layer "F.Cu")
		(net "N53608970")
	)
	(segment
		(start 179.999894 -8.737346)
		(end 179.622704 -9.114536)
		(width 0.1016)
		(layer "F.Cu")
		(net "N53608970")
	)
	(segment
		(start 179.999894 -7.799832)
		(end 179.999894 -8.737346)
		(width 0.1016)
		(layer "F.Cu")
		(net "N53608970")
	)
	(segment
		(start 77.850238 -26.409142)
		(end 77.850238 -29.149802)
		(width 0.1016)
		(layer "F.Cu")
		(net "TP_DDR3_NODE1_CS3_L")
	)
	(segment
		(start 78.9559 -25.30348)
		(end 77.850238 -26.409142)
		(width 0.1016)
		(layer "F.Cu")
		(net "TP_DDR3_NODE1_CS3_L")
	)
	(via
		(at 78.9559 -25.30348)
		(size 0.508)
		(drill 0.254)
		(layers "F.Cu" "B.Cu")
		(net "TP_DDR3_NODE1_CS3_L")
	)
	(segment
		(start 60.210192 -85.000846)
		(end 60.591192 -84.619846)
		(width 0.1016)
		(layer "F.Cu")
		(net "SPI_CPU_NODE1_SCLK_R")
	)
	(segment
		(start 60.21705 -85.000846)
		(end 60.210192 -85.000846)
		(width 0.1016)
		(layer "F.Cu")
		(net "SPI_CPU_NODE1_SCLK_R")
	)
	(via
		(at 59.74588 -88.462358)
		(size 0.6604)
		(drill 0.3302)
		(layers "F.Cu" "B.Cu")
		(net "SPI_CPU_NODE1_SCLK_R")
	)
	(via
		(at 60.591192 -84.619846)
		(size 0.508)
		(drill 0.254)
		(layers "F.Cu" "B.Cu")
		(net "SPI_CPU_NODE1_SCLK_R")
	)
	(segment
		(start 60.615322 -91.642184)
		(end 60.615322 -91.242134)
		(width 0.1016)
		(layer "B.Cu")
		(net "SPI_CPU_NODE1_SCLK_R")
	)
	(segment
		(start 60.615322 -91.242134)
		(end 60.905136 -90.95232)
		(width 0.1016)
		(layer "B.Cu")
		(net "SPI_CPU_NODE1_SCLK_R")
	)
	(segment
		(start 60.905136 -90.266774)
		(end 59.74588 -89.107518)
		(width 0.1016)
		(layer "B.Cu")
		(net "SPI_CPU_NODE1_SCLK_R")
	)
	(segment
		(start 60.029852 -85.326728)
		(end 60.591192 -84.765388)
		(width 0.1016)
		(layer "B.Cu")
		(net "SPI_CPU_NODE1_SCLK_R")
	)
	(segment
		(start 59.74588 -89.107518)
		(end 59.74588 -88.462358)
		(width 0.1016)
		(layer "B.Cu")
		(net "SPI_CPU_NODE1_SCLK_R")
	)
	(segment
		(start 60.905136 -90.95232)
		(end 60.905136 -90.266774)
		(width 0.1016)
		(layer "B.Cu")
		(net "SPI_CPU_NODE1_SCLK_R")
	)
	(segment
		(start 60.591192 -84.765388)
		(end 60.591192 -84.619846)
		(width 0.1016)
		(layer "B.Cu")
		(net "SPI_CPU_NODE1_SCLK_R")
	)
	(segment
		(start 59.74588 -88.462358)
		(end 60.029852 -88.178386)
		(width 0.1016)
		(layer "B.Cu")
		(net "SPI_CPU_NODE1_SCLK_R")
	)
	(segment
		(start 60.029852 -88.178386)
		(end 60.029852 -85.326728)
		(width 0.1016)
		(layer "B.Cu")
		(net "SPI_CPU_NODE1_SCLK_R")
	)
	(segment
		(start 43.527218 -67.015868)
		(end 43.654218 -67.015868)
		(width 0.1143)
		(layer "F.Cu")
		(net "CLK_100M_PCIE_RP0_NODE1_DN")
	)
	(segment
		(start 130.753866 -121.741946)
		(end 130.706368 -121.789444)
		(width 0.127)
		(layer "F.Cu")
		(net "CLK_100M_PCIE_RP0_NODE1_DN")
	)
	(segment
		(start 129.36728 -123.903994)
		(end 129.36728 -126.505208)
		(width 0.127)
		(layer "F.Cu")
		(net "CLK_100M_PCIE_RP0_NODE1_DN")
	)
	(segment
		(start 129.36728 -126.505208)
		(end 129.623058 -126.760986)
		(width 0.127)
		(layer "F.Cu")
		(net "CLK_100M_PCIE_RP0_NODE1_DN")
	)
	(segment
		(start 129.49936 -123.771914)
		(end 129.36728 -123.903994)
		(width 0.127)
		(layer "F.Cu")
		(net "CLK_100M_PCIE_RP0_NODE1_DN")
	)
	(segment
		(start 43.654218 -67.015868)
		(end 43.97248 -66.697606)
		(width 0.1143)
		(layer "F.Cu")
		(net "CLK_100M_PCIE_RP0_NODE1_DN")
	)
	(segment
		(start 43.97248 -66.697606)
		(end 44.008802 -66.697606)
		(width 0.1143)
		(layer "F.Cu")
		(net "CLK_100M_PCIE_RP0_NODE1_DN")
	)
	(segment
		(start 130.753866 -121.064528)
		(end 130.753866 -121.741946)
		(width 0.127)
		(layer "F.Cu")
		(net "CLK_100M_PCIE_RP0_NODE1_DN")
	)
	(segment
		(start 129.623058 -126.760986)
		(end 129.85242 -126.760986)
		(width 0.127)
		(layer "F.Cu")
		(net "CLK_100M_PCIE_RP0_NODE1_DN")
	)
	(segment
		(start 129.95402 -123.317762)
		(end 129.95402 -123.319286)
		(width 0.127)
		(layer "F.Cu")
		(net "CLK_100M_PCIE_RP0_NODE1_DN")
	)
	(segment
		(start 43.45813 -66.689986)
		(end 43.45813 -66.94678)
		(width 0.1143)
		(layer "F.Cu")
		(net "CLK_100M_PCIE_RP0_NODE1_DN")
	)
	(segment
		(start 130.706368 -121.789444)
		(end 130.706368 -122.565414)
		(width 0.127)
		(layer "F.Cu")
		(net "CLK_100M_PCIE_RP0_NODE1_DN")
	)
	(segment
		(start 130.706368 -122.565414)
		(end 129.95402 -123.317762)
		(width 0.127)
		(layer "F.Cu")
		(net "CLK_100M_PCIE_RP0_NODE1_DN")
	)
	(segment
		(start 129.95402 -123.319286)
		(end 129.501392 -123.771914)
		(width 0.127)
		(layer "F.Cu")
		(net "CLK_100M_PCIE_RP0_NODE1_DN")
	)
	(segment
		(start 129.501392 -123.771914)
		(end 129.49936 -123.771914)
		(width 0.127)
		(layer "F.Cu")
		(net "CLK_100M_PCIE_RP0_NODE1_DN")
	)
	(segment
		(start 43.45813 -66.94678)
		(end 43.527218 -67.015868)
		(width 0.1143)
		(layer "F.Cu")
		(net "CLK_100M_PCIE_RP0_NODE1_DN")
	)
	(via
		(at 129.85242 -126.760986)
		(size 0.508)
		(drill 0.254)
		(layers "F.Cu" "B.Cu")
		(net "CLK_100M_PCIE_RP0_NODE1_DN")
	)
	(via
		(at 44.008802 -66.697606)
		(size 0.508)
		(drill 0.254)
		(layers "F.Cu" "B.Cu")
		(net "CLK_100M_PCIE_RP0_NODE1_DN")
	)
	(segment
		(start 91.20124 -93.57487)
		(end 97.762822 -93.57487)
		(width 0.127)
		(layer "In7.Cu")
		(net "CLK_100M_PCIE_RP0_NODE1_DN")
	)
	(segment
		(start 102.01529 -90.401394)
		(end 102.148386 -90.268298)
		(width 0.127)
		(layer "In7.Cu")
		(net "CLK_100M_PCIE_RP0_NODE1_DN")
	)
	(segment
		(start 121.42724 -103.621078)
		(end 121.42724 -104.770936)
		(width 0.127)
		(layer "In7.Cu")
		(net "CLK_100M_PCIE_RP0_NODE1_DN")
	)
	(segment
		(start 90.951558 -93.824552)
		(end 91.20124 -93.57487)
		(width 0.127)
		(layer "In7.Cu")
		(net "CLK_100M_PCIE_RP0_NODE1_DN")
	)
	(segment
		(start 129.36347 -126.936246)
		(end 129.53873 -126.760986)
		(width 0.127)
		(layer "In7.Cu")
		(net "CLK_100M_PCIE_RP0_NODE1_DN")
	)
	(segment
		(start 105.613962 -90.268298)
		(end 105.747058 -90.401394)
		(width 0.127)
		(layer "In7.Cu")
		(net "CLK_100M_PCIE_RP0_NODE1_DN")
	)
	(segment
		(start 47.965614 -68.514214)
		(end 47.965614 -69.089524)
		(width 0.127)
		(layer "In7.Cu")
		(net "CLK_100M_PCIE_RP0_NODE1_DN")
	)
	(segment
		(start 106.261154 -90.268298)
		(end 106.642154 -90.268298)
		(width 0.127)
		(layer "In7.Cu")
		(net "CLK_100M_PCIE_RP0_NODE1_DN")
	)
	(segment
		(start 53.398674 -94.302834)
		(end 59.139836 -94.302834)
		(width 0.127)
		(layer "In7.Cu")
		(net "CLK_100M_PCIE_RP0_NODE1_DN")
	)
	(segment
		(start 105.747058 -90.401394)
		(end 106.128058 -90.401394)
		(width 0.127)
		(layer "In7.Cu")
		(net "CLK_100M_PCIE_RP0_NODE1_DN")
	)
	(segment
		(start 129.11582 -122.366024)
		(end 130.9243 -124.174504)
		(width 0.127)
		(layer "In7.Cu")
		(net "CLK_100M_PCIE_RP0_NODE1_DN")
	)
	(segment
		(start 106.642154 -90.268298)
		(end 106.77525 -90.401394)
		(width 0.127)
		(layer "In7.Cu")
		(net "CLK_100M_PCIE_RP0_NODE1_DN")
	)
	(segment
		(start 129.53873 -126.760986)
		(end 129.85242 -126.760986)
		(width 0.127)
		(layer "In7.Cu")
		(net "CLK_100M_PCIE_RP0_NODE1_DN")
	)
	(segment
		(start 106.128058 -90.401394)
		(end 106.261154 -90.268298)
		(width 0.127)
		(layer "In7.Cu")
		(net "CLK_100M_PCIE_RP0_NODE1_DN")
	)
	(segment
		(start 129.67462 -127.686816)
		(end 129.36347 -127.375666)
		(width 0.127)
		(layer "In7.Cu")
		(net "CLK_100M_PCIE_RP0_NODE1_DN")
	)
	(segment
		(start 44.27601 -67.296284)
		(end 44.675806 -67.69608)
		(width 0.127)
		(layer "In7.Cu")
		(net "CLK_100M_PCIE_RP0_NODE1_DN")
	)
	(segment
		(start 101.501194 -90.268298)
		(end 101.63429 -90.401394)
		(width 0.127)
		(layer "In7.Cu")
		(net "CLK_100M_PCIE_RP0_NODE1_DN")
	)
	(segment
		(start 119.351044 -101.744526)
		(end 119.620284 -102.013766)
		(width 0.127)
		(layer "In7.Cu")
		(net "CLK_100M_PCIE_RP0_NODE1_DN")
	)
	(segment
		(start 130.9243 -127.02032)
		(end 130.257804 -127.686816)
		(width 0.127)
		(layer "In7.Cu")
		(net "CLK_100M_PCIE_RP0_NODE1_DN")
	)
	(segment
		(start 101.63429 -90.401394)
		(end 102.01529 -90.401394)
		(width 0.127)
		(layer "In7.Cu")
		(net "CLK_100M_PCIE_RP0_NODE1_DN")
	)
	(segment
		(start 104.58577 -90.268298)
		(end 104.718866 -90.401394)
		(width 0.127)
		(layer "In7.Cu")
		(net "CLK_100M_PCIE_RP0_NODE1_DN")
	)
	(segment
		(start 124.8283 -114.039396)
		(end 126.69266 -115.903756)
		(width 0.127)
		(layer "In7.Cu")
		(net "CLK_100M_PCIE_RP0_NODE1_DN")
	)
	(segment
		(start 101.069394 -90.268298)
		(end 101.501194 -90.268298)
		(width 0.127)
		(layer "In7.Cu")
		(net "CLK_100M_PCIE_RP0_NODE1_DN")
	)
	(segment
		(start 44.27601 -66.970402)
		(end 44.27601 -67.296284)
		(width 0.127)
		(layer "In7.Cu")
		(net "CLK_100M_PCIE_RP0_NODE1_DN")
	)
	(segment
		(start 43.500294 -71.610474)
		(end 42.672 -72.438768)
		(width 0.127)
		(layer "In7.Cu")
		(net "CLK_100M_PCIE_RP0_NODE1_DN")
	)
	(segment
		(start 126.69266 -115.903756)
		(end 126.69266 -118.674134)
		(width 0.127)
		(layer "In7.Cu")
		(net "CLK_100M_PCIE_RP0_NODE1_DN")
	)
	(segment
		(start 105.232962 -90.268298)
		(end 105.613962 -90.268298)
		(width 0.127)
		(layer "In7.Cu")
		(net "CLK_100M_PCIE_RP0_NODE1_DN")
	)
	(segment
		(start 44.008802 -66.697606)
		(end 44.245784 -66.940176)
		(width 0.127)
		(layer "In7.Cu")
		(net "CLK_100M_PCIE_RP0_NODE1_DN")
	)
	(segment
		(start 46.17847 -68.099178)
		(end 47.550578 -68.099178)
		(width 0.127)
		(layer "In7.Cu")
		(net "CLK_100M_PCIE_RP0_NODE1_DN")
	)
	(segment
		(start 130.9243 -124.174504)
		(end 130.9243 -127.02032)
		(width 0.127)
		(layer "In7.Cu")
		(net "CLK_100M_PCIE_RP0_NODE1_DN")
	)
	(segment
		(start 107.15625 -90.401394)
		(end 107.289346 -90.268298)
		(width 0.127)
		(layer "In7.Cu")
		(net "CLK_100M_PCIE_RP0_NODE1_DN")
	)
	(segment
		(start 103.043482 -90.401394)
		(end 103.176578 -90.268298)
		(width 0.127)
		(layer "In7.Cu")
		(net "CLK_100M_PCIE_RP0_NODE1_DN")
	)
	(segment
		(start 62.748922 -94.227142)
		(end 78.40091 -94.227142)
		(width 0.127)
		(layer "In7.Cu")
		(net "CLK_100M_PCIE_RP0_NODE1_DN")
	)
	(segment
		(start 104.071674 -90.401394)
		(end 104.20477 -90.268298)
		(width 0.127)
		(layer "In7.Cu")
		(net "CLK_100M_PCIE_RP0_NODE1_DN")
	)
	(segment
		(start 87.4903 -93.824552)
		(end 90.951558 -93.824552)
		(width 0.127)
		(layer "In7.Cu")
		(net "CLK_100M_PCIE_RP0_NODE1_DN")
	)
	(segment
		(start 124.8283 -111.353854)
		(end 124.8283 -114.039396)
		(width 0.127)
		(layer "In7.Cu")
		(net "CLK_100M_PCIE_RP0_NODE1_DN")
	)
	(segment
		(start 102.148386 -90.268298)
		(end 102.529386 -90.268298)
		(width 0.127)
		(layer "In7.Cu")
		(net "CLK_100M_PCIE_RP0_NODE1_DN")
	)
	(segment
		(start 59.64047 -94.803468)
		(end 62.172596 -94.803468)
		(width 0.127)
		(layer "In7.Cu")
		(net "CLK_100M_PCIE_RP0_NODE1_DN")
	)
	(segment
		(start 120.089168 -102.48265)
		(end 120.358408 -102.75189)
		(width 0.127)
		(layer "In7.Cu")
		(net "CLK_100M_PCIE_RP0_NODE1_DN")
	)
	(segment
		(start 50.963068 -91.867228)
		(end 53.398674 -94.302834)
		(width 0.127)
		(layer "In7.Cu")
		(net "CLK_100M_PCIE_RP0_NODE1_DN")
	)
	(segment
		(start 48.542194 -71.610474)
		(end 43.500294 -71.610474)
		(width 0.127)
		(layer "In7.Cu")
		(net "CLK_100M_PCIE_RP0_NODE1_DN")
	)
	(segment
		(start 49.210468 -70.9422)
		(end 48.542194 -71.610474)
		(width 0.127)
		(layer "In7.Cu")
		(net "CLK_100M_PCIE_RP0_NODE1_DN")
	)
	(segment
		(start 106.77525 -90.401394)
		(end 107.15625 -90.401394)
		(width 0.127)
		(layer "In7.Cu")
		(net "CLK_100M_PCIE_RP0_NODE1_DN")
	)
	(segment
		(start 121.11736 -107.642914)
		(end 124.8283 -111.353854)
		(width 0.127)
		(layer "In7.Cu")
		(net "CLK_100M_PCIE_RP0_NODE1_DN")
	)
	(segment
		(start 104.718866 -90.401394)
		(end 105.099866 -90.401394)
		(width 0.127)
		(layer "In7.Cu")
		(net "CLK_100M_PCIE_RP0_NODE1_DN")
	)
	(segment
		(start 121.11736 -105.080816)
		(end 121.11736 -107.642914)
		(width 0.127)
		(layer "In7.Cu")
		(net "CLK_100M_PCIE_RP0_NODE1_DN")
	)
	(segment
		(start 44.559728 -91.867228)
		(end 50.963068 -91.867228)
		(width 0.127)
		(layer "In7.Cu")
		(net "CLK_100M_PCIE_RP0_NODE1_DN")
	)
	(segment
		(start 103.690674 -90.401394)
		(end 104.071674 -90.401394)
		(width 0.127)
		(layer "In7.Cu")
		(net "CLK_100M_PCIE_RP0_NODE1_DN")
	)
	(segment
		(start 108.07446 -90.268298)
		(end 119.351044 -101.544882)
		(width 0.127)
		(layer "In7.Cu")
		(net "CLK_100M_PCIE_RP0_NODE1_DN")
	)
	(segment
		(start 102.529386 -90.268298)
		(end 102.662482 -90.401394)
		(width 0.127)
		(layer "In7.Cu")
		(net "CLK_100M_PCIE_RP0_NODE1_DN")
	)
	(segment
		(start 59.139836 -94.302834)
		(end 59.64047 -94.803468)
		(width 0.127)
		(layer "In7.Cu")
		(net "CLK_100M_PCIE_RP0_NODE1_DN")
	)
	(segment
		(start 43.56608 -90.87358)
		(end 44.559728 -91.867228)
		(width 0.127)
		(layer "In7.Cu")
		(net "CLK_100M_PCIE_RP0_NODE1_DN")
	)
	(segment
		(start 120.089168 -102.283006)
		(end 120.089168 -102.48265)
		(width 0.127)
		(layer "In7.Cu")
		(net "CLK_100M_PCIE_RP0_NODE1_DN")
	)
	(segment
		(start 119.620284 -102.013766)
		(end 119.819928 -102.013766)
		(width 0.127)
		(layer "In7.Cu")
		(net "CLK_100M_PCIE_RP0_NODE1_DN")
	)
	(segment
		(start 102.662482 -90.401394)
		(end 103.043482 -90.401394)
		(width 0.127)
		(layer "In7.Cu")
		(net "CLK_100M_PCIE_RP0_NODE1_DN")
	)
	(segment
		(start 79.697326 -92.930726)
		(end 86.596474 -92.930726)
		(width 0.127)
		(layer "In7.Cu")
		(net "CLK_100M_PCIE_RP0_NODE1_DN")
	)
	(segment
		(start 42.672 -72.438768)
		(end 42.672 -84.991956)
		(width 0.127)
		(layer "In7.Cu")
		(net "CLK_100M_PCIE_RP0_NODE1_DN")
	)
	(segment
		(start 129.11582 -121.097294)
		(end 129.11582 -122.366024)
		(width 0.127)
		(layer "In7.Cu")
		(net "CLK_100M_PCIE_RP0_NODE1_DN")
	)
	(segment
		(start 119.819928 -102.013766)
		(end 120.089168 -102.283006)
		(width 0.127)
		(layer "In7.Cu")
		(net "CLK_100M_PCIE_RP0_NODE1_DN")
	)
	(segment
		(start 107.289346 -90.268298)
		(end 108.07446 -90.268298)
		(width 0.127)
		(layer "In7.Cu")
		(net "CLK_100M_PCIE_RP0_NODE1_DN")
	)
	(segment
		(start 97.762822 -93.57487)
		(end 101.069394 -90.268298)
		(width 0.127)
		(layer "In7.Cu")
		(net "CLK_100M_PCIE_RP0_NODE1_DN")
	)
	(segment
		(start 120.558052 -102.75189)
		(end 121.42724 -103.621078)
		(width 0.127)
		(layer "In7.Cu")
		(net "CLK_100M_PCIE_RP0_NODE1_DN")
	)
	(segment
		(start 44.245784 -66.940176)
		(end 44.27601 -66.970402)
		(width 0.127)
		(layer "In7.Cu")
		(net "CLK_100M_PCIE_RP0_NODE1_DN")
	)
	(segment
		(start 130.257804 -127.686816)
		(end 129.67462 -127.686816)
		(width 0.127)
		(layer "In7.Cu")
		(net "CLK_100M_PCIE_RP0_NODE1_DN")
	)
	(segment
		(start 43.56608 -85.886036)
		(end 43.56608 -90.87358)
		(width 0.127)
		(layer "In7.Cu")
		(net "CLK_100M_PCIE_RP0_NODE1_DN")
	)
	(segment
		(start 42.672 -84.991956)
		(end 43.56608 -85.886036)
		(width 0.127)
		(layer "In7.Cu")
		(net "CLK_100M_PCIE_RP0_NODE1_DN")
	)
	(segment
		(start 45.775372 -67.69608)
		(end 46.17847 -68.099178)
		(width 0.127)
		(layer "In7.Cu")
		(net "CLK_100M_PCIE_RP0_NODE1_DN")
	)
	(segment
		(start 105.099866 -90.401394)
		(end 105.232962 -90.268298)
		(width 0.127)
		(layer "In7.Cu")
		(net "CLK_100M_PCIE_RP0_NODE1_DN")
	)
	(segment
		(start 129.36347 -127.375666)
		(end 129.36347 -126.936246)
		(width 0.127)
		(layer "In7.Cu")
		(net "CLK_100M_PCIE_RP0_NODE1_DN")
	)
	(segment
		(start 119.351044 -101.544882)
		(end 119.351044 -101.744526)
		(width 0.127)
		(layer "In7.Cu")
		(net "CLK_100M_PCIE_RP0_NODE1_DN")
	)
	(segment
		(start 47.550578 -68.099178)
		(end 47.965614 -68.514214)
		(width 0.127)
		(layer "In7.Cu")
		(net "CLK_100M_PCIE_RP0_NODE1_DN")
	)
	(segment
		(start 126.69266 -118.674134)
		(end 129.11582 -121.097294)
		(width 0.127)
		(layer "In7.Cu")
		(net "CLK_100M_PCIE_RP0_NODE1_DN")
	)
	(segment
		(start 121.42724 -104.770936)
		(end 121.11736 -105.080816)
		(width 0.127)
		(layer "In7.Cu")
		(net "CLK_100M_PCIE_RP0_NODE1_DN")
	)
	(segment
		(start 86.596474 -92.930726)
		(end 87.4903 -93.824552)
		(width 0.127)
		(layer "In7.Cu")
		(net "CLK_100M_PCIE_RP0_NODE1_DN")
	)
	(segment
		(start 104.20477 -90.268298)
		(end 104.58577 -90.268298)
		(width 0.127)
		(layer "In7.Cu")
		(net "CLK_100M_PCIE_RP0_NODE1_DN")
	)
	(segment
		(start 103.557578 -90.268298)
		(end 103.690674 -90.401394)
		(width 0.127)
		(layer "In7.Cu")
		(net "CLK_100M_PCIE_RP0_NODE1_DN")
	)
	(segment
		(start 44.675806 -67.69608)
		(end 45.775372 -67.69608)
		(width 0.127)
		(layer "In7.Cu")
		(net "CLK_100M_PCIE_RP0_NODE1_DN")
	)
	(segment
		(start 62.172596 -94.803468)
		(end 62.748922 -94.227142)
		(width 0.127)
		(layer "In7.Cu")
		(net "CLK_100M_PCIE_RP0_NODE1_DN")
	)
	(segment
		(start 103.176578 -90.268298)
		(end 103.557578 -90.268298)
		(width 0.127)
		(layer "In7.Cu")
		(net "CLK_100M_PCIE_RP0_NODE1_DN")
	)
	(segment
		(start 120.358408 -102.75189)
		(end 120.558052 -102.75189)
		(width 0.127)
		(layer "In7.Cu")
		(net "CLK_100M_PCIE_RP0_NODE1_DN")
	)
	(segment
		(start 47.965614 -69.089524)
		(end 49.210468 -70.334378)
		(width 0.127)
		(layer "In7.Cu")
		(net "CLK_100M_PCIE_RP0_NODE1_DN")
	)
	(segment
		(start 49.210468 -70.334378)
		(end 49.210468 -70.9422)
		(width 0.127)
		(layer "In7.Cu")
		(net "CLK_100M_PCIE_RP0_NODE1_DN")
	)
	(segment
		(start 78.40091 -94.227142)
		(end 79.697326 -92.930726)
		(width 0.127)
		(layer "In7.Cu")
		(net "CLK_100M_PCIE_RP0_NODE1_DN")
	)
	(segment
		(start 95.325438 -31.77286)
		(end 96.012762 -31.77286)
		(width 0.1016)
		(layer "F.Cu")
		(net "PD_NODE1_DM6")
	)
	(segment
		(start 96.012762 -31.77286)
		(end 96.058482 -31.72714)
		(width 0.1016)
		(layer "F.Cu")
		(net "PD_NODE1_DM6")
	)
	(segment
		(start 94.050104 -30.497526)
		(end 95.325438 -31.77286)
		(width 0.1016)
		(layer "F.Cu")
		(net "PD_NODE1_DM6")
	)
	(segment
		(start 96.058482 -31.72714)
		(end 96.058482 -31.725616)
		(width 0.1016)
		(layer "F.Cu")
		(net "PD_NODE1_DM6")
	)
	(segment
		(start 94.050104 -29.149802)
		(end 94.050104 -30.497526)
		(width 0.1016)
		(layer "F.Cu")
		(net "PD_NODE1_DM6")
	)
	(via
		(at 96.058482 -31.725616)
		(size 0.508)
		(drill 0.254)
		(layers "F.Cu" "B.Cu")
		(net "PD_NODE1_DM6")
	)
	(segment
		(start 96.4311 -30.215078)
		(end 96.4311 -31.352998)
		(width 0.1016)
		(layer "B.Cu")
		(net "PD_NODE1_DM6")
	)
	(segment
		(start 96.4311 -31.352998)
		(end 96.058482 -31.725616)
		(width 0.1016)
		(layer "B.Cu")
		(net "PD_NODE1_DM6")
	)
	(segment
		(start 96.14154 -29.925518)
		(end 96.4311 -30.215078)
		(width 0.1016)
		(layer "B.Cu")
		(net "PD_NODE1_DM6")
	)
	(segment
		(start 96.141032 -29.925518)
		(end 96.14154 -29.925518)
		(width 0.1016)
		(layer "B.Cu")
		(net "PD_NODE1_DM6")
	)
	(segment
		(start 40.479726 -63.905638)
		(end 40.05326 -63.479172)
		(width 0.1016)
		(layer "F.Cu")
		(net "TP_CPU_NODE1_RP0_PERP1")
	)
	(segment
		(start 44.595288 -64.25692)
		(end 44.595288 -64.253364)
		(width 0.1016)
		(layer "F.Cu")
		(net "TP_CPU_NODE1_RP0_PERP1")
	)
	(segment
		(start 44.595288 -64.253364)
		(end 44.247562 -63.905638)
		(width 0.1016)
		(layer "F.Cu")
		(net "TP_CPU_NODE1_RP0_PERP1")
	)
	(segment
		(start 44.247562 -63.905638)
		(end 40.479726 -63.905638)
		(width 0.1016)
		(layer "F.Cu")
		(net "TP_CPU_NODE1_RP0_PERP1")
	)
	(via
		(at 40.05326 -63.479172)
		(size 0.508)
		(drill 0.254)
		(layers "F.Cu" "B.Cu")
		(net "TP_CPU_NODE1_RP0_PERP1")
	)
	(segment
		(start 124.566934 -109.114082)
		(end 124.697998 -108.983018)
		(width 0.127)
		(layer "F.Cu")
		(net "CLK_100M_DDR3_NODE1_DP")
	)
	(segment
		(start 125.599952 -115.423442)
		(end 124.566934 -114.390424)
		(width 0.127)
		(layer "F.Cu")
		(net "CLK_100M_DDR3_NODE1_DP")
	)
	(segment
		(start 124.566934 -107.446826)
		(end 124.566934 -102.779576)
		(width 0.127)
		(layer "F.Cu")
		(net "CLK_100M_DDR3_NODE1_DP")
	)
	(segment
		(start 124.697998 -108.602018)
		(end 124.566934 -108.470954)
		(width 0.127)
		(layer "F.Cu")
		(net "CLK_100M_DDR3_NODE1_DP")
	)
	(segment
		(start 124.697998 -111.674402)
		(end 124.566934 -111.543338)
		(width 0.127)
		(layer "F.Cu")
		(net "CLK_100M_DDR3_NODE1_DP")
	)
	(segment
		(start 124.697998 -107.95889)
		(end 124.697998 -107.57789)
		(width 0.127)
		(layer "F.Cu")
		(net "CLK_100M_DDR3_NODE1_DP")
	)
	(segment
		(start 124.566934 -114.390424)
		(end 124.566934 -112.186466)
		(width 0.127)
		(layer "F.Cu")
		(net "CLK_100M_DDR3_NODE1_DP")
	)
	(segment
		(start 124.566934 -109.495082)
		(end 124.566934 -109.114082)
		(width 0.127)
		(layer "F.Cu")
		(net "CLK_100M_DDR3_NODE1_DP")
	)
	(segment
		(start 124.697998 -112.055402)
		(end 124.697998 -111.674402)
		(width 0.127)
		(layer "F.Cu")
		(net "CLK_100M_DDR3_NODE1_DP")
	)
	(segment
		(start 128.873504 -115.714526)
		(end 128.834388 -115.753642)
		(width 0.127)
		(layer "F.Cu")
		(net "CLK_100M_DDR3_NODE1_DP")
	)
	(segment
		(start 124.566934 -108.089954)
		(end 124.697998 -107.95889)
		(width 0.127)
		(layer "F.Cu")
		(net "CLK_100M_DDR3_NODE1_DP")
	)
	(segment
		(start 124.697998 -109.626146)
		(end 124.566934 -109.495082)
		(width 0.127)
		(layer "F.Cu")
		(net "CLK_100M_DDR3_NODE1_DP")
	)
	(segment
		(start 127.078486 -100.268024)
		(end 127.078486 -99.153726)
		(width 0.127)
		(layer "F.Cu")
		(net "CLK_100M_DDR3_NODE1_DP")
	)
	(segment
		(start 124.566934 -112.186466)
		(end 124.697998 -112.055402)
		(width 0.127)
		(layer "F.Cu")
		(net "CLK_100M_DDR3_NODE1_DP")
	)
	(segment
		(start 127.415544 -115.423442)
		(end 125.599952 -115.423442)
		(width 0.127)
		(layer "F.Cu")
		(net "CLK_100M_DDR3_NODE1_DP")
	)
	(segment
		(start 124.566934 -111.543338)
		(end 124.566934 -111.162338)
		(width 0.127)
		(layer "F.Cu")
		(net "CLK_100M_DDR3_NODE1_DP")
	)
	(segment
		(start 124.566934 -111.162338)
		(end 124.697998 -111.031274)
		(width 0.127)
		(layer "F.Cu")
		(net "CLK_100M_DDR3_NODE1_DP")
	)
	(segment
		(start 124.566934 -102.779576)
		(end 127.078486 -100.268024)
		(width 0.127)
		(layer "F.Cu")
		(net "CLK_100M_DDR3_NODE1_DP")
	)
	(segment
		(start 63.729362 -65.843658)
		(end 63.355982 -66.217038)
		(width 0.127)
		(layer "F.Cu")
		(net "CLK_100M_DDR3_NODE1_DP")
	)
	(segment
		(start 124.697998 -111.031274)
		(end 124.697998 -110.650274)
		(width 0.127)
		(layer "F.Cu")
		(net "CLK_100M_DDR3_NODE1_DP")
	)
	(segment
		(start 63.729362 -65.836038)
		(end 63.729362 -65.843658)
		(width 0.127)
		(layer "F.Cu")
		(net "CLK_100M_DDR3_NODE1_DP")
	)
	(segment
		(start 124.566934 -110.13821)
		(end 124.697998 -110.007146)
		(width 0.127)
		(layer "F.Cu")
		(net "CLK_100M_DDR3_NODE1_DP")
	)
	(segment
		(start 128.834388 -115.753642)
		(end 127.745744 -115.753642)
		(width 0.127)
		(layer "F.Cu")
		(net "CLK_100M_DDR3_NODE1_DP")
	)
	(segment
		(start 124.566934 -110.51921)
		(end 124.566934 -110.13821)
		(width 0.127)
		(layer "F.Cu")
		(net "CLK_100M_DDR3_NODE1_DP")
	)
	(segment
		(start 127.745744 -115.753642)
		(end 127.415544 -115.423442)
		(width 0.127)
		(layer "F.Cu")
		(net "CLK_100M_DDR3_NODE1_DP")
	)
	(segment
		(start 129.403856 -115.714526)
		(end 128.873504 -115.714526)
		(width 0.127)
		(layer "F.Cu")
		(net "CLK_100M_DDR3_NODE1_DP")
	)
	(segment
		(start 124.566934 -108.470954)
		(end 124.566934 -108.089954)
		(width 0.127)
		(layer "F.Cu")
		(net "CLK_100M_DDR3_NODE1_DP")
	)
	(segment
		(start 124.697998 -110.007146)
		(end 124.697998 -109.626146)
		(width 0.127)
		(layer "F.Cu")
		(net "CLK_100M_DDR3_NODE1_DP")
	)
	(segment
		(start 124.697998 -107.57789)
		(end 124.566934 -107.446826)
		(width 0.127)
		(layer "F.Cu")
		(net "CLK_100M_DDR3_NODE1_DP")
	)
	(segment
		(start 124.697998 -108.983018)
		(end 124.697998 -108.602018)
		(width 0.127)
		(layer "F.Cu")
		(net "CLK_100M_DDR3_NODE1_DP")
	)
	(segment
		(start 124.697998 -110.650274)
		(end 124.566934 -110.51921)
		(width 0.127)
		(layer "F.Cu")
		(net "CLK_100M_DDR3_NODE1_DP")
	)
	(segment
		(start 127.078486 -99.153726)
		(end 127.536194 -98.696018)
		(width 0.127)
		(layer "F.Cu")
		(net "CLK_100M_DDR3_NODE1_DP")
	)
	(via
		(at 63.355982 -66.217038)
		(size 0.508)
		(drill 0.254)
		(layers "F.Cu" "B.Cu")
		(net "CLK_100M_DDR3_NODE1_DP")
	)
	(via
		(at 127.536194 -98.696018)
		(size 0.508)
		(drill 0.254)
		(layers "F.Cu" "B.Cu")
		(net "CLK_100M_DDR3_NODE1_DP")
	)
	(segment
		(start 86.0933 -74.14514)
		(end 86.0933 -73.796906)
		(width 0.127)
		(layer "In7.Cu")
		(net "CLK_100M_DDR3_NODE1_DP")
	)
	(segment
		(start 103.651812 -81.701132)
		(end 103.653082 -81.701132)
		(width 0.127)
		(layer "In7.Cu")
		(net "CLK_100M_DDR3_NODE1_DP")
	)
	(segment
		(start 87.242142 -73.261728)
		(end 87.53348 -72.97039)
		(width 0.127)
		(layer "In7.Cu")
		(net "CLK_100M_DDR3_NODE1_DP")
	)
	(segment
		(start 68.062856 -71.766684)
		(end 68.088256 -71.766684)
		(width 0.1016)
		(layer "In7.Cu")
		(net "CLK_100M_DDR3_NODE1_DP")
	)
	(segment
		(start 83.52536 -75.698858)
		(end 84.459318 -74.7649)
		(width 0.127)
		(layer "In7.Cu")
		(net "CLK_100M_DDR3_NODE1_DP")
	)
	(segment
		(start 111.140494 -81.959958)
		(end 127.07366 -97.893124)
		(width 0.127)
		(layer "In7.Cu")
		(net "CLK_100M_DDR3_NODE1_DP")
	)
	(segment
		(start 76.48194 -75.228958)
		(end 76.95184 -75.698858)
		(width 0.127)
		(layer "In7.Cu")
		(net "CLK_100M_DDR3_NODE1_DP")
	)
	(segment
		(start 63.355982 -66.217038)
		(end 63.355982 -66.404236)
		(width 0.1016)
		(layer "In7.Cu")
		(net "CLK_100M_DDR3_NODE1_DP")
	)
	(segment
		(start 72.523604 -73.478898)
		(end 72.523604 -74.312526)
		(width 0.127)
		(layer "In7.Cu")
		(net "CLK_100M_DDR3_NODE1_DP")
	)
	(segment
		(start 63.765176 -69.1642)
		(end 64.424814 -69.823838)
		(width 0.1016)
		(layer "In7.Cu")
		(net "CLK_100M_DDR3_NODE1_DP")
	)
	(segment
		(start 68.018406 -71.811134)
		(end 68.062856 -71.766684)
		(width 0.1016)
		(layer "In7.Cu")
		(net "CLK_100M_DDR3_NODE1_DP")
	)
	(segment
		(start 66.553334 -69.643498)
		(end 66.735198 -69.825362)
		(width 0.1016)
		(layer "In7.Cu")
		(net "CLK_100M_DDR3_NODE1_DP")
	)
	(segment
		(start 127.07366 -98.233484)
		(end 127.536194 -98.696018)
		(width 0.127)
		(layer "In7.Cu")
		(net "CLK_100M_DDR3_NODE1_DP")
	)
	(segment
		(start 72.523604 -74.312526)
		(end 73.440036 -75.228958)
		(width 0.127)
		(layer "In7.Cu")
		(net "CLK_100M_DDR3_NODE1_DP")
	)
	(segment
		(start 86.628478 -73.261728)
		(end 87.242142 -73.261728)
		(width 0.127)
		(layer "In7.Cu")
		(net "CLK_100M_DDR3_NODE1_DP")
	)
	(segment
		(start 76.95184 -75.698858)
		(end 83.52536 -75.698858)
		(width 0.127)
		(layer "In7.Cu")
		(net "CLK_100M_DDR3_NODE1_DP")
	)
	(segment
		(start 103.653082 -81.701132)
		(end 103.911908 -81.959958)
		(width 0.127)
		(layer "In7.Cu")
		(net "CLK_100M_DDR3_NODE1_DP")
	)
	(segment
		(start 73.440036 -75.228958)
		(end 76.48194 -75.228958)
		(width 0.127)
		(layer "In7.Cu")
		(net "CLK_100M_DDR3_NODE1_DP")
	)
	(segment
		(start 85.47354 -74.7649)
		(end 86.0933 -74.14514)
		(width 0.127)
		(layer "In7.Cu")
		(net "CLK_100M_DDR3_NODE1_DP")
	)
	(segment
		(start 87.53348 -72.97039)
		(end 94.92107 -72.97039)
		(width 0.127)
		(layer "In7.Cu")
		(net "CLK_100M_DDR3_NODE1_DP")
	)
	(segment
		(start 66.735198 -69.825362)
		(end 66.735198 -71.657718)
		(width 0.1016)
		(layer "In7.Cu")
		(net "CLK_100M_DDR3_NODE1_DP")
	)
	(segment
		(start 63.765176 -66.81343)
		(end 63.765176 -69.1642)
		(width 0.1016)
		(layer "In7.Cu")
		(net "CLK_100M_DDR3_NODE1_DP")
	)
	(segment
		(start 103.911908 -81.959958)
		(end 111.140494 -81.959958)
		(width 0.127)
		(layer "In7.Cu")
		(net "CLK_100M_DDR3_NODE1_DP")
	)
	(segment
		(start 68.088256 -71.766684)
		(end 71.269352 -71.766684)
		(width 0.127)
		(layer "In7.Cu")
		(net "CLK_100M_DDR3_NODE1_DP")
	)
	(segment
		(start 66.888614 -71.811134)
		(end 68.018406 -71.811134)
		(width 0.1016)
		(layer "In7.Cu")
		(net "CLK_100M_DDR3_NODE1_DP")
	)
	(segment
		(start 65.649094 -69.643498)
		(end 66.553334 -69.643498)
		(width 0.1016)
		(layer "In7.Cu")
		(net "CLK_100M_DDR3_NODE1_DP")
	)
	(segment
		(start 63.355982 -66.404236)
		(end 63.765176 -66.81343)
		(width 0.1016)
		(layer "In7.Cu")
		(net "CLK_100M_DDR3_NODE1_DP")
	)
	(segment
		(start 65.468754 -69.823838)
		(end 65.649094 -69.643498)
		(width 0.1016)
		(layer "In7.Cu")
		(net "CLK_100M_DDR3_NODE1_DP")
	)
	(segment
		(start 127.07366 -97.893124)
		(end 127.07366 -98.233484)
		(width 0.127)
		(layer "In7.Cu")
		(net "CLK_100M_DDR3_NODE1_DP")
	)
	(segment
		(start 64.424814 -69.823838)
		(end 65.468754 -69.823838)
		(width 0.1016)
		(layer "In7.Cu")
		(net "CLK_100M_DDR3_NODE1_DP")
	)
	(segment
		(start 72.001126 -72.95642)
		(end 72.523604 -73.478898)
		(width 0.127)
		(layer "In7.Cu")
		(net "CLK_100M_DDR3_NODE1_DP")
	)
	(segment
		(start 84.459318 -74.7649)
		(end 85.47354 -74.7649)
		(width 0.127)
		(layer "In7.Cu")
		(net "CLK_100M_DDR3_NODE1_DP")
	)
	(segment
		(start 71.269352 -71.766684)
		(end 72.001126 -72.498458)
		(width 0.127)
		(layer "In7.Cu")
		(net "CLK_100M_DDR3_NODE1_DP")
	)
	(segment
		(start 86.0933 -73.796906)
		(end 86.628478 -73.261728)
		(width 0.127)
		(layer "In7.Cu")
		(net "CLK_100M_DDR3_NODE1_DP")
	)
	(segment
		(start 72.001126 -72.498458)
		(end 72.001126 -72.95642)
		(width 0.127)
		(layer "In7.Cu")
		(net "CLK_100M_DDR3_NODE1_DP")
	)
	(segment
		(start 94.92107 -72.97039)
		(end 103.651812 -81.701132)
		(width 0.127)
		(layer "In7.Cu")
		(net "CLK_100M_DDR3_NODE1_DP")
	)
	(segment
		(start 66.735198 -71.657718)
		(end 66.888614 -71.811134)
		(width 0.1016)
		(layer "In7.Cu")
		(net "CLK_100M_DDR3_NODE1_DP")
	)
	(segment
		(start 68.352416 -85.762846)
		(end 68.70319 -86.11362)
		(width 0.1016)
		(layer "F.Cu")
		(net "SMB_TEMP1_NODE1_ALERT_L")
	)
	(segment
		(start 47.573438 -103.798878)
		(end 71.925942 -103.798878)
		(width 0.1016)
		(layer "F.Cu")
		(net "SMB_TEMP1_NODE1_ALERT_L")
	)
	(segment
		(start 73.346818 -100.057458)
		(end 72.48906 -99.1997)
		(width 0.1016)
		(layer "F.Cu")
		(net "SMB_TEMP1_NODE1_ALERT_L")
	)
	(segment
		(start 71.925942 -103.798878)
		(end 73.346818 -102.378002)
		(width 0.1016)
		(layer "F.Cu")
		(net "SMB_TEMP1_NODE1_ALERT_L")
	)
	(segment
		(start 46.573694 -102.799134)
		(end 47.573438 -103.798878)
		(width 0.1016)
		(layer "F.Cu")
		(net "SMB_TEMP1_NODE1_ALERT_L")
	)
	(segment
		(start 73.346818 -102.378002)
		(end 73.346818 -100.057458)
		(width 0.1016)
		(layer "F.Cu")
		(net "SMB_TEMP1_NODE1_ALERT_L")
	)
	(segment
		(start 68.16217 -85.762846)
		(end 68.352416 -85.762846)
		(width 0.1016)
		(layer "F.Cu")
		(net "SMB_TEMP1_NODE1_ALERT_L")
	)
	(via
		(at 72.48906 -99.1997)
		(size 0.508)
		(drill 0.254)
		(layers "F.Cu" "B.Cu")
		(net "SMB_TEMP1_NODE1_ALERT_L")
	)
	(via
		(at 68.70319 -86.11362)
		(size 0.508)
		(drill 0.254)
		(layers "F.Cu" "B.Cu")
		(net "SMB_TEMP1_NODE1_ALERT_L")
	)
	(segment
		(start 72.48906 -99.1997)
		(end 72.01662 -98.72726)
		(width 0.1016)
		(layer "B.Cu")
		(net "SMB_TEMP1_NODE1_ALERT_L")
	)
	(segment
		(start 70.499986 -96.777556)
		(end 69.37883 -95.6564)
		(width 0.1016)
		(layer "B.Cu")
		(net "SMB_TEMP1_NODE1_ALERT_L")
	)
	(segment
		(start 68.743576 -86.738206)
		(end 68.743576 -86.154006)
		(width 0.1016)
		(layer "B.Cu")
		(net "SMB_TEMP1_NODE1_ALERT_L")
	)
	(segment
		(start 69.18452 -94.270068)
		(end 69.18452 -87.17915)
		(width 0.1016)
		(layer "B.Cu")
		(net "SMB_TEMP1_NODE1_ALERT_L")
	)
	(segment
		(start 71.10476 -98.211386)
		(end 71.10476 -97.191068)
		(width 0.1016)
		(layer "B.Cu")
		(net "SMB_TEMP1_NODE1_ALERT_L")
	)
	(segment
		(start 71.10476 -97.191068)
		(end 70.691248 -96.777556)
		(width 0.1016)
		(layer "B.Cu")
		(net "SMB_TEMP1_NODE1_ALERT_L")
	)
	(segment
		(start 69.37883 -94.464378)
		(end 69.18452 -94.270068)
		(width 0.1016)
		(layer "B.Cu")
		(net "SMB_TEMP1_NODE1_ALERT_L")
	)
	(segment
		(start 69.37883 -95.6564)
		(end 69.37883 -94.464378)
		(width 0.1016)
		(layer "B.Cu")
		(net "SMB_TEMP1_NODE1_ALERT_L")
	)
	(segment
		(start 70.691248 -96.777556)
		(end 70.499986 -96.777556)
		(width 0.1016)
		(layer "B.Cu")
		(net "SMB_TEMP1_NODE1_ALERT_L")
	)
	(segment
		(start 71.620634 -98.72726)
		(end 71.10476 -98.211386)
		(width 0.1016)
		(layer "B.Cu")
		(net "SMB_TEMP1_NODE1_ALERT_L")
	)
	(segment
		(start 68.743576 -86.154006)
		(end 68.70319 -86.11362)
		(width 0.1016)
		(layer "B.Cu")
		(net "SMB_TEMP1_NODE1_ALERT_L")
	)
	(segment
		(start 69.18452 -87.17915)
		(end 68.743576 -86.738206)
		(width 0.1016)
		(layer "B.Cu")
		(net "SMB_TEMP1_NODE1_ALERT_L")
	)
	(segment
		(start 72.01662 -98.72726)
		(end 71.620634 -98.72726)
		(width 0.1016)
		(layer "B.Cu")
		(net "SMB_TEMP1_NODE1_ALERT_L")
	)
	(segment
		(start 45.01769 -63.49492)
		(end 45.184314 -63.328296)
		(width 0.1016)
		(layer "F.Cu")
		(net "TP_CPU_NODE1_RP0_PERN1")
	)
	(segment
		(start 44.595288 -63.49492)
		(end 45.01769 -63.49492)
		(width 0.1016)
		(layer "F.Cu")
		(net "TP_CPU_NODE1_RP0_PERN1")
	)
	(via
		(at 45.184314 -63.328296)
		(size 0.508)
		(drill 0.254)
		(layers "F.Cu" "B.Cu")
		(net "TP_CPU_NODE1_RP0_PERN1")
	)
	(segment
		(start 63.097156 -60.474606)
		(end 62.316868 -61.254894)
		(width 0.1016)
		(layer "F.Cu")
		(net "M_DDR3_NODE1_BS1")
	)
	(segment
		(start 62.216538 -63.491618)
		(end 61.938408 -63.769748)
		(width 0.1016)
		(layer "F.Cu")
		(net "M_DDR3_NODE1_BS1")
	)
	(segment
		(start 79.00162 -35.35172)
		(end 79.00162 -35.639756)
		(width 0.2286)
		(layer "F.Cu")
		(net "M_DDR3_NODE1_BS1")
	)
	(segment
		(start 74.850244 -29.149802)
		(end 74.849482 -29.149802)
		(width 0.2286)
		(layer "F.Cu")
		(net "M_DDR3_NODE1_BS1")
	)
	(segment
		(start 61.938408 -63.769748)
		(end 61.938408 -64.004698)
		(width 0.1016)
		(layer "F.Cu")
		(net "M_DDR3_NODE1_BS1")
	)
	(segment
		(start 78.760574 -43.886628)
		(end 78.760574 -43.88739)
		(width 0.2286)
		(layer "F.Cu")
		(net "M_DDR3_NODE1_BS1")
	)
	(segment
		(start 74.849482 -32.399478)
		(end 75.26782 -32.817816)
		(width 0.2286)
		(layer "F.Cu")
		(net "M_DDR3_NODE1_BS1")
	)
	(segment
		(start 77.97038 -34.736786)
		(end 78.358492 -35.124898)
		(width 0.2286)
		(layer "F.Cu")
		(net "M_DDR3_NODE1_BS1")
	)
	(segment
		(start 77.723492 -44.699428)
		(end 77.51064 -44.91228)
		(width 0.2286)
		(layer "F.Cu")
		(net "M_DDR3_NODE1_BS1")
	)
	(segment
		(start 70.894194 -54.833266)
		(end 64.922908 -54.833266)
		(width 0.2286)
		(layer "F.Cu")
		(net "M_DDR3_NODE1_BS1")
	)
	(segment
		(start 77.749908 -36.657026)
		(end 78.766162 -36.657026)
		(width 0.2286)
		(layer "F.Cu")
		(net "M_DDR3_NODE1_BS1")
	)
	(segment
		(start 77.726286 -38.120066)
		(end 77.51064 -38.335712)
		(width 0.2286)
		(layer "F.Cu")
		(net "M_DDR3_NODE1_BS1")
	)
	(segment
		(start 78.969362 -37.795454)
		(end 78.766162 -37.998654)
		(width 0.2286)
		(layer "F.Cu")
		(net "M_DDR3_NODE1_BS1")
	)
	(segment
		(start 77.534262 -36.44138)
		(end 77.749908 -36.657026)
		(width 0.2286)
		(layer "F.Cu")
		(net "M_DDR3_NODE1_BS1")
	)
	(segment
		(start 77.51064 -44.91228)
		(end 77.51064 -48.21682)
		(width 0.2286)
		(layer "F.Cu")
		(net "M_DDR3_NODE1_BS1")
	)
	(segment
		(start 75.788774 -34.45129)
		(end 76.00442 -34.235644)
		(width 0.2286)
		(layer "F.Cu")
		(net "M_DDR3_NODE1_BS1")
	)
	(segment
		(start 78.24724 -44.918376)
		(end 78.031594 -44.70273)
		(width 0.2286)
		(layer "F.Cu")
		(net "M_DDR3_NODE1_BS1")
	)
	(segment
		(start 78.031594 -44.701968)
		(end 77.723492 -44.701968)
		(width 0.2286)
		(layer "F.Cu")
		(net "M_DDR3_NODE1_BS1")
	)
	(segment
		(start 78.760574 -43.88739)
		(end 79.025242 -44.152058)
		(width 0.2286)
		(layer "F.Cu")
		(net "M_DDR3_NODE1_BS1")
	)
	(segment
		(start 77.97038 -33.271206)
		(end 77.97038 -34.736786)
		(width 0.2286)
		(layer "F.Cu")
		(net "M_DDR3_NODE1_BS1")
	)
	(segment
		(start 78.462886 -46.971458)
		(end 78.24724 -46.755812)
		(width 0.2286)
		(layer "F.Cu")
		(net "M_DDR3_NODE1_BS1")
	)
	(segment
		(start 77.51064 -43.678856)
		(end 77.718666 -43.886882)
		(width 0.2286)
		(layer "F.Cu")
		(net "M_DDR3_NODE1_BS1")
	)
	(segment
		(start 77.534262 -36.136072)
		(end 77.534262 -36.44138)
		(width 0.2286)
		(layer "F.Cu")
		(net "M_DDR3_NODE1_BS1")
	)
	(segment
		(start 77.51064 -38.335712)
		(end 77.51064 -43.678856)
		(width 0.2286)
		(layer "F.Cu")
		(net "M_DDR3_NODE1_BS1")
	)
	(segment
		(start 62.216538 -62.275212)
		(end 62.216538 -63.491618)
		(width 0.1016)
		(layer "F.Cu")
		(net "M_DDR3_NODE1_BS1")
	)
	(segment
		(start 77.51064 -48.21682)
		(end 70.894194 -54.833266)
		(width 0.2286)
		(layer "F.Cu")
		(net "M_DDR3_NODE1_BS1")
	)
	(segment
		(start 77.749908 -35.920426)
		(end 77.534262 -36.136072)
		(width 0.2286)
		(layer "F.Cu")
		(net "M_DDR3_NODE1_BS1")
	)
	(segment
		(start 63.45174 -58.338466)
		(end 63.45174 -58.59526)
		(width 0.1016)
		(layer "F.Cu")
		(net "M_DDR3_NODE1_BS1")
	)
	(segment
		(start 78.002384 -38.120066)
		(end 77.726286 -38.120066)
		(width 0.2286)
		(layer "F.Cu")
		(net "M_DDR3_NODE1_BS1")
	)
	(segment
		(start 79.025242 -46.725078)
		(end 78.778862 -46.971458)
		(width 0.2286)
		(layer "F.Cu")
		(net "M_DDR3_NODE1_BS1")
	)
	(segment
		(start 74.849482 -29.149802)
		(end 74.849482 -32.399478)
		(width 0.2286)
		(layer "F.Cu")
		(net "M_DDR3_NODE1_BS1")
	)
	(segment
		(start 63.097156 -58.949844)
		(end 63.097156 -60.474606)
		(width 0.1016)
		(layer "F.Cu")
		(net "M_DDR3_NODE1_BS1")
	)
	(segment
		(start 78.774798 -35.124898)
		(end 79.00162 -35.35172)
		(width 0.2286)
		(layer "F.Cu")
		(net "M_DDR3_NODE1_BS1")
	)
	(segment
		(start 78.24724 -46.755812)
		(end 78.24724 -44.918376)
		(width 0.2286)
		(layer "F.Cu")
		(net "M_DDR3_NODE1_BS1")
	)
	(segment
		(start 78.766162 -37.998654)
		(end 78.123796 -37.998654)
		(width 0.2286)
		(layer "F.Cu")
		(net "M_DDR3_NODE1_BS1")
	)
	(segment
		(start 78.123796 -37.998654)
		(end 78.002384 -38.120066)
		(width 0.2286)
		(layer "F.Cu")
		(net "M_DDR3_NODE1_BS1")
	)
	(segment
		(start 62.316868 -61.254894)
		(end 62.316868 -62.174882)
		(width 0.1016)
		(layer "F.Cu")
		(net "M_DDR3_NODE1_BS1")
	)
	(segment
		(start 78.031594 -44.70273)
		(end 78.031594 -44.701968)
		(width 0.2286)
		(layer "F.Cu")
		(net "M_DDR3_NODE1_BS1")
	)
	(segment
		(start 78.778862 -46.971458)
		(end 78.462886 -46.971458)
		(width 0.2286)
		(layer "F.Cu")
		(net "M_DDR3_NODE1_BS1")
	)
	(segment
		(start 77.338936 -32.639762)
		(end 77.97038 -33.271206)
		(width 0.2286)
		(layer "F.Cu")
		(net "M_DDR3_NODE1_BS1")
	)
	(segment
		(start 75.26782 -32.817816)
		(end 75.26782 -34.235644)
		(width 0.2286)
		(layer "F.Cu")
		(net "M_DDR3_NODE1_BS1")
	)
	(segment
		(start 75.483466 -34.45129)
		(end 75.788774 -34.45129)
		(width 0.2286)
		(layer "F.Cu")
		(net "M_DDR3_NODE1_BS1")
	)
	(segment
		(start 77.718666 -43.886882)
		(end 77.718666 -43.886628)
		(width 0.2286)
		(layer "F.Cu")
		(net "M_DDR3_NODE1_BS1")
	)
	(segment
		(start 78.358492 -35.124898)
		(end 78.774798 -35.124898)
		(width 0.2286)
		(layer "F.Cu")
		(net "M_DDR3_NODE1_BS1")
	)
	(segment
		(start 78.766162 -36.657026)
		(end 78.969362 -36.860226)
		(width 0.2286)
		(layer "F.Cu")
		(net "M_DDR3_NODE1_BS1")
	)
	(segment
		(start 78.969362 -36.860226)
		(end 78.969362 -37.795454)
		(width 0.2286)
		(layer "F.Cu")
		(net "M_DDR3_NODE1_BS1")
	)
	(segment
		(start 62.316868 -62.174882)
		(end 62.216538 -62.275212)
		(width 0.1016)
		(layer "F.Cu")
		(net "M_DDR3_NODE1_BS1")
	)
	(segment
		(start 64.922908 -54.833266)
		(end 63.45174 -56.304434)
		(width 0.2286)
		(layer "F.Cu")
		(net "M_DDR3_NODE1_BS1")
	)
	(segment
		(start 63.45174 -56.304434)
		(end 63.45174 -58.338466)
		(width 0.2286)
		(layer "F.Cu")
		(net "M_DDR3_NODE1_BS1")
	)
	(segment
		(start 79.025242 -44.152058)
		(end 79.025242 -46.725078)
		(width 0.2286)
		(layer "F.Cu")
		(net "M_DDR3_NODE1_BS1")
	)
	(segment
		(start 76.00442 -34.235644)
		(end 76.00442 -33.089342)
		(width 0.2286)
		(layer "F.Cu")
		(net "M_DDR3_NODE1_BS1")
	)
	(segment
		(start 78.72095 -35.920426)
		(end 77.749908 -35.920426)
		(width 0.2286)
		(layer "F.Cu")
		(net "M_DDR3_NODE1_BS1")
	)
	(segment
		(start 75.26782 -34.235644)
		(end 75.483466 -34.45129)
		(width 0.2286)
		(layer "F.Cu")
		(net "M_DDR3_NODE1_BS1")
	)
	(segment
		(start 77.718666 -43.886628)
		(end 78.760574 -43.886628)
		(width 0.2286)
		(layer "F.Cu")
		(net "M_DDR3_NODE1_BS1")
	)
	(segment
		(start 77.723492 -44.701968)
		(end 77.723492 -44.699428)
		(width 0.2286)
		(layer "F.Cu")
		(net "M_DDR3_NODE1_BS1")
	)
	(segment
		(start 76.00442 -33.089342)
		(end 76.454 -32.639762)
		(width 0.2286)
		(layer "F.Cu")
		(net "M_DDR3_NODE1_BS1")
	)
	(segment
		(start 63.45174 -58.59526)
		(end 63.097156 -58.949844)
		(width 0.1016)
		(layer "F.Cu")
		(net "M_DDR3_NODE1_BS1")
	)
	(segment
		(start 76.454 -32.639762)
		(end 77.338936 -32.639762)
		(width 0.2286)
		(layer "F.Cu")
		(net "M_DDR3_NODE1_BS1")
	)
	(segment
		(start 79.00162 -35.639756)
		(end 78.72095 -35.920426)
		(width 0.2286)
		(layer "F.Cu")
		(net "M_DDR3_NODE1_BS1")
	)
	(via
		(at 78.123796 -37.998654)
		(size 0.762)
		(drill 0.381)
		(layers "F.Cu" "B.Cu")
		(net "M_DDR3_NODE1_BS1")
	)
	(segment
		(start 129.403856 -116.114576)
		(end 128.942592 -116.114576)
		(width 0.127)
		(layer "F.Cu")
		(net "CLK_100M_DDR3_NODE1_DN")
	)
	(segment
		(start 126.773686 -100.141532)
		(end 126.773686 -99.20351)
		(width 0.127)
		(layer "F.Cu")
		(net "CLK_100M_DDR3_NODE1_DN")
	)
	(segment
		(start 124.262134 -102.653084)
		(end 126.773686 -100.141532)
		(width 0.127)
		(layer "F.Cu")
		(net "CLK_100M_DDR3_NODE1_DN")
	)
	(segment
		(start 126.773686 -99.20351)
		(end 126.266194 -98.696018)
		(width 0.127)
		(layer "F.Cu")
		(net "CLK_100M_DDR3_NODE1_DN")
	)
	(segment
		(start 124.262134 -114.516916)
		(end 124.262134 -102.653084)
		(width 0.127)
		(layer "F.Cu")
		(net "CLK_100M_DDR3_NODE1_DN")
	)
	(segment
		(start 63.729362 -66.605658)
		(end 63.355982 -66.979038)
		(width 0.127)
		(layer "F.Cu")
		(net "CLK_100M_DDR3_NODE1_DN")
	)
	(segment
		(start 125.47346 -115.728242)
		(end 124.262134 -114.516916)
		(width 0.127)
		(layer "F.Cu")
		(net "CLK_100M_DDR3_NODE1_DN")
	)
	(segment
		(start 127.619252 -116.058442)
		(end 127.289052 -115.728242)
		(width 0.127)
		(layer "F.Cu")
		(net "CLK_100M_DDR3_NODE1_DN")
	)
	(segment
		(start 63.729362 -66.598038)
		(end 63.729362 -66.605658)
		(width 0.127)
		(layer "F.Cu")
		(net "CLK_100M_DDR3_NODE1_DN")
	)
	(segment
		(start 128.886458 -116.058442)
		(end 127.619252 -116.058442)
		(width 0.127)
		(layer "F.Cu")
		(net "CLK_100M_DDR3_NODE1_DN")
	)
	(segment
		(start 128.942592 -116.114576)
		(end 128.886458 -116.058442)
		(width 0.127)
		(layer "F.Cu")
		(net "CLK_100M_DDR3_NODE1_DN")
	)
	(segment
		(start 127.289052 -115.728242)
		(end 125.47346 -115.728242)
		(width 0.127)
		(layer "F.Cu")
		(net "CLK_100M_DDR3_NODE1_DN")
	)
	(via
		(at 63.355982 -66.979038)
		(size 0.508)
		(drill 0.254)
		(layers "F.Cu" "B.Cu")
		(net "CLK_100M_DDR3_NODE1_DN")
	)
	(via
		(at 126.266194 -98.696018)
		(size 0.508)
		(drill 0.254)
		(layers "F.Cu" "B.Cu")
		(net "CLK_100M_DDR3_NODE1_DN")
	)
	(segment
		(start 113.606834 -84.94014)
		(end 113.60658 -85.040724)
		(width 0.127)
		(layer "In7.Cu")
		(net "CLK_100M_DDR3_NODE1_DN")
	)
	(segment
		(start 65.733422 -69.846698)
		(end 66.469006 -69.846698)
		(width 0.1016)
		(layer "In7.Cu")
		(net "CLK_100M_DDR3_NODE1_DN")
	)
	(segment
		(start 115.560348 -86.79307)
		(end 115.83035 -87.063072)
		(width 0.127)
		(layer "In7.Cu")
		(net "CLK_100M_DDR3_NODE1_DN")
	)
	(segment
		(start 63.456312 -66.979038)
		(end 63.561976 -67.084702)
		(width 0.1016)
		(layer "In7.Cu")
		(net "CLK_100M_DDR3_NODE1_DN")
	)
	(segment
		(start 71.709026 -73.077578)
		(end 72.231504 -73.600056)
		(width 0.127)
		(layer "In7.Cu")
		(net "CLK_100M_DDR3_NODE1_DN")
	)
	(segment
		(start 112.12449 -83.357212)
		(end 112.12449 -83.457796)
		(width 0.127)
		(layer "In7.Cu")
		(net "CLK_100M_DDR3_NODE1_DN")
	)
	(segment
		(start 113.13541 -84.569554)
		(end 113.336832 -84.569554)
		(width 0.127)
		(layer "In7.Cu")
		(net "CLK_100M_DDR3_NODE1_DN")
	)
	(segment
		(start 103.79075 -82.252058)
		(end 111.019336 -82.252058)
		(width 0.127)
		(layer "In7.Cu")
		(net "CLK_100M_DDR3_NODE1_DN")
	)
	(segment
		(start 63.561976 -69.248528)
		(end 64.340486 -70.027038)
		(width 0.1016)
		(layer "In7.Cu")
		(net "CLK_100M_DDR3_NODE1_DN")
	)
	(segment
		(start 116.100098 -87.534242)
		(end 116.30152 -87.534242)
		(width 0.127)
		(layer "In7.Cu")
		(net "CLK_100M_DDR3_NODE1_DN")
	)
	(segment
		(start 63.561976 -67.57416)
		(end 63.46952 -67.666616)
		(width 0.1016)
		(layer "In7.Cu")
		(net "CLK_100M_DDR3_NODE1_DN")
	)
	(segment
		(start 114.347752 -85.781896)
		(end 114.617754 -86.051898)
		(width 0.127)
		(layer "In7.Cu")
		(net "CLK_100M_DDR3_NODE1_DN")
	)
	(segment
		(start 87.654638 -73.26249)
		(end 94.799912 -73.26249)
		(width 0.127)
		(layer "In7.Cu")
		(net "CLK_100M_DDR3_NODE1_DN")
	)
	(segment
		(start 63.561976 -68.9356)
		(end 63.561976 -69.248528)
		(width 0.1016)
		(layer "In7.Cu")
		(net "CLK_100M_DDR3_NODE1_DN")
	)
	(segment
		(start 114.617754 -86.051898)
		(end 114.819176 -86.051898)
		(width 0.127)
		(layer "In7.Cu")
		(net "CLK_100M_DDR3_NODE1_DN")
	)
	(segment
		(start 71.148194 -72.058784)
		(end 71.709026 -72.619616)
		(width 0.127)
		(layer "In7.Cu")
		(net "CLK_100M_DDR3_NODE1_DN")
	)
	(segment
		(start 83.646518 -75.990958)
		(end 84.580476 -75.057)
		(width 0.127)
		(layer "In7.Cu")
		(net "CLK_100M_DDR3_NODE1_DN")
	)
	(segment
		(start 113.60658 -85.040724)
		(end 113.876582 -85.310726)
		(width 0.127)
		(layer "In7.Cu")
		(net "CLK_100M_DDR3_NODE1_DN")
	)
	(segment
		(start 73.318878 -75.521058)
		(end 76.360782 -75.521058)
		(width 0.127)
		(layer "In7.Cu")
		(net "CLK_100M_DDR3_NODE1_DN")
	)
	(segment
		(start 72.231504 -74.433684)
		(end 73.318878 -75.521058)
		(width 0.127)
		(layer "In7.Cu")
		(net "CLK_100M_DDR3_NODE1_DN")
	)
	(segment
		(start 86.749636 -73.553828)
		(end 87.3633 -73.553828)
		(width 0.127)
		(layer "In7.Cu")
		(net "CLK_100M_DDR3_NODE1_DN")
	)
	(segment
		(start 115.358926 -86.79307)
		(end 115.560348 -86.79307)
		(width 0.127)
		(layer "In7.Cu")
		(net "CLK_100M_DDR3_NODE1_DN")
	)
	(segment
		(start 63.561976 -68.063872)
		(end 63.561976 -68.439284)
		(width 0.1016)
		(layer "In7.Cu")
		(net "CLK_100M_DDR3_NODE1_DN")
	)
	(segment
		(start 84.580476 -75.057)
		(end 85.594698 -75.057)
		(width 0.127)
		(layer "In7.Cu")
		(net "CLK_100M_DDR3_NODE1_DN")
	)
	(segment
		(start 126.78156 -98.180652)
		(end 126.266194 -98.696018)
		(width 0.127)
		(layer "In7.Cu")
		(net "CLK_100M_DDR3_NODE1_DN")
	)
	(segment
		(start 113.606834 -84.839556)
		(end 113.606834 -84.94014)
		(width 0.127)
		(layer "In7.Cu")
		(net "CLK_100M_DDR3_NODE1_DN")
	)
	(segment
		(start 112.124236 -83.55838)
		(end 112.394238 -83.828382)
		(width 0.127)
		(layer "In7.Cu")
		(net "CLK_100M_DDR3_NODE1_DN")
	)
	(segment
		(start 65.553082 -70.027038)
		(end 65.733422 -69.846698)
		(width 0.1016)
		(layer "In7.Cu")
		(net "CLK_100M_DDR3_NODE1_DN")
	)
	(segment
		(start 87.3633 -73.553828)
		(end 87.654638 -73.26249)
		(width 0.127)
		(layer "In7.Cu")
		(net "CLK_100M_DDR3_NODE1_DN")
	)
	(segment
		(start 112.394238 -83.828382)
		(end 112.59566 -83.828382)
		(width 0.127)
		(layer "In7.Cu")
		(net "CLK_100M_DDR3_NODE1_DN")
	)
	(segment
		(start 64.340486 -70.027038)
		(end 65.553082 -70.027038)
		(width 0.1016)
		(layer "In7.Cu")
		(net "CLK_100M_DDR3_NODE1_DN")
	)
	(segment
		(start 63.561976 -68.439284)
		(end 63.466218 -68.535042)
		(width 0.1016)
		(layer "In7.Cu")
		(net "CLK_100M_DDR3_NODE1_DN")
	)
	(segment
		(start 63.561976 -67.084702)
		(end 63.561976 -67.57416)
		(width 0.1016)
		(layer "In7.Cu")
		(net "CLK_100M_DDR3_NODE1_DN")
	)
	(segment
		(start 115.089178 -86.422484)
		(end 115.088924 -86.523068)
		(width 0.127)
		(layer "In7.Cu")
		(net "CLK_100M_DDR3_NODE1_DN")
	)
	(segment
		(start 115.83035 -87.163656)
		(end 115.830096 -87.26424)
		(width 0.127)
		(layer "In7.Cu")
		(net "CLK_100M_DDR3_NODE1_DN")
	)
	(segment
		(start 66.804286 -72.014334)
		(end 68.018406 -72.014334)
		(width 0.1016)
		(layer "In7.Cu")
		(net "CLK_100M_DDR3_NODE1_DN")
	)
	(segment
		(start 68.062856 -72.058784)
		(end 68.088256 -72.058784)
		(width 0.1016)
		(layer "In7.Cu")
		(net "CLK_100M_DDR3_NODE1_DN")
	)
	(segment
		(start 63.466218 -68.535042)
		(end 63.466218 -68.839842)
		(width 0.1016)
		(layer "In7.Cu")
		(net "CLK_100M_DDR3_NODE1_DN")
	)
	(segment
		(start 63.355982 -66.979038)
		(end 63.456312 -66.979038)
		(width 0.1016)
		(layer "In7.Cu")
		(net "CLK_100M_DDR3_NODE1_DN")
	)
	(segment
		(start 116.30152 -87.534242)
		(end 126.78156 -98.014282)
		(width 0.127)
		(layer "In7.Cu")
		(net "CLK_100M_DDR3_NODE1_DN")
	)
	(segment
		(start 114.819176 -86.051898)
		(end 115.089178 -86.3219)
		(width 0.127)
		(layer "In7.Cu")
		(net "CLK_100M_DDR3_NODE1_DN")
	)
	(segment
		(start 76.830682 -75.990958)
		(end 83.646518 -75.990958)
		(width 0.127)
		(layer "In7.Cu")
		(net "CLK_100M_DDR3_NODE1_DN")
	)
	(segment
		(start 71.709026 -72.619616)
		(end 71.709026 -73.077578)
		(width 0.127)
		(layer "In7.Cu")
		(net "CLK_100M_DDR3_NODE1_DN")
	)
	(segment
		(start 111.383318 -82.61604)
		(end 111.383318 -82.716624)
		(width 0.127)
		(layer "In7.Cu")
		(net "CLK_100M_DDR3_NODE1_DN")
	)
	(segment
		(start 114.348006 -85.681312)
		(end 114.347752 -85.781896)
		(width 0.127)
		(layer "In7.Cu")
		(net "CLK_100M_DDR3_NODE1_DN")
	)
	(segment
		(start 63.46952 -67.666616)
		(end 63.46952 -67.971416)
		(width 0.1016)
		(layer "In7.Cu")
		(net "CLK_100M_DDR3_NODE1_DN")
	)
	(segment
		(start 115.088924 -86.523068)
		(end 115.358926 -86.79307)
		(width 0.127)
		(layer "In7.Cu")
		(net "CLK_100M_DDR3_NODE1_DN")
	)
	(segment
		(start 113.336832 -84.569554)
		(end 113.606834 -84.839556)
		(width 0.127)
		(layer "In7.Cu")
		(net "CLK_100M_DDR3_NODE1_DN")
	)
	(segment
		(start 86.3854 -74.266298)
		(end 86.3854 -73.918064)
		(width 0.127)
		(layer "In7.Cu")
		(net "CLK_100M_DDR3_NODE1_DN")
	)
	(segment
		(start 126.78156 -98.014282)
		(end 126.78156 -98.180652)
		(width 0.127)
		(layer "In7.Cu")
		(net "CLK_100M_DDR3_NODE1_DN")
	)
	(segment
		(start 66.531998 -69.90969)
		(end 66.531998 -71.742046)
		(width 0.1016)
		(layer "In7.Cu")
		(net "CLK_100M_DDR3_NODE1_DN")
	)
	(segment
		(start 115.83035 -87.063072)
		(end 115.83035 -87.163656)
		(width 0.127)
		(layer "In7.Cu")
		(net "CLK_100M_DDR3_NODE1_DN")
	)
	(segment
		(start 111.383318 -82.716624)
		(end 111.383064 -82.817208)
		(width 0.127)
		(layer "In7.Cu")
		(net "CLK_100M_DDR3_NODE1_DN")
	)
	(segment
		(start 111.854488 -83.08721)
		(end 112.12449 -83.357212)
		(width 0.127)
		(layer "In7.Cu")
		(net "CLK_100M_DDR3_NODE1_DN")
	)
	(segment
		(start 115.830096 -87.26424)
		(end 116.100098 -87.534242)
		(width 0.127)
		(layer "In7.Cu")
		(net "CLK_100M_DDR3_NODE1_DN")
	)
	(segment
		(start 115.089178 -86.3219)
		(end 115.089178 -86.422484)
		(width 0.127)
		(layer "In7.Cu")
		(net "CLK_100M_DDR3_NODE1_DN")
	)
	(segment
		(start 114.078004 -85.310726)
		(end 114.348006 -85.580728)
		(width 0.127)
		(layer "In7.Cu")
		(net "CLK_100M_DDR3_NODE1_DN")
	)
	(segment
		(start 85.594698 -75.057)
		(end 86.3854 -74.266298)
		(width 0.127)
		(layer "In7.Cu")
		(net "CLK_100M_DDR3_NODE1_DN")
	)
	(segment
		(start 68.088256 -72.058784)
		(end 71.148194 -72.058784)
		(width 0.127)
		(layer "In7.Cu")
		(net "CLK_100M_DDR3_NODE1_DN")
	)
	(segment
		(start 112.59566 -83.828382)
		(end 112.865662 -84.098384)
		(width 0.127)
		(layer "In7.Cu")
		(net "CLK_100M_DDR3_NODE1_DN")
	)
	(segment
		(start 111.019336 -82.252058)
		(end 111.383318 -82.61604)
		(width 0.127)
		(layer "In7.Cu")
		(net "CLK_100M_DDR3_NODE1_DN")
	)
	(segment
		(start 103.530654 -81.993232)
		(end 103.531924 -81.993232)
		(width 0.127)
		(layer "In7.Cu")
		(net "CLK_100M_DDR3_NODE1_DN")
	)
	(segment
		(start 72.231504 -73.600056)
		(end 72.231504 -74.433684)
		(width 0.127)
		(layer "In7.Cu")
		(net "CLK_100M_DDR3_NODE1_DN")
	)
	(segment
		(start 76.360782 -75.521058)
		(end 76.830682 -75.990958)
		(width 0.127)
		(layer "In7.Cu")
		(net "CLK_100M_DDR3_NODE1_DN")
	)
	(segment
		(start 94.799912 -73.26249)
		(end 103.530654 -81.993232)
		(width 0.127)
		(layer "In7.Cu")
		(net "CLK_100M_DDR3_NODE1_DN")
	)
	(segment
		(start 112.865662 -84.198968)
		(end 112.865408 -84.299552)
		(width 0.127)
		(layer "In7.Cu")
		(net "CLK_100M_DDR3_NODE1_DN")
	)
	(segment
		(start 63.466218 -68.839842)
		(end 63.561976 -68.9356)
		(width 0.1016)
		(layer "In7.Cu")
		(net "CLK_100M_DDR3_NODE1_DN")
	)
	(segment
		(start 68.018406 -72.014334)
		(end 68.062856 -72.058784)
		(width 0.1016)
		(layer "In7.Cu")
		(net "CLK_100M_DDR3_NODE1_DN")
	)
	(segment
		(start 111.383064 -82.817208)
		(end 111.653066 -83.08721)
		(width 0.127)
		(layer "In7.Cu")
		(net "CLK_100M_DDR3_NODE1_DN")
	)
	(segment
		(start 63.46952 -67.971416)
		(end 63.561976 -68.063872)
		(width 0.1016)
		(layer "In7.Cu")
		(net "CLK_100M_DDR3_NODE1_DN")
	)
	(segment
		(start 111.653066 -83.08721)
		(end 111.854488 -83.08721)
		(width 0.127)
		(layer "In7.Cu")
		(net "CLK_100M_DDR3_NODE1_DN")
	)
	(segment
		(start 103.531924 -81.993232)
		(end 103.79075 -82.252058)
		(width 0.127)
		(layer "In7.Cu")
		(net "CLK_100M_DDR3_NODE1_DN")
	)
	(segment
		(start 66.469006 -69.846698)
		(end 66.531998 -69.90969)
		(width 0.1016)
		(layer "In7.Cu")
		(net "CLK_100M_DDR3_NODE1_DN")
	)
	(segment
		(start 112.865662 -84.098384)
		(end 112.865662 -84.198968)
		(width 0.127)
		(layer "In7.Cu")
		(net "CLK_100M_DDR3_NODE1_DN")
	)
	(segment
		(start 86.3854 -73.918064)
		(end 86.749636 -73.553828)
		(width 0.127)
		(layer "In7.Cu")
		(net "CLK_100M_DDR3_NODE1_DN")
	)
	(segment
		(start 114.348006 -85.580728)
		(end 114.348006 -85.681312)
		(width 0.127)
		(layer "In7.Cu")
		(net "CLK_100M_DDR3_NODE1_DN")
	)
	(segment
		(start 112.12449 -83.457796)
		(end 112.124236 -83.55838)
		(width 0.127)
		(layer "In7.Cu")
		(net "CLK_100M_DDR3_NODE1_DN")
	)
	(segment
		(start 113.876582 -85.310726)
		(end 114.078004 -85.310726)
		(width 0.127)
		(layer "In7.Cu")
		(net "CLK_100M_DDR3_NODE1_DN")
	)
	(segment
		(start 66.531998 -71.742046)
		(end 66.804286 -72.014334)
		(width 0.1016)
		(layer "In7.Cu")
		(net "CLK_100M_DDR3_NODE1_DN")
	)
	(segment
		(start 112.865408 -84.299552)
		(end 113.13541 -84.569554)
		(width 0.127)
		(layer "In7.Cu")
		(net "CLK_100M_DDR3_NODE1_DN")
	)
	(segment
		(start 72.57288 -71.040752)
		(end 72.425814 -70.893686)
		(width 0.1016)
		(layer "F.Cu")
		(net "M1_DQ_NODE1_DQ51")
	)
	(segment
		(start 96.642682 -24.451818)
		(end 96.642682 -25.157938)
		(width 0.1651)
		(layer "F.Cu")
		(net "M1_DQ_NODE1_DQ51")
	)
	(segment
		(start 96.150176 -23.022052)
		(end 96.64192 -23.513796)
		(width 0.1651)
		(layer "F.Cu")
		(net "M1_DQ_NODE1_DQ51")
	)
	(segment
		(start 74.089514 -70.865746)
		(end 73.914508 -71.040752)
		(width 0.1016)
		(layer "F.Cu")
		(net "M1_DQ_NODE1_DQ51")
	)
	(segment
		(start 96.150176 -20.94992)
		(end 96.150176 -23.022052)
		(width 0.1651)
		(layer "F.Cu")
		(net "M1_DQ_NODE1_DQ51")
	)
	(segment
		(start 72.425814 -70.893686)
		(end 72.425814 -70.526656)
		(width 0.1016)
		(layer "F.Cu")
		(net "M1_DQ_NODE1_DQ51")
	)
	(segment
		(start 76.21778 -70.202044)
		(end 75.93584 -70.483984)
		(width 0.1016)
		(layer "F.Cu")
		(net "M1_DQ_NODE1_DQ51")
	)
	(segment
		(start 96.64192 -23.513796)
		(end 96.64192 -24.451056)
		(width 0.1651)
		(layer "F.Cu")
		(net "M1_DQ_NODE1_DQ51")
	)
	(segment
		(start 96.64192 -24.451056)
		(end 96.642682 -24.451818)
		(width 0.1651)
		(layer "F.Cu")
		(net "M1_DQ_NODE1_DQ51")
	)
	(segment
		(start 79.42072 -65.621662)
		(end 78.39456 -66.647822)
		(width 0.1651)
		(layer "F.Cu")
		(net "M1_DQ_NODE1_DQ51")
	)
	(segment
		(start 72.425814 -70.526656)
		(end 72.081136 -70.181978)
		(width 0.1016)
		(layer "F.Cu")
		(net "M1_DQ_NODE1_DQ51")
	)
	(segment
		(start 75.007978 -70.865746)
		(end 74.089514 -70.865746)
		(width 0.1016)
		(layer "F.Cu")
		(net "M1_DQ_NODE1_DQ51")
	)
	(segment
		(start 73.914508 -71.040752)
		(end 72.57288 -71.040752)
		(width 0.1016)
		(layer "F.Cu")
		(net "M1_DQ_NODE1_DQ51")
	)
	(segment
		(start 78.39456 -68.025264)
		(end 76.21778 -70.202044)
		(width 0.1651)
		(layer "F.Cu")
		(net "M1_DQ_NODE1_DQ51")
	)
	(segment
		(start 75.93584 -70.483984)
		(end 75.38974 -70.483984)
		(width 0.1016)
		(layer "F.Cu")
		(net "M1_DQ_NODE1_DQ51")
	)
	(segment
		(start 78.39456 -66.647822)
		(end 78.39456 -68.025264)
		(width 0.1651)
		(layer "F.Cu")
		(net "M1_DQ_NODE1_DQ51")
	)
	(segment
		(start 75.38974 -70.483984)
		(end 75.007978 -70.865746)
		(width 0.1016)
		(layer "F.Cu")
		(net "M1_DQ_NODE1_DQ51")
	)
	(via
		(at 79.42072 -65.621662)
		(size 0.508)
		(drill 0.254)
		(layers "F.Cu" "B.Cu")
		(net "M1_DQ_NODE1_DQ51")
	)
	(via
		(at 96.642682 -25.157938)
		(size 0.508)
		(drill 0.254)
		(layers "F.Cu" "B.Cu")
		(net "M1_DQ_NODE1_DQ51")
	)
	(segment
		(start 95.50146 -25.91689)
		(end 95.50146 -26.621486)
		(width 0.2032)
		(layer "In7.Cu")
		(net "M1_DQ_NODE1_DQ51")
	)
	(segment
		(start 94.66072 -37.357812)
		(end 95.3008 -37.997892)
		(width 0.2032)
		(layer "In7.Cu")
		(net "M1_DQ_NODE1_DQ51")
	)
	(segment
		(start 85.39226 -53.267864)
		(end 85.39226 -55.183786)
		(width 0.2032)
		(layer "In7.Cu")
		(net "M1_DQ_NODE1_DQ51")
	)
	(segment
		(start 85.39226 -55.183786)
		(end 79.8957 -60.680346)
		(width 0.2032)
		(layer "In7.Cu")
		(net "M1_DQ_NODE1_DQ51")
	)
	(segment
		(start 95.3008 -37.997892)
		(end 95.3008 -43.359324)
		(width 0.2032)
		(layer "In7.Cu")
		(net "M1_DQ_NODE1_DQ51")
	)
	(segment
		(start 79.8957 -60.680346)
		(end 79.8957 -65.146682)
		(width 0.2032)
		(layer "In7.Cu")
		(net "M1_DQ_NODE1_DQ51")
	)
	(segment
		(start 96.642682 -25.157938)
		(end 96.260412 -25.157938)
		(width 0.2032)
		(layer "In7.Cu")
		(net "M1_DQ_NODE1_DQ51")
	)
	(segment
		(start 79.8957 -65.146682)
		(end 79.42072 -65.621662)
		(width 0.2032)
		(layer "In7.Cu")
		(net "M1_DQ_NODE1_DQ51")
	)
	(segment
		(start 96.260412 -25.157938)
		(end 95.50146 -25.91689)
		(width 0.2032)
		(layer "In7.Cu")
		(net "M1_DQ_NODE1_DQ51")
	)
	(segment
		(start 95.3008 -43.359324)
		(end 85.39226 -53.267864)
		(width 0.2032)
		(layer "In7.Cu")
		(net "M1_DQ_NODE1_DQ51")
	)
	(segment
		(start 95.50146 -26.621486)
		(end 94.66072 -27.462226)
		(width 0.2032)
		(layer "In7.Cu")
		(net "M1_DQ_NODE1_DQ51")
	)
	(segment
		(start 94.66072 -27.462226)
		(end 94.66072 -37.357812)
		(width 0.2032)
		(layer "In7.Cu")
		(net "M1_DQ_NODE1_DQ51")
	)
	(segment
		(start 51.576732 -80.160622)
		(end 51.274472 -80.462882)
		(width 0.127)
		(layer "F.Cu")
		(net "CLK_100M_CPU_NODE1_DN")
	)
	(segment
		(start 128.978914 -117.314726)
		(end 128.94183 -117.277642)
		(width 0.127)
		(layer "F.Cu")
		(net "CLK_100M_CPU_NODE1_DN")
	)
	(segment
		(start 127.11176 -116.871242)
		(end 124.04598 -116.871242)
		(width 0.127)
		(layer "F.Cu")
		(net "CLK_100M_CPU_NODE1_DN")
	)
	(segment
		(start 124.04598 -116.871242)
		(end 122.7328 -115.558062)
		(width 0.127)
		(layer "F.Cu")
		(net "CLK_100M_CPU_NODE1_DN")
	)
	(segment
		(start 127.51816 -117.277642)
		(end 127.11176 -116.871242)
		(width 0.127)
		(layer "F.Cu")
		(net "CLK_100M_CPU_NODE1_DN")
	)
	(segment
		(start 122.7328 -107.7087)
		(end 122.2502 -107.2261)
		(width 0.127)
		(layer "F.Cu")
		(net "CLK_100M_CPU_NODE1_DN")
	)
	(segment
		(start 129.403856 -117.314726)
		(end 128.978914 -117.314726)
		(width 0.127)
		(layer "F.Cu")
		(net "CLK_100M_CPU_NODE1_DN")
	)
	(segment
		(start 51.274472 -80.462882)
		(end 51.274472 -80.600042)
		(width 0.127)
		(layer "F.Cu")
		(net "CLK_100M_CPU_NODE1_DN")
	)
	(segment
		(start 128.94183 -117.277642)
		(end 127.51816 -117.277642)
		(width 0.127)
		(layer "F.Cu")
		(net "CLK_100M_CPU_NODE1_DN")
	)
	(segment
		(start 122.7328 -115.558062)
		(end 122.7328 -107.7087)
		(width 0.127)
		(layer "F.Cu")
		(net "CLK_100M_CPU_NODE1_DN")
	)
	(via
		(at 122.2502 -107.2261)
		(size 0.508)
		(drill 0.254)
		(layers "F.Cu" "B.Cu")
		(net "CLK_100M_CPU_NODE1_DN")
	)
	(via
		(at 51.576732 -80.160622)
		(size 0.508)
		(drill 0.254)
		(layers "F.Cu" "B.Cu")
		(net "CLK_100M_CPU_NODE1_DN")
	)
	(segment
		(start 91.116912 -91.547442)
		(end 91.789758 -90.874596)
		(width 0.127)
		(layer "In7.Cu")
		(net "CLK_100M_CPU_NODE1_DN")
	)
	(segment
		(start 85.938868 -91.547442)
		(end 91.116912 -91.547442)
		(width 0.127)
		(layer "In7.Cu")
		(net "CLK_100M_CPU_NODE1_DN")
	)
	(segment
		(start 98.489516 -90.874596)
		(end 100.194618 -89.169494)
		(width 0.127)
		(layer "In7.Cu")
		(net "CLK_100M_CPU_NODE1_DN")
	)
	(segment
		(start 108.288836 -89.169494)
		(end 122.73915 -103.619808)
		(width 0.127)
		(layer "In7.Cu")
		(net "CLK_100M_CPU_NODE1_DN")
	)
	(segment
		(start 70.188836 -92.499434)
		(end 77.760576 -92.499434)
		(width 0.127)
		(layer "In7.Cu")
		(net "CLK_100M_CPU_NODE1_DN")
	)
	(segment
		(start 85.70976 -91.77655)
		(end 85.938868 -91.547442)
		(width 0.127)
		(layer "In7.Cu")
		(net "CLK_100M_CPU_NODE1_DN")
	)
	(segment
		(start 62.419738 -91.525852)
		(end 64.123824 -93.229938)
		(width 0.127)
		(layer "In7.Cu")
		(net "CLK_100M_CPU_NODE1_DN")
	)
	(segment
		(start 78.48346 -91.77655)
		(end 85.70976 -91.77655)
		(width 0.127)
		(layer "In7.Cu")
		(net "CLK_100M_CPU_NODE1_DN")
	)
	(segment
		(start 53.506116 -90.613992)
		(end 54.417976 -91.525852)
		(width 0.127)
		(layer "In7.Cu")
		(net "CLK_100M_CPU_NODE1_DN")
	)
	(segment
		(start 69.458332 -93.229938)
		(end 70.188836 -92.499434)
		(width 0.127)
		(layer "In7.Cu")
		(net "CLK_100M_CPU_NODE1_DN")
	)
	(segment
		(start 51.576732 -80.160622)
		(end 51.85918 -80.44307)
		(width 0.127)
		(layer "In7.Cu")
		(net "CLK_100M_CPU_NODE1_DN")
	)
	(segment
		(start 51.85918 -80.44307)
		(end 51.85918 -80.823816)
		(width 0.127)
		(layer "In7.Cu")
		(net "CLK_100M_CPU_NODE1_DN")
	)
	(segment
		(start 77.760576 -92.499434)
		(end 78.48346 -91.77655)
		(width 0.127)
		(layer "In7.Cu")
		(net "CLK_100M_CPU_NODE1_DN")
	)
	(segment
		(start 122.73915 -103.619808)
		(end 122.73915 -106.73715)
		(width 0.127)
		(layer "In7.Cu")
		(net "CLK_100M_CPU_NODE1_DN")
	)
	(segment
		(start 54.417976 -91.525852)
		(end 62.419738 -91.525852)
		(width 0.127)
		(layer "In7.Cu")
		(net "CLK_100M_CPU_NODE1_DN")
	)
	(segment
		(start 91.789758 -90.874596)
		(end 98.489516 -90.874596)
		(width 0.127)
		(layer "In7.Cu")
		(net "CLK_100M_CPU_NODE1_DN")
	)
	(segment
		(start 64.123824 -93.229938)
		(end 69.458332 -93.229938)
		(width 0.127)
		(layer "In7.Cu")
		(net "CLK_100M_CPU_NODE1_DN")
	)
	(segment
		(start 51.61407 -81.068926)
		(end 51.61407 -87.21979)
		(width 0.127)
		(layer "In7.Cu")
		(net "CLK_100M_CPU_NODE1_DN")
	)
	(segment
		(start 53.506116 -89.111836)
		(end 53.506116 -90.613992)
		(width 0.127)
		(layer "In7.Cu")
		(net "CLK_100M_CPU_NODE1_DN")
	)
	(segment
		(start 122.73915 -106.73715)
		(end 122.2502 -107.2261)
		(width 0.127)
		(layer "In7.Cu")
		(net "CLK_100M_CPU_NODE1_DN")
	)
	(segment
		(start 51.85918 -80.823816)
		(end 51.61407 -81.068926)
		(width 0.127)
		(layer "In7.Cu")
		(net "CLK_100M_CPU_NODE1_DN")
	)
	(segment
		(start 100.194618 -89.169494)
		(end 108.288836 -89.169494)
		(width 0.127)
		(layer "In7.Cu")
		(net "CLK_100M_CPU_NODE1_DN")
	)
	(segment
		(start 51.61407 -87.21979)
		(end 53.506116 -89.111836)
		(width 0.127)
		(layer "In7.Cu")
		(net "CLK_100M_CPU_NODE1_DN")
	)
	(segment
		(start 68.57746 -34.859722)
		(end 68.842382 -34.5948)
		(width 0.2286)
		(layer "F.Cu")
		(net "M_DDR3_NODE1_MA11")
	)
	(segment
		(start 68.842128 -42.595292)
		(end 68.842128 -42.290492)
		(width 0.2286)
		(layer "F.Cu")
		(net "M_DDR3_NODE1_MA11")
	)
	(segment
		(start 68.842128 -42.290492)
		(end 69.760084 -41.372536)
		(width 0.2286)
		(layer "F.Cu")
		(net "M_DDR3_NODE1_MA11")
	)
	(segment
		(start 59.15914 -54.547516)
		(end 62.7761 -50.930556)
		(width 0.2286)
		(layer "F.Cu")
		(net "M_DDR3_NODE1_MA11")
	)
	(segment
		(start 68.793106 -36.386008)
		(end 68.57746 -36.170362)
		(width 0.2286)
		(layer "F.Cu")
		(net "M_DDR3_NODE1_MA11")
	)
	(segment
		(start 69.147182 -34.5948)
		(end 69.724778 -35.172396)
		(width 0.2286)
		(layer "F.Cu")
		(net "M_DDR3_NODE1_MA11")
	)
	(segment
		(start 69.90588 -36.906962)
		(end 69.90588 -36.601654)
		(width 0.2286)
		(layer "F.Cu")
		(net "M_DDR3_NODE1_MA11")
	)
	(segment
		(start 69.390006 -38.595808)
		(end 69.705474 -38.595808)
		(width 0.2286)
		(layer "F.Cu")
		(net "M_DDR3_NODE1_MA11")
	)
	(segment
		(start 69.370194 -43.860466)
		(end 69.586348 -43.644312)
		(width 0.2286)
		(layer "F.Cu")
		(net "M_DDR3_NODE1_MA11")
	)
	(segment
		(start 69.17436 -39.116762)
		(end 69.17436 -38.811454)
		(width 0.2286)
		(layer "F.Cu")
		(net "M_DDR3_NODE1_MA11")
	)
	(segment
		(start 58.447432 -62.123066)
		(end 58.447432 -60.757562)
		(width 0.1016)
		(layer "F.Cu")
		(net "M_DDR3_NODE1_MA11")
	)
	(segment
		(start 58.104024 -64.25692)
		(end 58.462672 -63.898272)
		(width 0.1016)
		(layer "F.Cu")
		(net "M_DDR3_NODE1_MA11")
	)
	(segment
		(start 70.012306 -35.172396)
		(end 70.245732 -34.93897)
		(width 0.2286)
		(layer "F.Cu")
		(net "M_DDR3_NODE1_MA11")
	)
	(segment
		(start 69.90588 -36.601654)
		(end 69.690234 -36.386008)
		(width 0.2286)
		(layer "F.Cu")
		(net "M_DDR3_NODE1_MA11")
	)
	(segment
		(start 69.544438 -39.332408)
		(end 69.390006 -39.332408)
		(width 0.2286)
		(layer "F.Cu")
		(net "M_DDR3_NODE1_MA11")
	)
	(segment
		(start 64.974724 -45.420788)
		(end 65.190878 -45.636942)
		(width 0.2286)
		(layer "F.Cu")
		(net "M_DDR3_NODE1_MA11")
	)
	(segment
		(start 68.861178 -40.924734)
		(end 68.861178 -41.229534)
		(width 0.2286)
		(layer "F.Cu")
		(net "M_DDR3_NODE1_MA11")
	)
	(segment
		(start 63.923672 -47.208948)
		(end 64.283082 -46.849538)
		(width 0.2286)
		(layer "F.Cu")
		(net "M_DDR3_NODE1_MA11")
	)
	(segment
		(start 58.51652 -59.50839)
		(end 59.15914 -58.86577)
		(width 0.1016)
		(layer "F.Cu")
		(net "M_DDR3_NODE1_MA11")
	)
	(segment
		(start 58.63463 -62.786006)
		(end 58.63463 -62.310264)
		(width 0.1016)
		(layer "F.Cu")
		(net "M_DDR3_NODE1_MA11")
	)
	(segment
		(start 70.245732 -34.93897)
		(end 70.245732 -34.651442)
		(width 0.2286)
		(layer "F.Cu")
		(net "M_DDR3_NODE1_MA11")
	)
	(segment
		(start 58.447432 -60.757562)
		(end 58.51652 -60.688474)
		(width 0.1016)
		(layer "F.Cu")
		(net "M_DDR3_NODE1_MA11")
	)
	(segment
		(start 69.760084 -41.372536)
		(end 69.760084 -39.548054)
		(width 0.2286)
		(layer "F.Cu")
		(net "M_DDR3_NODE1_MA11")
	)
	(segment
		(start 69.92112 -38.074854)
		(end 69.705474 -37.859208)
		(width 0.2286)
		(layer "F.Cu")
		(net "M_DDR3_NODE1_MA11")
	)
	(segment
		(start 69.586348 -43.339512)
		(end 68.842128 -42.595292)
		(width 0.2286)
		(layer "F.Cu")
		(net "M_DDR3_NODE1_MA11")
	)
	(segment
		(start 70.245732 -34.651442)
		(end 69.668136 -34.073846)
		(width 0.2286)
		(layer "F.Cu")
		(net "M_DDR3_NODE1_MA11")
	)
	(segment
		(start 69.705474 -37.859208)
		(end 68.902326 -37.859208)
		(width 0.2286)
		(layer "F.Cu")
		(net "M_DDR3_NODE1_MA11")
	)
	(segment
		(start 59.15914 -58.86577)
		(end 59.15914 -58.682128)
		(width 0.1016)
		(layer "F.Cu")
		(net "M_DDR3_NODE1_MA11")
	)
	(segment
		(start 68.68668 -37.338254)
		(end 68.902326 -37.122608)
		(width 0.2286)
		(layer "F.Cu")
		(net "M_DDR3_NODE1_MA11")
	)
	(segment
		(start 69.668136 -33.769046)
		(end 70.924166 -32.513016)
		(width 0.2286)
		(layer "F.Cu")
		(net "M_DDR3_NODE1_MA11")
	)
	(segment
		(start 63.932816 -45.115988)
		(end 68.340224 -40.70858)
		(width 0.2286)
		(layer "F.Cu")
		(net "M_DDR3_NODE1_MA11")
	)
	(segment
		(start 58.462672 -63.898272)
		(end 58.462672 -62.957964)
		(width 0.1016)
		(layer "F.Cu")
		(net "M_DDR3_NODE1_MA11")
	)
	(segment
		(start 69.390006 -39.332408)
		(end 69.17436 -39.116762)
		(width 0.2286)
		(layer "F.Cu")
		(net "M_DDR3_NODE1_MA11")
	)
	(segment
		(start 58.462672 -62.957964)
		(end 58.63463 -62.786006)
		(width 0.1016)
		(layer "F.Cu")
		(net "M_DDR3_NODE1_MA11")
	)
	(segment
		(start 70.924166 -32.513016)
		(end 70.924166 -30.792674)
		(width 0.2286)
		(layer "F.Cu")
		(net "M_DDR3_NODE1_MA11")
	)
	(segment
		(start 62.7761 -50.08753)
		(end 63.923672 -48.939958)
		(width 0.2286)
		(layer "F.Cu")
		(net "M_DDR3_NODE1_MA11")
	)
	(segment
		(start 63.923672 -48.939958)
		(end 63.923672 -47.208948)
		(width 0.2286)
		(layer "F.Cu")
		(net "M_DDR3_NODE1_MA11")
	)
	(segment
		(start 58.63463 -62.310264)
		(end 58.447432 -62.123066)
		(width 0.1016)
		(layer "F.Cu")
		(net "M_DDR3_NODE1_MA11")
	)
	(segment
		(start 64.283082 -46.293278)
		(end 64.283082 -45.771054)
		(width 0.2286)
		(layer "F.Cu")
		(net "M_DDR3_NODE1_MA11")
	)
	(segment
		(start 68.902326 -37.122608)
		(end 69.690234 -37.122608)
		(width 0.2286)
		(layer "F.Cu")
		(net "M_DDR3_NODE1_MA11")
	)
	(segment
		(start 71.250302 -30.466538)
		(end 71.250302 -29.149802)
		(width 0.2286)
		(layer "F.Cu")
		(net "M_DDR3_NODE1_MA11")
	)
	(segment
		(start 69.586348 -43.644312)
		(end 69.586348 -43.339512)
		(width 0.2286)
		(layer "F.Cu")
		(net "M_DDR3_NODE1_MA11")
	)
	(segment
		(start 69.705474 -38.595808)
		(end 69.92112 -38.380162)
		(width 0.2286)
		(layer "F.Cu")
		(net "M_DDR3_NODE1_MA11")
	)
	(segment
		(start 68.68668 -37.643562)
		(end 68.68668 -37.338254)
		(width 0.2286)
		(layer "F.Cu")
		(net "M_DDR3_NODE1_MA11")
	)
	(segment
		(start 64.974724 -45.115988)
		(end 64.974724 -45.420788)
		(width 0.2286)
		(layer "F.Cu")
		(net "M_DDR3_NODE1_MA11")
	)
	(segment
		(start 62.7761 -50.930556)
		(end 62.7761 -50.08753)
		(width 0.2286)
		(layer "F.Cu")
		(net "M_DDR3_NODE1_MA11")
	)
	(segment
		(start 68.321174 -43.116246)
		(end 69.065394 -43.860466)
		(width 0.2286)
		(layer "F.Cu")
		(net "M_DDR3_NODE1_MA11")
	)
	(segment
		(start 69.92112 -38.380162)
		(end 69.92112 -38.074854)
		(width 0.2286)
		(layer "F.Cu")
		(net "M_DDR3_NODE1_MA11")
	)
	(segment
		(start 69.690234 -37.122608)
		(end 69.90588 -36.906962)
		(width 0.2286)
		(layer "F.Cu")
		(net "M_DDR3_NODE1_MA11")
	)
	(segment
		(start 69.668136 -34.073846)
		(end 69.668136 -33.769046)
		(width 0.2286)
		(layer "F.Cu")
		(net "M_DDR3_NODE1_MA11")
	)
	(segment
		(start 65.190878 -45.636942)
		(end 65.495678 -45.636942)
		(width 0.2286)
		(layer "F.Cu")
		(net "M_DDR3_NODE1_MA11")
	)
	(segment
		(start 68.902326 -37.859208)
		(end 68.68668 -37.643562)
		(width 0.2286)
		(layer "F.Cu")
		(net "M_DDR3_NODE1_MA11")
	)
	(segment
		(start 64.283082 -45.771054)
		(end 63.932816 -45.420788)
		(width 0.2286)
		(layer "F.Cu")
		(net "M_DDR3_NODE1_MA11")
	)
	(segment
		(start 64.283082 -46.849538)
		(end 64.283082 -46.293278)
		(width 0.2286)
		(layer "F.Cu")
		(net "M_DDR3_NODE1_MA11")
	)
	(segment
		(start 69.065394 -43.860466)
		(end 69.370194 -43.860466)
		(width 0.2286)
		(layer "F.Cu")
		(net "M_DDR3_NODE1_MA11")
	)
	(segment
		(start 63.932816 -45.420788)
		(end 63.932816 -45.115988)
		(width 0.2286)
		(layer "F.Cu")
		(net "M_DDR3_NODE1_MA11")
	)
	(segment
		(start 58.51652 -60.688474)
		(end 58.51652 -59.50839)
		(width 0.1016)
		(layer "F.Cu")
		(net "M_DDR3_NODE1_MA11")
	)
	(segment
		(start 68.016374 -43.116246)
		(end 68.321174 -43.116246)
		(width 0.2286)
		(layer "F.Cu")
		(net "M_DDR3_NODE1_MA11")
	)
	(segment
		(start 69.760084 -39.548054)
		(end 69.544438 -39.332408)
		(width 0.2286)
		(layer "F.Cu")
		(net "M_DDR3_NODE1_MA11")
	)
	(segment
		(start 69.690234 -36.386008)
		(end 68.793106 -36.386008)
		(width 0.2286)
		(layer "F.Cu")
		(net "M_DDR3_NODE1_MA11")
	)
	(segment
		(start 68.861178 -41.229534)
		(end 64.974724 -45.115988)
		(width 0.2286)
		(layer "F.Cu")
		(net "M_DDR3_NODE1_MA11")
	)
	(segment
		(start 68.57746 -36.170362)
		(end 68.57746 -34.859722)
		(width 0.2286)
		(layer "F.Cu")
		(net "M_DDR3_NODE1_MA11")
	)
	(segment
		(start 69.17436 -38.811454)
		(end 69.390006 -38.595808)
		(width 0.2286)
		(layer "F.Cu")
		(net "M_DDR3_NODE1_MA11")
	)
	(segment
		(start 68.645024 -40.70858)
		(end 68.861178 -40.924734)
		(width 0.2286)
		(layer "F.Cu")
		(net "M_DDR3_NODE1_MA11")
	)
	(segment
		(start 59.15914 -58.682128)
		(end 59.15914 -54.547516)
		(width 0.2286)
		(layer "F.Cu")
		(net "M_DDR3_NODE1_MA11")
	)
	(segment
		(start 65.495678 -45.636942)
		(end 68.016374 -43.116246)
		(width 0.2286)
		(layer "F.Cu")
		(net "M_DDR3_NODE1_MA11")
	)
	(segment
		(start 69.724778 -35.172396)
		(end 70.012306 -35.172396)
		(width 0.2286)
		(layer "F.Cu")
		(net "M_DDR3_NODE1_MA11")
	)
	(segment
		(start 68.340224 -40.70858)
		(end 68.645024 -40.70858)
		(width 0.2286)
		(layer "F.Cu")
		(net "M_DDR3_NODE1_MA11")
	)
	(segment
		(start 68.842382 -34.5948)
		(end 69.147182 -34.5948)
		(width 0.2286)
		(layer "F.Cu")
		(net "M_DDR3_NODE1_MA11")
	)
	(segment
		(start 70.924166 -30.792674)
		(end 71.250302 -30.466538)
		(width 0.2286)
		(layer "F.Cu")
		(net "M_DDR3_NODE1_MA11")
	)
	(via
		(at 64.283082 -46.293278)
		(size 0.762)
		(drill 0.381)
		(layers "F.Cu" "B.Cu")
		(net "M_DDR3_NODE1_MA11")
	)
	(segment
		(start 122.77852 -118.06809)
		(end 122.65152 -117.94109)
		(width 0.127)
		(layer "F.Cu")
		(net "CLK_100M_XDP_NODE1_DP")
	)
	(segment
		(start 112.112044 -66.821558)
		(end 112.884712 -67.594226)
		(width 0.127)
		(layer "F.Cu")
		(net "CLK_100M_XDP_NODE1_DP")
	)
	(segment
		(start 127.924052 -118.573042)
		(end 127.644652 -118.293642)
		(width 0.127)
		(layer "F.Cu")
		(net "CLK_100M_XDP_NODE1_DP")
	)
	(segment
		(start 111.87049 -66.821558)
		(end 112.112044 -66.821558)
		(width 0.127)
		(layer "F.Cu")
		(net "CLK_100M_XDP_NODE1_DP")
	)
	(segment
		(start 127.644652 -118.293642)
		(end 124.477526 -118.293642)
		(width 0.127)
		(layer "F.Cu")
		(net "CLK_100M_XDP_NODE1_DP")
	)
	(segment
		(start 114.13744 -68.636134)
		(end 114.26444 -68.763134)
		(width 0.127)
		(layer "F.Cu")
		(net "CLK_100M_XDP_NODE1_DP")
	)
	(segment
		(start 112.884712 -67.594226)
		(end 112.884712 -68.277486)
		(width 0.127)
		(layer "F.Cu")
		(net "CLK_100M_XDP_NODE1_DP")
	)
	(segment
		(start 112.884712 -68.277486)
		(end 113.24336 -68.636134)
		(width 0.127)
		(layer "F.Cu")
		(net "CLK_100M_XDP_NODE1_DP")
	)
	(segment
		(start 122.65152 -117.94109)
		(end 122.65152 -117.58549)
		(width 0.127)
		(layer "F.Cu")
		(net "CLK_100M_XDP_NODE1_DP")
	)
	(segment
		(start 129.015236 -118.514622)
		(end 128.956816 -118.573042)
		(width 0.127)
		(layer "F.Cu")
		(net "CLK_100M_XDP_NODE1_DP")
	)
	(segment
		(start 110.460028 -66.90614)
		(end 111.785908 -66.90614)
		(width 0.127)
		(layer "F.Cu")
		(net "CLK_100M_XDP_NODE1_DP")
	)
	(segment
		(start 114.26444 -68.763134)
		(end 114.26444 -69.118734)
		(width 0.127)
		(layer "F.Cu")
		(net "CLK_100M_XDP_NODE1_DP")
	)
	(segment
		(start 129.403856 -118.514622)
		(end 129.015236 -118.514622)
		(width 0.127)
		(layer "F.Cu")
		(net "CLK_100M_XDP_NODE1_DP")
	)
	(segment
		(start 124.251974 -118.06809)
		(end 122.77852 -118.06809)
		(width 0.127)
		(layer "F.Cu")
		(net "CLK_100M_XDP_NODE1_DP")
	)
	(segment
		(start 113.24336 -68.636134)
		(end 114.13744 -68.636134)
		(width 0.127)
		(layer "F.Cu")
		(net "CLK_100M_XDP_NODE1_DP")
	)
	(segment
		(start 128.956816 -118.573042)
		(end 127.924052 -118.573042)
		(width 0.127)
		(layer "F.Cu")
		(net "CLK_100M_XDP_NODE1_DP")
	)
	(segment
		(start 124.477526 -118.293642)
		(end 124.251974 -118.06809)
		(width 0.127)
		(layer "F.Cu")
		(net "CLK_100M_XDP_NODE1_DP")
	)
	(segment
		(start 111.785908 -66.90614)
		(end 111.87049 -66.821558)
		(width 0.127)
		(layer "F.Cu")
		(net "CLK_100M_XDP_NODE1_DP")
	)
	(via
		(at 114.26444 -69.118734)
		(size 0.508)
		(drill 0.254)
		(layers "F.Cu" "B.Cu")
		(net "CLK_100M_XDP_NODE1_DP")
	)
	(via
		(at 122.65152 -117.58549)
		(size 0.508)
		(drill 0.254)
		(layers "F.Cu" "B.Cu")
		(net "CLK_100M_XDP_NODE1_DP")
	)
	(segment
		(start 123.75896 -113.635028)
		(end 123.889516 -113.765584)
		(width 0.127)
		(layer "B.Cu")
		(net "CLK_100M_XDP_NODE1_DP")
	)
	(segment
		(start 123.889516 -114.788696)
		(end 123.889516 -115.169696)
		(width 0.127)
		(layer "B.Cu")
		(net "CLK_100M_XDP_NODE1_DP")
	)
	(segment
		(start 123.889516 -115.169696)
		(end 123.75896 -115.300252)
		(width 0.127)
		(layer "B.Cu")
		(net "CLK_100M_XDP_NODE1_DP")
	)
	(segment
		(start 116.88064 -75.052682)
		(end 116.88064 -75.433682)
		(width 0.127)
		(layer "B.Cu")
		(net "CLK_100M_XDP_NODE1_DP")
	)
	(segment
		(start 124.4981 -101.566218)
		(end 124.4981 -108.751624)
		(width 0.127)
		(layer "B.Cu")
		(net "CLK_100M_XDP_NODE1_DP")
	)
	(segment
		(start 117.00764 -74.544682)
		(end 117.00764 -74.925682)
		(width 0.127)
		(layer "B.Cu")
		(net "CLK_100M_XDP_NODE1_DP")
	)
	(segment
		(start 117.00764 -75.560682)
		(end 117.00764 -80.487012)
		(width 0.127)
		(layer "B.Cu")
		(net "CLK_100M_XDP_NODE1_DP")
	)
	(segment
		(start 123.75896 -114.27714)
		(end 123.75896 -114.65814)
		(width 0.127)
		(layer "B.Cu")
		(net "CLK_100M_XDP_NODE1_DP")
	)
	(segment
		(start 123.889516 -113.123472)
		(end 123.75896 -113.254028)
		(width 0.127)
		(layer "B.Cu")
		(net "CLK_100M_XDP_NODE1_DP")
	)
	(segment
		(start 123.75896 -115.681252)
		(end 123.889516 -115.811808)
		(width 0.127)
		(layer "B.Cu")
		(net "CLK_100M_XDP_NODE1_DP")
	)
	(segment
		(start 116.88064 -73.020682)
		(end 116.88064 -73.401682)
		(width 0.127)
		(layer "B.Cu")
		(net "CLK_100M_XDP_NODE1_DP")
	)
	(segment
		(start 123.75896 -111.207804)
		(end 123.75896 -111.588804)
		(width 0.127)
		(layer "B.Cu")
		(net "CLK_100M_XDP_NODE1_DP")
	)
	(segment
		(start 123.75896 -116.704364)
		(end 123.889516 -116.83492)
		(width 0.127)
		(layer "B.Cu")
		(net "CLK_100M_XDP_NODE1_DP")
	)
	(segment
		(start 117.00764 -73.528682)
		(end 117.00764 -73.909682)
		(width 0.127)
		(layer "B.Cu")
		(net "CLK_100M_XDP_NODE1_DP")
	)
	(segment
		(start 116.88064 -74.417682)
		(end 117.00764 -74.544682)
		(width 0.127)
		(layer "B.Cu")
		(net "CLK_100M_XDP_NODE1_DP")
	)
	(segment
		(start 123.889516 -117.50167)
		(end 123.323096 -118.06809)
		(width 0.127)
		(layer "B.Cu")
		(net "CLK_100M_XDP_NODE1_DP")
	)
	(segment
		(start 117.00764 -72.893682)
		(end 116.88064 -73.020682)
		(width 0.127)
		(layer "B.Cu")
		(net "CLK_100M_XDP_NODE1_DP")
	)
	(segment
		(start 123.889516 -114.146584)
		(end 123.75896 -114.27714)
		(width 0.127)
		(layer "B.Cu")
		(net "CLK_100M_XDP_NODE1_DP")
	)
	(segment
		(start 122.65152 -117.94109)
		(end 122.65152 -117.58549)
		(width 0.127)
		(layer "B.Cu")
		(net "CLK_100M_XDP_NODE1_DP")
	)
	(segment
		(start 123.889516 -115.811808)
		(end 123.889516 -116.192808)
		(width 0.127)
		(layer "B.Cu")
		(net "CLK_100M_XDP_NODE1_DP")
	)
	(segment
		(start 123.75896 -111.588804)
		(end 123.889516 -111.71936)
		(width 0.127)
		(layer "B.Cu")
		(net "CLK_100M_XDP_NODE1_DP")
	)
	(segment
		(start 118.06682 -95.134938)
		(end 124.4981 -101.566218)
		(width 0.127)
		(layer "B.Cu")
		(net "CLK_100M_XDP_NODE1_DP")
	)
	(segment
		(start 116.88064 -75.433682)
		(end 117.00764 -75.560682)
		(width 0.127)
		(layer "B.Cu")
		(net "CLK_100M_XDP_NODE1_DP")
	)
	(segment
		(start 117.00764 -74.925682)
		(end 116.88064 -75.052682)
		(width 0.127)
		(layer "B.Cu")
		(net "CLK_100M_XDP_NODE1_DP")
	)
	(segment
		(start 123.323096 -118.06809)
		(end 122.77852 -118.06809)
		(width 0.127)
		(layer "B.Cu")
		(net "CLK_100M_XDP_NODE1_DP")
	)
	(segment
		(start 118.06682 -81.546192)
		(end 118.06682 -95.134938)
		(width 0.127)
		(layer "B.Cu")
		(net "CLK_100M_XDP_NODE1_DP")
	)
	(segment
		(start 115.654074 -68.636134)
		(end 117.00764 -69.9897)
		(width 0.127)
		(layer "B.Cu")
		(net "CLK_100M_XDP_NODE1_DP")
	)
	(segment
		(start 117.00764 -73.909682)
		(end 116.88064 -74.036682)
		(width 0.127)
		(layer "B.Cu")
		(net "CLK_100M_XDP_NODE1_DP")
	)
	(segment
		(start 123.75896 -114.65814)
		(end 123.889516 -114.788696)
		(width 0.127)
		(layer "B.Cu")
		(net "CLK_100M_XDP_NODE1_DP")
	)
	(segment
		(start 123.75896 -112.230916)
		(end 123.75896 -112.611916)
		(width 0.127)
		(layer "B.Cu")
		(net "CLK_100M_XDP_NODE1_DP")
	)
	(segment
		(start 123.889516 -112.742472)
		(end 123.889516 -113.123472)
		(width 0.127)
		(layer "B.Cu")
		(net "CLK_100M_XDP_NODE1_DP")
	)
	(segment
		(start 124.4981 -108.751624)
		(end 123.889516 -109.360208)
		(width 0.127)
		(layer "B.Cu")
		(net "CLK_100M_XDP_NODE1_DP")
	)
	(segment
		(start 123.889516 -109.360208)
		(end 123.889516 -111.077248)
		(width 0.127)
		(layer "B.Cu")
		(net "CLK_100M_XDP_NODE1_DP")
	)
	(segment
		(start 122.77852 -118.06809)
		(end 122.65152 -117.94109)
		(width 0.127)
		(layer "B.Cu")
		(net "CLK_100M_XDP_NODE1_DP")
	)
	(segment
		(start 123.75896 -116.323364)
		(end 123.75896 -116.704364)
		(width 0.127)
		(layer "B.Cu")
		(net "CLK_100M_XDP_NODE1_DP")
	)
	(segment
		(start 123.889516 -116.83492)
		(end 123.889516 -117.50167)
		(width 0.127)
		(layer "B.Cu")
		(net "CLK_100M_XDP_NODE1_DP")
	)
	(segment
		(start 123.75896 -113.254028)
		(end 123.75896 -113.635028)
		(width 0.127)
		(layer "B.Cu")
		(net "CLK_100M_XDP_NODE1_DP")
	)
	(segment
		(start 123.889516 -111.71936)
		(end 123.889516 -112.10036)
		(width 0.127)
		(layer "B.Cu")
		(net "CLK_100M_XDP_NODE1_DP")
	)
	(segment
		(start 123.889516 -112.10036)
		(end 123.75896 -112.230916)
		(width 0.127)
		(layer "B.Cu")
		(net "CLK_100M_XDP_NODE1_DP")
	)
	(segment
		(start 114.26444 -69.118734)
		(end 114.26444 -68.763134)
		(width 0.127)
		(layer "B.Cu")
		(net "CLK_100M_XDP_NODE1_DP")
	)
	(segment
		(start 117.00764 -69.9897)
		(end 117.00764 -72.893682)
		(width 0.127)
		(layer "B.Cu")
		(net "CLK_100M_XDP_NODE1_DP")
	)
	(segment
		(start 116.88064 -74.036682)
		(end 116.88064 -74.417682)
		(width 0.127)
		(layer "B.Cu")
		(net "CLK_100M_XDP_NODE1_DP")
	)
	(segment
		(start 123.889516 -113.765584)
		(end 123.889516 -114.146584)
		(width 0.127)
		(layer "B.Cu")
		(net "CLK_100M_XDP_NODE1_DP")
	)
	(segment
		(start 114.26444 -68.763134)
		(end 114.39144 -68.636134)
		(width 0.127)
		(layer "B.Cu")
		(net "CLK_100M_XDP_NODE1_DP")
	)
	(segment
		(start 114.39144 -68.636134)
		(end 115.654074 -68.636134)
		(width 0.127)
		(layer "B.Cu")
		(net "CLK_100M_XDP_NODE1_DP")
	)
	(segment
		(start 123.75896 -115.300252)
		(end 123.75896 -115.681252)
		(width 0.127)
		(layer "B.Cu")
		(net "CLK_100M_XDP_NODE1_DP")
	)
	(segment
		(start 117.00764 -80.487012)
		(end 118.06682 -81.546192)
		(width 0.127)
		(layer "B.Cu")
		(net "CLK_100M_XDP_NODE1_DP")
	)
	(segment
		(start 123.889516 -111.077248)
		(end 123.75896 -111.207804)
		(width 0.127)
		(layer "B.Cu")
		(net "CLK_100M_XDP_NODE1_DP")
	)
	(segment
		(start 116.88064 -73.401682)
		(end 117.00764 -73.528682)
		(width 0.127)
		(layer "B.Cu")
		(net "CLK_100M_XDP_NODE1_DP")
	)
	(segment
		(start 123.889516 -116.192808)
		(end 123.75896 -116.323364)
		(width 0.127)
		(layer "B.Cu")
		(net "CLK_100M_XDP_NODE1_DP")
	)
	(segment
		(start 123.75896 -112.611916)
		(end 123.889516 -112.742472)
		(width 0.127)
		(layer "B.Cu")
		(net "CLK_100M_XDP_NODE1_DP")
	)
	(segment
		(start 64.650112 -29.149802)
		(end 63.476886 -29.149802)
		(width 0.1651)
		(layer "F.Cu")
		(net "M_DDR3_NODE1_ECC5")
	)
	(segment
		(start 66.809366 -68.871338)
		(end 66.809366 -68.869306)
		(width 0.1016)
		(layer "F.Cu")
		(net "M_DDR3_NODE1_ECC5")
	)
	(segment
		(start 66.415666 -69.265038)
		(end 66.809366 -68.871338)
		(width 0.1016)
		(layer "F.Cu")
		(net "M_DDR3_NODE1_ECC5")
	)
	(segment
		(start 63.476886 -29.149802)
		(end 63.361062 -29.033978)
		(width 0.1651)
		(layer "F.Cu")
		(net "M_DDR3_NODE1_ECC5")
	)
	(via
		(at 63.361062 -29.033978)
		(size 0.508)
		(drill 0.254)
		(layers "F.Cu" "B.Cu")
		(net "M_DDR3_NODE1_ECC5")
	)
	(via
		(at 66.809366 -68.869306)
		(size 0.508)
		(drill 0.254)
		(layers "F.Cu" "B.Cu")
		(net "M_DDR3_NODE1_ECC5")
	)
	(segment
		(start 62.748922 -27.501342)
		(end 62.748922 -27.50058)
		(width 0.2032)
		(layer "In7.Cu")
		(net "M_DDR3_NODE1_ECC5")
	)
	(segment
		(start 54.44998 -45.211746)
		(end 54.44998 -45.506386)
		(width 0.2032)
		(layer "In7.Cu")
		(net "M_DDR3_NODE1_ECC5")
	)
	(segment
		(start 64.384428 -65.220088)
		(end 64.384428 -66.338958)
		(width 0.1016)
		(layer "In7.Cu")
		(net "M_DDR3_NODE1_ECC5")
	)
	(segment
		(start 55.1688 -44.500546)
		(end 55.1688 -44.795186)
		(width 0.2032)
		(layer "In7.Cu")
		(net "M_DDR3_NODE1_ECC5")
	)
	(segment
		(start 54.44998 -49.07153)
		(end 58.53176 -53.15331)
		(width 0.2032)
		(layer "In7.Cu")
		(net "M_DDR3_NODE1_ECC5")
	)
	(segment
		(start 61.790072 -61.714634)
		(end 61.790072 -62.729872)
		(width 0.1016)
		(layer "In7.Cu")
		(net "M_DDR3_NODE1_ECC5")
	)
	(segment
		(start 54.96052 -46.425866)
		(end 54.65826 -46.425866)
		(width 0.2032)
		(layer "In7.Cu")
		(net "M_DDR3_NODE1_ECC5")
	)
	(segment
		(start 58.53176 -53.15331)
		(end 58.53176 -57.774078)
		(width 0.2032)
		(layer "In7.Cu")
		(net "M_DDR3_NODE1_ECC5")
	)
	(segment
		(start 62.748922 -27.50058)
		(end 62.545722 -27.70378)
		(width 0.2032)
		(layer "In7.Cu")
		(net "M_DDR3_NODE1_ECC5")
	)
	(segment
		(start 61.316362 -34.902394)
		(end 61.316362 -35.197034)
		(width 0.2032)
		(layer "In7.Cu")
		(net "M_DDR3_NODE1_ECC5")
	)
	(segment
		(start 61.264038 -33.84423)
		(end 60.969398 -33.84423)
		(width 0.2032)
		(layer "In7.Cu")
		(net "M_DDR3_NODE1_ECC5")
	)
	(segment
		(start 64.384428 -66.338958)
		(end 64.70777 -66.6623)
		(width 0.1016)
		(layer "In7.Cu")
		(net "M_DDR3_NODE1_ECC5")
	)
	(segment
		(start 63.361062 -27.728164)
		(end 63.13424 -27.501342)
		(width 0.2032)
		(layer "In7.Cu")
		(net "M_DDR3_NODE1_ECC5")
	)
	(segment
		(start 61.766958 -33.34131)
		(end 62.322202 -33.896554)
		(width 0.2032)
		(layer "In7.Cu")
		(net "M_DDR3_NODE1_ECC5")
	)
	(segment
		(start 56.78424 -38.029388)
		(end 56.78424 -40.03802)
		(width 0.2032)
		(layer "In7.Cu")
		(net "M_DDR3_NODE1_ECC5")
	)
	(segment
		(start 54.65826 -44.292266)
		(end 54.96052 -44.292266)
		(width 0.2032)
		(layer "In7.Cu")
		(net "M_DDR3_NODE1_ECC5")
	)
	(segment
		(start 60.65012 -60.574682)
		(end 61.790072 -61.714634)
		(width 0.1016)
		(layer "In7.Cu")
		(net "M_DDR3_NODE1_ECC5")
	)
	(segment
		(start 54.96052 -47.848266)
		(end 54.65826 -47.848266)
		(width 0.2032)
		(layer "In7.Cu")
		(net "M_DDR3_NODE1_ECC5")
	)
	(segment
		(start 62.545722 -27.70378)
		(end 62.545722 -28.680918)
		(width 0.2032)
		(layer "In7.Cu")
		(net "M_DDR3_NODE1_ECC5")
	)
	(segment
		(start 66.039238 -68.099178)
		(end 66.809366 -68.869306)
		(width 0.1016)
		(layer "In7.Cu")
		(net "M_DDR3_NODE1_ECC5")
	)
	(segment
		(start 59.963558 -34.85007)
		(end 59.182762 -35.630866)
		(width 0.2032)
		(layer "In7.Cu")
		(net "M_DDR3_NODE1_ECC5")
	)
	(segment
		(start 61.790072 -62.729872)
		(end 62.759844 -63.699644)
		(width 0.1016)
		(layer "In7.Cu")
		(net "M_DDR3_NODE1_ECC5")
	)
	(segment
		(start 54.65826 -47.137066)
		(end 54.96052 -47.137066)
		(width 0.2032)
		(layer "In7.Cu")
		(net "M_DDR3_NODE1_ECC5")
	)
	(segment
		(start 62.322202 -33.896554)
		(end 62.322202 -34.191194)
		(width 0.2032)
		(layer "In7.Cu")
		(net "M_DDR3_NODE1_ECC5")
	)
	(segment
		(start 54.44998 -46.634146)
		(end 54.44998 -46.928786)
		(width 0.2032)
		(layer "In7.Cu")
		(net "M_DDR3_NODE1_ECC5")
	)
	(segment
		(start 54.65826 -47.848266)
		(end 54.44998 -48.056546)
		(width 0.2032)
		(layer "In7.Cu")
		(net "M_DDR3_NODE1_ECC5")
	)
	(segment
		(start 58.097674 -35.846258)
		(end 58.385202 -36.133786)
		(width 0.2032)
		(layer "In7.Cu")
		(net "M_DDR3_NODE1_ECC5")
	)
	(segment
		(start 62.390782 -32.422846)
		(end 61.766958 -33.04667)
		(width 0.2032)
		(layer "In7.Cu")
		(net "M_DDR3_NODE1_ECC5")
	)
	(segment
		(start 54.44998 -46.928786)
		(end 54.65826 -47.137066)
		(width 0.2032)
		(layer "In7.Cu")
		(net "M_DDR3_NODE1_ECC5")
	)
	(segment
		(start 58.097674 -35.551618)
		(end 58.097674 -35.846258)
		(width 0.2032)
		(layer "In7.Cu")
		(net "M_DDR3_NODE1_ECC5")
	)
	(segment
		(start 59.182762 -35.630866)
		(end 58.888122 -35.630866)
		(width 0.2032)
		(layer "In7.Cu")
		(net "M_DDR3_NODE1_ECC5")
	)
	(segment
		(start 60.65012 -59.892438)
		(end 60.65012 -60.574682)
		(width 0.2032)
		(layer "In7.Cu")
		(net "M_DDR3_NODE1_ECC5")
	)
	(segment
		(start 55.1688 -46.217586)
		(end 54.96052 -46.425866)
		(width 0.2032)
		(layer "In7.Cu")
		(net "M_DDR3_NODE1_ECC5")
	)
	(segment
		(start 55.1688 -44.795186)
		(end 54.96052 -45.003466)
		(width 0.2032)
		(layer "In7.Cu")
		(net "M_DDR3_NODE1_ECC5")
	)
	(segment
		(start 54.65826 -45.714666)
		(end 54.96052 -45.714666)
		(width 0.2032)
		(layer "In7.Cu")
		(net "M_DDR3_NODE1_ECC5")
	)
	(segment
		(start 58.888122 -35.630866)
		(end 58.600594 -35.343338)
		(width 0.2032)
		(layer "In7.Cu")
		(net "M_DDR3_NODE1_ECC5")
	)
	(segment
		(start 54.65826 -46.425866)
		(end 54.44998 -46.634146)
		(width 0.2032)
		(layer "In7.Cu")
		(net "M_DDR3_NODE1_ECC5")
	)
	(segment
		(start 64.70777 -66.728594)
		(end 65.088262 -67.109086)
		(width 0.1016)
		(layer "In7.Cu")
		(net "M_DDR3_NODE1_ECC5")
	)
	(segment
		(start 63.13424 -27.501342)
		(end 62.748922 -27.501342)
		(width 0.2032)
		(layer "In7.Cu")
		(net "M_DDR3_NODE1_ECC5")
	)
	(segment
		(start 54.44998 -48.056546)
		(end 54.44998 -49.07153)
		(width 0.2032)
		(layer "In7.Cu")
		(net "M_DDR3_NODE1_ECC5")
	)
	(segment
		(start 54.96052 -47.137066)
		(end 55.1688 -47.345346)
		(width 0.2032)
		(layer "In7.Cu")
		(net "M_DDR3_NODE1_ECC5")
	)
	(segment
		(start 58.385202 -36.133786)
		(end 58.385202 -36.428426)
		(width 0.2032)
		(layer "In7.Cu")
		(net "M_DDR3_NODE1_ECC5")
	)
	(segment
		(start 60.813442 -35.405314)
		(end 60.258198 -34.85007)
		(width 0.2032)
		(layer "In7.Cu")
		(net "M_DDR3_NODE1_ECC5")
	)
	(segment
		(start 63.361062 -29.033978)
		(end 63.361062 -27.728164)
		(width 0.2032)
		(layer "In7.Cu")
		(net "M_DDR3_NODE1_ECC5")
	)
	(segment
		(start 64.70777 -66.6623)
		(end 64.70777 -66.728594)
		(width 0.1016)
		(layer "In7.Cu")
		(net "M_DDR3_NODE1_ECC5")
	)
	(segment
		(start 60.969398 -33.84423)
		(end 60.761118 -34.05251)
		(width 0.2032)
		(layer "In7.Cu")
		(net "M_DDR3_NODE1_ECC5")
	)
	(segment
		(start 55.1688 -47.639986)
		(end 54.96052 -47.848266)
		(width 0.2032)
		(layer "In7.Cu")
		(net "M_DDR3_NODE1_ECC5")
	)
	(segment
		(start 54.96052 -45.714666)
		(end 55.1688 -45.922946)
		(width 0.2032)
		(layer "In7.Cu")
		(net "M_DDR3_NODE1_ECC5")
	)
	(segment
		(start 54.65826 -45.003466)
		(end 54.44998 -45.211746)
		(width 0.2032)
		(layer "In7.Cu")
		(net "M_DDR3_NODE1_ECC5")
	)
	(segment
		(start 54.44998 -44.083986)
		(end 54.65826 -44.292266)
		(width 0.2032)
		(layer "In7.Cu")
		(net "M_DDR3_NODE1_ECC5")
	)
	(segment
		(start 58.305954 -35.343338)
		(end 58.097674 -35.551618)
		(width 0.2032)
		(layer "In7.Cu")
		(net "M_DDR3_NODE1_ECC5")
	)
	(segment
		(start 54.96052 -44.292266)
		(end 55.1688 -44.500546)
		(width 0.2032)
		(layer "In7.Cu")
		(net "M_DDR3_NODE1_ECC5")
	)
	(segment
		(start 55.1688 -47.345346)
		(end 55.1688 -47.639986)
		(width 0.2032)
		(layer "In7.Cu")
		(net "M_DDR3_NODE1_ECC5")
	)
	(segment
		(start 62.545722 -28.680918)
		(end 62.390782 -28.835858)
		(width 0.2032)
		(layer "In7.Cu")
		(net "M_DDR3_NODE1_ECC5")
	)
	(segment
		(start 62.390782 -28.835858)
		(end 62.390782 -32.422846)
		(width 0.2032)
		(layer "In7.Cu")
		(net "M_DDR3_NODE1_ECC5")
	)
	(segment
		(start 65.380108 -67.109086)
		(end 66.039238 -67.768216)
		(width 0.1016)
		(layer "In7.Cu")
		(net "M_DDR3_NODE1_ECC5")
	)
	(segment
		(start 62.113922 -34.399474)
		(end 61.819282 -34.399474)
		(width 0.2032)
		(layer "In7.Cu")
		(net "M_DDR3_NODE1_ECC5")
	)
	(segment
		(start 55.1688 -45.922946)
		(end 55.1688 -46.217586)
		(width 0.2032)
		(layer "In7.Cu")
		(net "M_DDR3_NODE1_ECC5")
	)
	(segment
		(start 61.108082 -35.405314)
		(end 60.813442 -35.405314)
		(width 0.2032)
		(layer "In7.Cu")
		(net "M_DDR3_NODE1_ECC5")
	)
	(segment
		(start 58.600594 -35.343338)
		(end 58.305954 -35.343338)
		(width 0.2032)
		(layer "In7.Cu")
		(net "M_DDR3_NODE1_ECC5")
	)
	(segment
		(start 60.761118 -34.05251)
		(end 60.761118 -34.34715)
		(width 0.2032)
		(layer "In7.Cu")
		(net "M_DDR3_NODE1_ECC5")
	)
	(segment
		(start 60.258198 -34.85007)
		(end 59.963558 -34.85007)
		(width 0.2032)
		(layer "In7.Cu")
		(net "M_DDR3_NODE1_ECC5")
	)
	(segment
		(start 54.44998 -45.506386)
		(end 54.65826 -45.714666)
		(width 0.2032)
		(layer "In7.Cu")
		(net "M_DDR3_NODE1_ECC5")
	)
	(segment
		(start 61.316362 -35.197034)
		(end 61.108082 -35.405314)
		(width 0.2032)
		(layer "In7.Cu")
		(net "M_DDR3_NODE1_ECC5")
	)
	(segment
		(start 60.761118 -34.34715)
		(end 61.316362 -34.902394)
		(width 0.2032)
		(layer "In7.Cu")
		(net "M_DDR3_NODE1_ECC5")
	)
	(segment
		(start 66.039238 -67.768216)
		(end 66.039238 -68.099178)
		(width 0.1016)
		(layer "In7.Cu")
		(net "M_DDR3_NODE1_ECC5")
	)
	(segment
		(start 54.44998 -42.37228)
		(end 54.44998 -44.083986)
		(width 0.2032)
		(layer "In7.Cu")
		(net "M_DDR3_NODE1_ECC5")
	)
	(segment
		(start 58.53176 -57.774078)
		(end 60.65012 -59.892438)
		(width 0.2032)
		(layer "In7.Cu")
		(net "M_DDR3_NODE1_ECC5")
	)
	(segment
		(start 62.863984 -63.699644)
		(end 64.384428 -65.220088)
		(width 0.1016)
		(layer "In7.Cu")
		(net "M_DDR3_NODE1_ECC5")
	)
	(segment
		(start 61.819282 -34.399474)
		(end 61.264038 -33.84423)
		(width 0.2032)
		(layer "In7.Cu")
		(net "M_DDR3_NODE1_ECC5")
	)
	(segment
		(start 62.322202 -34.191194)
		(end 62.113922 -34.399474)
		(width 0.2032)
		(layer "In7.Cu")
		(net "M_DDR3_NODE1_ECC5")
	)
	(segment
		(start 62.759844 -63.699644)
		(end 62.863984 -63.699644)
		(width 0.1016)
		(layer "In7.Cu")
		(net "M_DDR3_NODE1_ECC5")
	)
	(segment
		(start 58.385202 -36.428426)
		(end 56.78424 -38.029388)
		(width 0.2032)
		(layer "In7.Cu")
		(net "M_DDR3_NODE1_ECC5")
	)
	(segment
		(start 56.78424 -40.03802)
		(end 54.44998 -42.37228)
		(width 0.2032)
		(layer "In7.Cu")
		(net "M_DDR3_NODE1_ECC5")
	)
	(segment
		(start 54.96052 -45.003466)
		(end 54.65826 -45.003466)
		(width 0.2032)
		(layer "In7.Cu")
		(net "M_DDR3_NODE1_ECC5")
	)
	(segment
		(start 61.766958 -33.04667)
		(end 61.766958 -33.34131)
		(width 0.2032)
		(layer "In7.Cu")
		(net "M_DDR3_NODE1_ECC5")
	)
	(segment
		(start 65.088262 -67.109086)
		(end 65.380108 -67.109086)
		(width 0.1016)
		(layer "In7.Cu")
		(net "M_DDR3_NODE1_ECC5")
	)
	(segment
		(start 69.417946 -126.383288)
		(end 69.417946 -125.825504)
		(width 0.127)
		(layer "F.Cu")
		(net "CLK_100M_BMC_NODE1_DP")
	)
	(segment
		(start 71.941182 -119.033798)
		(end 72.791066 -119.033798)
		(width 0.127)
		(layer "F.Cu")
		(net "CLK_100M_BMC_NODE1_DP")
	)
	(segment
		(start 72.791066 -119.033798)
		(end 73.042018 -118.782846)
		(width 0.127)
		(layer "F.Cu")
		(net "CLK_100M_BMC_NODE1_DP")
	)
	(segment
		(start 128.726438 -119.714518)
		(end 128.67894 -119.762016)
		(width 0.127)
		(layer "F.Cu")
		(net "CLK_100M_BMC_NODE1_DP")
	)
	(segment
		(start 69.172328 -124.263404)
		(end 69.023484 -124.11456)
		(width 0.127)
		(layer "F.Cu")
		(net "CLK_100M_BMC_NODE1_DP")
	)
	(segment
		(start 69.023484 -124.793248)
		(end 69.172328 -124.644404)
		(width 0.127)
		(layer "F.Cu")
		(net "CLK_100M_BMC_NODE1_DP")
	)
	(segment
		(start 69.172328 -125.579886)
		(end 69.172328 -125.323092)
		(width 0.127)
		(layer "F.Cu")
		(net "CLK_100M_BMC_NODE1_DP")
	)
	(segment
		(start 69.172328 -123.584716)
		(end 69.172328 -121.802652)
		(width 0.127)
		(layer "F.Cu")
		(net "CLK_100M_BMC_NODE1_DP")
	)
	(segment
		(start 128.67894 -119.762016)
		(end 128.234186 -119.762016)
		(width 0.127)
		(layer "F.Cu")
		(net "CLK_100M_BMC_NODE1_DP")
	)
	(segment
		(start 69.172328 -125.323092)
		(end 69.023484 -125.174248)
		(width 0.127)
		(layer "F.Cu")
		(net "CLK_100M_BMC_NODE1_DP")
	)
	(segment
		(start 69.86778 -120.9167)
		(end 70.05828 -120.9167)
		(width 0.127)
		(layer "F.Cu")
		(net "CLK_100M_BMC_NODE1_DP")
	)
	(segment
		(start 69.417946 -125.825504)
		(end 69.172328 -125.579886)
		(width 0.127)
		(layer "F.Cu")
		(net "CLK_100M_BMC_NODE1_DP")
	)
	(segment
		(start 69.172328 -124.644404)
		(end 69.172328 -124.263404)
		(width 0.127)
		(layer "F.Cu")
		(net "CLK_100M_BMC_NODE1_DP")
	)
	(segment
		(start 70.05828 -120.9167)
		(end 71.941182 -119.033798)
		(width 0.127)
		(layer "F.Cu")
		(net "CLK_100M_BMC_NODE1_DP")
	)
	(segment
		(start 69.023484 -123.73356)
		(end 69.172328 -123.584716)
		(width 0.127)
		(layer "F.Cu")
		(net "CLK_100M_BMC_NODE1_DP")
	)
	(segment
		(start 69.172328 -121.802652)
		(end 69.598286 -121.376694)
		(width 0.127)
		(layer "F.Cu")
		(net "CLK_100M_BMC_NODE1_DP")
	)
	(segment
		(start 69.598286 -121.376694)
		(end 69.598286 -121.186194)
		(width 0.127)
		(layer "F.Cu")
		(net "CLK_100M_BMC_NODE1_DP")
	)
	(segment
		(start 127.11176 -120.884442)
		(end 122.411236 -120.884442)
		(width 0.127)
		(layer "F.Cu")
		(net "CLK_100M_BMC_NODE1_DP")
	)
	(segment
		(start 69.598286 -121.186194)
		(end 69.86778 -120.9167)
		(width 0.127)
		(layer "F.Cu")
		(net "CLK_100M_BMC_NODE1_DP")
	)
	(segment
		(start 69.023484 -125.174248)
		(end 69.023484 -124.793248)
		(width 0.127)
		(layer "F.Cu")
		(net "CLK_100M_BMC_NODE1_DP")
	)
	(segment
		(start 128.234186 -119.762016)
		(end 127.11176 -120.884442)
		(width 0.127)
		(layer "F.Cu")
		(net "CLK_100M_BMC_NODE1_DP")
	)
	(segment
		(start 69.341746 -126.459488)
		(end 69.417946 -126.383288)
		(width 0.127)
		(layer "F.Cu")
		(net "CLK_100M_BMC_NODE1_DP")
	)
	(segment
		(start 122.411236 -120.884442)
		(end 121.949972 -120.423178)
		(width 0.127)
		(layer "F.Cu")
		(net "CLK_100M_BMC_NODE1_DP")
	)
	(segment
		(start 129.403856 -119.714518)
		(end 128.726438 -119.714518)
		(width 0.127)
		(layer "F.Cu")
		(net "CLK_100M_BMC_NODE1_DP")
	)
	(segment
		(start 69.023484 -124.11456)
		(end 69.023484 -123.73356)
		(width 0.127)
		(layer "F.Cu")
		(net "CLK_100M_BMC_NODE1_DP")
	)
	(via
		(at 121.949972 -120.423178)
		(size 0.508)
		(drill 0.254)
		(layers "F.Cu" "B.Cu")
		(net "CLK_100M_BMC_NODE1_DP")
	)
	(via
		(at 73.042018 -118.782846)
		(size 0.508)
		(drill 0.254)
		(layers "F.Cu" "B.Cu")
		(net "CLK_100M_BMC_NODE1_DP")
	)
	(segment
		(start 121.80316 -120.912128)
		(end 121.949972 -120.765316)
		(width 0.127)
		(layer "In7.Cu")
		(net "CLK_100M_BMC_NODE1_DP")
	)
	(segment
		(start 100.737162 -111.151416)
		(end 118.206266 -111.151416)
		(width 0.127)
		(layer "In7.Cu")
		(net "CLK_100M_BMC_NODE1_DP")
	)
	(segment
		(start 77.432662 -116.75872)
		(end 80.86471 -116.75872)
		(width 0.127)
		(layer "In7.Cu")
		(net "CLK_100M_BMC_NODE1_DP")
	)
	(segment
		(start 121.27484 -114.21999)
		(end 121.27484 -115.174776)
		(width 0.127)
		(layer "In7.Cu")
		(net "CLK_100M_BMC_NODE1_DP")
	)
	(segment
		(start 86.580726 -112.208818)
		(end 92.314776 -112.208818)
		(width 0.127)
		(layer "In7.Cu")
		(net "CLK_100M_BMC_NODE1_DP")
	)
	(segment
		(start 120.53316 -120.337326)
		(end 121.107962 -120.912128)
		(width 0.127)
		(layer "In7.Cu")
		(net "CLK_100M_BMC_NODE1_DP")
	)
	(segment
		(start 99.582986 -112.305592)
		(end 100.737162 -111.151416)
		(width 0.127)
		(layer "In7.Cu")
		(net "CLK_100M_BMC_NODE1_DP")
	)
	(segment
		(start 121.949972 -120.765316)
		(end 121.949972 -120.423178)
		(width 0.127)
		(layer "In7.Cu")
		(net "CLK_100M_BMC_NODE1_DP")
	)
	(segment
		(start 73.042018 -118.782846)
		(end 73.275952 -119.01678)
		(width 0.127)
		(layer "In7.Cu")
		(net "CLK_100M_BMC_NODE1_DP")
	)
	(segment
		(start 81.783174 -117.00637)
		(end 86.580726 -112.208818)
		(width 0.127)
		(layer "In7.Cu")
		(net "CLK_100M_BMC_NODE1_DP")
	)
	(segment
		(start 121.107962 -120.912128)
		(end 121.80316 -120.912128)
		(width 0.127)
		(layer "In7.Cu")
		(net "CLK_100M_BMC_NODE1_DP")
	)
	(segment
		(start 80.86471 -116.75872)
		(end 81.11236 -117.00637)
		(width 0.127)
		(layer "In7.Cu")
		(net "CLK_100M_BMC_NODE1_DP")
	)
	(segment
		(start 73.275952 -119.01678)
		(end 75.174602 -119.01678)
		(width 0.127)
		(layer "In7.Cu")
		(net "CLK_100M_BMC_NODE1_DP")
	)
	(segment
		(start 118.206266 -111.151416)
		(end 121.27484 -114.21999)
		(width 0.127)
		(layer "In7.Cu")
		(net "CLK_100M_BMC_NODE1_DP")
	)
	(segment
		(start 75.174602 -119.01678)
		(end 77.432662 -116.75872)
		(width 0.127)
		(layer "In7.Cu")
		(net "CLK_100M_BMC_NODE1_DP")
	)
	(segment
		(start 92.314776 -112.208818)
		(end 92.41155 -112.305592)
		(width 0.127)
		(layer "In7.Cu")
		(net "CLK_100M_BMC_NODE1_DP")
	)
	(segment
		(start 121.27484 -115.174776)
		(end 120.53316 -115.916456)
		(width 0.127)
		(layer "In7.Cu")
		(net "CLK_100M_BMC_NODE1_DP")
	)
	(segment
		(start 92.41155 -112.305592)
		(end 99.582986 -112.305592)
		(width 0.127)
		(layer "In7.Cu")
		(net "CLK_100M_BMC_NODE1_DP")
	)
	(segment
		(start 120.53316 -115.916456)
		(end 120.53316 -120.337326)
		(width 0.127)
		(layer "In7.Cu")
		(net "CLK_100M_BMC_NODE1_DP")
	)
	(segment
		(start 81.11236 -117.00637)
		(end 81.783174 -117.00637)
		(width 0.127)
		(layer "In7.Cu")
		(net "CLK_100M_BMC_NODE1_DP")
	)
	(segment
		(start 52.799996 -71.798942)
		(end 52.399946 -71.398892)
		(width 0.3048)
		(layer "F.Cu")
		(net "A_NODE1_RP0_RCOMP")
	)
	(via
		(at 52.399946 -71.398892)
		(size 0.508)
		(drill 0.254)
		(layers "F.Cu" "B.Cu")
		(net "A_NODE1_RP0_RCOMP")
	)
	(via
		(at 50.2539 -69.257164)
		(size 0.6604)
		(drill 0.3302)
		(layers "F.Cu" "B.Cu")
		(net "A_NODE1_RP0_RCOMP")
	)
	(segment
		(start 52.249832 -70.512686)
		(end 52.249832 -69.656452)
		(width 0.1016)
		(layer "B.Cu")
		(net "A_NODE1_RP0_RCOMP")
	)
	(segment
		(start 52.249832 -69.656452)
		(end 51.761898 -69.168518)
		(width 0.1016)
		(layer "B.Cu")
		(net "A_NODE1_RP0_RCOMP")
	)
	(segment
		(start 51.761898 -69.168518)
		(end 50.342546 -69.168518)
		(width 0.1016)
		(layer "B.Cu")
		(net "A_NODE1_RP0_RCOMP")
	)
	(segment
		(start 50.342546 -69.168518)
		(end 50.2539 -69.257164)
		(width 0.1016)
		(layer "B.Cu")
		(net "A_NODE1_RP0_RCOMP")
	)
	(segment
		(start 52.249832 -71.248778)
		(end 52.249832 -70.512686)
		(width 0.381)
		(layer "B.Cu")
		(net "A_NODE1_RP0_RCOMP")
	)
	(segment
		(start 52.399946 -71.398892)
		(end 52.249832 -71.248778)
		(width 0.381)
		(layer "B.Cu")
		(net "A_NODE1_RP0_RCOMP")
	)
	(segment
		(start 53.797962 -68.503038)
		(end 53.790342 -68.503038)
		(width 0.1016)
		(layer "F.Cu")
		(net "M1_DQ_NODE1_DQ21")
	)
	(segment
		(start 52.225194 -31.148274)
		(end 52.650136 -30.723332)
		(width 0.1651)
		(layer "F.Cu")
		(net "M1_DQ_NODE1_DQ21")
	)
	(segment
		(start 53.790342 -68.503038)
		(end 53.416962 -68.129658)
		(width 0.1016)
		(layer "F.Cu")
		(net "M1_DQ_NODE1_DQ21")
	)
	(segment
		(start 52.650136 -30.723332)
		(end 52.650136 -29.149802)
		(width 0.1651)
		(layer "F.Cu")
		(net "M1_DQ_NODE1_DQ21")
	)
	(segment
		(start 49.393602 -31.148274)
		(end 52.225194 -31.148274)
		(width 0.1651)
		(layer "F.Cu")
		(net "M1_DQ_NODE1_DQ21")
	)
	(via
		(at 53.416962 -68.129658)
		(size 0.508)
		(drill 0.254)
		(layers "F.Cu" "B.Cu")
		(net "M1_DQ_NODE1_DQ21")
	)
	(via
		(at 49.393602 -31.148274)
		(size 0.508)
		(drill 0.254)
		(layers "F.Cu" "B.Cu")
		(net "M1_DQ_NODE1_DQ21")
	)
	(segment
		(start 39.9161 -48.618648)
		(end 39.70782 -48.826928)
		(width 0.2032)
		(layer "In7.Cu")
		(net "M1_DQ_NODE1_DQ21")
	)
	(segment
		(start 39.70782 -47.699168)
		(end 39.9161 -47.907448)
		(width 0.2032)
		(layer "In7.Cu")
		(net "M1_DQ_NODE1_DQ21")
	)
	(segment
		(start 49.11852 -32.28213)
		(end 49.46142 -32.28213)
		(width 0.2032)
		(layer "In7.Cu")
		(net "M1_DQ_NODE1_DQ21")
	)
	(segment
		(start 39.9161 -47.907448)
		(end 40.82034 -47.907448)
		(width 0.2032)
		(layer "In7.Cu")
		(net "M1_DQ_NODE1_DQ21")
	)
	(segment
		(start 41.824148 -50.553366)
		(end 42.032428 -50.761646)
		(width 0.2032)
		(layer "In7.Cu")
		(net "M1_DQ_NODE1_DQ21")
	)
	(segment
		(start 49.46142 -32.28213)
		(end 49.6697 -32.49041)
		(width 0.2032)
		(layer "In7.Cu")
		(net "M1_DQ_NODE1_DQ21")
	)
	(segment
		(start 49.11852 -32.99333)
		(end 48.91024 -33.20161)
		(width 0.2032)
		(layer "In7.Cu")
		(net "M1_DQ_NODE1_DQ21")
	)
	(segment
		(start 52.416964 -64.770762)
		(end 52.416964 -65.839086)
		(width 0.1016)
		(layer "In7.Cu")
		(net "M1_DQ_NODE1_DQ21")
	)
	(segment
		(start 40.82034 -47.907448)
		(end 41.02862 -48.115728)
		(width 0.2032)
		(layer "In7.Cu")
		(net "M1_DQ_NODE1_DQ21")
	)
	(segment
		(start 52.416964 -65.839086)
		(end 52.65674 -66.078862)
		(width 0.1016)
		(layer "In7.Cu")
		(net "M1_DQ_NODE1_DQ21")
	)
	(segment
		(start 53.409596 -68.129658)
		(end 53.416962 -68.129658)
		(width 0.1016)
		(layer "In7.Cu")
		(net "M1_DQ_NODE1_DQ21")
	)
	(segment
		(start 49.393602 -31.148274)
		(end 49.173384 -31.148274)
		(width 0.2032)
		(layer "In7.Cu")
		(net "M1_DQ_NODE1_DQ21")
	)
	(segment
		(start 40.82034 -48.618648)
		(end 39.9161 -48.618648)
		(width 0.2032)
		(layer "In7.Cu")
		(net "M1_DQ_NODE1_DQ21")
	)
	(segment
		(start 52.54752 -67.267582)
		(end 52.54752 -67.780916)
		(width 0.1016)
		(layer "In7.Cu")
		(net "M1_DQ_NODE1_DQ21")
	)
	(segment
		(start 51.06162 -60.156344)
		(end 51.06162 -62.027308)
		(width 0.2032)
		(layer "In7.Cu")
		(net "M1_DQ_NODE1_DQ21")
	)
	(segment
		(start 41.02862 -48.410368)
		(end 40.82034 -48.618648)
		(width 0.2032)
		(layer "In7.Cu")
		(net "M1_DQ_NODE1_DQ21")
	)
	(segment
		(start 40.505888 -51.656996)
		(end 41.112948 -51.656996)
		(width 0.2032)
		(layer "In7.Cu")
		(net "M1_DQ_NODE1_DQ21")
	)
	(segment
		(start 51.886358 -64.240156)
		(end 52.416964 -64.770762)
		(width 0.1016)
		(layer "In7.Cu")
		(net "M1_DQ_NODE1_DQ21")
	)
	(segment
		(start 39.70782 -49.121568)
		(end 39.9161 -49.329848)
		(width 0.2032)
		(layer "In7.Cu")
		(net "M1_DQ_NODE1_DQ21")
	)
	(segment
		(start 41.02862 -49.832768)
		(end 40.82034 -50.041048)
		(width 0.2032)
		(layer "In7.Cu")
		(net "M1_DQ_NODE1_DQ21")
	)
	(segment
		(start 52.687474 -67.92087)
		(end 53.200808 -67.92087)
		(width 0.1016)
		(layer "In7.Cu")
		(net "M1_DQ_NODE1_DQ21")
	)
	(segment
		(start 51.062128 -62.687962)
		(end 51.886358 -63.512192)
		(width 0.1016)
		(layer "In7.Cu")
		(net "M1_DQ_NODE1_DQ21")
	)
	(segment
		(start 52.65674 -66.344292)
		(end 52.416964 -66.584068)
		(width 0.1016)
		(layer "In7.Cu")
		(net "M1_DQ_NODE1_DQ21")
	)
	(segment
		(start 52.65674 -66.078862)
		(end 52.65674 -66.344292)
		(width 0.1016)
		(layer "In7.Cu")
		(net "M1_DQ_NODE1_DQ21")
	)
	(segment
		(start 49.6697 -32.49041)
		(end 49.6697 -32.78505)
		(width 0.2032)
		(layer "In7.Cu")
		(net "M1_DQ_NODE1_DQ21")
	)
	(segment
		(start 52.416964 -66.584068)
		(end 52.416964 -67.137026)
		(width 0.1016)
		(layer "In7.Cu")
		(net "M1_DQ_NODE1_DQ21")
	)
	(segment
		(start 42.032428 -51.448716)
		(end 42.240708 -51.656996)
		(width 0.2032)
		(layer "In7.Cu")
		(net "M1_DQ_NODE1_DQ21")
	)
	(segment
		(start 49.75352 -58.222388)
		(end 49.75352 -59.192414)
		(width 0.2032)
		(layer "In7.Cu")
		(net "M1_DQ_NODE1_DQ21")
	)
	(segment
		(start 53.200808 -67.92087)
		(end 53.409596 -68.129658)
		(width 0.1016)
		(layer "In7.Cu")
		(net "M1_DQ_NODE1_DQ21")
	)
	(segment
		(start 40.82034 -49.329848)
		(end 41.02862 -49.538128)
		(width 0.2032)
		(layer "In7.Cu")
		(net "M1_DQ_NODE1_DQ21")
	)
	(segment
		(start 52.416964 -67.137026)
		(end 52.54752 -67.267582)
		(width 0.1016)
		(layer "In7.Cu")
		(net "M1_DQ_NODE1_DQ21")
	)
	(segment
		(start 49.46142 -32.99333)
		(end 49.11852 -32.99333)
		(width 0.2032)
		(layer "In7.Cu")
		(net "M1_DQ_NODE1_DQ21")
	)
	(segment
		(start 41.112948 -51.656996)
		(end 41.321228 -51.448716)
		(width 0.2032)
		(layer "In7.Cu")
		(net "M1_DQ_NODE1_DQ21")
	)
	(segment
		(start 39.9161 -50.041048)
		(end 39.70782 -50.249328)
		(width 0.2032)
		(layer "In7.Cu")
		(net "M1_DQ_NODE1_DQ21")
	)
	(segment
		(start 39.70782 -43.104054)
		(end 39.70782 -47.699168)
		(width 0.2032)
		(layer "In7.Cu")
		(net "M1_DQ_NODE1_DQ21")
	)
	(segment
		(start 50.238406 -59.6773)
		(end 50.582576 -59.6773)
		(width 0.2032)
		(layer "In7.Cu")
		(net "M1_DQ_NODE1_DQ21")
	)
	(segment
		(start 40.82034 -50.041048)
		(end 39.9161 -50.041048)
		(width 0.2032)
		(layer "In7.Cu")
		(net "M1_DQ_NODE1_DQ21")
	)
	(segment
		(start 51.062128 -62.027308)
		(end 51.062128 -62.687962)
		(width 0.1016)
		(layer "In7.Cu")
		(net "M1_DQ_NODE1_DQ21")
	)
	(segment
		(start 49.173384 -31.148274)
		(end 48.91024 -31.411418)
		(width 0.2032)
		(layer "In7.Cu")
		(net "M1_DQ_NODE1_DQ21")
	)
	(segment
		(start 48.91024 -31.411418)
		(end 48.91024 -32.07385)
		(width 0.2032)
		(layer "In7.Cu")
		(net "M1_DQ_NODE1_DQ21")
	)
	(segment
		(start 39.70782 -50.858928)
		(end 40.505888 -51.656996)
		(width 0.2032)
		(layer "In7.Cu")
		(net "M1_DQ_NODE1_DQ21")
	)
	(segment
		(start 49.6697 -32.78505)
		(end 49.46142 -32.99333)
		(width 0.2032)
		(layer "In7.Cu")
		(net "M1_DQ_NODE1_DQ21")
	)
	(segment
		(start 48.91024 -33.20161)
		(end 48.91024 -33.901634)
		(width 0.2032)
		(layer "In7.Cu")
		(net "M1_DQ_NODE1_DQ21")
	)
	(segment
		(start 41.321228 -51.448716)
		(end 41.321228 -50.761646)
		(width 0.2032)
		(layer "In7.Cu")
		(net "M1_DQ_NODE1_DQ21")
	)
	(segment
		(start 48.91024 -33.901634)
		(end 39.70782 -43.104054)
		(width 0.2032)
		(layer "In7.Cu")
		(net "M1_DQ_NODE1_DQ21")
	)
	(segment
		(start 39.70782 -50.249328)
		(end 39.70782 -50.858928)
		(width 0.2032)
		(layer "In7.Cu")
		(net "M1_DQ_NODE1_DQ21")
	)
	(segment
		(start 48.91024 -32.07385)
		(end 49.11852 -32.28213)
		(width 0.2032)
		(layer "In7.Cu")
		(net "M1_DQ_NODE1_DQ21")
	)
	(segment
		(start 42.032428 -50.761646)
		(end 42.032428 -51.448716)
		(width 0.2032)
		(layer "In7.Cu")
		(net "M1_DQ_NODE1_DQ21")
	)
	(segment
		(start 39.70782 -48.826928)
		(end 39.70782 -49.121568)
		(width 0.2032)
		(layer "In7.Cu")
		(net "M1_DQ_NODE1_DQ21")
	)
	(segment
		(start 41.529508 -50.553366)
		(end 41.824148 -50.553366)
		(width 0.2032)
		(layer "In7.Cu")
		(net "M1_DQ_NODE1_DQ21")
	)
	(segment
		(start 41.02862 -48.115728)
		(end 41.02862 -48.410368)
		(width 0.2032)
		(layer "In7.Cu")
		(net "M1_DQ_NODE1_DQ21")
	)
	(segment
		(start 39.9161 -49.329848)
		(end 40.82034 -49.329848)
		(width 0.2032)
		(layer "In7.Cu")
		(net "M1_DQ_NODE1_DQ21")
	)
	(segment
		(start 51.886358 -63.512192)
		(end 51.886358 -64.240156)
		(width 0.1016)
		(layer "In7.Cu")
		(net "M1_DQ_NODE1_DQ21")
	)
	(segment
		(start 41.02862 -49.538128)
		(end 41.02862 -49.832768)
		(width 0.2032)
		(layer "In7.Cu")
		(net "M1_DQ_NODE1_DQ21")
	)
	(segment
		(start 43.188128 -51.656996)
		(end 49.75352 -58.222388)
		(width 0.2032)
		(layer "In7.Cu")
		(net "M1_DQ_NODE1_DQ21")
	)
	(segment
		(start 49.75352 -59.192414)
		(end 50.238406 -59.6773)
		(width 0.2032)
		(layer "In7.Cu")
		(net "M1_DQ_NODE1_DQ21")
	)
	(segment
		(start 42.240708 -51.656996)
		(end 43.188128 -51.656996)
		(width 0.2032)
		(layer "In7.Cu")
		(net "M1_DQ_NODE1_DQ21")
	)
	(segment
		(start 41.321228 -50.761646)
		(end 41.529508 -50.553366)
		(width 0.2032)
		(layer "In7.Cu")
		(net "M1_DQ_NODE1_DQ21")
	)
	(segment
		(start 52.54752 -67.780916)
		(end 52.687474 -67.92087)
		(width 0.1016)
		(layer "In7.Cu")
		(net "M1_DQ_NODE1_DQ21")
	)
	(segment
		(start 51.06162 -62.027308)
		(end 51.062128 -62.027308)
		(width 0.2032)
		(layer "In7.Cu")
		(net "M1_DQ_NODE1_DQ21")
	)
	(segment
		(start 50.582576 -59.6773)
		(end 51.06162 -60.156344)
		(width 0.2032)
		(layer "In7.Cu")
		(net "M1_DQ_NODE1_DQ21")
	)
	(segment
		(start 129.403856 -118.914672)
		(end 128.993646 -118.914672)
		(width 0.127)
		(layer "F.Cu")
		(net "CLK_100M_XDP_NODE1_DN")
	)
	(segment
		(start 122.77852 -118.37289)
		(end 122.65152 -118.49989)
		(width 0.127)
		(layer "F.Cu")
		(net "CLK_100M_XDP_NODE1_DN")
	)
	(segment
		(start 122.65152 -118.49989)
		(end 122.65152 -118.85549)
		(width 0.127)
		(layer "F.Cu")
		(net "CLK_100M_XDP_NODE1_DN")
	)
	(segment
		(start 124.125482 -118.37289)
		(end 122.77852 -118.37289)
		(width 0.127)
		(layer "F.Cu")
		(net "CLK_100M_XDP_NODE1_DN")
	)
	(segment
		(start 110.460028 -66.406268)
		(end 111.785908 -66.406268)
		(width 0.127)
		(layer "F.Cu")
		(net "CLK_100M_XDP_NODE1_DN")
	)
	(segment
		(start 111.896398 -66.516758)
		(end 112.238536 -66.516758)
		(width 0.127)
		(layer "F.Cu")
		(net "CLK_100M_XDP_NODE1_DN")
	)
	(segment
		(start 113.189512 -67.467734)
		(end 113.189512 -68.150994)
		(width 0.127)
		(layer "F.Cu")
		(net "CLK_100M_XDP_NODE1_DN")
	)
	(segment
		(start 113.189512 -68.150994)
		(end 113.369852 -68.331334)
		(width 0.127)
		(layer "F.Cu")
		(net "CLK_100M_XDP_NODE1_DN")
	)
	(segment
		(start 127.51816 -118.598442)
		(end 124.351034 -118.598442)
		(width 0.127)
		(layer "F.Cu")
		(net "CLK_100M_XDP_NODE1_DN")
	)
	(segment
		(start 124.351034 -118.598442)
		(end 124.125482 -118.37289)
		(width 0.127)
		(layer "F.Cu")
		(net "CLK_100M_XDP_NODE1_DN")
	)
	(segment
		(start 113.369852 -68.331334)
		(end 114.13744 -68.331334)
		(width 0.127)
		(layer "F.Cu")
		(net "CLK_100M_XDP_NODE1_DN")
	)
	(segment
		(start 112.238536 -66.516758)
		(end 113.189512 -67.467734)
		(width 0.127)
		(layer "F.Cu")
		(net "CLK_100M_XDP_NODE1_DN")
	)
	(segment
		(start 114.13744 -68.331334)
		(end 114.26444 -68.204334)
		(width 0.127)
		(layer "F.Cu")
		(net "CLK_100M_XDP_NODE1_DN")
	)
	(segment
		(start 128.956816 -118.877842)
		(end 127.79756 -118.877842)
		(width 0.127)
		(layer "F.Cu")
		(net "CLK_100M_XDP_NODE1_DN")
	)
	(segment
		(start 127.79756 -118.877842)
		(end 127.51816 -118.598442)
		(width 0.127)
		(layer "F.Cu")
		(net "CLK_100M_XDP_NODE1_DN")
	)
	(segment
		(start 114.26444 -68.204334)
		(end 114.26444 -67.848734)
		(width 0.127)
		(layer "F.Cu")
		(net "CLK_100M_XDP_NODE1_DN")
	)
	(segment
		(start 111.785908 -66.406268)
		(end 111.896398 -66.516758)
		(width 0.127)
		(layer "F.Cu")
		(net "CLK_100M_XDP_NODE1_DN")
	)
	(segment
		(start 128.993646 -118.914672)
		(end 128.956816 -118.877842)
		(width 0.127)
		(layer "F.Cu")
		(net "CLK_100M_XDP_NODE1_DN")
	)
	(via
		(at 114.26444 -67.848734)
		(size 0.508)
		(drill 0.254)
		(layers "F.Cu" "B.Cu")
		(net "CLK_100M_XDP_NODE1_DN")
	)
	(via
		(at 122.65152 -118.85549)
		(size 0.508)
		(drill 0.254)
		(layers "F.Cu" "B.Cu")
		(net "CLK_100M_XDP_NODE1_DN")
	)
	(segment
		(start 124.8029 -101.439726)
		(end 124.8029 -108.878116)
		(width 0.127)
		(layer "B.Cu")
		(net "CLK_100M_XDP_NODE1_DN")
	)
	(segment
		(start 118.37162 -95.008446)
		(end 124.8029 -101.439726)
		(width 0.127)
		(layer "B.Cu")
		(net "CLK_100M_XDP_NODE1_DN")
	)
	(segment
		(start 123.449588 -118.37289)
		(end 122.77852 -118.37289)
		(width 0.127)
		(layer "B.Cu")
		(net "CLK_100M_XDP_NODE1_DN")
	)
	(segment
		(start 115.780566 -68.331334)
		(end 117.31244 -69.863208)
		(width 0.127)
		(layer "B.Cu")
		(net "CLK_100M_XDP_NODE1_DN")
	)
	(segment
		(start 117.31244 -69.863208)
		(end 117.31244 -80.36052)
		(width 0.127)
		(layer "B.Cu")
		(net "CLK_100M_XDP_NODE1_DN")
	)
	(segment
		(start 117.31244 -80.36052)
		(end 118.37162 -81.4197)
		(width 0.127)
		(layer "B.Cu")
		(net "CLK_100M_XDP_NODE1_DN")
	)
	(segment
		(start 114.26444 -68.204334)
		(end 114.39144 -68.331334)
		(width 0.127)
		(layer "B.Cu")
		(net "CLK_100M_XDP_NODE1_DN")
	)
	(segment
		(start 122.65152 -118.49989)
		(end 122.65152 -118.85549)
		(width 0.127)
		(layer "B.Cu")
		(net "CLK_100M_XDP_NODE1_DN")
	)
	(segment
		(start 124.194316 -109.4867)
		(end 124.194316 -117.628162)
		(width 0.127)
		(layer "B.Cu")
		(net "CLK_100M_XDP_NODE1_DN")
	)
	(segment
		(start 114.39144 -68.331334)
		(end 115.780566 -68.331334)
		(width 0.127)
		(layer "B.Cu")
		(net "CLK_100M_XDP_NODE1_DN")
	)
	(segment
		(start 124.194316 -117.628162)
		(end 123.449588 -118.37289)
		(width 0.127)
		(layer "B.Cu")
		(net "CLK_100M_XDP_NODE1_DN")
	)
	(segment
		(start 122.77852 -118.37289)
		(end 122.65152 -118.49989)
		(width 0.127)
		(layer "B.Cu")
		(net "CLK_100M_XDP_NODE1_DN")
	)
	(segment
		(start 118.37162 -81.4197)
		(end 118.37162 -95.008446)
		(width 0.127)
		(layer "B.Cu")
		(net "CLK_100M_XDP_NODE1_DN")
	)
	(segment
		(start 114.26444 -67.848734)
		(end 114.26444 -68.204334)
		(width 0.127)
		(layer "B.Cu")
		(net "CLK_100M_XDP_NODE1_DN")
	)
	(segment
		(start 124.8029 -108.878116)
		(end 124.194316 -109.4867)
		(width 0.127)
		(layer "B.Cu")
		(net "CLK_100M_XDP_NODE1_DN")
	)
	(segment
		(start 70.404482 -63.266066)
		(end 70.404482 -63.556642)
		(width 0.1016)
		(layer "F.Cu")
		(net "M1_DQ_NODE1_DQ33")
	)
	(segment
		(start 69.848222 -62.709806)
		(end 70.404482 -63.266066)
		(width 0.1016)
		(layer "F.Cu")
		(net "M1_DQ_NODE1_DQ33")
	)
	(segment
		(start 69.24548 -60.617862)
		(end 69.848222 -61.220604)
		(width 0.1016)
		(layer "F.Cu")
		(net "M1_DQ_NODE1_DQ33")
	)
	(segment
		(start 82.950304 -23.190454)
		(end 82.950304 -20.94992)
		(width 0.1651)
		(layer "F.Cu")
		(net "M1_DQ_NODE1_DQ33")
	)
	(segment
		(start 82.64144 -23.499318)
		(end 82.950304 -23.190454)
		(width 0.1651)
		(layer "F.Cu")
		(net "M1_DQ_NODE1_DQ33")
	)
	(segment
		(start 69.848222 -61.220604)
		(end 69.848222 -62.709806)
		(width 0.1016)
		(layer "F.Cu")
		(net "M1_DQ_NODE1_DQ33")
	)
	(via
		(at 82.64144 -23.499318)
		(size 0.508)
		(drill 0.254)
		(layers "F.Cu" "B.Cu")
		(net "M1_DQ_NODE1_DQ33")
	)
	(via
		(at 69.24548 -60.617862)
		(size 0.508)
		(drill 0.254)
		(layers "F.Cu" "B.Cu")
		(net "M1_DQ_NODE1_DQ33")
	)
	(segment
		(start 79.168244 -33.37814)
		(end 78.415134 -33.37814)
		(width 0.2032)
		(layer "In7.Cu")
		(net "M1_DQ_NODE1_DQ33")
	)
	(segment
		(start 79.376524 -33.16986)
		(end 79.168244 -33.37814)
		(width 0.2032)
		(layer "In7.Cu")
		(net "M1_DQ_NODE1_DQ33")
	)
	(segment
		(start 71.821802 -37.603938)
		(end 70.616064 -38.809676)
		(width 0.2032)
		(layer "In7.Cu")
		(net "M1_DQ_NODE1_DQ33")
	)
	(segment
		(start 82.68716 -23.545038)
		(end 82.68716 -24.341074)
		(width 0.2032)
		(layer "In7.Cu")
		(net "M1_DQ_NODE1_DQ33")
	)
	(segment
		(start 79.83474 -27.718004)
		(end 78.93558 -27.718004)
		(width 0.2032)
		(layer "In7.Cu")
		(net "M1_DQ_NODE1_DQ33")
	)
	(segment
		(start 78.93558 -27.718004)
		(end 78.27264 -28.380944)
		(width 0.2032)
		(layer "In7.Cu")
		(net "M1_DQ_NODE1_DQ33")
	)
	(segment
		(start 82.050382 -24.977852)
		(end 82.050382 -25.502362)
		(width 0.2032)
		(layer "In7.Cu")
		(net "M1_DQ_NODE1_DQ33")
	)
	(segment
		(start 82.050382 -25.502362)
		(end 79.83474 -27.718004)
		(width 0.2032)
		(layer "In7.Cu")
		(net "M1_DQ_NODE1_DQ33")
	)
	(segment
		(start 71.621904 -38.809676)
		(end 72.324722 -38.106858)
		(width 0.2032)
		(layer "In7.Cu")
		(net "M1_DQ_NODE1_DQ33")
	)
	(segment
		(start 68.04406 -58.302144)
		(end 69.08546 -59.343544)
		(width 0.2032)
		(layer "In7.Cu")
		(net "M1_DQ_NODE1_DQ33")
	)
	(segment
		(start 78.415134 -34.08934)
		(end 79.168244 -34.08934)
		(width 0.2032)
		(layer "In7.Cu")
		(net "M1_DQ_NODE1_DQ33")
	)
	(segment
		(start 78.206854 -33.58642)
		(end 78.206854 -33.88106)
		(width 0.2032)
		(layer "In7.Cu")
		(net "M1_DQ_NODE1_DQ33")
	)
	(segment
		(start 79.376524 -35.350196)
		(end 79.168244 -35.558476)
		(width 0.2032)
		(layer "In7.Cu")
		(net "M1_DQ_NODE1_DQ33")
	)
	(segment
		(start 78.415134 -33.37814)
		(end 78.206854 -33.58642)
		(width 0.2032)
		(layer "In7.Cu")
		(net "M1_DQ_NODE1_DQ33")
	)
	(segment
		(start 72.324722 -38.106858)
		(end 72.324722 -37.812218)
		(width 0.2032)
		(layer "In7.Cu")
		(net "M1_DQ_NODE1_DQ33")
	)
	(segment
		(start 72.116442 -37.603938)
		(end 71.821802 -37.603938)
		(width 0.2032)
		(layer "In7.Cu")
		(net "M1_DQ_NODE1_DQ33")
	)
	(segment
		(start 69.08546 -59.82208)
		(end 69.24548 -59.9821)
		(width 0.2032)
		(layer "In7.Cu")
		(net "M1_DQ_NODE1_DQ33")
	)
	(segment
		(start 78.206854 -33.88106)
		(end 78.415134 -34.08934)
		(width 0.2032)
		(layer "In7.Cu")
		(net "M1_DQ_NODE1_DQ33")
	)
	(segment
		(start 70.616064 -39.104316)
		(end 71.327264 -39.815516)
		(width 0.2032)
		(layer "In7.Cu")
		(net "M1_DQ_NODE1_DQ33")
	)
	(segment
		(start 69.24548 -59.9821)
		(end 69.24548 -60.617862)
		(width 0.2032)
		(layer "In7.Cu")
		(net "M1_DQ_NODE1_DQ33")
	)
	(segment
		(start 82.64144 -23.499318)
		(end 82.68716 -23.545038)
		(width 0.2032)
		(layer "In7.Cu")
		(net "M1_DQ_NODE1_DQ33")
	)
	(segment
		(start 79.168244 -35.558476)
		(end 75.878944 -35.558476)
		(width 0.2032)
		(layer "In7.Cu")
		(net "M1_DQ_NODE1_DQ33")
	)
	(segment
		(start 69.08546 -59.343544)
		(end 69.08546 -59.82208)
		(width 0.2032)
		(layer "In7.Cu")
		(net "M1_DQ_NODE1_DQ33")
	)
	(segment
		(start 71.327264 -39.815516)
		(end 71.327264 -40.110156)
		(width 0.2032)
		(layer "In7.Cu")
		(net "M1_DQ_NODE1_DQ33")
	)
	(segment
		(start 78.27264 -28.380944)
		(end 78.27264 -31.324042)
		(width 0.2032)
		(layer "In7.Cu")
		(net "M1_DQ_NODE1_DQ33")
	)
	(segment
		(start 78.27264 -31.324042)
		(end 79.376524 -32.427926)
		(width 0.2032)
		(layer "In7.Cu")
		(net "M1_DQ_NODE1_DQ33")
	)
	(segment
		(start 79.376524 -32.427926)
		(end 79.376524 -33.16986)
		(width 0.2032)
		(layer "In7.Cu")
		(net "M1_DQ_NODE1_DQ33")
	)
	(segment
		(start 72.324722 -37.812218)
		(end 72.116442 -37.603938)
		(width 0.2032)
		(layer "In7.Cu")
		(net "M1_DQ_NODE1_DQ33")
	)
	(segment
		(start 75.878944 -35.558476)
		(end 72.124824 -39.312596)
		(width 0.2032)
		(layer "In7.Cu")
		(net "M1_DQ_NODE1_DQ33")
	)
	(segment
		(start 79.376524 -34.29762)
		(end 79.376524 -35.350196)
		(width 0.2032)
		(layer "In7.Cu")
		(net "M1_DQ_NODE1_DQ33")
	)
	(segment
		(start 68.04406 -43.39336)
		(end 68.04406 -58.302144)
		(width 0.2032)
		(layer "In7.Cu")
		(net "M1_DQ_NODE1_DQ33")
	)
	(segment
		(start 70.616064 -38.809676)
		(end 70.616064 -39.104316)
		(width 0.2032)
		(layer "In7.Cu")
		(net "M1_DQ_NODE1_DQ33")
	)
	(segment
		(start 72.124824 -39.312596)
		(end 71.830184 -39.312596)
		(width 0.2032)
		(layer "In7.Cu")
		(net "M1_DQ_NODE1_DQ33")
	)
	(segment
		(start 79.168244 -34.08934)
		(end 79.376524 -34.29762)
		(width 0.2032)
		(layer "In7.Cu")
		(net "M1_DQ_NODE1_DQ33")
	)
	(segment
		(start 82.68716 -24.341074)
		(end 82.050382 -24.977852)
		(width 0.2032)
		(layer "In7.Cu")
		(net "M1_DQ_NODE1_DQ33")
	)
	(segment
		(start 71.621904 -39.104316)
		(end 71.621904 -38.809676)
		(width 0.2032)
		(layer "In7.Cu")
		(net "M1_DQ_NODE1_DQ33")
	)
	(segment
		(start 71.327264 -40.110156)
		(end 68.04406 -43.39336)
		(width 0.2032)
		(layer "In7.Cu")
		(net "M1_DQ_NODE1_DQ33")
	)
	(segment
		(start 71.830184 -39.312596)
		(end 71.621904 -39.104316)
		(width 0.2032)
		(layer "In7.Cu")
		(net "M1_DQ_NODE1_DQ33")
	)
	(segment
		(start 67.050158 -27.544014)
		(end 66.668142 -27.161998)
		(width 0.1651)
		(layer "F.Cu")
		(net "M_DDR3_NODE1_ECC7")
	)
	(segment
		(start 66.069972 -66.582798)
		(end 66.057272 -66.595498)
		(width 0.1016)
		(layer "F.Cu")
		(net "M_DDR3_NODE1_ECC7")
	)
	(segment
		(start 65.891664 -64.718946)
		(end 66.069972 -64.897254)
		(width 0.1016)
		(layer "F.Cu")
		(net "M_DDR3_NODE1_ECC7")
	)
	(segment
		(start 66.069972 -64.897254)
		(end 66.069972 -66.582798)
		(width 0.1016)
		(layer "F.Cu")
		(net "M_DDR3_NODE1_ECC7")
	)
	(segment
		(start 67.050158 -29.149802)
		(end 67.050158 -27.544014)
		(width 0.1651)
		(layer "F.Cu")
		(net "M_DDR3_NODE1_ECC7")
	)
	(via
		(at 66.057272 -66.595498)
		(size 0.508)
		(drill 0.254)
		(layers "F.Cu" "B.Cu")
		(net "M_DDR3_NODE1_ECC7")
	)
	(via
		(at 66.668142 -27.161998)
		(size 0.508)
		(drill 0.254)
		(layers "F.Cu" "B.Cu")
		(net "M_DDR3_NODE1_ECC7")
	)
	(segment
		(start 65.97396 -35.01771)
		(end 65.77076 -34.81451)
		(width 0.2032)
		(layer "In7.Cu")
		(net "M_DDR3_NODE1_ECC7")
	)
	(segment
		(start 62.56274 -51.600608)
		(end 62.35446 -51.392328)
		(width 0.2032)
		(layer "In7.Cu")
		(net "M_DDR3_NODE1_ECC7")
	)
	(segment
		(start 66.057272 -66.595498)
		(end 66.196464 -66.456306)
		(width 0.1016)
		(layer "In7.Cu")
		(net "M_DDR3_NODE1_ECC7")
	)
	(segment
		(start 66.668142 -27.868626)
		(end 66.668142 -27.161998)
		(width 0.2032)
		(layer "In7.Cu")
		(net "M_DDR3_NODE1_ECC7")
	)
	(segment
		(start 67.567302 -35.01771)
		(end 65.97396 -35.01771)
		(width 0.2032)
		(layer "In7.Cu")
		(net "M_DDR3_NODE1_ECC7")
	)
	(segment
		(start 61.90488 -52.606448)
		(end 61.90488 -52.311808)
		(width 0.2032)
		(layer "In7.Cu")
		(net "M_DDR3_NODE1_ECC7")
	)
	(segment
		(start 67.775582 -33.80359)
		(end 67.567302 -33.59531)
		(width 0.2032)
		(layer "In7.Cu")
		(net "M_DDR3_NODE1_ECC7")
	)
	(segment
		(start 68.012564 -32.812228)
		(end 69.30644 -31.518352)
		(width 0.2032)
		(layer "In7.Cu")
		(net "M_DDR3_NODE1_ECC7")
	)
	(segment
		(start 62.0649 -46.98492)
		(end 62.065408 -46.98492)
		(width 0.2032)
		(layer "In7.Cu")
		(net "M_DDR3_NODE1_ECC7")
	)
	(segment
		(start 66.01968 -33.59531)
		(end 65.81648 -33.39211)
		(width 0.2032)
		(layer "In7.Cu")
		(net "M_DDR3_NODE1_ECC7")
	)
	(segment
		(start 62.56274 -48.755808)
		(end 62.35446 -48.547528)
		(width 0.2032)
		(layer "In7.Cu")
		(net "M_DDR3_NODE1_ECC7")
	)
	(segment
		(start 62.35446 -53.525928)
		(end 62.56274 -53.317648)
		(width 0.2032)
		(layer "In7.Cu")
		(net "M_DDR3_NODE1_ECC7")
	)
	(segment
		(start 63.98768 -37.954204)
		(end 66.212974 -35.72891)
		(width 0.2032)
		(layer "In7.Cu")
		(net "M_DDR3_NODE1_ECC7")
	)
	(segment
		(start 66.196464 -66.456306)
		(end 66.196464 -65.067942)
		(width 0.1016)
		(layer "In7.Cu")
		(net "M_DDR3_NODE1_ECC7")
	)
	(segment
		(start 61.90488 -49.761648)
		(end 61.90488 -49.467008)
		(width 0.2032)
		(layer "In7.Cu")
		(net "M_DDR3_NODE1_ECC7")
	)
	(segment
		(start 67.567302 -34.30651)
		(end 67.775582 -34.09823)
		(width 0.2032)
		(layer "In7.Cu")
		(net "M_DDR3_NODE1_ECC7")
	)
	(segment
		(start 62.11316 -52.814728)
		(end 61.90488 -52.606448)
		(width 0.2032)
		(layer "In7.Cu")
		(net "M_DDR3_NODE1_ECC7")
	)
	(segment
		(start 61.90488 -54.028848)
		(end 61.90488 -53.734208)
		(width 0.2032)
		(layer "In7.Cu")
		(net "M_DDR3_NODE1_ECC7")
	)
	(segment
		(start 65.77076 -34.81451)
		(end 65.77076 -34.50971)
		(width 0.2032)
		(layer "In7.Cu")
		(net "M_DDR3_NODE1_ECC7")
	)
	(segment
		(start 62.11316 -48.547528)
		(end 61.90488 -48.339248)
		(width 0.2032)
		(layer "In7.Cu")
		(net "M_DDR3_NODE1_ECC7")
	)
	(segment
		(start 66.196464 -65.067942)
		(end 65.388236 -64.259714)
		(width 0.1016)
		(layer "In7.Cu")
		(net "M_DDR3_NODE1_ECC7")
	)
	(segment
		(start 64.972692 -62.982602)
		(end 63.28664 -61.29655)
		(width 0.2032)
		(layer "In7.Cu")
		(net "M_DDR3_NODE1_ECC7")
	)
	(segment
		(start 62.46114 -54.237128)
		(end 62.11316 -54.237128)
		(width 0.2032)
		(layer "In7.Cu")
		(net "M_DDR3_NODE1_ECC7")
	)
	(segment
		(start 63.28664 -61.29655)
		(end 63.28664 -59.298332)
		(width 0.2032)
		(layer "In7.Cu")
		(net "M_DDR3_NODE1_ECC7")
	)
	(segment
		(start 62.065408 -46.98492)
		(end 63.98768 -45.062648)
		(width 0.2032)
		(layer "In7.Cu")
		(net "M_DDR3_NODE1_ECC7")
	)
	(segment
		(start 67.567302 -35.72891)
		(end 67.775582 -35.52063)
		(width 0.2032)
		(layer "In7.Cu")
		(net "M_DDR3_NODE1_ECC7")
	)
	(segment
		(start 62.66434 -54.440328)
		(end 62.46114 -54.237128)
		(width 0.2032)
		(layer "In7.Cu")
		(net "M_DDR3_NODE1_ECC7")
	)
	(segment
		(start 62.56274 -50.472848)
		(end 62.56274 -50.178208)
		(width 0.2032)
		(layer "In7.Cu")
		(net "M_DDR3_NODE1_ECC7")
	)
	(segment
		(start 62.56274 -53.317648)
		(end 62.56274 -53.023008)
		(width 0.2032)
		(layer "In7.Cu")
		(net "M_DDR3_NODE1_ECC7")
	)
	(segment
		(start 62.11316 -53.525928)
		(end 62.35446 -53.525928)
		(width 0.2032)
		(layer "In7.Cu")
		(net "M_DDR3_NODE1_ECC7")
	)
	(segment
		(start 61.90488 -55.156608)
		(end 62.11316 -54.948328)
		(width 0.2032)
		(layer "In7.Cu")
		(net "M_DDR3_NODE1_ECC7")
	)
	(segment
		(start 62.11316 -52.103528)
		(end 62.35446 -52.103528)
		(width 0.2032)
		(layer "In7.Cu")
		(net "M_DDR3_NODE1_ECC7")
	)
	(segment
		(start 62.35446 -49.969928)
		(end 62.11316 -49.969928)
		(width 0.2032)
		(layer "In7.Cu")
		(net "M_DDR3_NODE1_ECC7")
	)
	(segment
		(start 62.97422 -57.768236)
		(end 61.90488 -56.698896)
		(width 0.2032)
		(layer "In7.Cu")
		(net "M_DDR3_NODE1_ECC7")
	)
	(segment
		(start 61.90488 -48.339248)
		(end 61.90488 -47.14494)
		(width 0.2032)
		(layer "In7.Cu")
		(net "M_DDR3_NODE1_ECC7")
	)
	(segment
		(start 62.11316 -49.969928)
		(end 61.90488 -49.761648)
		(width 0.2032)
		(layer "In7.Cu")
		(net "M_DDR3_NODE1_ECC7")
	)
	(segment
		(start 62.11316 -49.258728)
		(end 62.35446 -49.258728)
		(width 0.2032)
		(layer "In7.Cu")
		(net "M_DDR3_NODE1_ECC7")
	)
	(segment
		(start 62.97422 -58.985912)
		(end 62.97422 -57.768236)
		(width 0.2032)
		(layer "In7.Cu")
		(net "M_DDR3_NODE1_ECC7")
	)
	(segment
		(start 66.212974 -35.72891)
		(end 67.567302 -35.72891)
		(width 0.2032)
		(layer "In7.Cu")
		(net "M_DDR3_NODE1_ECC7")
	)
	(segment
		(start 62.11316 -51.392328)
		(end 61.90488 -51.184048)
		(width 0.2032)
		(layer "In7.Cu")
		(net "M_DDR3_NODE1_ECC7")
	)
	(segment
		(start 62.11316 -54.237128)
		(end 61.90488 -54.028848)
		(width 0.2032)
		(layer "In7.Cu")
		(net "M_DDR3_NODE1_ECC7")
	)
	(segment
		(start 62.35446 -52.814728)
		(end 62.11316 -52.814728)
		(width 0.2032)
		(layer "In7.Cu")
		(net "M_DDR3_NODE1_ECC7")
	)
	(segment
		(start 62.56274 -50.178208)
		(end 62.35446 -49.969928)
		(width 0.2032)
		(layer "In7.Cu")
		(net "M_DDR3_NODE1_ECC7")
	)
	(segment
		(start 61.90488 -51.184048)
		(end 61.90488 -50.889408)
		(width 0.2032)
		(layer "In7.Cu")
		(net "M_DDR3_NODE1_ECC7")
	)
	(segment
		(start 65.81648 -33.39211)
		(end 65.81648 -33.015428)
		(width 0.2032)
		(layer "In7.Cu")
		(net "M_DDR3_NODE1_ECC7")
	)
	(segment
		(start 67.775582 -34.09823)
		(end 67.775582 -33.80359)
		(width 0.2032)
		(layer "In7.Cu")
		(net "M_DDR3_NODE1_ECC7")
	)
	(segment
		(start 62.46114 -54.948328)
		(end 62.66434 -54.745128)
		(width 0.2032)
		(layer "In7.Cu")
		(net "M_DDR3_NODE1_ECC7")
	)
	(segment
		(start 63.98768 -45.062648)
		(end 63.98768 -37.954204)
		(width 0.2032)
		(layer "In7.Cu")
		(net "M_DDR3_NODE1_ECC7")
	)
	(segment
		(start 61.90488 -52.311808)
		(end 62.11316 -52.103528)
		(width 0.2032)
		(layer "In7.Cu")
		(net "M_DDR3_NODE1_ECC7")
	)
	(segment
		(start 65.97396 -34.30651)
		(end 67.567302 -34.30651)
		(width 0.2032)
		(layer "In7.Cu")
		(net "M_DDR3_NODE1_ECC7")
	)
	(segment
		(start 62.35446 -50.681128)
		(end 62.56274 -50.472848)
		(width 0.2032)
		(layer "In7.Cu")
		(net "M_DDR3_NODE1_ECC7")
	)
	(segment
		(start 62.11316 -54.948328)
		(end 62.46114 -54.948328)
		(width 0.2032)
		(layer "In7.Cu")
		(net "M_DDR3_NODE1_ECC7")
	)
	(segment
		(start 62.35446 -48.547528)
		(end 62.11316 -48.547528)
		(width 0.2032)
		(layer "In7.Cu")
		(net "M_DDR3_NODE1_ECC7")
	)
	(segment
		(start 67.567302 -33.59531)
		(end 66.01968 -33.59531)
		(width 0.2032)
		(layer "In7.Cu")
		(net "M_DDR3_NODE1_ECC7")
	)
	(segment
		(start 62.66434 -54.745128)
		(end 62.66434 -54.440328)
		(width 0.2032)
		(layer "In7.Cu")
		(net "M_DDR3_NODE1_ECC7")
	)
	(segment
		(start 62.56274 -51.895248)
		(end 62.56274 -51.600608)
		(width 0.2032)
		(layer "In7.Cu")
		(net "M_DDR3_NODE1_ECC7")
	)
	(segment
		(start 67.775582 -35.22599)
		(end 67.567302 -35.01771)
		(width 0.2032)
		(layer "In7.Cu")
		(net "M_DDR3_NODE1_ECC7")
	)
	(segment
		(start 62.56274 -53.023008)
		(end 62.35446 -52.814728)
		(width 0.2032)
		(layer "In7.Cu")
		(net "M_DDR3_NODE1_ECC7")
	)
	(segment
		(start 61.90488 -49.467008)
		(end 62.11316 -49.258728)
		(width 0.2032)
		(layer "In7.Cu")
		(net "M_DDR3_NODE1_ECC7")
	)
	(segment
		(start 61.90488 -50.889408)
		(end 62.11316 -50.681128)
		(width 0.2032)
		(layer "In7.Cu")
		(net "M_DDR3_NODE1_ECC7")
	)
	(segment
		(start 65.388236 -63.72606)
		(end 64.972692 -63.310516)
		(width 0.1016)
		(layer "In7.Cu")
		(net "M_DDR3_NODE1_ECC7")
	)
	(segment
		(start 69.30644 -31.518352)
		(end 69.30644 -30.506924)
		(width 0.2032)
		(layer "In7.Cu")
		(net "M_DDR3_NODE1_ECC7")
	)
	(segment
		(start 61.90488 -56.698896)
		(end 61.90488 -55.156608)
		(width 0.2032)
		(layer "In7.Cu")
		(net "M_DDR3_NODE1_ECC7")
	)
	(segment
		(start 62.35446 -52.103528)
		(end 62.56274 -51.895248)
		(width 0.2032)
		(layer "In7.Cu")
		(net "M_DDR3_NODE1_ECC7")
	)
	(segment
		(start 69.30644 -30.506924)
		(end 66.668142 -27.868626)
		(width 0.2032)
		(layer "In7.Cu")
		(net "M_DDR3_NODE1_ECC7")
	)
	(segment
		(start 65.77076 -34.50971)
		(end 65.97396 -34.30651)
		(width 0.2032)
		(layer "In7.Cu")
		(net "M_DDR3_NODE1_ECC7")
	)
	(segment
		(start 62.35446 -51.392328)
		(end 62.11316 -51.392328)
		(width 0.2032)
		(layer "In7.Cu")
		(net "M_DDR3_NODE1_ECC7")
	)
	(segment
		(start 63.28664 -59.298332)
		(end 62.97422 -58.985912)
		(width 0.2032)
		(layer "In7.Cu")
		(net "M_DDR3_NODE1_ECC7")
	)
	(segment
		(start 66.01968 -32.812228)
		(end 68.012564 -32.812228)
		(width 0.2032)
		(layer "In7.Cu")
		(net "M_DDR3_NODE1_ECC7")
	)
	(segment
		(start 62.35446 -49.258728)
		(end 62.56274 -49.050448)
		(width 0.2032)
		(layer "In7.Cu")
		(net "M_DDR3_NODE1_ECC7")
	)
	(segment
		(start 61.90488 -47.14494)
		(end 62.0649 -46.98492)
		(width 0.2032)
		(layer "In7.Cu")
		(net "M_DDR3_NODE1_ECC7")
	)
	(segment
		(start 61.90488 -53.734208)
		(end 62.11316 -53.525928)
		(width 0.2032)
		(layer "In7.Cu")
		(net "M_DDR3_NODE1_ECC7")
	)
	(segment
		(start 67.775582 -35.52063)
		(end 67.775582 -35.22599)
		(width 0.2032)
		(layer "In7.Cu")
		(net "M_DDR3_NODE1_ECC7")
	)
	(segment
		(start 64.972692 -63.310516)
		(end 64.972692 -62.982602)
		(width 0.2032)
		(layer "In7.Cu")
		(net "M_DDR3_NODE1_ECC7")
	)
	(segment
		(start 65.81648 -33.015428)
		(end 66.01968 -32.812228)
		(width 0.2032)
		(layer "In7.Cu")
		(net "M_DDR3_NODE1_ECC7")
	)
	(segment
		(start 62.56274 -49.050448)
		(end 62.56274 -48.755808)
		(width 0.2032)
		(layer "In7.Cu")
		(net "M_DDR3_NODE1_ECC7")
	)
	(segment
		(start 62.11316 -50.681128)
		(end 62.35446 -50.681128)
		(width 0.2032)
		(layer "In7.Cu")
		(net "M_DDR3_NODE1_ECC7")
	)
	(segment
		(start 65.388236 -64.259714)
		(end 65.388236 -63.72606)
		(width 0.1016)
		(layer "In7.Cu")
		(net "M_DDR3_NODE1_ECC7")
	)
	(segment
		(start 55.784242 -68.845938)
		(end 55.159402 -68.221098)
		(width 0.1016)
		(layer "F.Cu")
		(net "M1_DQ_NODE1_DQ22")
	)
	(segment
		(start 54.43728 -25.902412)
		(end 54.549802 -26.014934)
		(width 0.1651)
		(layer "F.Cu")
		(net "M1_DQ_NODE1_DQ22")
	)
	(segment
		(start 54.549802 -26.014934)
		(end 54.549802 -27.464258)
		(width 0.1651)
		(layer "F.Cu")
		(net "M1_DQ_NODE1_DQ22")
	)
	(segment
		(start 54.450234 -27.563826)
		(end 54.450234 -29.149802)
		(width 0.1651)
		(layer "F.Cu")
		(net "M1_DQ_NODE1_DQ22")
	)
	(segment
		(start 55.159402 -68.221098)
		(end 54.910736 -68.221098)
		(width 0.1016)
		(layer "F.Cu")
		(net "M1_DQ_NODE1_DQ22")
	)
	(segment
		(start 54.549802 -27.464258)
		(end 54.450234 -27.563826)
		(width 0.1651)
		(layer "F.Cu")
		(net "M1_DQ_NODE1_DQ22")
	)
	(segment
		(start 55.784242 -68.884038)
		(end 55.784242 -68.845938)
		(width 0.1016)
		(layer "F.Cu")
		(net "M1_DQ_NODE1_DQ22")
	)
	(via
		(at 54.910736 -68.221098)
		(size 0.49022)
		(drill 0.254)
		(layers "F.Cu" "B.Cu")
		(net "M1_DQ_NODE1_DQ22")
	)
	(via
		(at 54.43728 -25.902412)
		(size 0.508)
		(drill 0.254)
		(layers "F.Cu" "B.Cu")
		(net "M1_DQ_NODE1_DQ22")
	)
	(segment
		(start 56.747664 -64.131698)
		(end 56.747664 -64.512952)
		(width 0.1016)
		(layer "In7.Cu")
		(net "M1_DQ_NODE1_DQ22")
	)
	(segment
		(start 55.89524 -32.003238)
		(end 54.85638 -33.042098)
		(width 0.2032)
		(layer "In7.Cu")
		(net "M1_DQ_NODE1_DQ22")
	)
	(segment
		(start 55.89524 -30.223714)
		(end 55.89524 -32.003238)
		(width 0.2032)
		(layer "In7.Cu")
		(net "M1_DQ_NODE1_DQ22")
	)
	(segment
		(start 52.933854 -52.84724)
		(end 52.933854 -53.14188)
		(width 0.2032)
		(layer "In7.Cu")
		(net "M1_DQ_NODE1_DQ22")
	)
	(segment
		(start 54.945534 -54.85892)
		(end 54.945534 -55.15356)
		(width 0.2032)
		(layer "In7.Cu")
		(net "M1_DQ_NODE1_DQ22")
	)
	(segment
		(start 52.748942 -54.037992)
		(end 53.043582 -54.037992)
		(width 0.2032)
		(layer "In7.Cu")
		(net "M1_DQ_NODE1_DQ22")
	)
	(segment
		(start 56.75122 -29.367734)
		(end 55.89524 -30.223714)
		(width 0.2032)
		(layer "In7.Cu")
		(net "M1_DQ_NODE1_DQ22")
	)
	(segment
		(start 49.79416 -42.797476)
		(end 49.79416 -49.707546)
		(width 0.2032)
		(layer "In7.Cu")
		(net "M1_DQ_NODE1_DQ22")
	)
	(segment
		(start 51.534822 -52.529232)
		(end 51.534822 -52.823872)
		(width 0.2032)
		(layer "In7.Cu")
		(net "M1_DQ_NODE1_DQ22")
	)
	(segment
		(start 54.43728 -25.902412)
		(end 55.44312 -24.896572)
		(width 0.2032)
		(layer "In7.Cu")
		(net "M1_DQ_NODE1_DQ22")
	)
	(segment
		(start 50.00244 -42.589196)
		(end 49.79416 -42.797476)
		(width 0.2032)
		(layer "In7.Cu")
		(net "M1_DQ_NODE1_DQ22")
	)
	(segment
		(start 53.436774 -53.6448)
		(end 53.731414 -53.6448)
		(width 0.2032)
		(layer "In7.Cu")
		(net "M1_DQ_NODE1_DQ22")
	)
	(segment
		(start 50.33772 -41.877996)
		(end 50.546 -42.086276)
		(width 0.2032)
		(layer "In7.Cu")
		(net "M1_DQ_NODE1_DQ22")
	)
	(segment
		(start 56.747664 -64.512952)
		(end 56.114188 -65.146428)
		(width 0.1016)
		(layer "In7.Cu")
		(net "M1_DQ_NODE1_DQ22")
	)
	(segment
		(start 54.552342 -55.546752)
		(end 54.552342 -55.841392)
		(width 0.2032)
		(layer "In7.Cu")
		(net "M1_DQ_NODE1_DQ22")
	)
	(segment
		(start 56.114188 -67.017646)
		(end 54.910736 -68.221098)
		(width 0.1016)
		(layer "In7.Cu")
		(net "M1_DQ_NODE1_DQ22")
	)
	(segment
		(start 50.00244 -41.877996)
		(end 50.33772 -41.877996)
		(width 0.2032)
		(layer "In7.Cu")
		(net "M1_DQ_NODE1_DQ22")
	)
	(segment
		(start 53.546502 -54.835552)
		(end 53.754782 -55.043832)
		(width 0.2032)
		(layer "In7.Cu")
		(net "M1_DQ_NODE1_DQ22")
	)
	(segment
		(start 54.049422 -55.043832)
		(end 54.442614 -54.65064)
		(width 0.2032)
		(layer "In7.Cu")
		(net "M1_DQ_NODE1_DQ22")
	)
	(segment
		(start 49.79416 -49.707546)
		(end 51.928014 -51.8414)
		(width 0.2032)
		(layer "In7.Cu")
		(net "M1_DQ_NODE1_DQ22")
	)
	(segment
		(start 49.79416 -40.570404)
		(end 49.79416 -41.669716)
		(width 0.2032)
		(layer "In7.Cu")
		(net "M1_DQ_NODE1_DQ22")
	)
	(segment
		(start 50.546 -42.380916)
		(end 50.33772 -42.589196)
		(width 0.2032)
		(layer "In7.Cu")
		(net "M1_DQ_NODE1_DQ22")
	)
	(segment
		(start 53.939694 -54.14772)
		(end 53.546502 -54.540912)
		(width 0.2032)
		(layer "In7.Cu")
		(net "M1_DQ_NODE1_DQ22")
	)
	(segment
		(start 53.546502 -54.540912)
		(end 53.546502 -54.835552)
		(width 0.2032)
		(layer "In7.Cu")
		(net "M1_DQ_NODE1_DQ22")
	)
	(segment
		(start 51.928014 -51.8414)
		(end 51.928014 -52.13604)
		(width 0.2032)
		(layer "In7.Cu")
		(net "M1_DQ_NODE1_DQ22")
	)
	(segment
		(start 56.75122 -25.651206)
		(end 56.75122 -29.367734)
		(width 0.2032)
		(layer "In7.Cu")
		(net "M1_DQ_NODE1_DQ22")
	)
	(segment
		(start 54.737254 -54.65064)
		(end 54.945534 -54.85892)
		(width 0.2032)
		(layer "In7.Cu")
		(net "M1_DQ_NODE1_DQ22")
	)
	(segment
		(start 52.540662 -53.535072)
		(end 52.540662 -53.829712)
		(width 0.2032)
		(layer "In7.Cu")
		(net "M1_DQ_NODE1_DQ22")
	)
	(segment
		(start 52.540662 -53.829712)
		(end 52.748942 -54.037992)
		(width 0.2032)
		(layer "In7.Cu")
		(net "M1_DQ_NODE1_DQ22")
	)
	(segment
		(start 55.2958 -56.58485)
		(end 55.2958 -57.927494)
		(width 0.2032)
		(layer "In7.Cu")
		(net "M1_DQ_NODE1_DQ22")
	)
	(segment
		(start 54.945534 -55.15356)
		(end 54.552342 -55.546752)
		(width 0.2032)
		(layer "In7.Cu")
		(net "M1_DQ_NODE1_DQ22")
	)
	(segment
		(start 53.754782 -55.043832)
		(end 54.049422 -55.043832)
		(width 0.2032)
		(layer "In7.Cu")
		(net "M1_DQ_NODE1_DQ22")
	)
	(segment
		(start 52.037742 -53.032152)
		(end 52.430934 -52.63896)
		(width 0.2032)
		(layer "In7.Cu")
		(net "M1_DQ_NODE1_DQ22")
	)
	(segment
		(start 54.442614 -54.65064)
		(end 54.737254 -54.65064)
		(width 0.2032)
		(layer "In7.Cu")
		(net "M1_DQ_NODE1_DQ22")
	)
	(segment
		(start 54.85638 -33.042098)
		(end 54.85638 -35.508184)
		(width 0.2032)
		(layer "In7.Cu")
		(net "M1_DQ_NODE1_DQ22")
	)
	(segment
		(start 51.928014 -52.13604)
		(end 51.534822 -52.529232)
		(width 0.2032)
		(layer "In7.Cu")
		(net "M1_DQ_NODE1_DQ22")
	)
	(segment
		(start 55.44312 -24.896572)
		(end 55.996586 -24.896572)
		(width 0.2032)
		(layer "In7.Cu")
		(net "M1_DQ_NODE1_DQ22")
	)
	(segment
		(start 53.731414 -53.6448)
		(end 53.939694 -53.85308)
		(width 0.2032)
		(layer "In7.Cu")
		(net "M1_DQ_NODE1_DQ22")
	)
	(segment
		(start 50.546 -42.086276)
		(end 50.546 -42.380916)
		(width 0.2032)
		(layer "In7.Cu")
		(net "M1_DQ_NODE1_DQ22")
	)
	(segment
		(start 51.534822 -52.823872)
		(end 51.743102 -53.032152)
		(width 0.2032)
		(layer "In7.Cu")
		(net "M1_DQ_NODE1_DQ22")
	)
	(segment
		(start 52.430934 -52.63896)
		(end 52.725574 -52.63896)
		(width 0.2032)
		(layer "In7.Cu")
		(net "M1_DQ_NODE1_DQ22")
	)
	(segment
		(start 55.996586 -24.896572)
		(end 56.75122 -25.651206)
		(width 0.2032)
		(layer "In7.Cu")
		(net "M1_DQ_NODE1_DQ22")
	)
	(segment
		(start 55.61076 -61.750194)
		(end 56.747664 -62.887098)
		(width 0.2032)
		(layer "In7.Cu")
		(net "M1_DQ_NODE1_DQ22")
	)
	(segment
		(start 54.552342 -55.841392)
		(end 55.2958 -56.58485)
		(width 0.2032)
		(layer "In7.Cu")
		(net "M1_DQ_NODE1_DQ22")
	)
	(segment
		(start 50.33772 -42.589196)
		(end 50.00244 -42.589196)
		(width 0.2032)
		(layer "In7.Cu")
		(net "M1_DQ_NODE1_DQ22")
	)
	(segment
		(start 54.85638 -35.508184)
		(end 49.79416 -40.570404)
		(width 0.2032)
		(layer "In7.Cu")
		(net "M1_DQ_NODE1_DQ22")
	)
	(segment
		(start 53.939694 -53.85308)
		(end 53.939694 -54.14772)
		(width 0.2032)
		(layer "In7.Cu")
		(net "M1_DQ_NODE1_DQ22")
	)
	(segment
		(start 56.747664 -62.887098)
		(end 56.747664 -64.131698)
		(width 0.2032)
		(layer "In7.Cu")
		(net "M1_DQ_NODE1_DQ22")
	)
	(segment
		(start 49.79416 -41.669716)
		(end 50.00244 -41.877996)
		(width 0.2032)
		(layer "In7.Cu")
		(net "M1_DQ_NODE1_DQ22")
	)
	(segment
		(start 51.743102 -53.032152)
		(end 52.037742 -53.032152)
		(width 0.2032)
		(layer "In7.Cu")
		(net "M1_DQ_NODE1_DQ22")
	)
	(segment
		(start 55.2958 -57.927494)
		(end 55.61076 -58.242454)
		(width 0.2032)
		(layer "In7.Cu")
		(net "M1_DQ_NODE1_DQ22")
	)
	(segment
		(start 52.933854 -53.14188)
		(end 52.540662 -53.535072)
		(width 0.2032)
		(layer "In7.Cu")
		(net "M1_DQ_NODE1_DQ22")
	)
	(segment
		(start 55.61076 -58.242454)
		(end 55.61076 -61.750194)
		(width 0.2032)
		(layer "In7.Cu")
		(net "M1_DQ_NODE1_DQ22")
	)
	(segment
		(start 52.725574 -52.63896)
		(end 52.933854 -52.84724)
		(width 0.2032)
		(layer "In7.Cu")
		(net "M1_DQ_NODE1_DQ22")
	)
	(segment
		(start 53.043582 -54.037992)
		(end 53.436774 -53.6448)
		(width 0.2032)
		(layer "In7.Cu")
		(net "M1_DQ_NODE1_DQ22")
	)
	(segment
		(start 56.114188 -65.146428)
		(end 56.114188 -67.017646)
		(width 0.1016)
		(layer "In7.Cu")
		(net "M1_DQ_NODE1_DQ22")
	)
	(segment
		(start 129.403856 -120.114568)
		(end 128.726692 -120.114568)
		(width 0.127)
		(layer "F.Cu")
		(net "CLK_100M_BMC_NODE1_DN")
	)
	(segment
		(start 72.067674 -119.338598)
		(end 72.83577 -119.338598)
		(width 0.127)
		(layer "F.Cu")
		(net "CLK_100M_BMC_NODE1_DN")
	)
	(segment
		(start 69.341746 -127.259588)
		(end 69.722746 -126.878588)
		(width 0.127)
		(layer "F.Cu")
		(net "CLK_100M_BMC_NODE1_DN")
	)
	(segment
		(start 122.453908 -121.189242)
		(end 121.949972 -121.693178)
		(width 0.127)
		(layer "F.Cu")
		(net "CLK_100M_BMC_NODE1_DN")
	)
	(segment
		(start 128.726692 -120.114568)
		(end 128.67894 -120.066816)
		(width 0.127)
		(layer "F.Cu")
		(net "CLK_100M_BMC_NODE1_DN")
	)
	(segment
		(start 128.360678 -120.066816)
		(end 127.238252 -121.189242)
		(width 0.127)
		(layer "F.Cu")
		(net "CLK_100M_BMC_NODE1_DN")
	)
	(segment
		(start 128.67894 -120.066816)
		(end 128.360678 -120.066816)
		(width 0.127)
		(layer "F.Cu")
		(net "CLK_100M_BMC_NODE1_DN")
	)
	(segment
		(start 69.477128 -121.929144)
		(end 72.067674 -119.338598)
		(width 0.127)
		(layer "F.Cu")
		(net "CLK_100M_BMC_NODE1_DN")
	)
	(segment
		(start 69.722746 -125.699012)
		(end 69.477128 -125.453394)
		(width 0.127)
		(layer "F.Cu")
		(net "CLK_100M_BMC_NODE1_DN")
	)
	(segment
		(start 127.238252 -121.189242)
		(end 122.453908 -121.189242)
		(width 0.127)
		(layer "F.Cu")
		(net "CLK_100M_BMC_NODE1_DN")
	)
	(segment
		(start 69.722746 -126.878588)
		(end 69.722746 -125.699012)
		(width 0.127)
		(layer "F.Cu")
		(net "CLK_100M_BMC_NODE1_DN")
	)
	(segment
		(start 72.83577 -119.338598)
		(end 73.042018 -119.544846)
		(width 0.127)
		(layer "F.Cu")
		(net "CLK_100M_BMC_NODE1_DN")
	)
	(segment
		(start 69.477128 -125.453394)
		(end 69.477128 -121.929144)
		(width 0.127)
		(layer "F.Cu")
		(net "CLK_100M_BMC_NODE1_DN")
	)
	(via
		(at 73.042018 -119.544846)
		(size 0.508)
		(drill 0.254)
		(layers "F.Cu" "B.Cu")
		(net "CLK_100M_BMC_NODE1_DN")
	)
	(via
		(at 121.949972 -121.693178)
		(size 0.508)
		(drill 0.254)
		(layers "F.Cu" "B.Cu")
		(net "CLK_100M_BMC_NODE1_DN")
	)
	(segment
		(start 99.704144 -112.597692)
		(end 100.85832 -111.443516)
		(width 0.127)
		(layer "In7.Cu")
		(net "CLK_100M_BMC_NODE1_DN")
	)
	(segment
		(start 120.24106 -120.458484)
		(end 120.986804 -121.204228)
		(width 0.127)
		(layer "In7.Cu")
		(net "CLK_100M_BMC_NODE1_DN")
	)
	(segment
		(start 92.290392 -112.597692)
		(end 99.704144 -112.597692)
		(width 0.127)
		(layer "In7.Cu")
		(net "CLK_100M_BMC_NODE1_DN")
	)
	(segment
		(start 75.29576 -119.30888)
		(end 77.55382 -117.05082)
		(width 0.127)
		(layer "In7.Cu")
		(net "CLK_100M_BMC_NODE1_DN")
	)
	(segment
		(start 100.85832 -111.443516)
		(end 118.085108 -111.443516)
		(width 0.127)
		(layer "In7.Cu")
		(net "CLK_100M_BMC_NODE1_DN")
	)
	(segment
		(start 86.701884 -112.500918)
		(end 92.193618 -112.500918)
		(width 0.127)
		(layer "In7.Cu")
		(net "CLK_100M_BMC_NODE1_DN")
	)
	(segment
		(start 118.085108 -111.443516)
		(end 120.98274 -114.341148)
		(width 0.127)
		(layer "In7.Cu")
		(net "CLK_100M_BMC_NODE1_DN")
	)
	(segment
		(start 121.81586 -121.204228)
		(end 121.949972 -121.33834)
		(width 0.127)
		(layer "In7.Cu")
		(net "CLK_100M_BMC_NODE1_DN")
	)
	(segment
		(start 120.986804 -121.204228)
		(end 121.81586 -121.204228)
		(width 0.127)
		(layer "In7.Cu")
		(net "CLK_100M_BMC_NODE1_DN")
	)
	(segment
		(start 80.991202 -117.29847)
		(end 81.904332 -117.29847)
		(width 0.127)
		(layer "In7.Cu")
		(net "CLK_100M_BMC_NODE1_DN")
	)
	(segment
		(start 92.193618 -112.500918)
		(end 92.290392 -112.597692)
		(width 0.127)
		(layer "In7.Cu")
		(net "CLK_100M_BMC_NODE1_DN")
	)
	(segment
		(start 120.24106 -115.795298)
		(end 120.24106 -120.458484)
		(width 0.127)
		(layer "In7.Cu")
		(net "CLK_100M_BMC_NODE1_DN")
	)
	(segment
		(start 77.55382 -117.05082)
		(end 80.743552 -117.05082)
		(width 0.127)
		(layer "In7.Cu")
		(net "CLK_100M_BMC_NODE1_DN")
	)
	(segment
		(start 120.98274 -114.341148)
		(end 120.98274 -115.053618)
		(width 0.127)
		(layer "In7.Cu")
		(net "CLK_100M_BMC_NODE1_DN")
	)
	(segment
		(start 80.743552 -117.05082)
		(end 80.991202 -117.29847)
		(width 0.127)
		(layer "In7.Cu")
		(net "CLK_100M_BMC_NODE1_DN")
	)
	(segment
		(start 121.949972 -121.33834)
		(end 121.949972 -121.693178)
		(width 0.127)
		(layer "In7.Cu")
		(net "CLK_100M_BMC_NODE1_DN")
	)
	(segment
		(start 73.277984 -119.30888)
		(end 75.29576 -119.30888)
		(width 0.127)
		(layer "In7.Cu")
		(net "CLK_100M_BMC_NODE1_DN")
	)
	(segment
		(start 73.042018 -119.544846)
		(end 73.277984 -119.30888)
		(width 0.127)
		(layer "In7.Cu")
		(net "CLK_100M_BMC_NODE1_DN")
	)
	(segment
		(start 81.904332 -117.29847)
		(end 86.701884 -112.500918)
		(width 0.127)
		(layer "In7.Cu")
		(net "CLK_100M_BMC_NODE1_DN")
	)
	(segment
		(start 120.98274 -115.053618)
		(end 120.24106 -115.795298)
		(width 0.127)
		(layer "In7.Cu")
		(net "CLK_100M_BMC_NODE1_DN")
	)
	(segment
		(start 65.44691 -27.055318)
		(end 64.346582 -27.055318)
		(width 0.1651)
		(layer "F.Cu")
		(net "M_DDR3_NODE1_ECC6")
	)
	(segment
		(start 64.346582 -27.055318)
		(end 64.181482 -26.890218)
		(width 0.1651)
		(layer "F.Cu")
		(net "M_DDR3_NODE1_ECC6")
	)
	(segment
		(start 65.508378 -65.247774)
		(end 65.164462 -65.247774)
		(width 0.1016)
		(layer "F.Cu")
		(net "M_DDR3_NODE1_ECC6")
	)
	(segment
		(start 66.45021 -28.058618)
		(end 65.44691 -27.055318)
		(width 0.1651)
		(layer "F.Cu")
		(net "M_DDR3_NODE1_ECC6")
	)
	(segment
		(start 66.45021 -29.149802)
		(end 66.45021 -28.058618)
		(width 0.1651)
		(layer "F.Cu")
		(net "M_DDR3_NODE1_ECC6")
	)
	(segment
		(start 65.715642 -65.455038)
		(end 65.508378 -65.247774)
		(width 0.1016)
		(layer "F.Cu")
		(net "M_DDR3_NODE1_ECC6")
	)
	(via
		(at 64.181482 -26.890218)
		(size 0.508)
		(drill 0.254)
		(layers "F.Cu" "B.Cu")
		(net "M_DDR3_NODE1_ECC6")
	)
	(via
		(at 65.164462 -65.247774)
		(size 0.508)
		(drill 0.254)
		(layers "F.Cu" "B.Cu")
		(net "M_DDR3_NODE1_ECC6")
	)
	(segment
		(start 57.28208 -43.724068)
		(end 57.28208 -48.20412)
		(width 0.2032)
		(layer "In7.Cu")
		(net "M_DDR3_NODE1_ECC6")
	)
	(segment
		(start 61.1251 -60.551568)
		(end 62.310264 -61.736732)
		(width 0.1016)
		(layer "In7.Cu")
		(net "M_DDR3_NODE1_ECC6")
	)
	(segment
		(start 55.85968 -49.581816)
		(end 59.16676 -52.888896)
		(width 0.2032)
		(layer "In7.Cu")
		(net "M_DDR3_NODE1_ECC6")
	)
	(segment
		(start 57.0738 -48.4124)
		(end 56.06796 -48.4124)
		(width 0.2032)
		(layer "In7.Cu")
		(net "M_DDR3_NODE1_ECC6")
	)
	(segment
		(start 63.025782 -34.72561)
		(end 61.598302 -36.15309)
		(width 0.2032)
		(layer "In7.Cu")
		(net "M_DDR3_NODE1_ECC6")
	)
	(segment
		(start 64.130682 -29.496258)
		(end 63.025782 -30.601158)
		(width 0.2032)
		(layer "In7.Cu")
		(net "M_DDR3_NODE1_ECC6")
	)
	(segment
		(start 56.3626 -47.7012)
		(end 56.57088 -47.49292)
		(width 0.2032)
		(layer "In7.Cu")
		(net "M_DDR3_NODE1_ECC6")
	)
	(segment
		(start 59.561984 -36.15309)
		(end 57.41924 -38.295834)
		(width 0.2032)
		(layer "In7.Cu")
		(net "M_DDR3_NODE1_ECC6")
	)
	(segment
		(start 57.41924 -38.295834)
		(end 57.41924 -40.302942)
		(width 0.2032)
		(layer "In7.Cu")
		(net "M_DDR3_NODE1_ECC6")
	)
	(segment
		(start 59.16676 -52.888896)
		(end 59.16676 -57.508648)
		(width 0.2032)
		(layer "In7.Cu")
		(net "M_DDR3_NODE1_ECC6")
	)
	(segment
		(start 62.310264 -61.736732)
		(end 62.310264 -62.393576)
		(width 0.1016)
		(layer "In7.Cu")
		(net "M_DDR3_NODE1_ECC6")
	)
	(segment
		(start 55.85968 -48.62068)
		(end 55.85968 -49.581816)
		(width 0.2032)
		(layer "In7.Cu")
		(net "M_DDR3_NODE1_ECC6")
	)
	(segment
		(start 57.28208 -48.20412)
		(end 57.0738 -48.4124)
		(width 0.2032)
		(layer "In7.Cu")
		(net "M_DDR3_NODE1_ECC6")
	)
	(segment
		(start 55.85968 -47.49292)
		(end 56.06796 -47.7012)
		(width 0.2032)
		(layer "In7.Cu")
		(net "M_DDR3_NODE1_ECC6")
	)
	(segment
		(start 64.130682 -26.941018)
		(end 64.130682 -29.496258)
		(width 0.2032)
		(layer "In7.Cu")
		(net "M_DDR3_NODE1_ECC6")
	)
	(segment
		(start 61.598302 -36.15309)
		(end 59.561984 -36.15309)
		(width 0.2032)
		(layer "In7.Cu")
		(net "M_DDR3_NODE1_ECC6")
	)
	(segment
		(start 62.310264 -62.393576)
		(end 65.164462 -65.247774)
		(width 0.1016)
		(layer "In7.Cu")
		(net "M_DDR3_NODE1_ECC6")
	)
	(segment
		(start 64.181482 -26.890218)
		(end 64.130682 -26.941018)
		(width 0.2032)
		(layer "In7.Cu")
		(net "M_DDR3_NODE1_ECC6")
	)
	(segment
		(start 55.85968 -41.862502)
		(end 55.85968 -47.49292)
		(width 0.2032)
		(layer "In7.Cu")
		(net "M_DDR3_NODE1_ECC6")
	)
	(segment
		(start 56.57088 -43.724068)
		(end 56.77408 -43.520868)
		(width 0.2032)
		(layer "In7.Cu")
		(net "M_DDR3_NODE1_ECC6")
	)
	(segment
		(start 61.1251 -59.466988)
		(end 61.1251 -60.551568)
		(width 0.1016)
		(layer "In7.Cu")
		(net "M_DDR3_NODE1_ECC6")
	)
	(segment
		(start 63.025782 -30.601158)
		(end 63.025782 -34.72561)
		(width 0.2032)
		(layer "In7.Cu")
		(net "M_DDR3_NODE1_ECC6")
	)
	(segment
		(start 57.41924 -40.302942)
		(end 55.85968 -41.862502)
		(width 0.2032)
		(layer "In7.Cu")
		(net "M_DDR3_NODE1_ECC6")
	)
	(segment
		(start 56.06796 -48.4124)
		(end 55.85968 -48.62068)
		(width 0.2032)
		(layer "In7.Cu")
		(net "M_DDR3_NODE1_ECC6")
	)
	(segment
		(start 56.57088 -47.49292)
		(end 56.57088 -43.724068)
		(width 0.2032)
		(layer "In7.Cu")
		(net "M_DDR3_NODE1_ECC6")
	)
	(segment
		(start 56.06796 -47.7012)
		(end 56.3626 -47.7012)
		(width 0.2032)
		(layer "In7.Cu")
		(net "M_DDR3_NODE1_ECC6")
	)
	(segment
		(start 56.77408 -43.520868)
		(end 57.07888 -43.520868)
		(width 0.2032)
		(layer "In7.Cu")
		(net "M_DDR3_NODE1_ECC6")
	)
	(segment
		(start 57.07888 -43.520868)
		(end 57.28208 -43.724068)
		(width 0.2032)
		(layer "In7.Cu")
		(net "M_DDR3_NODE1_ECC6")
	)
	(segment
		(start 59.16676 -57.508648)
		(end 61.1251 -59.466988)
		(width 0.2032)
		(layer "In7.Cu")
		(net "M_DDR3_NODE1_ECC6")
	)
	(segment
		(start 128.639824 -115.14455)
		(end 128.639824 -113.519712)
		(width 0.1016)
		(layer "F.Cu")
		(net "FM_CPLD_CLK_R_PG_NODE1_R")
	)
	(segment
		(start 128.810004 -115.31473)
		(end 128.639824 -115.14455)
		(width 0.1016)
		(layer "F.Cu")
		(net "FM_CPLD_CLK_R_PG_NODE1_R")
	)
	(segment
		(start 128.639824 -113.519712)
		(end 128.224788 -113.104676)
		(width 0.1016)
		(layer "F.Cu")
		(net "FM_CPLD_CLK_R_PG_NODE1_R")
	)
	(segment
		(start 128.224788 -113.104676)
		(end 127.245872 -113.104676)
		(width 0.1016)
		(layer "F.Cu")
		(net "FM_CPLD_CLK_R_PG_NODE1_R")
	)
	(segment
		(start 129.403856 -115.31473)
		(end 128.810004 -115.31473)
		(width 0.1016)
		(layer "F.Cu")
		(net "FM_CPLD_CLK_R_PG_NODE1_R")
	)
	(segment
		(start 127.22733 -113.123218)
		(end 127.22733 -114.239294)
		(width 0.1016)
		(layer "F.Cu")
		(net "FM_CPLD_CLK_R_PG_NODE1_R")
	)
	(segment
		(start 127.245872 -113.104676)
		(end 127.22733 -113.123218)
		(width 0.1016)
		(layer "F.Cu")
		(net "FM_CPLD_CLK_R_PG_NODE1_R")
	)
	(via
		(at 128.639824 -113.519712)
		(size 0.508)
		(drill 0.254)
		(layers "F.Cu" "B.Cu")
		(net "FM_CPLD_CLK_R_PG_NODE1_R")
	)
	(segment
		(start 44.320206 -27.569414)
		(end 44.850304 -28.099512)
		(width 0.1651)
		(layer "F.Cu")
		(net "M1_DQ_NODE1_DQ6")
	)
	(segment
		(start 43.553888 -27.569414)
		(end 44.320206 -27.569414)
		(width 0.1651)
		(layer "F.Cu")
		(net "M1_DQ_NODE1_DQ6")
	)
	(segment
		(start 44.850304 -28.099512)
		(end 44.850304 -29.149802)
		(width 0.1651)
		(layer "F.Cu")
		(net "M1_DQ_NODE1_DQ6")
	)
	(segment
		(start 47.839122 -67.360038)
		(end 47.839122 -67.352418)
		(width 0.1016)
		(layer "F.Cu")
		(net "M1_DQ_NODE1_DQ6")
	)
	(segment
		(start 47.839122 -67.352418)
		(end 47.465742 -66.979038)
		(width 0.1016)
		(layer "F.Cu")
		(net "M1_DQ_NODE1_DQ6")
	)
	(segment
		(start 43.05554 -27.071066)
		(end 43.553888 -27.569414)
		(width 0.1651)
		(layer "F.Cu")
		(net "M1_DQ_NODE1_DQ6")
	)
	(via
		(at 47.465742 -66.979038)
		(size 0.508)
		(drill 0.254)
		(layers "F.Cu" "B.Cu")
		(net "M1_DQ_NODE1_DQ6")
	)
	(via
		(at 43.05554 -27.071066)
		(size 0.508)
		(drill 0.254)
		(layers "F.Cu" "B.Cu")
		(net "M1_DQ_NODE1_DQ6")
	)
	(segment
		(start 43.46702 -24.925528)
		(end 43.07078 -24.529288)
		(width 0.2032)
		(layer "In7.Cu")
		(net "M1_DQ_NODE1_DQ6")
	)
	(segment
		(start 40.91686 -24.73325)
		(end 40.91686 -25.559512)
		(width 0.2032)
		(layer "In7.Cu")
		(net "M1_DQ_NODE1_DQ6")
	)
	(segment
		(start 40.49268 -25.983692)
		(end 40.49268 -26.392632)
		(width 0.2032)
		(layer "In7.Cu")
		(net "M1_DQ_NODE1_DQ6")
	)
	(segment
		(start 44.57573 -64.60617)
		(end 46.305724 -66.336164)
		(width 0.1016)
		(layer "In7.Cu")
		(net "M1_DQ_NODE1_DQ6")
	)
	(segment
		(start 43.05554 -26.63317)
		(end 43.46702 -26.22169)
		(width 0.2032)
		(layer "In7.Cu")
		(net "M1_DQ_NODE1_DQ6")
	)
	(segment
		(start 41.994074 -62.661546)
		(end 43.938698 -64.60617)
		(width 0.2032)
		(layer "In7.Cu")
		(net "M1_DQ_NODE1_DQ6")
	)
	(segment
		(start 43.938698 -64.60617)
		(end 44.57573 -64.60617)
		(width 0.1016)
		(layer "In7.Cu")
		(net "M1_DQ_NODE1_DQ6")
	)
	(segment
		(start 30.30728 -55.313326)
		(end 35.705288 -60.711334)
		(width 0.2032)
		(layer "In7.Cu")
		(net "M1_DQ_NODE1_DQ6")
	)
	(segment
		(start 43.07078 -24.529288)
		(end 41.120822 -24.529288)
		(width 0.2032)
		(layer "In7.Cu")
		(net "M1_DQ_NODE1_DQ6")
	)
	(segment
		(start 30.30728 -31.403036)
		(end 30.30728 -55.313326)
		(width 0.2032)
		(layer "In7.Cu")
		(net "M1_DQ_NODE1_DQ6")
	)
	(segment
		(start 40.91686 -25.559512)
		(end 40.49268 -25.983692)
		(width 0.2032)
		(layer "In7.Cu")
		(net "M1_DQ_NODE1_DQ6")
	)
	(segment
		(start 43.05554 -27.071066)
		(end 43.05554 -26.63317)
		(width 0.2032)
		(layer "In7.Cu")
		(net "M1_DQ_NODE1_DQ6")
	)
	(segment
		(start 37.8841 -60.711334)
		(end 39.362126 -62.18936)
		(width 0.2032)
		(layer "In7.Cu")
		(net "M1_DQ_NODE1_DQ6")
	)
	(segment
		(start 35.705288 -60.711334)
		(end 37.8841 -60.711334)
		(width 0.2032)
		(layer "In7.Cu")
		(net "M1_DQ_NODE1_DQ6")
	)
	(segment
		(start 39.651178 -27.234134)
		(end 34.476182 -27.234134)
		(width 0.2032)
		(layer "In7.Cu")
		(net "M1_DQ_NODE1_DQ6")
	)
	(segment
		(start 40.9067 -62.661546)
		(end 41.994074 -62.661546)
		(width 0.2032)
		(layer "In7.Cu")
		(net "M1_DQ_NODE1_DQ6")
	)
	(segment
		(start 40.49268 -26.392632)
		(end 39.651178 -27.234134)
		(width 0.2032)
		(layer "In7.Cu")
		(net "M1_DQ_NODE1_DQ6")
	)
	(segment
		(start 43.46702 -26.22169)
		(end 43.46702 -24.925528)
		(width 0.2032)
		(layer "In7.Cu")
		(net "M1_DQ_NODE1_DQ6")
	)
	(segment
		(start 39.362126 -62.18936)
		(end 40.434514 -62.18936)
		(width 0.2032)
		(layer "In7.Cu")
		(net "M1_DQ_NODE1_DQ6")
	)
	(segment
		(start 46.305724 -66.336164)
		(end 46.822868 -66.336164)
		(width 0.1016)
		(layer "In7.Cu")
		(net "M1_DQ_NODE1_DQ6")
	)
	(segment
		(start 34.476182 -27.234134)
		(end 30.30728 -31.403036)
		(width 0.2032)
		(layer "In7.Cu")
		(net "M1_DQ_NODE1_DQ6")
	)
	(segment
		(start 40.434514 -62.18936)
		(end 40.9067 -62.661546)
		(width 0.2032)
		(layer "In7.Cu")
		(net "M1_DQ_NODE1_DQ6")
	)
	(segment
		(start 46.822868 -66.336164)
		(end 47.465742 -66.979038)
		(width 0.1016)
		(layer "In7.Cu")
		(net "M1_DQ_NODE1_DQ6")
	)
	(segment
		(start 41.120822 -24.529288)
		(end 40.91686 -24.73325)
		(width 0.2032)
		(layer "In7.Cu")
		(net "M1_DQ_NODE1_DQ6")
	)
	(segment
		(start 138.66876 -107.970574)
		(end 138.66876 -107.701842)
		(width 0.508)
		(layer "F.Cu")
		(net "P3V3_CLK_NODE1")
	)
	(segment
		(start 126.213616 -114.239294)
		(end 125.857 -113.882678)
		(width 0.508)
		(layer "F.Cu")
		(net "P3V3_CLK_NODE1")
	)
	(segment
		(start 137.481818 -116.914676)
		(end 137.728452 -116.668042)
		(width 0.1778)
		(layer "F.Cu")
		(net "P3V3_CLK_NODE1")
	)
	(segment
		(start 138.66876 -107.701842)
		(end 138.303 -107.336082)
		(width 0.508)
		(layer "F.Cu")
		(net "P3V3_CLK_NODE1")
	)
	(segment
		(start 141.00556 -113.983008)
		(end 141.00556 -113.26876)
		(width 0.508)
		(layer "F.Cu")
		(net "P3V3_CLK_NODE1")
	)
	(segment
		(start 137.728452 -116.668042)
		(end 138.007852 -116.668042)
		(width 0.1778)
		(layer "F.Cu")
		(net "P3V3_CLK_NODE1")
	)
	(segment
		(start 137.42289 -114.483642)
		(end 137.626852 -114.483642)
		(width 0.1778)
		(layer "F.Cu")
		(net "P3V3_CLK_NODE1")
	)
	(segment
		(start 132.753862 -113.286032)
		(end 133.054852 -112.985042)
		(width 0.1778)
		(layer "F.Cu")
		(net "P3V3_CLK_NODE1")
	)
	(segment
		(start 137.5791 -107.25912)
		(end 137.39876 -107.43946)
		(width 0.508)
		(layer "F.Cu")
		(net "P3V3_CLK_NODE1")
	)
	(segment
		(start 136.503664 -114.91468)
		(end 136.991852 -114.91468)
		(width 0.1778)
		(layer "F.Cu")
		(net "P3V3_CLK_NODE1")
	)
	(segment
		(start 133.054852 -112.985042)
		(end 133.054852 -112.451642)
		(width 0.1778)
		(layer "F.Cu")
		(net "P3V3_CLK_NODE1")
	)
	(segment
		(start 136.503664 -116.914676)
		(end 137.481818 -116.914676)
		(width 0.1778)
		(layer "F.Cu")
		(net "P3V3_CLK_NODE1")
	)
	(segment
		(start 133.71576 -107.970574)
		(end 133.71576 -107.296712)
		(width 0.508)
		(layer "F.Cu")
		(net "P3V3_CLK_NODE1")
	)
	(segment
		(start 131.153662 -113.96472)
		(end 131.153662 -112.653318)
		(width 0.1778)
		(layer "F.Cu")
		(net "P3V3_CLK_NODE1")
	)
	(segment
		(start 136.12876 -107.308142)
		(end 136.25576 -107.181142)
		(width 0.508)
		(layer "F.Cu")
		(net "P3V3_CLK_NODE1")
	)
	(segment
		(start 125.857 -113.882678)
		(end 125.857 -113.65611)
		(width 0.508)
		(layer "F.Cu")
		(net "P3V3_CLK_NODE1")
	)
	(segment
		(start 136.12876 -107.970574)
		(end 136.12876 -107.308142)
		(width 0.508)
		(layer "F.Cu")
		(net "P3V3_CLK_NODE1")
	)
	(segment
		(start 137.39876 -107.43946)
		(end 137.39876 -107.970574)
		(width 0.508)
		(layer "F.Cu")
		(net "P3V3_CLK_NODE1")
	)
	(segment
		(start 132.753862 -113.96472)
		(end 132.753862 -113.286032)
		(width 0.1778)
		(layer "F.Cu")
		(net "P3V3_CLK_NODE1")
	)
	(segment
		(start 140.685266 -111.497872)
		(end 141.482318 -111.497872)
		(width 0.508)
		(layer "F.Cu")
		(net "P3V3_CLK_NODE1")
	)
	(segment
		(start 126.42723 -114.239294)
		(end 126.213616 -114.239294)
		(width 0.508)
		(layer "F.Cu")
		(net "P3V3_CLK_NODE1")
	)
	(segment
		(start 135.553704 -113.43259)
		(end 135.823452 -113.162842)
		(width 0.1778)
		(layer "F.Cu")
		(net "P3V3_CLK_NODE1")
	)
	(segment
		(start 143.15821 -117.082824)
		(end 143.778986 -117.082824)
		(width 0.508)
		(layer "F.Cu")
		(net "P3V3_CLK_NODE1")
	)
	(segment
		(start 136.991852 -114.91468)
		(end 137.42289 -114.483642)
		(width 0.1778)
		(layer "F.Cu")
		(net "P3V3_CLK_NODE1")
	)
	(segment
		(start 140.67536 -111.507778)
		(end 140.685266 -111.497872)
		(width 0.508)
		(layer "F.Cu")
		(net "P3V3_CLK_NODE1")
	)
	(segment
		(start 143.13281 -115.863624)
		(end 143.758158 -115.863624)
		(width 0.508)
		(layer "F.Cu")
		(net "P3V3_CLK_NODE1")
	)
	(segment
		(start 135.553704 -113.96472)
		(end 135.553704 -113.43259)
		(width 0.1778)
		(layer "F.Cu")
		(net "P3V3_CLK_NODE1")
	)
	(via
		(at 133.9342 -106.011472)
		(size 0.508)
		(drill 0.254)
		(layers "F.Cu" "B.Cu")
		(net "P3V3_CLK_NODE1")
	)
	(via
		(at 125.857 -113.65611)
		(size 0.508)
		(drill 0.254)
		(layers "F.Cu" "B.Cu")
		(net "P3V3_CLK_NODE1")
	)
	(via
		(at 141.482318 -111.497872)
		(size 0.508)
		(drill 0.254)
		(layers "F.Cu" "B.Cu")
		(net "P3V3_CLK_NODE1")
	)
	(via
		(at 133.054852 -112.451642)
		(size 0.508)
		(drill 0.254)
		(layers "F.Cu" "B.Cu")
		(net "P3V3_CLK_NODE1")
	)
	(via
		(at 131.153662 -112.653318)
		(size 0.508)
		(drill 0.254)
		(layers "F.Cu" "B.Cu")
		(net "P3V3_CLK_NODE1")
	)
	(via
		(at 136.25576 -107.181142)
		(size 0.508)
		(drill 0.254)
		(layers "F.Cu" "B.Cu")
		(net "P3V3_CLK_NODE1")
	)
	(via
		(at 143.758158 -115.863624)
		(size 0.508)
		(drill 0.254)
		(layers "F.Cu" "B.Cu")
		(net "P3V3_CLK_NODE1")
	)
	(via
		(at 135.823452 -113.162842)
		(size 0.508)
		(drill 0.254)
		(layers "F.Cu" "B.Cu")
		(net "P3V3_CLK_NODE1")
	)
	(via
		(at 137.3378 -106.388408)
		(size 0.508)
		(drill 0.254)
		(layers "F.Cu" "B.Cu")
		(net "P3V3_CLK_NODE1")
	)
	(via
		(at 137.5791 -107.25912)
		(size 0.508)
		(drill 0.254)
		(layers "F.Cu" "B.Cu")
		(net "P3V3_CLK_NODE1")
	)
	(via
		(at 133.71576 -107.296712)
		(size 0.508)
		(drill 0.254)
		(layers "F.Cu" "B.Cu")
		(net "P3V3_CLK_NODE1")
	)
	(via
		(at 143.778986 -117.082824)
		(size 0.508)
		(drill 0.254)
		(layers "F.Cu" "B.Cu")
		(net "P3V3_CLK_NODE1")
	)
	(via
		(at 139.591796 -109.875828)
		(size 0.508)
		(drill 0.254)
		(layers "F.Cu" "B.Cu")
		(net "P3V3_CLK_NODE1")
	)
	(via
		(at 137.626852 -114.483642)
		(size 0.508)
		(drill 0.254)
		(layers "F.Cu" "B.Cu")
		(net "P3V3_CLK_NODE1")
	)
	(via
		(at 141.00556 -113.26876)
		(size 0.508)
		(drill 0.254)
		(layers "F.Cu" "B.Cu")
		(net "P3V3_CLK_NODE1")
	)
	(via
		(at 138.303 -107.336082)
		(size 0.508)
		(drill 0.254)
		(layers "F.Cu" "B.Cu")
		(net "P3V3_CLK_NODE1")
	)
	(via
		(at 138.007852 -116.668042)
		(size 0.508)
		(drill 0.254)
		(layers "F.Cu" "B.Cu")
		(net "P3V3_CLK_NODE1")
	)
	(segment
		(start 99.39274 -25.29078)
		(end 100.350066 -24.333454)
		(width 0.1651)
		(layer "F.Cu")
		(net "M1_DQ_NODE1_DQ59")
	)
	(segment
		(start 73.641458 -73.188322)
		(end 73.774808 -73.321672)
		(width 0.1016)
		(layer "F.Cu")
		(net "M1_DQ_NODE1_DQ59")
	)
	(segment
		(start 75.923394 -73.321672)
		(end 76.224384 -73.020682)
		(width 0.1016)
		(layer "F.Cu")
		(net "M1_DQ_NODE1_DQ59")
	)
	(segment
		(start 76.224384 -72.151748)
		(end 76.583032 -71.7931)
		(width 0.1016)
		(layer "F.Cu")
		(net "M1_DQ_NODE1_DQ59")
	)
	(segment
		(start 73.774808 -73.321672)
		(end 75.923394 -73.321672)
		(width 0.1016)
		(layer "F.Cu")
		(net "M1_DQ_NODE1_DQ59")
	)
	(segment
		(start 100.350066 -24.333454)
		(end 100.350066 -20.94992)
		(width 0.1651)
		(layer "F.Cu")
		(net "M1_DQ_NODE1_DQ59")
	)
	(segment
		(start 76.583032 -71.7931)
		(end 76.574142 -71.7931)
		(width 0.1016)
		(layer "F.Cu")
		(net "M1_DQ_NODE1_DQ59")
	)
	(segment
		(start 76.224384 -73.020682)
		(end 76.224384 -72.151748)
		(width 0.1016)
		(layer "F.Cu")
		(net "M1_DQ_NODE1_DQ59")
	)
	(via
		(at 99.39274 -25.29078)
		(size 0.508)
		(drill 0.254)
		(layers "F.Cu" "B.Cu")
		(net "M1_DQ_NODE1_DQ59")
	)
	(via
		(at 76.574142 -71.7931)
		(size 0.508)
		(drill 0.254)
		(layers "F.Cu" "B.Cu")
		(net "M1_DQ_NODE1_DQ59")
	)
	(segment
		(start 98.8822 -34.328354)
		(end 98.631502 -34.077656)
		(width 0.2032)
		(layer "In7.Cu")
		(net "M1_DQ_NODE1_DQ59")
	)
	(segment
		(start 99.002342 -28.845002)
		(end 98.794062 -28.636722)
		(width 0.2032)
		(layer "In7.Cu")
		(net "M1_DQ_NODE1_DQ59")
	)
	(segment
		(start 99.002342 -30.612842)
		(end 98.794062 -30.404562)
		(width 0.2032)
		(layer "In7.Cu")
		(net "M1_DQ_NODE1_DQ59")
	)
	(segment
		(start 98.631502 -34.077656)
		(end 98.631502 -32.186118)
		(width 0.2032)
		(layer "In7.Cu")
		(net "M1_DQ_NODE1_DQ59")
	)
	(segment
		(start 96.768412 -50.597054)
		(end 96.976692 -50.805334)
		(width 0.2032)
		(layer "In7.Cu")
		(net "M1_DQ_NODE1_DQ59")
	)
	(segment
		(start 85.0392 -66.40322)
		(end 85.0392 -63.920878)
		(width 0.2032)
		(layer "In7.Cu")
		(net "M1_DQ_NODE1_DQ59")
	)
	(segment
		(start 81.73212 -69.7103)
		(end 85.0392 -66.40322)
		(width 0.2032)
		(layer "In7.Cu")
		(net "M1_DQ_NODE1_DQ59")
	)
	(segment
		(start 84.52866 -63.410338)
		(end 84.52866 -62.842902)
		(width 0.2032)
		(layer "In7.Cu")
		(net "M1_DQ_NODE1_DQ59")
	)
	(segment
		(start 98.8822 -49.194466)
		(end 98.8822 -34.328354)
		(width 0.2032)
		(layer "In7.Cu")
		(net "M1_DQ_NODE1_DQ59")
	)
	(segment
		(start 96.976692 -50.805334)
		(end 97.271332 -50.805334)
		(width 0.2032)
		(layer "In7.Cu")
		(net "M1_DQ_NODE1_DQ59")
	)
	(segment
		(start 99.002342 -29.556202)
		(end 99.5045 -29.556202)
		(width 0.2032)
		(layer "In7.Cu")
		(net "M1_DQ_NODE1_DQ59")
	)
	(segment
		(start 76.574142 -71.7931)
		(end 76.574142 -71.543672)
		(width 0.1016)
		(layer "In7.Cu")
		(net "M1_DQ_NODE1_DQ59")
	)
	(segment
		(start 99.5045 -28.845002)
		(end 99.002342 -28.845002)
		(width 0.2032)
		(layer "In7.Cu")
		(net "M1_DQ_NODE1_DQ59")
	)
	(segment
		(start 98.05035 -48.725836)
		(end 98.05035 -49.020476)
		(width 0.2032)
		(layer "In7.Cu")
		(net "M1_DQ_NODE1_DQ59")
	)
	(segment
		(start 101.425502 -30.816042)
		(end 101.42474 -30.816042)
		(width 0.2032)
		(layer "In7.Cu")
		(net "M1_DQ_NODE1_DQ59")
	)
	(segment
		(start 98.794062 -25.889458)
		(end 99.39274 -25.29078)
		(width 0.2032)
		(layer "In7.Cu")
		(net "M1_DQ_NODE1_DQ59")
	)
	(segment
		(start 101.22154 -31.324042)
		(end 101.42474 -31.120842)
		(width 0.2032)
		(layer "In7.Cu")
		(net "M1_DQ_NODE1_DQ59")
	)
	(segment
		(start 84.52866 -62.842902)
		(end 85.018626 -62.352936)
		(width 0.2032)
		(layer "In7.Cu")
		(net "M1_DQ_NODE1_DQ59")
	)
	(segment
		(start 85.0392 -63.920878)
		(end 84.52866 -63.410338)
		(width 0.2032)
		(layer "In7.Cu")
		(net "M1_DQ_NODE1_DQ59")
	)
	(segment
		(start 85.72373 -62.352936)
		(end 96.473772 -51.602894)
		(width 0.2032)
		(layer "In7.Cu")
		(net "M1_DQ_NODE1_DQ59")
	)
	(segment
		(start 98.794062 -32.023558)
		(end 98.794062 -31.532322)
		(width 0.2032)
		(layer "In7.Cu")
		(net "M1_DQ_NODE1_DQ59")
	)
	(segment
		(start 96.473772 -51.308254)
		(end 95.762572 -50.597054)
		(width 0.2032)
		(layer "In7.Cu")
		(net "M1_DQ_NODE1_DQ59")
	)
	(segment
		(start 99.002342 -31.324042)
		(end 101.22154 -31.324042)
		(width 0.2032)
		(layer "In7.Cu")
		(net "M1_DQ_NODE1_DQ59")
	)
	(segment
		(start 96.768412 -50.302414)
		(end 96.768412 -50.597054)
		(width 0.2032)
		(layer "In7.Cu")
		(net "M1_DQ_NODE1_DQ59")
	)
	(segment
		(start 98.794062 -30.404562)
		(end 98.794062 -29.764482)
		(width 0.2032)
		(layer "In7.Cu")
		(net "M1_DQ_NODE1_DQ59")
	)
	(segment
		(start 85.018626 -62.352936)
		(end 85.72373 -62.352936)
		(width 0.2032)
		(layer "In7.Cu")
		(net "M1_DQ_NODE1_DQ59")
	)
	(segment
		(start 99.71278 -29.053282)
		(end 99.5045 -28.845002)
		(width 0.2032)
		(layer "In7.Cu")
		(net "M1_DQ_NODE1_DQ59")
	)
	(segment
		(start 101.22154 -30.612842)
		(end 99.002342 -30.612842)
		(width 0.2032)
		(layer "In7.Cu")
		(net "M1_DQ_NODE1_DQ59")
	)
	(segment
		(start 99.5045 -29.556202)
		(end 99.71278 -29.347922)
		(width 0.2032)
		(layer "In7.Cu")
		(net "M1_DQ_NODE1_DQ59")
	)
	(segment
		(start 95.762572 -50.597054)
		(end 95.762572 -50.302414)
		(width 0.2032)
		(layer "In7.Cu")
		(net "M1_DQ_NODE1_DQ59")
	)
	(segment
		(start 99.71278 -29.347922)
		(end 99.71278 -29.053282)
		(width 0.2032)
		(layer "In7.Cu")
		(net "M1_DQ_NODE1_DQ59")
	)
	(segment
		(start 97.54743 -48.517556)
		(end 97.84207 -48.517556)
		(width 0.2032)
		(layer "In7.Cu")
		(net "M1_DQ_NODE1_DQ59")
	)
	(segment
		(start 101.42474 -30.816042)
		(end 101.22154 -30.612842)
		(width 0.2032)
		(layer "In7.Cu")
		(net "M1_DQ_NODE1_DQ59")
	)
	(segment
		(start 98.05035 -49.020476)
		(end 96.768412 -50.302414)
		(width 0.2032)
		(layer "In7.Cu")
		(net "M1_DQ_NODE1_DQ59")
	)
	(segment
		(start 101.425502 -31.120842)
		(end 101.425502 -30.816042)
		(width 0.2032)
		(layer "In7.Cu")
		(net "M1_DQ_NODE1_DQ59")
	)
	(segment
		(start 98.794062 -28.636722)
		(end 98.794062 -25.889458)
		(width 0.2032)
		(layer "In7.Cu")
		(net "M1_DQ_NODE1_DQ59")
	)
	(segment
		(start 96.473772 -51.602894)
		(end 96.473772 -51.308254)
		(width 0.2032)
		(layer "In7.Cu")
		(net "M1_DQ_NODE1_DQ59")
	)
	(segment
		(start 76.574142 -71.543672)
		(end 77.551788 -70.566026)
		(width 0.1016)
		(layer "In7.Cu")
		(net "M1_DQ_NODE1_DQ59")
	)
	(segment
		(start 77.551788 -70.566026)
		(end 78.407514 -69.7103)
		(width 0.2032)
		(layer "In7.Cu")
		(net "M1_DQ_NODE1_DQ59")
	)
	(segment
		(start 98.794062 -29.764482)
		(end 99.002342 -29.556202)
		(width 0.2032)
		(layer "In7.Cu")
		(net "M1_DQ_NODE1_DQ59")
	)
	(segment
		(start 97.271332 -50.805334)
		(end 98.8822 -49.194466)
		(width 0.2032)
		(layer "In7.Cu")
		(net "M1_DQ_NODE1_DQ59")
	)
	(segment
		(start 98.794062 -31.532322)
		(end 99.002342 -31.324042)
		(width 0.2032)
		(layer "In7.Cu")
		(net "M1_DQ_NODE1_DQ59")
	)
	(segment
		(start 98.631502 -32.186118)
		(end 98.794062 -32.023558)
		(width 0.2032)
		(layer "In7.Cu")
		(net "M1_DQ_NODE1_DQ59")
	)
	(segment
		(start 78.407514 -69.7103)
		(end 81.73212 -69.7103)
		(width 0.2032)
		(layer "In7.Cu")
		(net "M1_DQ_NODE1_DQ59")
	)
	(segment
		(start 95.762572 -50.302414)
		(end 97.54743 -48.517556)
		(width 0.2032)
		(layer "In7.Cu")
		(net "M1_DQ_NODE1_DQ59")
	)
	(segment
		(start 97.84207 -48.517556)
		(end 98.05035 -48.725836)
		(width 0.2032)
		(layer "In7.Cu")
		(net "M1_DQ_NODE1_DQ59")
	)
	(segment
		(start 101.42474 -31.120842)
		(end 101.425502 -31.120842)
		(width 0.2032)
		(layer "In7.Cu")
		(net "M1_DQ_NODE1_DQ59")
	)
	(segment
		(start 129.403856 -118.114572)
		(end 128.484122 -118.114572)
		(width 0.1778)
		(layer "F.Cu")
		(net "P1V5_CLK_NODE1")
	)
	(segment
		(start 136.503664 -118.914672)
		(end 137.225024 -118.914672)
		(width 0.1524)
		(layer "F.Cu")
		(net "P1V5_CLK_NODE1")
	)
	(segment
		(start 137.624312 -119.31396)
		(end 138.560302 -119.31396)
		(width 0.1524)
		(layer "F.Cu")
		(net "P1V5_CLK_NODE1")
	)
	(segment
		(start 137.225024 -118.914672)
		(end 137.624312 -119.31396)
		(width 0.1524)
		(layer "F.Cu")
		(net "P1V5_CLK_NODE1")
	)
	(via
		(at 128.484122 -118.114572)
		(size 0.508)
		(drill 0.254)
		(layers "F.Cu" "B.Cu")
		(net "P1V5_CLK_NODE1")
	)
	(via
		(at 140.8557 -119.297196)
		(size 0.508)
		(drill 0.254)
		(layers "F.Cu" "B.Cu")
		(net "P1V5_CLK_NODE1")
	)
	(via
		(at 138.560302 -119.31396)
		(size 0.508)
		(drill 0.254)
		(layers "F.Cu" "B.Cu")
		(net "P1V5_CLK_NODE1")
	)
	(segment
		(start 138.38682 -119.487442)
		(end 138.560302 -119.31396)
		(width 0.508)
		(layer "B.Cu")
		(net "P1V5_CLK_NODE1")
	)
	(segment
		(start 129.200402 -119.055642)
		(end 129.200402 -118.830852)
		(width 0.508)
		(layer "B.Cu")
		(net "P1V5_CLK_NODE1")
	)
	(segment
		(start 129.200402 -118.830852)
		(end 128.484122 -118.114572)
		(width 0.508)
		(layer "B.Cu")
		(net "P1V5_CLK_NODE1")
	)
	(segment
		(start 136.782302 -119.487442)
		(end 138.38682 -119.487442)
		(width 0.508)
		(layer "B.Cu")
		(net "P1V5_CLK_NODE1")
	)
	(segment
		(start 52.82438 -60.180728)
		(end 52.82438 -62.991746)
		(width 0.1016)
		(layer "F.Cu")
		(net "M1_DQ_NODE1_DQ26")
	)
	(segment
		(start 52.82438 -62.991746)
		(end 52.879752 -63.047118)
		(width 0.1016)
		(layer "F.Cu")
		(net "M1_DQ_NODE1_DQ26")
	)
	(segment
		(start 58.950098 -22.980142)
		(end 58.677302 -23.252938)
		(width 0.1651)
		(layer "F.Cu")
		(net "M1_DQ_NODE1_DQ26")
	)
	(segment
		(start 52.20589 -59.562238)
		(end 52.82438 -60.180728)
		(width 0.1016)
		(layer "F.Cu")
		(net "M1_DQ_NODE1_DQ26")
	)
	(segment
		(start 58.950098 -20.94992)
		(end 58.950098 -22.980142)
		(width 0.1651)
		(layer "F.Cu")
		(net "M1_DQ_NODE1_DQ26")
	)
	(via
		(at 58.677302 -23.252938)
		(size 0.508)
		(drill 0.254)
		(layers "F.Cu" "B.Cu")
		(net "M1_DQ_NODE1_DQ26")
	)
	(via
		(at 52.20589 -59.562238)
		(size 0.508)
		(drill 0.254)
		(layers "F.Cu" "B.Cu")
		(net "M1_DQ_NODE1_DQ26")
	)
	(segment
		(start 44.2214 -48.63973)
		(end 44.2214 -44.651422)
		(width 0.2032)
		(layer "In2.Cu")
		(net "M1_DQ_NODE1_DQ26")
	)
	(segment
		(start 57.742582 -29.206444)
		(end 57.742582 -26.839926)
		(width 0.2032)
		(layer "In2.Cu")
		(net "M1_DQ_NODE1_DQ26")
	)
	(segment
		(start 57.742582 -25.695148)
		(end 57.742582 -25.366726)
		(width 0.2032)
		(layer "In2.Cu")
		(net "M1_DQ_NODE1_DQ26")
	)
	(segment
		(start 52.204112 -58.735722)
		(end 51.26228 -57.79389)
		(width 0.1016)
		(layer "In2.Cu")
		(net "M1_DQ_NODE1_DQ26")
	)
	(segment
		(start 45.6438 -43.438318)
		(end 56.111902 -32.970216)
		(width 0.2032)
		(layer "In2.Cu")
		(net "M1_DQ_NODE1_DQ26")
	)
	(segment
		(start 44.7294 -44.448222)
		(end 44.9326 -44.651422)
		(width 0.2032)
		(layer "In2.Cu")
		(net "M1_DQ_NODE1_DQ26")
	)
	(segment
		(start 51.26228 -55.68061)
		(end 45.6311 -50.04943)
		(width 0.2032)
		(layer "In2.Cu")
		(net "M1_DQ_NODE1_DQ26")
	)
	(segment
		(start 56.111902 -30.260798)
		(end 56.96839 -29.40431)
		(width 0.2032)
		(layer "In2.Cu")
		(net "M1_DQ_NODE1_DQ26")
	)
	(segment
		(start 45.14088 -48.414686)
		(end 45.43552 -48.414686)
		(width 0.2032)
		(layer "In2.Cu")
		(net "M1_DQ_NODE1_DQ26")
	)
	(segment
		(start 44.890182 -49.308512)
		(end 44.2214 -48.63973)
		(width 0.2032)
		(layer "In2.Cu")
		(net "M1_DQ_NODE1_DQ26")
	)
	(segment
		(start 57.742582 -24.221948)
		(end 57.742582 -23.754334)
		(width 0.2032)
		(layer "In2.Cu")
		(net "M1_DQ_NODE1_DQ26")
	)
	(segment
		(start 44.2214 -44.651422)
		(end 44.4246 -44.448222)
		(width 0.2032)
		(layer "In2.Cu")
		(net "M1_DQ_NODE1_DQ26")
	)
	(segment
		(start 51.26228 -57.79389)
		(end 51.26228 -56.973978)
		(width 0.1016)
		(layer "In2.Cu")
		(net "M1_DQ_NODE1_DQ26")
	)
	(segment
		(start 44.9326 -48.206406)
		(end 45.14088 -48.414686)
		(width 0.2032)
		(layer "In2.Cu")
		(net "M1_DQ_NODE1_DQ26")
	)
	(segment
		(start 52.204112 -59.56046)
		(end 52.204112 -58.735722)
		(width 0.1016)
		(layer "In2.Cu")
		(net "M1_DQ_NODE1_DQ26")
	)
	(segment
		(start 44.4246 -44.448222)
		(end 44.7294 -44.448222)
		(width 0.2032)
		(layer "In2.Cu")
		(net "M1_DQ_NODE1_DQ26")
	)
	(segment
		(start 58.243978 -23.252938)
		(end 58.677302 -23.252938)
		(width 0.2032)
		(layer "In2.Cu")
		(net "M1_DQ_NODE1_DQ26")
	)
	(segment
		(start 51.26228 -56.973978)
		(end 51.26228 -55.68061)
		(width 0.2032)
		(layer "In2.Cu")
		(net "M1_DQ_NODE1_DQ26")
	)
	(segment
		(start 57.544716 -29.40431)
		(end 57.742582 -29.206444)
		(width 0.2032)
		(layer "In2.Cu")
		(net "M1_DQ_NODE1_DQ26")
	)
	(segment
		(start 44.9326 -44.651422)
		(end 44.9326 -48.206406)
		(width 0.2032)
		(layer "In2.Cu")
		(net "M1_DQ_NODE1_DQ26")
	)
	(segment
		(start 45.6311 -50.04943)
		(end 45.6311 -49.616868)
		(width 0.2032)
		(layer "In2.Cu")
		(net "M1_DQ_NODE1_DQ26")
	)
	(segment
		(start 45.322744 -49.308512)
		(end 44.890182 -49.308512)
		(width 0.2032)
		(layer "In2.Cu")
		(net "M1_DQ_NODE1_DQ26")
	)
	(segment
		(start 57.742582 -26.839926)
		(end 58.15076 -26.431748)
		(width 0.2032)
		(layer "In2.Cu")
		(net "M1_DQ_NODE1_DQ26")
	)
	(segment
		(start 58.15076 -24.958548)
		(end 58.15076 -24.630126)
		(width 0.2032)
		(layer "In2.Cu")
		(net "M1_DQ_NODE1_DQ26")
	)
	(segment
		(start 58.15076 -26.103326)
		(end 57.742582 -25.695148)
		(width 0.2032)
		(layer "In2.Cu")
		(net "M1_DQ_NODE1_DQ26")
	)
	(segment
		(start 57.742582 -23.754334)
		(end 58.243978 -23.252938)
		(width 0.2032)
		(layer "In2.Cu")
		(net "M1_DQ_NODE1_DQ26")
	)
	(segment
		(start 45.6438 -48.206406)
		(end 45.6438 -43.438318)
		(width 0.2032)
		(layer "In2.Cu")
		(net "M1_DQ_NODE1_DQ26")
	)
	(segment
		(start 52.20589 -59.562238)
		(end 52.204112 -59.56046)
		(width 0.1016)
		(layer "In2.Cu")
		(net "M1_DQ_NODE1_DQ26")
	)
	(segment
		(start 57.742582 -25.366726)
		(end 58.15076 -24.958548)
		(width 0.2032)
		(layer "In2.Cu")
		(net "M1_DQ_NODE1_DQ26")
	)
	(segment
		(start 56.111902 -32.970216)
		(end 56.111902 -30.260798)
		(width 0.2032)
		(layer "In2.Cu")
		(net "M1_DQ_NODE1_DQ26")
	)
	(segment
		(start 56.96839 -29.40431)
		(end 57.544716 -29.40431)
		(width 0.2032)
		(layer "In2.Cu")
		(net "M1_DQ_NODE1_DQ26")
	)
	(segment
		(start 58.15076 -24.630126)
		(end 57.742582 -24.221948)
		(width 0.2032)
		(layer "In2.Cu")
		(net "M1_DQ_NODE1_DQ26")
	)
	(segment
		(start 58.15076 -26.431748)
		(end 58.15076 -26.103326)
		(width 0.2032)
		(layer "In2.Cu")
		(net "M1_DQ_NODE1_DQ26")
	)
	(segment
		(start 45.43552 -48.414686)
		(end 45.6438 -48.206406)
		(width 0.2032)
		(layer "In2.Cu")
		(net "M1_DQ_NODE1_DQ26")
	)
	(segment
		(start 45.6311 -49.616868)
		(end 45.322744 -49.308512)
		(width 0.2032)
		(layer "In2.Cu")
		(net "M1_DQ_NODE1_DQ26")
	)
	(segment
		(start 102.60711 -31.378398)
		(end 107.160822 -31.378398)
		(width 0.1016)
		(layer "F.Cu")
		(net "TP_NODE1_ERR_OUT_DIMM0")
	)
	(segment
		(start 101.85019 -30.621478)
		(end 102.60711 -31.378398)
		(width 0.1016)
		(layer "F.Cu")
		(net "TP_NODE1_ERR_OUT_DIMM0")
	)
	(segment
		(start 101.85019 -29.149802)
		(end 101.85019 -30.621478)
		(width 0.1016)
		(layer "F.Cu")
		(net "TP_NODE1_ERR_OUT_DIMM0")
	)
	(via
		(at 107.160822 -31.378398)
		(size 0.508)
		(drill 0.254)
		(layers "F.Cu" "B.Cu")
		(net "TP_NODE1_ERR_OUT_DIMM0")
	)
	(via
		(at 142.83436 -123.000008)
		(size 0.508)
		(drill 0.254)
		(layers "F.Cu" "B.Cu")
		(net "P1V5_CLK_NODE1_R")
	)
	(segment
		(start 93.3069 -31.477458)
		(end 93.053408 -31.477458)
		(width 0.1651)
		(layer "F.Cu")
		(net "M1_DQ_NODE1_DQ52")
	)
	(segment
		(start 92.25026 -30.67431)
		(end 92.25026 -29.149802)
		(width 0.1651)
		(layer "F.Cu")
		(net "M1_DQ_NODE1_DQ52")
	)
	(segment
		(start 72.901556 -69.580506)
		(end 73.209404 -69.272658)
		(width 0.1016)
		(layer "F.Cu")
		(net "M1_DQ_NODE1_DQ52")
	)
	(segment
		(start 73.209404 -69.272658)
		(end 74.940414 -69.272658)
		(width 0.1016)
		(layer "F.Cu")
		(net "M1_DQ_NODE1_DQ52")
	)
	(segment
		(start 76.321158 -67.891914)
		(end 76.321158 -67.31254)
		(width 0.1016)
		(layer "F.Cu")
		(net "M1_DQ_NODE1_DQ52")
	)
	(segment
		(start 74.940414 -69.272658)
		(end 76.321158 -67.891914)
		(width 0.1016)
		(layer "F.Cu")
		(net "M1_DQ_NODE1_DQ52")
	)
	(segment
		(start 93.053408 -31.477458)
		(end 92.25026 -30.67431)
		(width 0.1651)
		(layer "F.Cu")
		(net "M1_DQ_NODE1_DQ52")
	)
	(via
		(at 76.321158 -67.31254)
		(size 0.508)
		(drill 0.254)
		(layers "F.Cu" "B.Cu")
		(net "M1_DQ_NODE1_DQ52")
	)
	(via
		(at 93.3069 -31.477458)
		(size 0.508)
		(drill 0.254)
		(layers "F.Cu" "B.Cu")
		(net "M1_DQ_NODE1_DQ52")
	)
	(segment
		(start 78.99654 -64.867028)
		(end 78.62062 -64.867028)
		(width 0.2032)
		(layer "In7.Cu")
		(net "M1_DQ_NODE1_DQ52")
	)
	(segment
		(start 83.88858 -52.250594)
		(end 83.88858 -52.555394)
		(width 0.2032)
		(layer "In7.Cu")
		(net "M1_DQ_NODE1_DQ52")
	)
	(segment
		(start 79.98968 -57.76722)
		(end 80.19796 -57.9755)
		(width 0.2032)
		(layer "In7.Cu")
		(net "M1_DQ_NODE1_DQ52")
	)
	(segment
		(start 86.716362 -48.302164)
		(end 85.564472 -49.454054)
		(width 0.2032)
		(layer "In7.Cu")
		(net "M1_DQ_NODE1_DQ52")
	)
	(segment
		(start 80.19796 -57.9755)
		(end 80.19796 -58.27014)
		(width 0.2032)
		(layer "In7.Cu")
		(net "M1_DQ_NODE1_DQ52")
	)
	(segment
		(start 78.41234 -60.097924)
		(end 78.41234 -63.947548)
		(width 0.2032)
		(layer "In7.Cu")
		(net "M1_DQ_NODE1_DQ52")
	)
	(segment
		(start 85.972396 -50.166778)
		(end 85.972396 -50.471578)
		(width 0.2032)
		(layer "In7.Cu")
		(net "M1_DQ_NODE1_DQ52")
	)
	(segment
		(start 79.833978 -55.489348)
		(end 79.529178 -55.489348)
		(width 0.2032)
		(layer "In7.Cu")
		(net "M1_DQ_NODE1_DQ52")
	)
	(segment
		(start 82.438748 -52.579778)
		(end 82.438748 -52.884578)
		(width 0.2032)
		(layer "In7.Cu")
		(net "M1_DQ_NODE1_DQ52")
	)
	(segment
		(start 80.19796 -58.27014)
		(end 79.98968 -58.47842)
		(width 0.2032)
		(layer "In7.Cu")
		(net "M1_DQ_NODE1_DQ52")
	)
	(segment
		(start 79.20482 -64.364108)
		(end 79.20482 -64.658748)
		(width 0.2032)
		(layer "In7.Cu")
		(net "M1_DQ_NODE1_DQ52")
	)
	(segment
		(start 93.37294 -31.543498)
		(end 93.37294 -38.225984)
		(width 0.2032)
		(layer "In7.Cu")
		(net "M1_DQ_NODE1_DQ52")
	)
	(segment
		(start 78.41234 -65.401444)
		(end 77.134974 -66.67881)
		(width 0.2032)
		(layer "In7.Cu")
		(net "M1_DQ_NODE1_DQ52")
	)
	(segment
		(start 84.714334 -51.72964)
		(end 84.409534 -51.72964)
		(width 0.2032)
		(layer "In7.Cu")
		(net "M1_DQ_NODE1_DQ52")
	)
	(segment
		(start 81.39684 -53.621686)
		(end 81.39684 -53.926486)
		(width 0.2032)
		(layer "In7.Cu")
		(net "M1_DQ_NODE1_DQ52")
	)
	(segment
		(start 82.630518 -53.813456)
		(end 82.325718 -53.813456)
		(width 0.2032)
		(layer "In7.Cu")
		(net "M1_DQ_NODE1_DQ52")
	)
	(segment
		(start 82.438748 -52.884578)
		(end 82.846672 -53.292502)
		(width 0.2032)
		(layer "In7.Cu")
		(net "M1_DQ_NODE1_DQ52")
	)
	(segment
		(start 85.564472 -49.758854)
		(end 85.972396 -50.166778)
		(width 0.2032)
		(layer "In7.Cu")
		(net "M1_DQ_NODE1_DQ52")
	)
	(segment
		(start 79.529178 -55.489348)
		(end 79.15402 -55.864506)
		(width 0.2032)
		(layer "In7.Cu")
		(net "M1_DQ_NODE1_DQ52")
	)
	(segment
		(start 93.8784 -38.731444)
		(end 93.8784 -42.532554)
		(width 0.2032)
		(layer "In7.Cu")
		(net "M1_DQ_NODE1_DQ52")
	)
	(segment
		(start 83.88858 -52.555394)
		(end 83.672426 -52.771548)
		(width 0.2032)
		(layer "In7.Cu")
		(net "M1_DQ_NODE1_DQ52")
	)
	(segment
		(start 83.367626 -52.771548)
		(end 82.959702 -52.363624)
		(width 0.2032)
		(layer "In7.Cu")
		(net "M1_DQ_NODE1_DQ52")
	)
	(segment
		(start 79.3623 -57.76722)
		(end 79.98968 -57.76722)
		(width 0.2032)
		(layer "In7.Cu")
		(net "M1_DQ_NODE1_DQ52")
	)
	(segment
		(start 82.654902 -52.363624)
		(end 82.438748 -52.579778)
		(width 0.2032)
		(layer "In7.Cu")
		(net "M1_DQ_NODE1_DQ52")
	)
	(segment
		(start 85.451442 -50.687732)
		(end 85.043518 -50.279808)
		(width 0.2032)
		(layer "In7.Cu")
		(net "M1_DQ_NODE1_DQ52")
	)
	(segment
		(start 84.522564 -50.800762)
		(end 84.930488 -51.208686)
		(width 0.2032)
		(layer "In7.Cu")
		(net "M1_DQ_NODE1_DQ52")
	)
	(segment
		(start 84.522564 -50.495962)
		(end 84.522564 -50.800762)
		(width 0.2032)
		(layer "In7.Cu")
		(net "M1_DQ_NODE1_DQ52")
	)
	(segment
		(start 84.738718 -50.279808)
		(end 84.522564 -50.495962)
		(width 0.2032)
		(layer "In7.Cu")
		(net "M1_DQ_NODE1_DQ52")
	)
	(segment
		(start 80.241902 -55.897272)
		(end 79.833978 -55.489348)
		(width 0.2032)
		(layer "In7.Cu")
		(net "M1_DQ_NODE1_DQ52")
	)
	(segment
		(start 81.612994 -53.405532)
		(end 81.39684 -53.621686)
		(width 0.2032)
		(layer "In7.Cu")
		(net "M1_DQ_NODE1_DQ52")
	)
	(segment
		(start 80.354932 -54.663594)
		(end 80.354932 -54.968394)
		(width 0.2032)
		(layer "In7.Cu")
		(net "M1_DQ_NODE1_DQ52")
	)
	(segment
		(start 81.917794 -53.405532)
		(end 81.612994 -53.405532)
		(width 0.2032)
		(layer "In7.Cu")
		(net "M1_DQ_NODE1_DQ52")
	)
	(segment
		(start 93.3069 -31.477458)
		(end 93.37294 -31.543498)
		(width 0.2032)
		(layer "In7.Cu")
		(net "M1_DQ_NODE1_DQ52")
	)
	(segment
		(start 85.756242 -50.687732)
		(end 85.451442 -50.687732)
		(width 0.2032)
		(layer "In7.Cu")
		(net "M1_DQ_NODE1_DQ52")
	)
	(segment
		(start 78.99654 -64.155828)
		(end 79.20482 -64.364108)
		(width 0.2032)
		(layer "In7.Cu")
		(net "M1_DQ_NODE1_DQ52")
	)
	(segment
		(start 79.20482 -64.658748)
		(end 78.99654 -64.867028)
		(width 0.2032)
		(layer "In7.Cu")
		(net "M1_DQ_NODE1_DQ52")
	)
	(segment
		(start 79.98968 -58.47842)
		(end 79.3623 -58.47842)
		(width 0.2032)
		(layer "In7.Cu")
		(net "M1_DQ_NODE1_DQ52")
	)
	(segment
		(start 81.28381 -54.855364)
		(end 80.875886 -54.44744)
		(width 0.2032)
		(layer "In7.Cu")
		(net "M1_DQ_NODE1_DQ52")
	)
	(segment
		(start 79.3623 -58.47842)
		(end 79.15402 -58.6867)
		(width 0.2032)
		(layer "In7.Cu")
		(net "M1_DQ_NODE1_DQ52")
	)
	(segment
		(start 80.354932 -54.968394)
		(end 80.762856 -55.376318)
		(width 0.2032)
		(layer "In7.Cu")
		(net "M1_DQ_NODE1_DQ52")
	)
	(segment
		(start 78.41234 -63.947548)
		(end 78.62062 -64.155828)
		(width 0.2032)
		(layer "In7.Cu")
		(net "M1_DQ_NODE1_DQ52")
	)
	(segment
		(start 77.134974 -66.67881)
		(end 76.501244 -67.31254)
		(width 0.1016)
		(layer "In7.Cu")
		(net "M1_DQ_NODE1_DQ52")
	)
	(segment
		(start 80.762856 -55.376318)
		(end 80.762856 -55.681118)
		(width 0.2032)
		(layer "In7.Cu")
		(net "M1_DQ_NODE1_DQ52")
	)
	(segment
		(start 80.875886 -54.44744)
		(end 80.571086 -54.44744)
		(width 0.2032)
		(layer "In7.Cu")
		(net "M1_DQ_NODE1_DQ52")
	)
	(segment
		(start 81.804764 -54.33441)
		(end 81.804764 -54.63921)
		(width 0.2032)
		(layer "In7.Cu")
		(net "M1_DQ_NODE1_DQ52")
	)
	(segment
		(start 93.8784 -42.532554)
		(end 88.10879 -48.302164)
		(width 0.2032)
		(layer "In7.Cu")
		(net "M1_DQ_NODE1_DQ52")
	)
	(segment
		(start 80.762856 -55.681118)
		(end 80.546702 -55.897272)
		(width 0.2032)
		(layer "In7.Cu")
		(net "M1_DQ_NODE1_DQ52")
	)
	(segment
		(start 81.804764 -54.63921)
		(end 81.58861 -54.855364)
		(width 0.2032)
		(layer "In7.Cu")
		(net "M1_DQ_NODE1_DQ52")
	)
	(segment
		(start 81.39684 -53.926486)
		(end 81.804764 -54.33441)
		(width 0.2032)
		(layer "In7.Cu")
		(net "M1_DQ_NODE1_DQ52")
	)
	(segment
		(start 79.15402 -58.6867)
		(end 79.15402 -59.356244)
		(width 0.2032)
		(layer "In7.Cu")
		(net "M1_DQ_NODE1_DQ52")
	)
	(segment
		(start 93.37294 -38.225984)
		(end 93.8784 -38.731444)
		(width 0.2032)
		(layer "In7.Cu")
		(net "M1_DQ_NODE1_DQ52")
	)
	(segment
		(start 82.325718 -53.813456)
		(end 81.917794 -53.405532)
		(width 0.2032)
		(layer "In7.Cu")
		(net "M1_DQ_NODE1_DQ52")
	)
	(segment
		(start 84.00161 -51.321716)
		(end 83.69681 -51.321716)
		(width 0.2032)
		(layer "In7.Cu")
		(net "M1_DQ_NODE1_DQ52")
	)
	(segment
		(start 78.62062 -64.155828)
		(end 78.99654 -64.155828)
		(width 0.2032)
		(layer "In7.Cu")
		(net "M1_DQ_NODE1_DQ52")
	)
	(segment
		(start 81.58861 -54.855364)
		(end 81.28381 -54.855364)
		(width 0.2032)
		(layer "In7.Cu")
		(net "M1_DQ_NODE1_DQ52")
	)
	(segment
		(start 78.62062 -64.867028)
		(end 78.41234 -65.075308)
		(width 0.2032)
		(layer "In7.Cu")
		(net "M1_DQ_NODE1_DQ52")
	)
	(segment
		(start 82.959702 -52.363624)
		(end 82.654902 -52.363624)
		(width 0.2032)
		(layer "In7.Cu")
		(net "M1_DQ_NODE1_DQ52")
	)
	(segment
		(start 85.564472 -49.454054)
		(end 85.564472 -49.758854)
		(width 0.2032)
		(layer "In7.Cu")
		(net "M1_DQ_NODE1_DQ52")
	)
	(segment
		(start 82.846672 -53.292502)
		(end 82.846672 -53.597302)
		(width 0.2032)
		(layer "In7.Cu")
		(net "M1_DQ_NODE1_DQ52")
	)
	(segment
		(start 84.930488 -51.208686)
		(end 84.930488 -51.513486)
		(width 0.2032)
		(layer "In7.Cu")
		(net "M1_DQ_NODE1_DQ52")
	)
	(segment
		(start 82.846672 -53.597302)
		(end 82.630518 -53.813456)
		(width 0.2032)
		(layer "In7.Cu")
		(net "M1_DQ_NODE1_DQ52")
	)
	(segment
		(start 88.10879 -48.302164)
		(end 86.716362 -48.302164)
		(width 0.2032)
		(layer "In7.Cu")
		(net "M1_DQ_NODE1_DQ52")
	)
	(segment
		(start 84.930488 -51.513486)
		(end 84.714334 -51.72964)
		(width 0.2032)
		(layer "In7.Cu")
		(net "M1_DQ_NODE1_DQ52")
	)
	(segment
		(start 76.501244 -67.31254)
		(end 76.321158 -67.31254)
		(width 0.1016)
		(layer "In7.Cu")
		(net "M1_DQ_NODE1_DQ52")
	)
	(segment
		(start 85.043518 -50.279808)
		(end 84.738718 -50.279808)
		(width 0.2032)
		(layer "In7.Cu")
		(net "M1_DQ_NODE1_DQ52")
	)
	(segment
		(start 79.15402 -55.864506)
		(end 79.15402 -57.55894)
		(width 0.2032)
		(layer "In7.Cu")
		(net "M1_DQ_NODE1_DQ52")
	)
	(segment
		(start 85.972396 -50.471578)
		(end 85.756242 -50.687732)
		(width 0.2032)
		(layer "In7.Cu")
		(net "M1_DQ_NODE1_DQ52")
	)
	(segment
		(start 80.546702 -55.897272)
		(end 80.241902 -55.897272)
		(width 0.2032)
		(layer "In7.Cu")
		(net "M1_DQ_NODE1_DQ52")
	)
	(segment
		(start 78.41234 -65.075308)
		(end 78.41234 -65.401444)
		(width 0.2032)
		(layer "In7.Cu")
		(net "M1_DQ_NODE1_DQ52")
	)
	(segment
		(start 79.15402 -57.55894)
		(end 79.3623 -57.76722)
		(width 0.2032)
		(layer "In7.Cu")
		(net "M1_DQ_NODE1_DQ52")
	)
	(segment
		(start 80.571086 -54.44744)
		(end 80.354932 -54.663594)
		(width 0.2032)
		(layer "In7.Cu")
		(net "M1_DQ_NODE1_DQ52")
	)
	(segment
		(start 83.480656 -51.53787)
		(end 83.480656 -51.84267)
		(width 0.2032)
		(layer "In7.Cu")
		(net "M1_DQ_NODE1_DQ52")
	)
	(segment
		(start 83.69681 -51.321716)
		(end 83.480656 -51.53787)
		(width 0.2032)
		(layer "In7.Cu")
		(net "M1_DQ_NODE1_DQ52")
	)
	(segment
		(start 79.15402 -59.356244)
		(end 78.41234 -60.097924)
		(width 0.2032)
		(layer "In7.Cu")
		(net "M1_DQ_NODE1_DQ52")
	)
	(segment
		(start 83.672426 -52.771548)
		(end 83.367626 -52.771548)
		(width 0.2032)
		(layer "In7.Cu")
		(net "M1_DQ_NODE1_DQ52")
	)
	(segment
		(start 83.480656 -51.84267)
		(end 83.88858 -52.250594)
		(width 0.2032)
		(layer "In7.Cu")
		(net "M1_DQ_NODE1_DQ52")
	)
	(segment
		(start 84.409534 -51.72964)
		(end 84.00161 -51.321716)
		(width 0.2032)
		(layer "In7.Cu")
		(net "M1_DQ_NODE1_DQ52")
	)
	(segment
		(start 78.38821 -96.886522)
		(end 78.862936 -97.361248)
		(width 0.1016)
		(layer "F.Cu")
		(net "CLK_33K_CPU_NODE1_SUSCLK_R")
	)
	(segment
		(start 79.558388 -97.061782)
		(end 79.162402 -97.061782)
		(width 0.1016)
		(layer "F.Cu")
		(net "CLK_33K_CPU_NODE1_SUSCLK_R")
	)
	(segment
		(start 77.929486 -96.886522)
		(end 78.38821 -96.886522)
		(width 0.1016)
		(layer "F.Cu")
		(net "CLK_33K_CPU_NODE1_SUSCLK_R")
	)
	(segment
		(start 79.162402 -97.061782)
		(end 78.862936 -97.361248)
		(width 0.1016)
		(layer "F.Cu")
		(net "CLK_33K_CPU_NODE1_SUSCLK_R")
	)
	(via
		(at 78.862936 -97.361248)
		(size 0.508)
		(drill 0.254)
		(layers "F.Cu" "B.Cu")
		(net "CLK_33K_CPU_NODE1_SUSCLK_R")
	)
	(segment
		(start 55.55869 -61.307726)
		(end 55.410354 -61.15939)
		(width 0.1016)
		(layer "F.Cu")
		(net "M1_DQ_NODE1_DQ27")
	)
	(segment
		(start 55.55869 -62.51702)
		(end 55.55869 -61.307726)
		(width 0.1016)
		(layer "F.Cu")
		(net "M1_DQ_NODE1_DQ27")
	)
	(segment
		(start 54.99735 -63.338964)
		(end 54.99735 -63.07836)
		(width 0.1016)
		(layer "F.Cu")
		(net "M1_DQ_NODE1_DQ27")
	)
	(segment
		(start 54.99735 -63.07836)
		(end 55.55869 -62.51702)
		(width 0.1016)
		(layer "F.Cu")
		(net "M1_DQ_NODE1_DQ27")
	)
	(segment
		(start 59.5503 -20.94992)
		(end 59.5503 -23.023576)
		(width 0.1651)
		(layer "F.Cu")
		(net "M1_DQ_NODE1_DQ27")
	)
	(segment
		(start 54.78399 -63.552324)
		(end 54.99735 -63.338964)
		(width 0.1016)
		(layer "F.Cu")
		(net "M1_DQ_NODE1_DQ27")
	)
	(segment
		(start 59.5503 -23.023576)
		(end 59.718702 -23.191978)
		(width 0.1651)
		(layer "F.Cu")
		(net "M1_DQ_NODE1_DQ27")
	)
	(segment
		(start 55.410354 -61.15939)
		(end 55.15229 -61.15939)
		(width 0.1016)
		(layer "F.Cu")
		(net "M1_DQ_NODE1_DQ27")
	)
	(via
		(at 59.718702 -23.191978)
		(size 0.508)
		(drill 0.254)
		(layers "F.Cu" "B.Cu")
		(net "M1_DQ_NODE1_DQ27")
	)
	(via
		(at 55.15229 -61.15939)
		(size 0.508)
		(drill 0.254)
		(layers "F.Cu" "B.Cu")
		(net "M1_DQ_NODE1_DQ27")
	)
	(segment
		(start 66.27368 -26.390092)
		(end 66.48196 -26.181812)
		(width 0.2032)
		(layer "In2.Cu")
		(net "M1_DQ_NODE1_DQ27")
	)
	(segment
		(start 66.275458 -27.958288)
		(end 66.12382 -27.958288)
		(width 0.2032)
		(layer "In2.Cu")
		(net "M1_DQ_NODE1_DQ27")
	)
	(segment
		(start 66.48196 -25.887172)
		(end 66.27368 -25.678892)
		(width 0.2032)
		(layer "In2.Cu")
		(net "M1_DQ_NODE1_DQ27")
	)
	(segment
		(start 64.515746 -28.897326)
		(end 66.29781 -28.897326)
		(width 0.2032)
		(layer "In2.Cu")
		(net "M1_DQ_NODE1_DQ27")
	)
	(segment
		(start 57.31256 -39.253414)
		(end 62.61862 -33.947354)
		(width 0.2032)
		(layer "In2.Cu")
		(net "M1_DQ_NODE1_DQ27")
	)
	(segment
		(start 55.15229 -61.15939)
		(end 55.15229 -60.90158)
		(width 0.1016)
		(layer "In2.Cu")
		(net "M1_DQ_NODE1_DQ27")
	)
	(segment
		(start 65.94094 -27.775408)
		(end 65.94094 -26.598372)
		(width 0.2032)
		(layer "In2.Cu")
		(net "M1_DQ_NODE1_DQ27")
	)
	(segment
		(start 61.80074 -23.937468)
		(end 61.80074 -23.407624)
		(width 0.2032)
		(layer "In2.Cu")
		(net "M1_DQ_NODE1_DQ27")
	)
	(segment
		(start 66.27368 -25.678892)
		(end 66.14922 -25.678892)
		(width 0.2032)
		(layer "In2.Cu")
		(net "M1_DQ_NODE1_DQ27")
	)
	(segment
		(start 65.94094 -24.689562)
		(end 65.745868 -24.49449)
		(width 0.2032)
		(layer "In2.Cu")
		(net "M1_DQ_NODE1_DQ27")
	)
	(segment
		(start 65.94094 -25.470612)
		(end 65.94094 -24.689562)
		(width 0.2032)
		(layer "In2.Cu")
		(net "M1_DQ_NODE1_DQ27")
	)
	(segment
		(start 57.31256 -48.125634)
		(end 57.31256 -39.253414)
		(width 0.2032)
		(layer "In2.Cu")
		(net "M1_DQ_NODE1_DQ27")
	)
	(segment
		(start 60.825888 -21.742654)
		(end 59.82716 -21.742654)
		(width 0.2032)
		(layer "In2.Cu")
		(net "M1_DQ_NODE1_DQ27")
	)
	(segment
		(start 66.12382 -27.958288)
		(end 65.94094 -27.775408)
		(width 0.2032)
		(layer "In2.Cu")
		(net "M1_DQ_NODE1_DQ27")
	)
	(segment
		(start 65.745868 -24.49449)
		(end 64.94018 -24.49449)
		(width 0.2032)
		(layer "In2.Cu")
		(net "M1_DQ_NODE1_DQ27")
	)
	(segment
		(start 56.1594 -57.684162)
		(end 56.1594 -51.374294)
		(width 0.2032)
		(layer "In2.Cu")
		(net "M1_DQ_NODE1_DQ27")
	)
	(segment
		(start 57.64784 -49.27981)
		(end 57.64784 -48.460914)
		(width 0.2032)
		(layer "In2.Cu")
		(net "M1_DQ_NODE1_DQ27")
	)
	(segment
		(start 64.515746 -28.899612)
		(end 64.515746 -28.897326)
		(width 0.2032)
		(layer "In2.Cu")
		(net "M1_DQ_NODE1_DQ27")
	)
	(segment
		(start 59.479688 -22.952964)
		(end 59.718702 -23.191978)
		(width 0.2032)
		(layer "In2.Cu")
		(net "M1_DQ_NODE1_DQ27")
	)
	(segment
		(start 66.14922 -25.678892)
		(end 65.94094 -25.470612)
		(width 0.2032)
		(layer "In2.Cu")
		(net "M1_DQ_NODE1_DQ27")
	)
	(segment
		(start 66.44386 -28.751276)
		(end 66.44386 -28.12669)
		(width 0.2032)
		(layer "In2.Cu")
		(net "M1_DQ_NODE1_DQ27")
	)
	(segment
		(start 62.61862 -33.947354)
		(end 62.61862 -28.600146)
		(width 0.2032)
		(layer "In2.Cu")
		(net "M1_DQ_NODE1_DQ27")
	)
	(segment
		(start 56.1594 -58.320432)
		(end 56.1594 -57.684162)
		(width 0.1016)
		(layer "In2.Cu")
		(net "M1_DQ_NODE1_DQ27")
	)
	(segment
		(start 56.92394 -50.00371)
		(end 57.64784 -49.27981)
		(width 0.2032)
		(layer "In2.Cu")
		(net "M1_DQ_NODE1_DQ27")
	)
	(segment
		(start 61.80074 -23.407624)
		(end 61.11748 -22.724364)
		(width 0.2032)
		(layer "In2.Cu")
		(net "M1_DQ_NODE1_DQ27")
	)
	(segment
		(start 62.82436 -28.394406)
		(end 64.01054 -28.394406)
		(width 0.2032)
		(layer "In2.Cu")
		(net "M1_DQ_NODE1_DQ27")
	)
	(segment
		(start 57.64784 -48.460914)
		(end 57.31256 -48.125634)
		(width 0.2032)
		(layer "In2.Cu")
		(net "M1_DQ_NODE1_DQ27")
	)
	(segment
		(start 61.11748 -22.724364)
		(end 61.11748 -22.034754)
		(width 0.2032)
		(layer "In2.Cu")
		(net "M1_DQ_NODE1_DQ27")
	)
	(segment
		(start 59.82716 -21.742654)
		(end 59.479688 -22.090126)
		(width 0.2032)
		(layer "In2.Cu")
		(net "M1_DQ_NODE1_DQ27")
	)
	(segment
		(start 55.6641 -58.815732)
		(end 56.1594 -58.320432)
		(width 0.1016)
		(layer "In2.Cu")
		(net "M1_DQ_NODE1_DQ27")
	)
	(segment
		(start 66.14922 -26.390092)
		(end 66.27368 -26.390092)
		(width 0.2032)
		(layer "In2.Cu")
		(net "M1_DQ_NODE1_DQ27")
	)
	(segment
		(start 66.29781 -28.897326)
		(end 66.44386 -28.751276)
		(width 0.2032)
		(layer "In2.Cu")
		(net "M1_DQ_NODE1_DQ27")
	)
	(segment
		(start 63.993776 -25.440894)
		(end 63.304166 -25.440894)
		(width 0.2032)
		(layer "In2.Cu")
		(net "M1_DQ_NODE1_DQ27")
	)
	(segment
		(start 56.1594 -51.374294)
		(end 56.92394 -50.609754)
		(width 0.2032)
		(layer "In2.Cu")
		(net "M1_DQ_NODE1_DQ27")
	)
	(segment
		(start 64.01054 -28.394406)
		(end 64.515746 -28.899612)
		(width 0.2032)
		(layer "In2.Cu")
		(net "M1_DQ_NODE1_DQ27")
	)
	(segment
		(start 62.61862 -28.600146)
		(end 62.82436 -28.394406)
		(width 0.2032)
		(layer "In2.Cu")
		(net "M1_DQ_NODE1_DQ27")
	)
	(segment
		(start 61.11748 -22.034754)
		(end 60.825888 -21.743162)
		(width 0.2032)
		(layer "In2.Cu")
		(net "M1_DQ_NODE1_DQ27")
	)
	(segment
		(start 55.15356 -60.90158)
		(end 55.6641 -60.39104)
		(width 0.1016)
		(layer "In2.Cu")
		(net "M1_DQ_NODE1_DQ27")
	)
	(segment
		(start 55.15229 -60.90158)
		(end 55.15356 -60.90158)
		(width 0.1016)
		(layer "In2.Cu")
		(net "M1_DQ_NODE1_DQ27")
	)
	(segment
		(start 65.94094 -26.598372)
		(end 66.14922 -26.390092)
		(width 0.2032)
		(layer "In2.Cu")
		(net "M1_DQ_NODE1_DQ27")
	)
	(segment
		(start 55.6641 -60.39104)
		(end 55.6641 -58.815732)
		(width 0.1016)
		(layer "In2.Cu")
		(net "M1_DQ_NODE1_DQ27")
	)
	(segment
		(start 59.479688 -22.090126)
		(end 59.479688 -22.952964)
		(width 0.2032)
		(layer "In2.Cu")
		(net "M1_DQ_NODE1_DQ27")
	)
	(segment
		(start 63.304166 -25.440894)
		(end 61.80074 -23.937468)
		(width 0.2032)
		(layer "In2.Cu")
		(net "M1_DQ_NODE1_DQ27")
	)
	(segment
		(start 56.92394 -50.609754)
		(end 56.92394 -50.00371)
		(width 0.2032)
		(layer "In2.Cu")
		(net "M1_DQ_NODE1_DQ27")
	)
	(segment
		(start 66.44386 -28.12669)
		(end 66.275458 -27.958288)
		(width 0.2032)
		(layer "In2.Cu")
		(net "M1_DQ_NODE1_DQ27")
	)
	(segment
		(start 64.94018 -24.49449)
		(end 63.993776 -25.440894)
		(width 0.2032)
		(layer "In2.Cu")
		(net "M1_DQ_NODE1_DQ27")
	)
	(segment
		(start 60.825888 -21.743162)
		(end 60.825888 -21.742654)
		(width 0.2032)
		(layer "In2.Cu")
		(net "M1_DQ_NODE1_DQ27")
	)
	(segment
		(start 66.48196 -26.181812)
		(end 66.48196 -25.887172)
		(width 0.2032)
		(layer "In2.Cu")
		(net "M1_DQ_NODE1_DQ27")
	)
	(segment
		(start 51.999896 -80.600042)
		(end 52.399946 -80.199992)
		(width 0.127)
		(layer "F.Cu")
		(net "CLK_100M_CPU_NODE1_DP")
	)
	(segment
		(start 128.897888 -116.972842)
		(end 127.644652 -116.972842)
		(width 0.127)
		(layer "F.Cu")
		(net "CLK_100M_CPU_NODE1_DP")
	)
	(segment
		(start 123.0376 -112.027208)
		(end 123.16714 -111.897668)
		(width 0.127)
		(layer "F.Cu")
		(net "CLK_100M_CPU_NODE1_DP")
	)
	(segment
		(start 123.0376 -113.048288)
		(end 123.16714 -112.918748)
		(width 0.127)
		(layer "F.Cu")
		(net "CLK_100M_CPU_NODE1_DP")
	)
	(segment
		(start 123.0376 -115.43157)
		(end 123.0376 -114.743484)
		(width 0.127)
		(layer "F.Cu")
		(net "CLK_100M_CPU_NODE1_DP")
	)
	(segment
		(start 123.0376 -111.006128)
		(end 123.16714 -110.876588)
		(width 0.127)
		(layer "F.Cu")
		(net "CLK_100M_CPU_NODE1_DP")
	)
	(segment
		(start 123.0376 -114.062764)
		(end 123.0376 -113.048288)
		(width 0.127)
		(layer "F.Cu")
		(net "CLK_100M_CPU_NODE1_DP")
	)
	(segment
		(start 123.0376 -111.387128)
		(end 123.0376 -111.006128)
		(width 0.127)
		(layer "F.Cu")
		(net "CLK_100M_CPU_NODE1_DP")
	)
	(segment
		(start 123.0376 -114.743484)
		(end 123.18746 -114.593624)
		(width 0.127)
		(layer "F.Cu")
		(net "CLK_100M_CPU_NODE1_DP")
	)
	(segment
		(start 123.0376 -107.7087)
		(end 123.5202 -107.2261)
		(width 0.127)
		(layer "F.Cu")
		(net "CLK_100M_CPU_NODE1_DP")
	)
	(segment
		(start 123.16714 -110.495588)
		(end 123.0376 -110.366048)
		(width 0.127)
		(layer "F.Cu")
		(net "CLK_100M_CPU_NODE1_DP")
	)
	(segment
		(start 127.644652 -116.972842)
		(end 127.238252 -116.566442)
		(width 0.127)
		(layer "F.Cu")
		(net "CLK_100M_CPU_NODE1_DP")
	)
	(segment
		(start 123.18746 -114.593624)
		(end 123.18746 -114.212624)
		(width 0.127)
		(layer "F.Cu")
		(net "CLK_100M_CPU_NODE1_DP")
	)
	(segment
		(start 123.16714 -111.516668)
		(end 123.0376 -111.387128)
		(width 0.127)
		(layer "F.Cu")
		(net "CLK_100M_CPU_NODE1_DP")
	)
	(segment
		(start 123.16714 -112.918748)
		(end 123.16714 -112.537748)
		(width 0.127)
		(layer "F.Cu")
		(net "CLK_100M_CPU_NODE1_DP")
	)
	(segment
		(start 123.16714 -110.876588)
		(end 123.16714 -110.495588)
		(width 0.127)
		(layer "F.Cu")
		(net "CLK_100M_CPU_NODE1_DP")
	)
	(segment
		(start 127.238252 -116.566442)
		(end 124.172472 -116.566442)
		(width 0.127)
		(layer "F.Cu")
		(net "CLK_100M_CPU_NODE1_DP")
	)
	(segment
		(start 123.0376 -112.408208)
		(end 123.0376 -112.027208)
		(width 0.127)
		(layer "F.Cu")
		(net "CLK_100M_CPU_NODE1_DP")
	)
	(segment
		(start 123.16714 -111.897668)
		(end 123.16714 -111.516668)
		(width 0.127)
		(layer "F.Cu")
		(net "CLK_100M_CPU_NODE1_DP")
	)
	(segment
		(start 123.0376 -110.366048)
		(end 123.0376 -107.7087)
		(width 0.127)
		(layer "F.Cu")
		(net "CLK_100M_CPU_NODE1_DP")
	)
	(segment
		(start 124.172472 -116.566442)
		(end 123.0376 -115.43157)
		(width 0.127)
		(layer "F.Cu")
		(net "CLK_100M_CPU_NODE1_DP")
	)
	(segment
		(start 128.956054 -116.914676)
		(end 128.897888 -116.972842)
		(width 0.127)
		(layer "F.Cu")
		(net "CLK_100M_CPU_NODE1_DP")
	)
	(segment
		(start 123.18746 -114.212624)
		(end 123.0376 -114.062764)
		(width 0.127)
		(layer "F.Cu")
		(net "CLK_100M_CPU_NODE1_DP")
	)
	(segment
		(start 129.403856 -116.914676)
		(end 128.956054 -116.914676)
		(width 0.127)
		(layer "F.Cu")
		(net "CLK_100M_CPU_NODE1_DP")
	)
	(segment
		(start 123.16714 -112.537748)
		(end 123.0376 -112.408208)
		(width 0.127)
		(layer "F.Cu")
		(net "CLK_100M_CPU_NODE1_DP")
	)
	(via
		(at 52.399946 -80.199992)
		(size 0.508)
		(drill 0.254)
		(layers "F.Cu" "B.Cu")
		(net "CLK_100M_CPU_NODE1_DP")
	)
	(via
		(at 123.5202 -107.2261)
		(size 0.508)
		(drill 0.254)
		(layers "F.Cu" "B.Cu")
		(net "CLK_100M_CPU_NODE1_DP")
	)
	(segment
		(start 100.07346 -88.877394)
		(end 108.410756 -88.877394)
		(width 0.127)
		(layer "In7.Cu")
		(net "CLK_100M_CPU_NODE1_DP")
	)
	(segment
		(start 51.90617 -81.190084)
		(end 51.90617 -87.098632)
		(width 0.127)
		(layer "In7.Cu")
		(net "CLK_100M_CPU_NODE1_DP")
	)
	(segment
		(start 78.362302 -91.48445)
		(end 85.588602 -91.48445)
		(width 0.127)
		(layer "In7.Cu")
		(net "CLK_100M_CPU_NODE1_DP")
	)
	(segment
		(start 53.798216 -88.990678)
		(end 53.798216 -90.492834)
		(width 0.127)
		(layer "In7.Cu")
		(net "CLK_100M_CPU_NODE1_DP")
	)
	(segment
		(start 69.337174 -92.937838)
		(end 70.067678 -92.207334)
		(width 0.127)
		(layer "In7.Cu")
		(net "CLK_100M_CPU_NODE1_DP")
	)
	(segment
		(start 53.798216 -90.492834)
		(end 54.539134 -91.233752)
		(width 0.127)
		(layer "In7.Cu")
		(net "CLK_100M_CPU_NODE1_DP")
	)
	(segment
		(start 98.368358 -90.582496)
		(end 100.07346 -88.877394)
		(width 0.127)
		(layer "In7.Cu")
		(net "CLK_100M_CPU_NODE1_DP")
	)
	(segment
		(start 54.539134 -91.233752)
		(end 62.540896 -91.233752)
		(width 0.127)
		(layer "In7.Cu")
		(net "CLK_100M_CPU_NODE1_DP")
	)
	(segment
		(start 70.067678 -92.207334)
		(end 77.639418 -92.207334)
		(width 0.127)
		(layer "In7.Cu")
		(net "CLK_100M_CPU_NODE1_DP")
	)
	(segment
		(start 85.588602 -91.48445)
		(end 85.81771 -91.255342)
		(width 0.127)
		(layer "In7.Cu")
		(net "CLK_100M_CPU_NODE1_DP")
	)
	(segment
		(start 62.540896 -91.233752)
		(end 64.244982 -92.937838)
		(width 0.127)
		(layer "In7.Cu")
		(net "CLK_100M_CPU_NODE1_DP")
	)
	(segment
		(start 108.410756 -88.877394)
		(end 123.03125 -103.497888)
		(width 0.127)
		(layer "In7.Cu")
		(net "CLK_100M_CPU_NODE1_DP")
	)
	(segment
		(start 91.6686 -90.582496)
		(end 98.368358 -90.582496)
		(width 0.127)
		(layer "In7.Cu")
		(net "CLK_100M_CPU_NODE1_DP")
	)
	(segment
		(start 123.03125 -103.497888)
		(end 123.03125 -106.73715)
		(width 0.127)
		(layer "In7.Cu")
		(net "CLK_100M_CPU_NODE1_DP")
	)
	(segment
		(start 52.399946 -80.199992)
		(end 52.15128 -80.448658)
		(width 0.127)
		(layer "In7.Cu")
		(net "CLK_100M_CPU_NODE1_DP")
	)
	(segment
		(start 52.15128 -80.448658)
		(end 52.15128 -80.944974)
		(width 0.127)
		(layer "In7.Cu")
		(net "CLK_100M_CPU_NODE1_DP")
	)
	(segment
		(start 90.995754 -91.255342)
		(end 91.6686 -90.582496)
		(width 0.127)
		(layer "In7.Cu")
		(net "CLK_100M_CPU_NODE1_DP")
	)
	(segment
		(start 123.03125 -106.73715)
		(end 123.5202 -107.2261)
		(width 0.127)
		(layer "In7.Cu")
		(net "CLK_100M_CPU_NODE1_DP")
	)
	(segment
		(start 85.81771 -91.255342)
		(end 90.995754 -91.255342)
		(width 0.127)
		(layer "In7.Cu")
		(net "CLK_100M_CPU_NODE1_DP")
	)
	(segment
		(start 52.15128 -80.944974)
		(end 51.90617 -81.190084)
		(width 0.127)
		(layer "In7.Cu")
		(net "CLK_100M_CPU_NODE1_DP")
	)
	(segment
		(start 51.90617 -87.098632)
		(end 53.798216 -88.990678)
		(width 0.127)
		(layer "In7.Cu")
		(net "CLK_100M_CPU_NODE1_DP")
	)
	(segment
		(start 64.244982 -92.937838)
		(end 69.337174 -92.937838)
		(width 0.127)
		(layer "In7.Cu")
		(net "CLK_100M_CPU_NODE1_DP")
	)
	(segment
		(start 77.639418 -92.207334)
		(end 78.362302 -91.48445)
		(width 0.127)
		(layer "In7.Cu")
		(net "CLK_100M_CPU_NODE1_DP")
	)
	(segment
		(start 76.583794 -66.599816)
		(end 76.583794 -66.729102)
		(width 0.1016)
		(layer "F.Cu")
		(net "M1_DQ_NODE1_DQ49")
	)
	(segment
		(start 75.145646 -69.535548)
		(end 74.06259 -69.535548)
		(width 0.1016)
		(layer "F.Cu")
		(net "M1_DQ_NODE1_DQ49")
	)
	(segment
		(start 76.82484 -67.856354)
		(end 75.145646 -69.535548)
		(width 0.1016)
		(layer "F.Cu")
		(net "M1_DQ_NODE1_DQ49")
	)
	(segment
		(start 92.548202 -24.012652)
		(end 92.548202 -20.951952)
		(width 0.1651)
		(layer "F.Cu")
		(net "M1_DQ_NODE1_DQ49")
	)
	(segment
		(start 93.89618 -25.36063)
		(end 92.548202 -24.012652)
		(width 0.1651)
		(layer "F.Cu")
		(net "M1_DQ_NODE1_DQ49")
	)
	(segment
		(start 76.583794 -66.729102)
		(end 76.82484 -66.970148)
		(width 0.1016)
		(layer "F.Cu")
		(net "M1_DQ_NODE1_DQ49")
	)
	(segment
		(start 74.06259 -69.535548)
		(end 73.986136 -69.612002)
		(width 0.1016)
		(layer "F.Cu")
		(net "M1_DQ_NODE1_DQ49")
	)
	(segment
		(start 76.82484 -66.970148)
		(end 76.82484 -67.856354)
		(width 0.1016)
		(layer "F.Cu")
		(net "M1_DQ_NODE1_DQ49")
	)
	(segment
		(start 73.986136 -69.612002)
		(end 73.63968 -69.612002)
		(width 0.1016)
		(layer "F.Cu")
		(net "M1_DQ_NODE1_DQ49")
	)
	(segment
		(start 92.548202 -20.951952)
		(end 92.550234 -20.94992)
		(width 0.1651)
		(layer "F.Cu")
		(net "M1_DQ_NODE1_DQ49")
	)
	(via
		(at 76.583794 -66.599816)
		(size 0.508)
		(drill 0.254)
		(layers "F.Cu" "B.Cu")
		(net "M1_DQ_NODE1_DQ49")
	)
	(via
		(at 93.89618 -25.36063)
		(size 0.508)
		(drill 0.254)
		(layers "F.Cu" "B.Cu")
		(net "M1_DQ_NODE1_DQ49")
	)
	(segment
		(start 77.68336 -59.926728)
		(end 77.68336 -65.067942)
		(width 0.2032)
		(layer "In7.Cu")
		(net "M1_DQ_NODE1_DQ49")
	)
	(segment
		(start 92.662248 -39.514272)
		(end 92.967556 -39.514272)
		(width 0.2032)
		(layer "In7.Cu")
		(net "M1_DQ_NODE1_DQ49")
	)
	(segment
		(start 88.368124 -47.143416)
		(end 87.846662 -47.664878)
		(width 0.2032)
		(layer "In7.Cu")
		(net "M1_DQ_NODE1_DQ49")
	)
	(segment
		(start 91.436952 -43.364404)
		(end 91.132152 -43.364404)
		(width 0.2032)
		(layer "In7.Cu")
		(net "M1_DQ_NODE1_DQ49")
	)
	(segment
		(start 92.967556 -39.514272)
		(end 93.1926 -39.739316)
		(width 0.2032)
		(layer "In7.Cu")
		(net "M1_DQ_NODE1_DQ49")
	)
	(segment
		(start 77.68336 -65.067942)
		(end 76.583794 -66.167508)
		(width 0.2032)
		(layer "In7.Cu")
		(net "M1_DQ_NODE1_DQ49")
	)
	(segment
		(start 78.51902 -59.091068)
		(end 77.68336 -59.926728)
		(width 0.2032)
		(layer "In7.Cu")
		(net "M1_DQ_NODE1_DQ49")
	)
	(segment
		(start 92.384626 -28.806648)
		(end 92.674694 -28.806648)
		(width 0.2032)
		(layer "In7.Cu")
		(net "M1_DQ_NODE1_DQ49")
	)
	(segment
		(start 93.1926 -42.31894)
		(end 91.944444 -43.567096)
		(width 0.2032)
		(layer "In7.Cu")
		(net "M1_DQ_NODE1_DQ49")
	)
	(segment
		(start 88.28532 -46.471332)
		(end 88.28532 -46.765972)
		(width 0.2032)
		(layer "In7.Cu")
		(net "M1_DQ_NODE1_DQ49")
	)
	(segment
		(start 90.597736 -44.609004)
		(end 90.395044 -44.406312)
		(width 0.2032)
		(layer "In7.Cu")
		(net "M1_DQ_NODE1_DQ49")
	)
	(segment
		(start 76.583794 -66.167508)
		(end 76.583794 -66.599816)
		(width 0.2032)
		(layer "In7.Cu")
		(net "M1_DQ_NODE1_DQ49")
	)
	(segment
		(start 92.674694 -28.070048)
		(end 92.384626 -28.070048)
		(width 0.2032)
		(layer "In7.Cu")
		(net "M1_DQ_NODE1_DQ49")
	)
	(segment
		(start 91.11869 -44.08805)
		(end 91.11869 -44.39285)
		(width 0.2032)
		(layer "In7.Cu")
		(net "M1_DQ_NODE1_DQ49")
	)
	(segment
		(start 92.674694 -28.806648)
		(end 92.89034 -29.022294)
		(width 0.2032)
		(layer "In7.Cu")
		(net "M1_DQ_NODE1_DQ49")
	)
	(segment
		(start 89.87409 -44.927266)
		(end 90.076782 -45.129958)
		(width 0.2032)
		(layer "In7.Cu")
		(net "M1_DQ_NODE1_DQ49")
	)
	(segment
		(start 90.902536 -44.609004)
		(end 90.597736 -44.609004)
		(width 0.2032)
		(layer "In7.Cu")
		(net "M1_DQ_NODE1_DQ49")
	)
	(segment
		(start 89.87409 -44.622466)
		(end 89.87409 -44.927266)
		(width 0.2032)
		(layer "In7.Cu")
		(net "M1_DQ_NODE1_DQ49")
	)
	(segment
		(start 89.165684 -46.345856)
		(end 88.871044 -46.345856)
		(width 0.2032)
		(layer "In7.Cu")
		(net "M1_DQ_NODE1_DQ49")
	)
	(segment
		(start 91.639644 -43.567096)
		(end 91.436952 -43.364404)
		(width 0.2032)
		(layer "In7.Cu")
		(net "M1_DQ_NODE1_DQ49")
	)
	(segment
		(start 92.28582 -39.137844)
		(end 92.662248 -39.514272)
		(width 0.2032)
		(layer "In7.Cu")
		(net "M1_DQ_NODE1_DQ49")
	)
	(segment
		(start 92.16898 -28.591002)
		(end 92.384626 -28.806648)
		(width 0.2032)
		(layer "In7.Cu")
		(net "M1_DQ_NODE1_DQ49")
	)
	(segment
		(start 92.28582 -30.202124)
		(end 92.28582 -39.137844)
		(width 0.2032)
		(layer "In7.Cu")
		(net "M1_DQ_NODE1_DQ49")
	)
	(segment
		(start 86.455504 -47.664878)
		(end 78.51902 -55.601362)
		(width 0.2032)
		(layer "In7.Cu")
		(net "M1_DQ_NODE1_DQ49")
	)
	(segment
		(start 93.1926 -39.739316)
		(end 93.1926 -42.31894)
		(width 0.2032)
		(layer "In7.Cu")
		(net "M1_DQ_NODE1_DQ49")
	)
	(segment
		(start 92.89034 -29.022294)
		(end 92.89034 -29.597604)
		(width 0.2032)
		(layer "In7.Cu")
		(net "M1_DQ_NODE1_DQ49")
	)
	(segment
		(start 88.78824 -46.263052)
		(end 88.4936 -46.263052)
		(width 0.2032)
		(layer "In7.Cu")
		(net "M1_DQ_NODE1_DQ49")
	)
	(segment
		(start 91.944444 -43.567096)
		(end 91.639644 -43.567096)
		(width 0.2032)
		(layer "In7.Cu")
		(net "M1_DQ_NODE1_DQ49")
	)
	(segment
		(start 93.89618 -26.25979)
		(end 92.89034 -27.26563)
		(width 0.2032)
		(layer "In7.Cu")
		(net "M1_DQ_NODE1_DQ49")
	)
	(segment
		(start 91.11869 -44.39285)
		(end 90.902536 -44.609004)
		(width 0.2032)
		(layer "In7.Cu")
		(net "M1_DQ_NODE1_DQ49")
	)
	(segment
		(start 93.89618 -25.36063)
		(end 93.89618 -26.25979)
		(width 0.2032)
		(layer "In7.Cu")
		(net "M1_DQ_NODE1_DQ49")
	)
	(segment
		(start 90.395044 -44.406312)
		(end 90.090244 -44.406312)
		(width 0.2032)
		(layer "In7.Cu")
		(net "M1_DQ_NODE1_DQ49")
	)
	(segment
		(start 92.384626 -28.070048)
		(end 92.16898 -28.285694)
		(width 0.2032)
		(layer "In7.Cu")
		(net "M1_DQ_NODE1_DQ49")
	)
	(segment
		(start 92.16898 -28.285694)
		(end 92.16898 -28.591002)
		(width 0.2032)
		(layer "In7.Cu")
		(net "M1_DQ_NODE1_DQ49")
	)
	(segment
		(start 90.076782 -45.129958)
		(end 90.076782 -45.434758)
		(width 0.2032)
		(layer "In7.Cu")
		(net "M1_DQ_NODE1_DQ49")
	)
	(segment
		(start 78.51902 -55.601362)
		(end 78.51902 -59.091068)
		(width 0.2032)
		(layer "In7.Cu")
		(net "M1_DQ_NODE1_DQ49")
	)
	(segment
		(start 88.871044 -46.345856)
		(end 88.78824 -46.263052)
		(width 0.2032)
		(layer "In7.Cu")
		(net "M1_DQ_NODE1_DQ49")
	)
	(segment
		(start 88.28532 -46.765972)
		(end 88.368124 -46.848776)
		(width 0.2032)
		(layer "In7.Cu")
		(net "M1_DQ_NODE1_DQ49")
	)
	(segment
		(start 90.076782 -45.434758)
		(end 89.165684 -46.345856)
		(width 0.2032)
		(layer "In7.Cu")
		(net "M1_DQ_NODE1_DQ49")
	)
	(segment
		(start 88.368124 -46.848776)
		(end 88.368124 -47.143416)
		(width 0.2032)
		(layer "In7.Cu")
		(net "M1_DQ_NODE1_DQ49")
	)
	(segment
		(start 92.89034 -29.597604)
		(end 92.28582 -30.202124)
		(width 0.2032)
		(layer "In7.Cu")
		(net "M1_DQ_NODE1_DQ49")
	)
	(segment
		(start 91.132152 -43.364404)
		(end 90.915998 -43.580558)
		(width 0.2032)
		(layer "In7.Cu")
		(net "M1_DQ_NODE1_DQ49")
	)
	(segment
		(start 87.846662 -47.664878)
		(end 86.455504 -47.664878)
		(width 0.2032)
		(layer "In7.Cu")
		(net "M1_DQ_NODE1_DQ49")
	)
	(segment
		(start 90.915998 -43.885358)
		(end 91.11869 -44.08805)
		(width 0.2032)
		(layer "In7.Cu")
		(net "M1_DQ_NODE1_DQ49")
	)
	(segment
		(start 88.4936 -46.263052)
		(end 88.28532 -46.471332)
		(width 0.2032)
		(layer "In7.Cu")
		(net "M1_DQ_NODE1_DQ49")
	)
	(segment
		(start 92.89034 -27.854402)
		(end 92.674694 -28.070048)
		(width 0.2032)
		(layer "In7.Cu")
		(net "M1_DQ_NODE1_DQ49")
	)
	(segment
		(start 92.89034 -27.26563)
		(end 92.89034 -27.854402)
		(width 0.2032)
		(layer "In7.Cu")
		(net "M1_DQ_NODE1_DQ49")
	)
	(segment
		(start 90.915998 -43.580558)
		(end 90.915998 -43.885358)
		(width 0.2032)
		(layer "In7.Cu")
		(net "M1_DQ_NODE1_DQ49")
	)
	(segment
		(start 90.090244 -44.406312)
		(end 89.87409 -44.622466)
		(width 0.2032)
		(layer "In7.Cu")
		(net "M1_DQ_NODE1_DQ49")
	)
	(segment
		(start 133.553708 -121.064528)
		(end 133.553708 -121.916952)
		(width 0.1778)
		(layer "F.Cu")
		(net "P1V05_CLK_NODE1")
	)
	(segment
		(start 128.818132 -117.714522)
		(end 128.736852 -117.633242)
		(width 0.1778)
		(layer "F.Cu")
		(net "P1V05_CLK_NODE1")
	)
	(segment
		(start 129.403856 -117.714522)
		(end 128.818132 -117.714522)
		(width 0.1778)
		(layer "F.Cu")
		(net "P1V05_CLK_NODE1")
	)
	(segment
		(start 133.553708 -121.916952)
		(end 133.503162 -121.967498)
		(width 0.1778)
		(layer "F.Cu")
		(net "P1V05_CLK_NODE1")
	)
	(segment
		(start 127.924052 -117.633242)
		(end 127.746252 -117.811042)
		(width 0.1778)
		(layer "F.Cu")
		(net "P1V05_CLK_NODE1")
	)
	(segment
		(start 128.736852 -117.633242)
		(end 127.924052 -117.633242)
		(width 0.1778)
		(layer "F.Cu")
		(net "P1V05_CLK_NODE1")
	)
	(via
		(at 133.503162 -121.967498)
		(size 0.508)
		(drill 0.254)
		(layers "F.Cu" "B.Cu")
		(net "P1V05_CLK_NODE1")
	)
	(via
		(at 127.746252 -117.811042)
		(size 0.508)
		(drill 0.254)
		(layers "F.Cu" "B.Cu")
		(net "P1V05_CLK_NODE1")
	)
	(segment
		(start 120.60936 -166.256716)
		(end 119.680736 -166.256716)
		(width 0.1016)
		(layer "F.Cu")
		(net "FAN_MAX_CTRL")
	)
	(segment
		(start 119.680736 -166.256716)
		(end 119.07774 -165.65372)
		(width 0.1016)
		(layer "F.Cu")
		(net "FAN_MAX_CTRL")
	)
	(segment
		(start 78.994762 -163.322254)
		(end 78.855062 -163.182554)
		(width 0.1016)
		(layer "F.Cu")
		(net "FAN_MAX_CTRL")
	)
	(segment
		(start 78.994762 -164.374576)
		(end 78.994762 -163.322254)
		(width 0.1016)
		(layer "F.Cu")
		(net "FAN_MAX_CTRL")
	)
	(via
		(at 78.855062 -163.182554)
		(size 0.508)
		(drill 0.254)
		(layers "F.Cu" "B.Cu")
		(net "FAN_MAX_CTRL")
	)
	(via
		(at 119.07774 -165.65372)
		(size 0.508)
		(drill 0.254)
		(layers "F.Cu" "B.Cu")
		(net "FAN_MAX_CTRL")
	)
	(segment
		(start 120.010174 -166.805102)
		(end 119.07774 -165.872668)
		(width 0.1016)
		(layer "B.Cu")
		(net "FAN_MAX_CTRL")
	)
	(segment
		(start 119.07774 -165.872668)
		(end 119.07774 -165.65372)
		(width 0.1016)
		(layer "B.Cu")
		(net "FAN_MAX_CTRL")
	)
	(segment
		(start 119.555006 -165.494462)
		(end 119.236998 -165.494462)
		(width 0.1016)
		(layer "B.Cu")
		(net "FAN_MAX_CTRL")
	)
	(segment
		(start 120.370092 -165.810692)
		(end 119.871236 -165.810692)
		(width 0.1016)
		(layer "B.Cu")
		(net "FAN_MAX_CTRL")
	)
	(segment
		(start 119.871236 -165.810692)
		(end 119.555006 -165.494462)
		(width 0.1016)
		(layer "B.Cu")
		(net "FAN_MAX_CTRL")
	)
	(segment
		(start 119.236998 -165.494462)
		(end 119.07774 -165.65372)
		(width 0.1016)
		(layer "B.Cu")
		(net "FAN_MAX_CTRL")
	)
	(segment
		(start 120.196864 -166.805102)
		(end 120.010174 -166.805102)
		(width 0.1016)
		(layer "B.Cu")
		(net "FAN_MAX_CTRL")
	)
	(segment
		(start 78.855062 -163.182554)
		(end 79.472536 -163.182554)
		(width 0.1143)
		(layer "In2.Cu")
		(net "FAN_MAX_CTRL")
	)
	(segment
		(start 107.567476 -165.549834)
		(end 111.462566 -165.549834)
		(width 0.1143)
		(layer "In2.Cu")
		(net "FAN_MAX_CTRL")
	)
	(segment
		(start 102.710742 -165.376352)
		(end 104.55656 -165.376352)
		(width 0.1143)
		(layer "In2.Cu")
		(net "FAN_MAX_CTRL")
	)
	(segment
		(start 102.48646 -165.15207)
		(end 102.710742 -165.376352)
		(width 0.1143)
		(layer "In2.Cu")
		(net "FAN_MAX_CTRL")
	)
	(segment
		(start 84.21243 -161.716466)
		(end 85.577172 -163.081208)
		(width 0.1143)
		(layer "In2.Cu")
		(net "FAN_MAX_CTRL")
	)
	(segment
		(start 95.708216 -163.685474)
		(end 96.211898 -164.189156)
		(width 0.1143)
		(layer "In2.Cu")
		(net "FAN_MAX_CTRL")
	)
	(segment
		(start 89.45118 -163.1696)
		(end 93.473016 -163.1696)
		(width 0.1143)
		(layer "In2.Cu")
		(net "FAN_MAX_CTRL")
	)
	(segment
		(start 80.366362 -163.523168)
		(end 82.173064 -161.716466)
		(width 0.1143)
		(layer "In2.Cu")
		(net "FAN_MAX_CTRL")
	)
	(segment
		(start 111.462566 -165.549834)
		(end 112.3442 -164.6682)
		(width 0.1143)
		(layer "In2.Cu")
		(net "FAN_MAX_CTRL")
	)
	(segment
		(start 118.870222 -165.446202)
		(end 119.07774 -165.65372)
		(width 0.1143)
		(layer "In2.Cu")
		(net "FAN_MAX_CTRL")
	)
	(segment
		(start 104.55656 -165.376352)
		(end 104.577134 -165.355778)
		(width 0.1143)
		(layer "In2.Cu")
		(net "FAN_MAX_CTRL")
	)
	(segment
		(start 97.518982 -164.189156)
		(end 98.481896 -165.15207)
		(width 0.1143)
		(layer "In2.Cu")
		(net "FAN_MAX_CTRL")
	)
	(segment
		(start 98.481896 -165.15207)
		(end 102.48646 -165.15207)
		(width 0.1143)
		(layer "In2.Cu")
		(net "FAN_MAX_CTRL")
	)
	(segment
		(start 93.98889 -163.685474)
		(end 95.708216 -163.685474)
		(width 0.1143)
		(layer "In2.Cu")
		(net "FAN_MAX_CTRL")
	)
	(segment
		(start 86.9569 -163.081208)
		(end 87.454232 -163.57854)
		(width 0.1143)
		(layer "In2.Cu")
		(net "FAN_MAX_CTRL")
	)
	(segment
		(start 79.472536 -163.182554)
		(end 79.81315 -163.523168)
		(width 0.1143)
		(layer "In2.Cu")
		(net "FAN_MAX_CTRL")
	)
	(segment
		(start 87.454232 -163.57854)
		(end 89.04224 -163.57854)
		(width 0.1143)
		(layer "In2.Cu")
		(net "FAN_MAX_CTRL")
	)
	(segment
		(start 79.81315 -163.523168)
		(end 80.366362 -163.523168)
		(width 0.1143)
		(layer "In2.Cu")
		(net "FAN_MAX_CTRL")
	)
	(segment
		(start 107.37342 -165.355778)
		(end 107.567476 -165.549834)
		(width 0.1143)
		(layer "In2.Cu")
		(net "FAN_MAX_CTRL")
	)
	(segment
		(start 96.211898 -164.189156)
		(end 97.518982 -164.189156)
		(width 0.1143)
		(layer "In2.Cu")
		(net "FAN_MAX_CTRL")
	)
	(segment
		(start 82.173064 -161.716466)
		(end 84.21243 -161.716466)
		(width 0.1143)
		(layer "In2.Cu")
		(net "FAN_MAX_CTRL")
	)
	(segment
		(start 104.577134 -165.355778)
		(end 107.37342 -165.355778)
		(width 0.1143)
		(layer "In2.Cu")
		(net "FAN_MAX_CTRL")
	)
	(segment
		(start 112.3442 -164.6682)
		(end 114.988086 -164.6682)
		(width 0.1143)
		(layer "In2.Cu")
		(net "FAN_MAX_CTRL")
	)
	(segment
		(start 114.988086 -164.6682)
		(end 115.766088 -165.446202)
		(width 0.1143)
		(layer "In2.Cu")
		(net "FAN_MAX_CTRL")
	)
	(segment
		(start 93.473016 -163.1696)
		(end 93.98889 -163.685474)
		(width 0.1143)
		(layer "In2.Cu")
		(net "FAN_MAX_CTRL")
	)
	(segment
		(start 115.766088 -165.446202)
		(end 118.870222 -165.446202)
		(width 0.1143)
		(layer "In2.Cu")
		(net "FAN_MAX_CTRL")
	)
	(segment
		(start 89.04224 -163.57854)
		(end 89.45118 -163.1696)
		(width 0.1143)
		(layer "In2.Cu")
		(net "FAN_MAX_CTRL")
	)
	(segment
		(start 85.577172 -163.081208)
		(end 86.9569 -163.081208)
		(width 0.1143)
		(layer "In2.Cu")
		(net "FAN_MAX_CTRL")
	)
	(segment
		(start 160.869122 -121.41454)
		(end 160.871408 -121.41454)
		(width 0.1016)
		(layer "F.Cu")
		(net "PWRGD_NODE1_DDR3_SYSPWRGD")
	)
	(segment
		(start 57.770522 -66.217038)
		(end 57.770522 -66.224658)
		(width 0.1016)
		(layer "F.Cu")
		(net "PWRGD_NODE1_DDR3_SYSPWRGD")
	)
	(segment
		(start 160.871408 -121.41454)
		(end 161.252408 -121.03354)
		(width 0.1016)
		(layer "F.Cu")
		(net "PWRGD_NODE1_DDR3_SYSPWRGD")
	)
	(segment
		(start 57.770522 -66.224658)
		(end 57.397142 -66.598038)
		(width 0.1016)
		(layer "F.Cu")
		(net "PWRGD_NODE1_DDR3_SYSPWRGD")
	)
	(segment
		(start 161.252408 -121.03354)
		(end 161.252408 -120.634506)
		(width 0.1016)
		(layer "F.Cu")
		(net "PWRGD_NODE1_DDR3_SYSPWRGD")
	)
	(segment
		(start 158.1404 -124.143262)
		(end 160.869122 -121.41454)
		(width 0.1016)
		(layer "F.Cu")
		(net "PWRGD_NODE1_DDR3_SYSPWRGD")
	)
	(via
		(at 57.397142 -66.598038)
		(size 0.508)
		(drill 0.254)
		(layers "F.Cu" "B.Cu")
		(net "PWRGD_NODE1_DDR3_SYSPWRGD")
	)
	(via
		(at 158.1404 -124.143262)
		(size 0.508)
		(drill 0.254)
		(layers "F.Cu" "B.Cu")
		(net "PWRGD_NODE1_DDR3_SYSPWRGD")
	)
	(segment
		(start 57.491376 -66.692272)
		(end 57.397142 -66.598038)
		(width 0.1016)
		(layer "B.Cu")
		(net "PWRGD_NODE1_DDR3_SYSPWRGD")
	)
	(segment
		(start 58.10123 -66.692272)
		(end 57.491376 -66.692272)
		(width 0.1016)
		(layer "B.Cu")
		(net "PWRGD_NODE1_DDR3_SYSPWRGD")
	)
	(segment
		(start 69.412612 -73.531984)
		(end 73.625202 -77.744574)
		(width 0.1143)
		(layer "In7.Cu")
		(net "PWRGD_NODE1_DDR3_SYSPWRGD")
	)
	(segment
		(start 65.91427 -72.241664)
		(end 65.91427 -73.60158)
		(width 0.1143)
		(layer "In7.Cu")
		(net "PWRGD_NODE1_DDR3_SYSPWRGD")
	)
	(segment
		(start 85.178646 -76.875132)
		(end 85.789008 -76.26477)
		(width 0.1143)
		(layer "In7.Cu")
		(net "PWRGD_NODE1_DDR3_SYSPWRGD")
	)
	(segment
		(start 78.140306 -77.744574)
		(end 79.009748 -76.875132)
		(width 0.1143)
		(layer "In7.Cu")
		(net "PWRGD_NODE1_DDR3_SYSPWRGD")
	)
	(segment
		(start 61.7728 -70.029324)
		(end 62.35827 -70.029324)
		(width 0.1143)
		(layer "In7.Cu")
		(net "PWRGD_NODE1_DDR3_SYSPWRGD")
	)
	(segment
		(start 147.451826 -107.200192)
		(end 147.45208 -107.200192)
		(width 0.1143)
		(layer "In7.Cu")
		(net "PWRGD_NODE1_DDR3_SYSPWRGD")
	)
	(segment
		(start 67.569842 -74.04354)
		(end 68.081398 -73.531984)
		(width 0.1143)
		(layer "In7.Cu")
		(net "PWRGD_NODE1_DDR3_SYSPWRGD")
	)
	(segment
		(start 61.586618 -70.215506)
		(end 61.7728 -70.029324)
		(width 0.1143)
		(layer "In7.Cu")
		(net "PWRGD_NODE1_DDR3_SYSPWRGD")
	)
	(segment
		(start 99.57816 -79.5274)
		(end 99.57816 -80.360266)
		(width 0.1143)
		(layer "In7.Cu")
		(net "PWRGD_NODE1_DDR3_SYSPWRGD")
	)
	(segment
		(start 99.57816 -80.360266)
		(end 102.769924 -83.55203)
		(width 0.1143)
		(layer "In7.Cu")
		(net "PWRGD_NODE1_DDR3_SYSPWRGD")
	)
	(segment
		(start 79.009748 -76.875132)
		(end 85.178646 -76.875132)
		(width 0.1143)
		(layer "In7.Cu")
		(net "PWRGD_NODE1_DDR3_SYSPWRGD")
	)
	(segment
		(start 57.809892 -68.971668)
		(end 57.487566 -69.293994)
		(width 0.1143)
		(layer "In7.Cu")
		(net "PWRGD_NODE1_DDR3_SYSPWRGD")
	)
	(segment
		(start 57.487566 -69.881496)
		(end 57.821576 -70.215506)
		(width 0.1143)
		(layer "In7.Cu")
		(net "PWRGD_NODE1_DDR3_SYSPWRGD")
	)
	(segment
		(start 88.600534 -74.175366)
		(end 94.226126 -74.175366)
		(width 0.1143)
		(layer "In7.Cu")
		(net "PWRGD_NODE1_DDR3_SYSPWRGD")
	)
	(segment
		(start 123.2027 -96.436688)
		(end 123.2027 -97.331276)
		(width 0.1143)
		(layer "In7.Cu")
		(net "PWRGD_NODE1_DDR3_SYSPWRGD")
	)
	(segment
		(start 64.51092 -70.838314)
		(end 65.91427 -72.241664)
		(width 0.1143)
		(layer "In7.Cu")
		(net "PWRGD_NODE1_DDR3_SYSPWRGD")
	)
	(segment
		(start 102.769924 -83.55203)
		(end 110.318042 -83.55203)
		(width 0.1143)
		(layer "In7.Cu")
		(net "PWRGD_NODE1_DDR3_SYSPWRGD")
	)
	(segment
		(start 63.16726 -70.838314)
		(end 64.51092 -70.838314)
		(width 0.1143)
		(layer "In7.Cu")
		(net "PWRGD_NODE1_DDR3_SYSPWRGD")
	)
	(segment
		(start 147.45208 -108.08208)
		(end 152.63368 -113.26368)
		(width 0.1143)
		(layer "In7.Cu")
		(net "PWRGD_NODE1_DDR3_SYSPWRGD")
	)
	(segment
		(start 123.2027 -97.331276)
		(end 126.630938 -100.759514)
		(width 0.1143)
		(layer "In7.Cu")
		(net "PWRGD_NODE1_DDR3_SYSPWRGD")
	)
	(segment
		(start 66.35623 -74.04354)
		(end 67.569842 -74.04354)
		(width 0.1143)
		(layer "In7.Cu")
		(net "PWRGD_NODE1_DDR3_SYSPWRGD")
	)
	(segment
		(start 94.226126 -74.175366)
		(end 99.57816 -79.5274)
		(width 0.1143)
		(layer "In7.Cu")
		(net "PWRGD_NODE1_DDR3_SYSPWRGD")
	)
	(segment
		(start 57.487566 -69.293994)
		(end 57.487566 -69.881496)
		(width 0.1143)
		(layer "In7.Cu")
		(net "PWRGD_NODE1_DDR3_SYSPWRGD")
	)
	(segment
		(start 57.809892 -67.010788)
		(end 57.809892 -68.971668)
		(width 0.1143)
		(layer "In7.Cu")
		(net "PWRGD_NODE1_DDR3_SYSPWRGD")
	)
	(segment
		(start 65.91427 -73.60158)
		(end 66.35623 -74.04354)
		(width 0.1143)
		(layer "In7.Cu")
		(net "PWRGD_NODE1_DDR3_SYSPWRGD")
	)
	(segment
		(start 85.789008 -76.26477)
		(end 86.51113 -76.26477)
		(width 0.1143)
		(layer "In7.Cu")
		(net "PWRGD_NODE1_DDR3_SYSPWRGD")
	)
	(segment
		(start 126.630938 -100.759514)
		(end 141.011148 -100.759514)
		(width 0.1143)
		(layer "In7.Cu")
		(net "PWRGD_NODE1_DDR3_SYSPWRGD")
	)
	(segment
		(start 57.397142 -66.598038)
		(end 57.809892 -67.010788)
		(width 0.1143)
		(layer "In7.Cu")
		(net "PWRGD_NODE1_DDR3_SYSPWRGD")
	)
	(segment
		(start 57.821576 -70.215506)
		(end 61.586618 -70.215506)
		(width 0.1143)
		(layer "In7.Cu")
		(net "PWRGD_NODE1_DDR3_SYSPWRGD")
	)
	(segment
		(start 152.63368 -118.636542)
		(end 158.1404 -124.143262)
		(width 0.1143)
		(layer "In7.Cu")
		(net "PWRGD_NODE1_DDR3_SYSPWRGD")
	)
	(segment
		(start 141.011148 -100.759514)
		(end 147.451826 -107.200192)
		(width 0.1143)
		(layer "In7.Cu")
		(net "PWRGD_NODE1_DDR3_SYSPWRGD")
	)
	(segment
		(start 110.318042 -83.55203)
		(end 123.2027 -96.436688)
		(width 0.1143)
		(layer "In7.Cu")
		(net "PWRGD_NODE1_DDR3_SYSPWRGD")
	)
	(segment
		(start 86.51113 -76.26477)
		(end 88.600534 -74.175366)
		(width 0.1143)
		(layer "In7.Cu")
		(net "PWRGD_NODE1_DDR3_SYSPWRGD")
	)
	(segment
		(start 68.081398 -73.531984)
		(end 69.412612 -73.531984)
		(width 0.1143)
		(layer "In7.Cu")
		(net "PWRGD_NODE1_DDR3_SYSPWRGD")
	)
	(segment
		(start 73.625202 -77.744574)
		(end 78.140306 -77.744574)
		(width 0.1143)
		(layer "In7.Cu")
		(net "PWRGD_NODE1_DDR3_SYSPWRGD")
	)
	(segment
		(start 147.45208 -107.200192)
		(end 147.45208 -108.08208)
		(width 0.1143)
		(layer "In7.Cu")
		(net "PWRGD_NODE1_DDR3_SYSPWRGD")
	)
	(segment
		(start 62.35827 -70.029324)
		(end 63.16726 -70.838314)
		(width 0.1143)
		(layer "In7.Cu")
		(net "PWRGD_NODE1_DDR3_SYSPWRGD")
	)
	(segment
		(start 152.63368 -113.26368)
		(end 152.63368 -118.636542)
		(width 0.1143)
		(layer "In7.Cu")
		(net "PWRGD_NODE1_DDR3_SYSPWRGD")
	)
	(segment
		(start 67.20078 -60.873386)
		(end 65.670684 -62.403482)
		(width 0.1016)
		(layer "F.Cu")
		(net "M_DDR3_NODE1_ODT1")
	)
	(segment
		(start 81.65338 -46.83125)
		(end 81.850484 -47.028354)
		(width 0.1651)
		(layer "F.Cu")
		(net "M_DDR3_NODE1_ODT1")
	)
	(segment
		(start 82.395822 -38.221158)
		(end 81.65338 -38.9636)
		(width 0.1651)
		(layer "F.Cu")
		(net "M_DDR3_NODE1_ODT1")
	)
	(segment
		(start 82.802476 -39.509954)
		(end 82.99958 -39.707058)
		(width 0.1651)
		(layer "F.Cu")
		(net "M_DDR3_NODE1_ODT1")
	)
	(segment
		(start 80.850232 -29.149802)
		(end 80.850232 -31.299404)
		(width 0.1651)
		(layer "F.Cu")
		(net "M_DDR3_NODE1_ODT1")
	)
	(segment
		(start 81.971642 -32.200596)
		(end 82.39506 -32.624014)
		(width 0.1651)
		(layer "F.Cu")
		(net "M_DDR3_NODE1_ODT1")
	)
	(segment
		(start 67.20078 -60.456318)
		(end 67.20078 -60.873386)
		(width 0.1016)
		(layer "F.Cu")
		(net "M_DDR3_NODE1_ODT1")
	)
	(segment
		(start 67.20078 -58.877962)
		(end 67.20078 -60.456318)
		(width 0.1651)
		(layer "F.Cu")
		(net "M_DDR3_NODE1_ODT1")
	)
	(segment
		(start 80.850232 -31.299404)
		(end 81.751424 -32.200596)
		(width 0.1651)
		(layer "F.Cu")
		(net "M_DDR3_NODE1_ODT1")
	)
	(segment
		(start 81.751424 -32.200596)
		(end 81.971642 -32.200596)
		(width 0.1651)
		(layer "F.Cu")
		(net "M_DDR3_NODE1_ODT1")
	)
	(segment
		(start 82.32648 -39.707058)
		(end 82.523584 -39.509954)
		(width 0.1651)
		(layer "F.Cu")
		(net "M_DDR3_NODE1_ODT1")
	)
	(segment
		(start 82.39506 -33.17113)
		(end 82.395822 -33.17113)
		(width 0.1651)
		(layer "F.Cu")
		(net "M_DDR3_NODE1_ODT1")
	)
	(segment
		(start 80.866742 -49.56429)
		(end 79.259176 -49.56429)
		(width 0.1651)
		(layer "F.Cu")
		(net "M_DDR3_NODE1_ODT1")
	)
	(segment
		(start 79.259176 -49.56429)
		(end 71.646288 -57.177178)
		(width 0.1651)
		(layer "F.Cu")
		(net "M_DDR3_NODE1_ODT1")
	)
	(segment
		(start 65.670684 -62.549532)
		(end 65.671192 -62.55004)
		(width 0.1016)
		(layer "F.Cu")
		(net "M_DDR3_NODE1_ODT1")
	)
	(segment
		(start 82.395822 -37.333936)
		(end 82.395822 -38.221158)
		(width 0.1651)
		(layer "F.Cu")
		(net "M_DDR3_NODE1_ODT1")
	)
	(segment
		(start 71.210932 -58.204862)
		(end 67.87388 -58.204862)
		(width 0.1651)
		(layer "F.Cu")
		(net "M_DDR3_NODE1_ODT1")
	)
	(segment
		(start 81.65338 -38.9636)
		(end 81.65338 -46.83125)
		(width 0.1651)
		(layer "F.Cu")
		(net "M_DDR3_NODE1_ODT1")
	)
	(segment
		(start 65.670684 -62.403482)
		(end 65.670684 -62.549532)
		(width 0.1016)
		(layer "F.Cu")
		(net "M_DDR3_NODE1_ODT1")
	)
	(segment
		(start 82.129376 -47.028354)
		(end 82.32648 -46.83125)
		(width 0.1651)
		(layer "F.Cu")
		(net "M_DDR3_NODE1_ODT1")
	)
	(segment
		(start 82.99958 -47.431452)
		(end 80.866742 -49.56429)
		(width 0.1651)
		(layer "F.Cu")
		(net "M_DDR3_NODE1_ODT1")
	)
	(segment
		(start 71.646288 -57.769506)
		(end 71.210932 -58.204862)
		(width 0.1651)
		(layer "F.Cu")
		(net "M_DDR3_NODE1_ODT1")
	)
	(segment
		(start 82.395822 -33.17113)
		(end 82.395822 -37.333936)
		(width 0.1651)
		(layer "F.Cu")
		(net "M_DDR3_NODE1_ODT1")
	)
	(segment
		(start 82.99958 -39.707058)
		(end 82.99958 -47.431452)
		(width 0.1651)
		(layer "F.Cu")
		(net "M_DDR3_NODE1_ODT1")
	)
	(segment
		(start 81.850484 -47.028354)
		(end 82.129376 -47.028354)
		(width 0.1651)
		(layer "F.Cu")
		(net "M_DDR3_NODE1_ODT1")
	)
	(segment
		(start 82.32648 -46.83125)
		(end 82.32648 -39.707058)
		(width 0.1651)
		(layer "F.Cu")
		(net "M_DDR3_NODE1_ODT1")
	)
	(segment
		(start 71.646288 -57.177178)
		(end 71.646288 -57.769506)
		(width 0.1651)
		(layer "F.Cu")
		(net "M_DDR3_NODE1_ODT1")
	)
	(segment
		(start 82.39506 -32.624014)
		(end 82.39506 -33.17113)
		(width 0.1651)
		(layer "F.Cu")
		(net "M_DDR3_NODE1_ODT1")
	)
	(segment
		(start 82.523584 -39.509954)
		(end 82.802476 -39.509954)
		(width 0.1651)
		(layer "F.Cu")
		(net "M_DDR3_NODE1_ODT1")
	)
	(segment
		(start 67.87388 -58.204862)
		(end 67.20078 -58.877962)
		(width 0.1651)
		(layer "F.Cu")
		(net "M_DDR3_NODE1_ODT1")
	)
	(via
		(at 82.395822 -37.333936)
		(size 0.762)
		(drill 0.381)
		(layers "F.Cu" "B.Cu")
		(net "M_DDR3_NODE1_ODT1")
	)
	(segment
		(start 129.17932 -110.92815)
		(end 129.34442 -111.09325)
		(width 0.1016)
		(layer "F.Cu")
		(net "XTAL_CLK_NODE1_X2")
	)
	(segment
		(start 129.409444 -110.291372)
		(end 129.17932 -110.521496)
		(width 0.1016)
		(layer "F.Cu")
		(net "XTAL_CLK_NODE1_X2")
	)
	(segment
		(start 129.34442 -112.47501)
		(end 130.353816 -113.484406)
		(width 0.1016)
		(layer "F.Cu")
		(net "XTAL_CLK_NODE1_X2")
	)
	(segment
		(start 129.34442 -112.04575)
		(end 129.34442 -112.47501)
		(width 0.1016)
		(layer "F.Cu")
		(net "XTAL_CLK_NODE1_X2")
	)
	(segment
		(start 129.409444 -108.69295)
		(end 129.409444 -110.192566)
		(width 0.1016)
		(layer "F.Cu")
		(net "XTAL_CLK_NODE1_X2")
	)
	(segment
		(start 129.17932 -110.521496)
		(end 129.17932 -110.92815)
		(width 0.1016)
		(layer "F.Cu")
		(net "XTAL_CLK_NODE1_X2")
	)
	(segment
		(start 128.14427 -107.427776)
		(end 129.409444 -108.69295)
		(width 0.1016)
		(layer "F.Cu")
		(net "XTAL_CLK_NODE1_X2")
	)
	(segment
		(start 129.409444 -110.192566)
		(end 129.409444 -110.291372)
		(width 0.1016)
		(layer "F.Cu")
		(net "XTAL_CLK_NODE1_X2")
	)
	(segment
		(start 130.353816 -113.484406)
		(end 130.353816 -113.96472)
		(width 0.1016)
		(layer "F.Cu")
		(net "XTAL_CLK_NODE1_X2")
	)
	(segment
		(start 129.34442 -111.09325)
		(end 129.34442 -112.04575)
		(width 0.1016)
		(layer "F.Cu")
		(net "XTAL_CLK_NODE1_X2")
	)
	(via
		(at 129.409444 -110.192566)
		(size 0.508)
		(drill 0.254)
		(layers "F.Cu" "B.Cu")
		(net "XTAL_CLK_NODE1_X2")
	)
	(segment
		(start 40.432482 -136.564624)
		(end 40.43299 -136.564116)
		(width 0.1016)
		(layer "F.Cu")
		(net "BMC_NODE1_DDR_D5")
	)
	(segment
		(start 59.741816 -135.259572)
		(end 59.73953 -135.259572)
		(width 0.1016)
		(layer "F.Cu")
		(net "BMC_NODE1_DDR_D5")
	)
	(segment
		(start 59.73953 -135.259572)
		(end 59.341004 -135.658098)
		(width 0.1016)
		(layer "F.Cu")
		(net "BMC_NODE1_DDR_D5")
	)
	(segment
		(start 40.83304 -136.163558)
		(end 40.83304 -136.163812)
		(width 0.1016)
		(layer "F.Cu")
		(net "BMC_NODE1_DDR_D5")
	)
	(segment
		(start 40.432228 -136.564624)
		(end 40.432482 -136.564624)
		(width 0.1016)
		(layer "F.Cu")
		(net "BMC_NODE1_DDR_D5")
	)
	(segment
		(start 40.83304 -136.163812)
		(end 40.432228 -136.564624)
		(width 0.1016)
		(layer "F.Cu")
		(net "BMC_NODE1_DDR_D5")
	)
	(via
		(at 59.341004 -135.658098)
		(size 0.49022)
		(drill 0.254)
		(layers "F.Cu" "B.Cu")
		(net "BMC_NODE1_DDR_D5")
	)
	(via
		(at 40.43299 -136.564116)
		(size 0.508)
		(drill 0.254)
		(layers "F.Cu" "B.Cu")
		(net "BMC_NODE1_DDR_D5")
	)
	(segment
		(start 42.504106 -138.316462)
		(end 43.169078 -138.316462)
		(width 0.1143)
		(layer "In7.Cu")
		(net "BMC_NODE1_DDR_D5")
	)
	(segment
		(start 47.254668 -140.040868)
		(end 47.621444 -140.104876)
		(width 0.1143)
		(layer "In7.Cu")
		(net "BMC_NODE1_DDR_D5")
	)
	(segment
		(start 55.207916 -139.143232)
		(end 58.295286 -136.055862)
		(width 0.1143)
		(layer "In7.Cu")
		(net "BMC_NODE1_DDR_D5")
	)
	(segment
		(start 41.851834 -137.66419)
		(end 42.504106 -138.316462)
		(width 0.1143)
		(layer "In7.Cu")
		(net "BMC_NODE1_DDR_D5")
	)
	(segment
		(start 45.29582 -139.292584)
		(end 47.254668 -140.040868)
		(width 0.1143)
		(layer "In7.Cu")
		(net "BMC_NODE1_DDR_D5")
	)
	(segment
		(start 50.3174 -140.574776)
		(end 52.94122 -140.574776)
		(width 0.1143)
		(layer "In7.Cu")
		(net "BMC_NODE1_DDR_D5")
	)
	(segment
		(start 58.310526 -136.055862)
		(end 58.636916 -136.055862)
		(width 0.1016)
		(layer "In7.Cu")
		(net "BMC_NODE1_DDR_D5")
	)
	(segment
		(start 54.730396 -139.44473)
		(end 55.207916 -139.143232)
		(width 0.1143)
		(layer "In7.Cu")
		(net "BMC_NODE1_DDR_D5")
	)
	(segment
		(start 52.94122 -140.574776)
		(end 54.730396 -139.44473)
		(width 0.1143)
		(layer "In7.Cu")
		(net "BMC_NODE1_DDR_D5")
	)
	(segment
		(start 58.94324 -136.055862)
		(end 59.341004 -135.658098)
		(width 0.1143)
		(layer "In7.Cu")
		(net "BMC_NODE1_DDR_D5")
	)
	(segment
		(start 47.621444 -140.104876)
		(end 50.3174 -140.574776)
		(width 0.1143)
		(layer "In7.Cu")
		(net "BMC_NODE1_DDR_D5")
	)
	(segment
		(start 58.636916 -136.055862)
		(end 58.94324 -136.055862)
		(width 0.1143)
		(layer "In7.Cu")
		(net "BMC_NODE1_DDR_D5")
	)
	(segment
		(start 40.43299 -136.564116)
		(end 41.851834 -137.66419)
		(width 0.1143)
		(layer "In7.Cu")
		(net "BMC_NODE1_DDR_D5")
	)
	(segment
		(start 43.169078 -138.316462)
		(end 44.31919 -139.466574)
		(width 0.1143)
		(layer "In7.Cu")
		(net "BMC_NODE1_DDR_D5")
	)
	(segment
		(start 44.924472 -139.292584)
		(end 45.29582 -139.292584)
		(width 0.1143)
		(layer "In7.Cu")
		(net "BMC_NODE1_DDR_D5")
	)
	(segment
		(start 44.750482 -139.466574)
		(end 44.924472 -139.292584)
		(width 0.1143)
		(layer "In7.Cu")
		(net "BMC_NODE1_DDR_D5")
	)
	(segment
		(start 58.295286 -136.055862)
		(end 58.310526 -136.055862)
		(width 0.1143)
		(layer "In7.Cu")
		(net "BMC_NODE1_DDR_D5")
	)
	(segment
		(start 44.31919 -139.466574)
		(end 44.750482 -139.466574)
		(width 0.1143)
		(layer "In7.Cu")
		(net "BMC_NODE1_DDR_D5")
	)
	(segment
		(start 75.90409 -22.30501)
		(end 75.90409 -22.887178)
		(width 0.1651)
		(layer "F.Cu")
		(net "M_DDR3_NODE1_CK0P")
	)
	(segment
		(start 61.369702 -68.114418)
		(end 61.369702 -68.122038)
		(width 0.09906)
		(layer "F.Cu")
		(net "M_DDR3_NODE1_CK0P")
	)
	(segment
		(start 61.743082 -67.741038)
		(end 61.369702 -68.114418)
		(width 0.09906)
		(layer "F.Cu")
		(net "M_DDR3_NODE1_CK0P")
	)
	(segment
		(start 75.750166 -22.151086)
		(end 75.90409 -22.30501)
		(width 0.1651)
		(layer "F.Cu")
		(net "M_DDR3_NODE1_CK0P")
	)
	(segment
		(start 75.750166 -20.94992)
		(end 75.750166 -22.151086)
		(width 0.1651)
		(layer "F.Cu")
		(net "M_DDR3_NODE1_CK0P")
	)
	(segment
		(start 75.90409 -22.887178)
		(end 75.40498 -23.386288)
		(width 0.1651)
		(layer "F.Cu")
		(net "M_DDR3_NODE1_CK0P")
	)
	(via
		(at 75.40498 -23.386288)
		(size 0.508)
		(drill 0.254)
		(layers "F.Cu" "B.Cu")
		(net "M_DDR3_NODE1_CK0P")
	)
	(via
		(at 61.369702 -68.122038)
		(size 0.508)
		(drill 0.254)
		(layers "F.Cu" "B.Cu")
		(net "M_DDR3_NODE1_CK0P")
	)
	(segment
		(start 62.053216 -67.672966)
		(end 62.331092 -67.39509)
		(width 0.09906)
		(layer "In2.Cu")
		(net "M_DDR3_NODE1_CK0P")
	)
	(segment
		(start 63.87338 -65.079118)
		(end 62.987682 -64.19342)
		(width 0.2032)
		(layer "In2.Cu")
		(net "M_DDR3_NODE1_CK0P")
	)
	(segment
		(start 72.248522 -47.780194)
		(end 72.037956 -47.569628)
		(width 0.2032)
		(layer "In2.Cu")
		(net "M_DDR3_NODE1_CK0P")
	)
	(segment
		(start 62.987682 -63.50381)
		(end 63.485268 -63.006224)
		(width 0.2032)
		(layer "In2.Cu")
		(net "M_DDR3_NODE1_CK0P")
	)
	(segment
		(start 76.05268 -29.222954)
		(end 76.05268 -25.920192)
		(width 0.2032)
		(layer "In2.Cu")
		(net "M_DDR3_NODE1_CK0P")
	)
	(segment
		(start 70.564502 -49.043082)
		(end 70.564502 -48.47463)
		(width 0.2032)
		(layer "In2.Cu")
		(net "M_DDR3_NODE1_CK0P")
	)
	(segment
		(start 75.888342 -23.86965)
		(end 75.40498 -23.386288)
		(width 0.2032)
		(layer "In2.Cu")
		(net "M_DDR3_NODE1_CK0P")
	)
	(segment
		(start 75.888342 -24.17064)
		(end 75.888342 -23.86965)
		(width 0.2032)
		(layer "In2.Cu")
		(net "M_DDR3_NODE1_CK0P")
	)
	(segment
		(start 72.038972 -48.283368)
		(end 72.248522 -48.073818)
		(width 0.2032)
		(layer "In2.Cu")
		(net "M_DDR3_NODE1_CK0P")
	)
	(segment
		(start 75.72756 -34.743898)
		(end 75.3237 -34.340038)
		(width 0.2032)
		(layer "In2.Cu")
		(net "M_DDR3_NODE1_CK0P")
	)
	(segment
		(start 63.87338 -66.815462)
		(end 63.87338 -65.079118)
		(width 0.2032)
		(layer "In2.Cu")
		(net "M_DDR3_NODE1_CK0P")
	)
	(segment
		(start 63.93688 -67.218052)
		(end 63.93688 -66.90487)
		(width 0.09906)
		(layer "In2.Cu")
		(net "M_DDR3_NODE1_CK0P")
	)
	(segment
		(start 63.93688 -66.90487)
		(end 63.87338 -66.84137)
		(width 0.09906)
		(layer "In2.Cu")
		(net "M_DDR3_NODE1_CK0P")
	)
	(segment
		(start 70.565518 -49.756822)
		(end 70.775068 -49.547272)
		(width 0.2032)
		(layer "In2.Cu")
		(net "M_DDR3_NODE1_CK0P")
	)
	(segment
		(start 70.775068 -49.253648)
		(end 70.564502 -49.043082)
		(width 0.2032)
		(layer "In2.Cu")
		(net "M_DDR3_NODE1_CK0P")
	)
	(segment
		(start 70.564502 -48.47463)
		(end 70.96633 -48.072802)
		(width 0.2032)
		(layer "In2.Cu")
		(net "M_DDR3_NODE1_CK0P")
	)
	(segment
		(start 66.06032 -62.323218)
		(end 65.90792 -62.170818)
		(width 0.2032)
		(layer "In2.Cu")
		(net "M_DDR3_NODE1_CK0P")
	)
	(segment
		(start 70.27164 -49.756822)
		(end 70.565518 -49.756822)
		(width 0.2032)
		(layer "In2.Cu")
		(net "M_DDR3_NODE1_CK0P")
	)
	(segment
		(start 71.534528 -48.072802)
		(end 71.745094 -48.283368)
		(width 0.2032)
		(layer "In2.Cu")
		(net "M_DDR3_NODE1_CK0P")
	)
	(segment
		(start 62.053216 -68.029074)
		(end 62.053216 -67.672966)
		(width 0.09906)
		(layer "In2.Cu")
		(net "M_DDR3_NODE1_CK0P")
	)
	(segment
		(start 75.3237 -32.521652)
		(end 75.12558 -32.323532)
		(width 0.2032)
		(layer "In2.Cu")
		(net "M_DDR3_NODE1_CK0P")
	)
	(segment
		(start 63.7032 -55.335932)
		(end 69.492876 -49.546256)
		(width 0.2032)
		(layer "In2.Cu")
		(net "M_DDR3_NODE1_CK0P")
	)
	(segment
		(start 72.037956 -47.001176)
		(end 75.72756 -43.311572)
		(width 0.2032)
		(layer "In2.Cu")
		(net "M_DDR3_NODE1_CK0P")
	)
	(segment
		(start 76.05268 -25.920192)
		(end 75.64882 -25.516332)
		(width 0.2032)
		(layer "In2.Cu")
		(net "M_DDR3_NODE1_CK0P")
	)
	(segment
		(start 75.64882 -24.410162)
		(end 75.888342 -24.17064)
		(width 0.2032)
		(layer "In2.Cu")
		(net "M_DDR3_NODE1_CK0P")
	)
	(segment
		(start 75.3237 -34.340038)
		(end 75.3237 -32.521652)
		(width 0.2032)
		(layer "In2.Cu")
		(net "M_DDR3_NODE1_CK0P")
	)
	(segment
		(start 72.248522 -48.073818)
		(end 72.248522 -47.780194)
		(width 0.2032)
		(layer "In2.Cu")
		(net "M_DDR3_NODE1_CK0P")
	)
	(segment
		(start 63.759842 -67.39509)
		(end 63.93688 -67.218052)
		(width 0.09906)
		(layer "In2.Cu")
		(net "M_DDR3_NODE1_CK0P")
	)
	(segment
		(start 75.12558 -30.150054)
		(end 76.05268 -29.222954)
		(width 0.2032)
		(layer "In2.Cu")
		(net "M_DDR3_NODE1_CK0P")
	)
	(segment
		(start 63.485268 -63.006224)
		(end 65.90792 -63.006224)
		(width 0.2032)
		(layer "In2.Cu")
		(net "M_DDR3_NODE1_CK0P")
	)
	(segment
		(start 64.276986 -62.170818)
		(end 63.7032 -61.597032)
		(width 0.2032)
		(layer "In2.Cu")
		(net "M_DDR3_NODE1_CK0P")
	)
	(segment
		(start 70.061074 -49.546256)
		(end 70.27164 -49.756822)
		(width 0.2032)
		(layer "In2.Cu")
		(net "M_DDR3_NODE1_CK0P")
	)
	(segment
		(start 65.90792 -63.006224)
		(end 66.06032 -62.853824)
		(width 0.2032)
		(layer "In2.Cu")
		(net "M_DDR3_NODE1_CK0P")
	)
	(segment
		(start 75.12558 -32.323532)
		(end 75.12558 -30.150054)
		(width 0.2032)
		(layer "In2.Cu")
		(net "M_DDR3_NODE1_CK0P")
	)
	(segment
		(start 62.331092 -67.39509)
		(end 63.759842 -67.39509)
		(width 0.09906)
		(layer "In2.Cu")
		(net "M_DDR3_NODE1_CK0P")
	)
	(segment
		(start 70.775068 -49.547272)
		(end 70.775068 -49.253648)
		(width 0.2032)
		(layer "In2.Cu")
		(net "M_DDR3_NODE1_CK0P")
	)
	(segment
		(start 71.745094 -48.283368)
		(end 72.038972 -48.283368)
		(width 0.2032)
		(layer "In2.Cu")
		(net "M_DDR3_NODE1_CK0P")
	)
	(segment
		(start 61.960252 -68.122038)
		(end 62.053216 -68.029074)
		(width 0.09906)
		(layer "In2.Cu")
		(net "M_DDR3_NODE1_CK0P")
	)
	(segment
		(start 61.369702 -68.122038)
		(end 61.960252 -68.122038)
		(width 0.09906)
		(layer "In2.Cu")
		(net "M_DDR3_NODE1_CK0P")
	)
	(segment
		(start 62.987682 -64.19342)
		(end 62.987682 -63.50381)
		(width 0.2032)
		(layer "In2.Cu")
		(net "M_DDR3_NODE1_CK0P")
	)
	(segment
		(start 72.037956 -47.569628)
		(end 72.037956 -47.001176)
		(width 0.2032)
		(layer "In2.Cu")
		(net "M_DDR3_NODE1_CK0P")
	)
	(segment
		(start 63.87338 -66.84137)
		(end 63.87338 -66.815462)
		(width 0.09906)
		(layer "In2.Cu")
		(net "M_DDR3_NODE1_CK0P")
	)
	(segment
		(start 75.64882 -25.516332)
		(end 75.64882 -24.410162)
		(width 0.2032)
		(layer "In2.Cu")
		(net "M_DDR3_NODE1_CK0P")
	)
	(segment
		(start 66.06032 -62.853824)
		(end 66.06032 -62.323218)
		(width 0.2032)
		(layer "In2.Cu")
		(net "M_DDR3_NODE1_CK0P")
	)
	(segment
		(start 69.492876 -49.546256)
		(end 70.061074 -49.546256)
		(width 0.2032)
		(layer "In2.Cu")
		(net "M_DDR3_NODE1_CK0P")
	)
	(segment
		(start 63.7032 -61.597032)
		(end 63.7032 -55.335932)
		(width 0.2032)
		(layer "In2.Cu")
		(net "M_DDR3_NODE1_CK0P")
	)
	(segment
		(start 65.90792 -62.170818)
		(end 64.276986 -62.170818)
		(width 0.2032)
		(layer "In2.Cu")
		(net "M_DDR3_NODE1_CK0P")
	)
	(segment
		(start 75.72756 -43.311572)
		(end 75.72756 -34.743898)
		(width 0.2032)
		(layer "In2.Cu")
		(net "M_DDR3_NODE1_CK0P")
	)
	(segment
		(start 70.96633 -48.072802)
		(end 71.534528 -48.072802)
		(width 0.2032)
		(layer "In2.Cu")
		(net "M_DDR3_NODE1_CK0P")
	)
	(via
		(at 124.544836 -126.324868)
		(size 0.508)
		(drill 0.254)
		(layers "F.Cu" "B.Cu")
		(net "P1V05_CLK_NODE1_R")
	)
	(segment
		(start 54.21757 -135.208264)
		(end 53.666898 -134.657592)
		(width 0.10414)
		(layer "F.Cu")
		(net "BMC_NODE1_DDR_CLK_DP")
	)
	(segment
		(start 57.34177 -134.459472)
		(end 57.020714 -134.459472)
		(width 0.10414)
		(layer "F.Cu")
		(net "BMC_NODE1_DDR_CLK_DP")
	)
	(segment
		(start 56.271922 -135.208264)
		(end 54.21757 -135.208264)
		(width 0.10414)
		(layer "F.Cu")
		(net "BMC_NODE1_DDR_CLK_DP")
	)
	(segment
		(start 53.666898 -134.657592)
		(end 53.666898 -134.250938)
		(width 0.10414)
		(layer "F.Cu")
		(net "BMC_NODE1_DDR_CLK_DP")
	)
	(segment
		(start 57.020714 -134.459472)
		(end 56.271922 -135.208264)
		(width 0.10414)
		(layer "F.Cu")
		(net "BMC_NODE1_DDR_CLK_DP")
	)
	(segment
		(start 44.833032 -134.563612)
		(end 44.37888 -134.964424)
		(width 0.10414)
		(layer "F.Cu")
		(net "BMC_NODE1_DDR_CLK_DP")
	)
	(via
		(at 53.666898 -134.250938)
		(size 0.508)
		(drill 0.254)
		(layers "F.Cu" "B.Cu")
		(net "BMC_NODE1_DDR_CLK_DP")
	)
	(via
		(at 44.37888 -134.964424)
		(size 0.49022)
		(drill 0.254)
		(layers "F.Cu" "B.Cu")
		(net "BMC_NODE1_DDR_CLK_DP")
	)
	(segment
		(start 52.934108 -132.139182)
		(end 53.835046 -133.669532)
		(width 0.10414)
		(layer "In7.Cu")
		(net "BMC_NODE1_DDR_CLK_DP")
	)
	(segment
		(start 44.79163 -134.189216)
		(end 44.79163 -134.021576)
		(width 0.10414)
		(layer "In7.Cu")
		(net "BMC_NODE1_DDR_CLK_DP")
	)
	(segment
		(start 44.37888 -134.964424)
		(end 44.37888 -134.601966)
		(width 0.10414)
		(layer "In7.Cu")
		(net "BMC_NODE1_DDR_CLK_DP")
	)
	(segment
		(start 47.182278 -130.123184)
		(end 50.91811 -130.123184)
		(width 0.10414)
		(layer "In7.Cu")
		(net "BMC_NODE1_DDR_CLK_DP")
	)
	(segment
		(start 53.835046 -133.669532)
		(end 53.835046 -134.08279)
		(width 0.10414)
		(layer "In7.Cu")
		(net "BMC_NODE1_DDR_CLK_DP")
	)
	(segment
		(start 53.835046 -134.08279)
		(end 53.666898 -134.250938)
		(width 0.10414)
		(layer "In7.Cu")
		(net "BMC_NODE1_DDR_CLK_DP")
	)
	(segment
		(start 46.835568 -130.469894)
		(end 47.182278 -130.123184)
		(width 0.10414)
		(layer "In7.Cu")
		(net "BMC_NODE1_DDR_CLK_DP")
	)
	(segment
		(start 50.91811 -130.123184)
		(end 52.934108 -132.139182)
		(width 0.10414)
		(layer "In7.Cu")
		(net "BMC_NODE1_DDR_CLK_DP")
	)
	(segment
		(start 44.37888 -134.601966)
		(end 44.79163 -134.189216)
		(width 0.10414)
		(layer "In7.Cu")
		(net "BMC_NODE1_DDR_CLK_DP")
	)
	(segment
		(start 46.835568 -131.977638)
		(end 46.835568 -130.469894)
		(width 0.10414)
		(layer "In7.Cu")
		(net "BMC_NODE1_DDR_CLK_DP")
	)
	(segment
		(start 44.79163 -134.021576)
		(end 46.835568 -131.977638)
		(width 0.10414)
		(layer "In7.Cu")
		(net "BMC_NODE1_DDR_CLK_DP")
	)
	(segment
		(start 67.918076 -78.255622)
		(end 68.311776 -78.649322)
		(width 0.1016)
		(layer "F.Cu")
		(net "FM_CPU_NODE1_JTAG_POK")
	)
	(segment
		(start 84.71916 -79.737458)
		(end 84.71916 -80.15986)
		(width 0.1016)
		(layer "F.Cu")
		(net "FM_CPU_NODE1_JTAG_POK")
	)
	(segment
		(start 161.235898 -125.580394)
		(end 161.58718 -125.229112)
		(width 0.1016)
		(layer "F.Cu")
		(net "FM_CPU_NODE1_JTAG_POK")
	)
	(segment
		(start 84.416392 -79.43469)
		(end 84.71916 -79.737458)
		(width 0.1016)
		(layer "F.Cu")
		(net "FM_CPU_NODE1_JTAG_POK")
	)
	(segment
		(start 67.916044 -78.255622)
		(end 67.918076 -78.255622)
		(width 0.1016)
		(layer "F.Cu")
		(net "FM_CPU_NODE1_JTAG_POK")
	)
	(segment
		(start 84.416392 -78.969108)
		(end 84.416392 -79.43469)
		(width 0.1016)
		(layer "F.Cu")
		(net "FM_CPU_NODE1_JTAG_POK")
	)
	(segment
		(start 161.235898 -127.37338)
		(end 161.235898 -125.580394)
		(width 0.1016)
		(layer "F.Cu")
		(net "FM_CPU_NODE1_JTAG_POK")
	)
	(via
		(at 161.58718 -125.229112)
		(size 0.508)
		(drill 0.254)
		(layers "F.Cu" "B.Cu")
		(net "FM_CPU_NODE1_JTAG_POK")
	)
	(via
		(at 84.71916 -80.15986)
		(size 0.508)
		(drill 0.254)
		(layers "F.Cu" "B.Cu")
		(net "FM_CPU_NODE1_JTAG_POK")
	)
	(via
		(at 68.311776 -78.649322)
		(size 0.508)
		(drill 0.254)
		(layers "F.Cu" "B.Cu")
		(net "FM_CPU_NODE1_JTAG_POK")
	)
	(via
		(at 101.56952 -81.170272)
		(size 0.508)
		(drill 0.254)
		(layers "F.Cu" "B.Cu")
		(net "FM_CPU_NODE1_JTAG_POK")
	)
	(segment
		(start 68.298822 -79.326994)
		(end 68.540376 -79.568548)
		(width 0.1143)
		(layer "In2.Cu")
		(net "FM_CPU_NODE1_JTAG_POK")
	)
	(segment
		(start 101.075236 -81.504028)
		(end 90.222578 -81.504028)
		(width 0.1143)
		(layer "In2.Cu")
		(net "FM_CPU_NODE1_JTAG_POK")
	)
	(segment
		(start 85.298026 -79.99349)
		(end 85.133942 -80.157574)
		(width 0.1143)
		(layer "In2.Cu")
		(net "FM_CPU_NODE1_JTAG_POK")
	)
	(segment
		(start 68.983098 -79.568548)
		(end 69.114924 -79.700374)
		(width 0.1143)
		(layer "In2.Cu")
		(net "FM_CPU_NODE1_JTAG_POK")
	)
	(segment
		(start 88.71204 -79.99349)
		(end 85.298026 -79.99349)
		(width 0.1143)
		(layer "In2.Cu")
		(net "FM_CPU_NODE1_JTAG_POK")
	)
	(segment
		(start 82.45221 -79.175102)
		(end 82.891376 -79.614268)
		(width 0.1143)
		(layer "In2.Cu")
		(net "FM_CPU_NODE1_JTAG_POK")
	)
	(segment
		(start 68.540376 -79.568548)
		(end 68.983098 -79.568548)
		(width 0.1143)
		(layer "In2.Cu")
		(net "FM_CPU_NODE1_JTAG_POK")
	)
	(segment
		(start 85.133942 -80.157574)
		(end 84.71916 -80.157574)
		(width 0.1143)
		(layer "In2.Cu")
		(net "FM_CPU_NODE1_JTAG_POK")
	)
	(segment
		(start 101.56952 -81.170272)
		(end 101.408992 -81.170272)
		(width 0.1143)
		(layer "In2.Cu")
		(net "FM_CPU_NODE1_JTAG_POK")
	)
	(segment
		(start 69.114924 -79.700374)
		(end 74.90079 -79.700374)
		(width 0.1143)
		(layer "In2.Cu")
		(net "FM_CPU_NODE1_JTAG_POK")
	)
	(segment
		(start 68.311776 -78.649322)
		(end 68.311776 -78.971648)
		(width 0.1143)
		(layer "In2.Cu")
		(net "FM_CPU_NODE1_JTAG_POK")
	)
	(segment
		(start 78.753208 -79.175102)
		(end 82.45221 -79.175102)
		(width 0.1143)
		(layer "In2.Cu")
		(net "FM_CPU_NODE1_JTAG_POK")
	)
	(segment
		(start 74.90079 -79.700374)
		(end 75.11796 -79.483204)
		(width 0.1143)
		(layer "In2.Cu")
		(net "FM_CPU_NODE1_JTAG_POK")
	)
	(segment
		(start 84.175854 -79.614268)
		(end 84.71916 -80.157574)
		(width 0.1143)
		(layer "In2.Cu")
		(net "FM_CPU_NODE1_JTAG_POK")
	)
	(segment
		(start 78.445106 -79.483204)
		(end 78.753208 -79.175102)
		(width 0.1143)
		(layer "In2.Cu")
		(net "FM_CPU_NODE1_JTAG_POK")
	)
	(segment
		(start 75.11796 -79.483204)
		(end 78.445106 -79.483204)
		(width 0.1143)
		(layer "In2.Cu")
		(net "FM_CPU_NODE1_JTAG_POK")
	)
	(segment
		(start 84.71916 -80.157574)
		(end 84.71916 -80.15986)
		(width 0.1143)
		(layer "In2.Cu")
		(net "FM_CPU_NODE1_JTAG_POK")
	)
	(segment
		(start 68.298822 -78.984602)
		(end 68.298822 -79.326994)
		(width 0.1143)
		(layer "In2.Cu")
		(net "FM_CPU_NODE1_JTAG_POK")
	)
	(segment
		(start 101.408992 -81.170272)
		(end 101.075236 -81.504028)
		(width 0.1143)
		(layer "In2.Cu")
		(net "FM_CPU_NODE1_JTAG_POK")
	)
	(segment
		(start 90.222578 -81.504028)
		(end 88.71204 -79.99349)
		(width 0.1143)
		(layer "In2.Cu")
		(net "FM_CPU_NODE1_JTAG_POK")
	)
	(segment
		(start 82.891376 -79.614268)
		(end 84.175854 -79.614268)
		(width 0.1143)
		(layer "In2.Cu")
		(net "FM_CPU_NODE1_JTAG_POK")
	)
	(segment
		(start 68.311776 -78.971648)
		(end 68.298822 -78.984602)
		(width 0.1143)
		(layer "In2.Cu")
		(net "FM_CPU_NODE1_JTAG_POK")
	)
	(segment
		(start 103.32847 -82.929222)
		(end 101.56952 -81.170272)
		(width 0.1143)
		(layer "In7.Cu")
		(net "FM_CPU_NODE1_JTAG_POK")
	)
	(segment
		(start 123.82754 -96.195388)
		(end 110.561374 -82.929222)
		(width 0.1143)
		(layer "In7.Cu")
		(net "FM_CPU_NODE1_JTAG_POK")
	)
	(segment
		(start 141.264894 -100.12045)
		(end 127.070866 -100.12045)
		(width 0.1143)
		(layer "In7.Cu")
		(net "FM_CPU_NODE1_JTAG_POK")
	)
	(segment
		(start 147.98548 -106.841036)
		(end 141.264894 -100.12045)
		(width 0.1143)
		(layer "In7.Cu")
		(net "FM_CPU_NODE1_JTAG_POK")
	)
	(segment
		(start 153.16708 -117.935248)
		(end 153.16708 -113.0427)
		(width 0.1143)
		(layer "In7.Cu")
		(net "FM_CPU_NODE1_JTAG_POK")
	)
	(segment
		(start 147.98548 -107.8611)
		(end 147.98548 -106.841036)
		(width 0.1143)
		(layer "In7.Cu")
		(net "FM_CPU_NODE1_JTAG_POK")
	)
	(segment
		(start 160.5661 -124.208032)
		(end 159.439864 -124.208032)
		(width 0.1143)
		(layer "In7.Cu")
		(net "FM_CPU_NODE1_JTAG_POK")
	)
	(segment
		(start 159.439864 -124.208032)
		(end 153.16708 -117.935248)
		(width 0.1143)
		(layer "In7.Cu")
		(net "FM_CPU_NODE1_JTAG_POK")
	)
	(segment
		(start 153.16708 -113.0427)
		(end 147.98548 -107.8611)
		(width 0.1143)
		(layer "In7.Cu")
		(net "FM_CPU_NODE1_JTAG_POK")
	)
	(segment
		(start 127.070866 -100.12045)
		(end 123.82754 -96.877124)
		(width 0.1143)
		(layer "In7.Cu")
		(net "FM_CPU_NODE1_JTAG_POK")
	)
	(segment
		(start 161.58718 -125.229112)
		(end 160.5661 -124.208032)
		(width 0.1143)
		(layer "In7.Cu")
		(net "FM_CPU_NODE1_JTAG_POK")
	)
	(segment
		(start 123.82754 -96.877124)
		(end 123.82754 -96.195388)
		(width 0.1143)
		(layer "In7.Cu")
		(net "FM_CPU_NODE1_JTAG_POK")
	)
	(segment
		(start 110.561374 -82.929222)
		(end 103.32847 -82.929222)
		(width 0.1143)
		(layer "In7.Cu")
		(net "FM_CPU_NODE1_JTAG_POK")
	)
	(segment
		(start 69.149468 -62.53353)
		(end 69.149468 -62.189868)
		(width 0.09906)
		(layer "F.Cu")
		(net "M_DDR3_NODE1_DQS4N")
	)
	(segment
		(start 84.1502 -22.151086)
		(end 84.304124 -22.30501)
		(width 0.1651)
		(layer "F.Cu")
		(net "M_DDR3_NODE1_DQS4N")
	)
	(segment
		(start 84.304124 -22.709378)
		(end 84.483702 -22.888956)
		(width 0.1651)
		(layer "F.Cu")
		(net "M_DDR3_NODE1_DQS4N")
	)
	(segment
		(start 84.483702 -23.082758)
		(end 83.989672 -23.576788)
		(width 0.1651)
		(layer "F.Cu")
		(net "M_DDR3_NODE1_DQS4N")
	)
	(segment
		(start 68.898008 -62.78499)
		(end 69.149468 -62.53353)
		(width 0.09906)
		(layer "F.Cu")
		(net "M_DDR3_NODE1_DQS4N")
	)
	(segment
		(start 68.898008 -63.158624)
		(end 68.898008 -62.78499)
		(width 0.09906)
		(layer "F.Cu")
		(net "M_DDR3_NODE1_DQS4N")
	)
	(segment
		(start 84.483702 -22.888956)
		(end 84.483702 -23.082758)
		(width 0.1651)
		(layer "F.Cu")
		(net "M_DDR3_NODE1_DQS4N")
	)
	(segment
		(start 84.1502 -20.94992)
		(end 84.1502 -22.151086)
		(width 0.1651)
		(layer "F.Cu")
		(net "M_DDR3_NODE1_DQS4N")
	)
	(segment
		(start 84.304124 -22.30501)
		(end 84.304124 -22.709378)
		(width 0.1651)
		(layer "F.Cu")
		(net "M_DDR3_NODE1_DQS4N")
	)
	(via
		(at 83.989672 -23.576788)
		(size 0.508)
		(drill 0.254)
		(layers "F.Cu" "B.Cu")
		(net "M_DDR3_NODE1_DQS4N")
	)
	(via
		(at 69.149468 -62.189868)
		(size 0.508)
		(drill 0.254)
		(layers "F.Cu" "B.Cu")
		(net "M_DDR3_NODE1_DQS4N")
	)
	(segment
		(start 78.808834 -38.46195)
		(end 79.402432 -39.055548)
		(width 0.2032)
		(layer "In7.Cu")
		(net "M_DDR3_NODE1_DQS4N")
	)
	(segment
		(start 76.749656 -42.002456)
		(end 76.958952 -41.79316)
		(width 0.2032)
		(layer "In7.Cu")
		(net "M_DDR3_NODE1_DQS4N")
	)
	(segment
		(start 70.61962 -58.509154)
		(end 70.61962 -58.483246)
		(width 0.09906)
		(layer "In7.Cu")
		(net "M_DDR3_NODE1_DQS4N")
	)
	(segment
		(start 74.08926 -45.230796)
		(end 74.08926 -44.662852)
		(width 0.2032)
		(layer "In7.Cu")
		(net "M_DDR3_NODE1_DQS4N")
	)
	(segment
		(start 75.283822 -42.770806)
		(end 75.283822 -42.202354)
		(width 0.2032)
		(layer "In7.Cu")
		(net "M_DDR3_NODE1_DQS4N")
	)
	(segment
		(start 73.903078 -46.050708)
		(end 74.197718 -46.050708)
		(width 0.2032)
		(layer "In7.Cu")
		(net "M_DDR3_NODE1_DQS4N")
	)
	(segment
		(start 69.87794 -61.726064)
		(end 70.333108 -61.270896)
		(width 0.09906)
		(layer "In7.Cu")
		(net "M_DDR3_NODE1_DQS4N")
	)
	(segment
		(start 78.240382 -38.46195)
		(end 78.808834 -38.46195)
		(width 0.2032)
		(layer "In7.Cu")
		(net "M_DDR3_NODE1_DQS4N")
	)
	(segment
		(start 72.615806 -46.136306)
		(end 73.018396 -45.733716)
		(width 0.2032)
		(layer "In7.Cu")
		(net "M_DDR3_NODE1_DQS4N")
	)
	(segment
		(start 71.505064 -60.006484)
		(end 70.68312 -59.18454)
		(width 0.09906)
		(layer "In7.Cu")
		(net "M_DDR3_NODE1_DQS4N")
	)
	(segment
		(start 78.22311 -40.529002)
		(end 78.432406 -40.319706)
		(width 0.2032)
		(layer "In7.Cu")
		(net "M_DDR3_NODE1_DQS4N")
	)
	(segment
		(start 71.233538 -61.270896)
		(end 71.505064 -60.99937)
		(width 0.09906)
		(layer "In7.Cu")
		(net "M_DDR3_NODE1_DQS4N")
	)
	(segment
		(start 77.33538 -39.935404)
		(end 77.928978 -40.529002)
		(width 0.2032)
		(layer "In7.Cu")
		(net "M_DDR3_NODE1_DQS4N")
	)
	(segment
		(start 70.61962 -54.386988)
		(end 70.61962 -48.132492)
		(width 0.2032)
		(layer "In7.Cu")
		(net "M_DDR3_NODE1_DQS4N")
	)
	(segment
		(start 69.479414 -62.841124)
		(end 69.87794 -62.442598)
		(width 0.09906)
		(layer "In7.Cu")
		(net "M_DDR3_NODE1_DQS4N")
	)
	(segment
		(start 82.677762 -31.294832)
		(end 82.677762 -30.060138)
		(width 0.2032)
		(layer "In7.Cu")
		(net "M_DDR3_NODE1_DQS4N")
	)
	(segment
		(start 79.696564 -39.055548)
		(end 81.910682 -36.84143)
		(width 0.2032)
		(layer "In7.Cu")
		(net "M_DDR3_NODE1_DQS4N")
	)
	(segment
		(start 70.61962 -55.240428)
		(end 70.4977 -55.118508)
		(width 0.2032)
		(layer "In7.Cu")
		(net "M_DDR3_NODE1_DQS4N")
	)
	(segment
		(start 71.544942 -47.20717)
		(end 72.112886 -47.20717)
		(width 0.2032)
		(layer "In7.Cu")
		(net "M_DDR3_NODE1_DQS4N")
	)
	(segment
		(start 70.68312 -59.18454)
		(end 70.68312 -58.572654)
		(width 0.09906)
		(layer "In7.Cu")
		(net "M_DDR3_NODE1_DQS4N")
	)
	(segment
		(start 74.08926 -44.662852)
		(end 75.485498 -43.266614)
		(width 0.2032)
		(layer "In7.Cu")
		(net "M_DDR3_NODE1_DQS4N")
	)
	(segment
		(start 69.08419 -62.841124)
		(end 69.479414 -62.841124)
		(width 0.09906)
		(layer "In7.Cu")
		(net "M_DDR3_NODE1_DQS4N")
	)
	(segment
		(start 79.402432 -39.055548)
		(end 79.696564 -39.055548)
		(width 0.2032)
		(layer "In7.Cu")
		(net "M_DDR3_NODE1_DQS4N")
	)
	(segment
		(start 72.112886 -47.20717)
		(end 72.547226 -47.641256)
		(width 0.2032)
		(layer "In7.Cu")
		(net "M_DDR3_NODE1_DQS4N")
	)
	(segment
		(start 84.498942 -23.776178)
		(end 84.299552 -23.576788)
		(width 0.2032)
		(layer "In7.Cu")
		(net "M_DDR3_NODE1_DQS4N")
	)
	(segment
		(start 76.365354 -40.90543)
		(end 76.365354 -40.336978)
		(width 0.2032)
		(layer "In7.Cu")
		(net "M_DDR3_NODE1_DQS4N")
	)
	(segment
		(start 72.547226 -47.641256)
		(end 72.841612 -47.641256)
		(width 0.2032)
		(layer "In7.Cu")
		(net "M_DDR3_NODE1_DQS4N")
	)
	(segment
		(start 70.4977 -54.508908)
		(end 70.61962 -54.386988)
		(width 0.2032)
		(layer "In7.Cu")
		(net "M_DDR3_NODE1_DQS4N")
	)
	(segment
		(start 81.910682 -36.84143)
		(end 81.910682 -32.061912)
		(width 0.2032)
		(layer "In7.Cu")
		(net "M_DDR3_NODE1_DQS4N")
	)
	(segment
		(start 75.485498 -42.972482)
		(end 75.283822 -42.770806)
		(width 0.2032)
		(layer "In7.Cu")
		(net "M_DDR3_NODE1_DQS4N")
	)
	(segment
		(start 69.87794 -62.442598)
		(end 69.87794 -61.726064)
		(width 0.09906)
		(layer "In7.Cu")
		(net "M_DDR3_NODE1_DQS4N")
	)
	(segment
		(start 76.253848 -41.80078)
		(end 76.455524 -42.002456)
		(width 0.2032)
		(layer "In7.Cu")
		(net "M_DDR3_NODE1_DQS4N")
	)
	(segment
		(start 77.928978 -40.529002)
		(end 78.22311 -40.529002)
		(width 0.2032)
		(layer "In7.Cu")
		(net "M_DDR3_NODE1_DQS4N")
	)
	(segment
		(start 83.88604 -27.682952)
		(end 83.88604 -24.732234)
		(width 0.2032)
		(layer "In7.Cu")
		(net "M_DDR3_NODE1_DQS4N")
	)
	(segment
		(start 70.333108 -61.270896)
		(end 71.233538 -61.270896)
		(width 0.09906)
		(layer "In7.Cu")
		(net "M_DDR3_NODE1_DQS4N")
	)
	(segment
		(start 73.58634 -45.733716)
		(end 73.903078 -46.050708)
		(width 0.2032)
		(layer "In7.Cu")
		(net "M_DDR3_NODE1_DQS4N")
	)
	(segment
		(start 69.149468 -62.189868)
		(end 68.948046 -62.39129)
		(width 0.09906)
		(layer "In7.Cu")
		(net "M_DDR3_NODE1_DQS4N")
	)
	(segment
		(start 74.197718 -46.050708)
		(end 74.40676 -45.84192)
		(width 0.2032)
		(layer "In7.Cu")
		(net "M_DDR3_NODE1_DQS4N")
	)
	(segment
		(start 76.958952 -41.79316)
		(end 76.958952 -41.499028)
		(width 0.2032)
		(layer "In7.Cu")
		(net "M_DDR3_NODE1_DQS4N")
	)
	(segment
		(start 75.485498 -43.266614)
		(end 75.485498 -42.972482)
		(width 0.2032)
		(layer "In7.Cu")
		(net "M_DDR3_NODE1_DQS4N")
	)
	(segment
		(start 73.018396 -45.733716)
		(end 73.58634 -45.733716)
		(width 0.2032)
		(layer "In7.Cu")
		(net "M_DDR3_NODE1_DQS4N")
	)
	(segment
		(start 76.958952 -41.499028)
		(end 76.365354 -40.90543)
		(width 0.2032)
		(layer "In7.Cu")
		(net "M_DDR3_NODE1_DQS4N")
	)
	(segment
		(start 70.4977 -55.118508)
		(end 70.4977 -54.508908)
		(width 0.2032)
		(layer "In7.Cu")
		(net "M_DDR3_NODE1_DQS4N")
	)
	(segment
		(start 82.677762 -30.060138)
		(end 82.677 -30.060138)
		(width 0.2032)
		(layer "In7.Cu")
		(net "M_DDR3_NODE1_DQS4N")
	)
	(segment
		(start 71.505064 -60.99937)
		(end 71.505064 -60.006484)
		(width 0.09906)
		(layer "In7.Cu")
		(net "M_DDR3_NODE1_DQS4N")
	)
	(segment
		(start 78.432406 -40.319706)
		(end 78.432406 -40.025574)
		(width 0.2032)
		(layer "In7.Cu")
		(net "M_DDR3_NODE1_DQS4N")
	)
	(segment
		(start 76.766928 -39.935404)
		(end 77.33538 -39.935404)
		(width 0.2032)
		(layer "In7.Cu")
		(net "M_DDR3_NODE1_DQS4N")
	)
	(segment
		(start 83.88604 -24.732234)
		(end 84.498942 -24.119332)
		(width 0.2032)
		(layer "In7.Cu")
		(net "M_DDR3_NODE1_DQS4N")
	)
	(segment
		(start 72.841612 -47.641256)
		(end 73.049892 -47.432976)
		(width 0.2032)
		(layer "In7.Cu")
		(net "M_DDR3_NODE1_DQS4N")
	)
	(segment
		(start 84.299552 -23.576788)
		(end 83.989672 -23.576788)
		(width 0.2032)
		(layer "In7.Cu")
		(net "M_DDR3_NODE1_DQS4N")
	)
	(segment
		(start 81.910682 -32.061912)
		(end 82.677762 -31.294832)
		(width 0.2032)
		(layer "In7.Cu")
		(net "M_DDR3_NODE1_DQS4N")
	)
	(segment
		(start 84.498942 -24.119332)
		(end 84.498942 -23.776178)
		(width 0.2032)
		(layer "In7.Cu")
		(net "M_DDR3_NODE1_DQS4N")
	)
	(segment
		(start 75.685396 -41.80078)
		(end 76.253848 -41.80078)
		(width 0.2032)
		(layer "In7.Cu")
		(net "M_DDR3_NODE1_DQS4N")
	)
	(segment
		(start 75.283822 -42.202354)
		(end 75.685396 -41.80078)
		(width 0.2032)
		(layer "In7.Cu")
		(net "M_DDR3_NODE1_DQS4N")
	)
	(segment
		(start 68.948046 -62.39129)
		(end 68.948046 -62.70498)
		(width 0.09906)
		(layer "In7.Cu")
		(net "M_DDR3_NODE1_DQS4N")
	)
	(segment
		(start 73.049892 -47.13859)
		(end 72.615806 -46.70425)
		(width 0.2032)
		(layer "In7.Cu")
		(net "M_DDR3_NODE1_DQS4N")
	)
	(segment
		(start 77.838808 -39.431976)
		(end 77.838808 -38.863524)
		(width 0.2032)
		(layer "In7.Cu")
		(net "M_DDR3_NODE1_DQS4N")
	)
	(segment
		(start 82.677 -30.060138)
		(end 82.677 -28.891992)
		(width 0.2032)
		(layer "In7.Cu")
		(net "M_DDR3_NODE1_DQS4N")
	)
	(segment
		(start 76.365354 -40.336978)
		(end 76.766928 -39.935404)
		(width 0.2032)
		(layer "In7.Cu")
		(net "M_DDR3_NODE1_DQS4N")
	)
	(segment
		(start 78.432406 -40.025574)
		(end 77.838808 -39.431976)
		(width 0.2032)
		(layer "In7.Cu")
		(net "M_DDR3_NODE1_DQS4N")
	)
	(segment
		(start 68.948046 -62.70498)
		(end 69.08419 -62.841124)
		(width 0.09906)
		(layer "In7.Cu")
		(net "M_DDR3_NODE1_DQS4N")
	)
	(segment
		(start 70.61962 -58.483246)
		(end 70.61962 -55.240428)
		(width 0.2032)
		(layer "In7.Cu")
		(net "M_DDR3_NODE1_DQS4N")
	)
	(segment
		(start 70.61962 -48.132492)
		(end 71.544942 -47.20717)
		(width 0.2032)
		(layer "In7.Cu")
		(net "M_DDR3_NODE1_DQS4N")
	)
	(segment
		(start 82.677 -28.891992)
		(end 83.88604 -27.682952)
		(width 0.2032)
		(layer "In7.Cu")
		(net "M_DDR3_NODE1_DQS4N")
	)
	(segment
		(start 73.049892 -47.432976)
		(end 73.049892 -47.13859)
		(width 0.2032)
		(layer "In7.Cu")
		(net "M_DDR3_NODE1_DQS4N")
	)
	(segment
		(start 74.40676 -45.548042)
		(end 74.08926 -45.230796)
		(width 0.2032)
		(layer "In7.Cu")
		(net "M_DDR3_NODE1_DQS4N")
	)
	(segment
		(start 72.615806 -46.70425)
		(end 72.615806 -46.136306)
		(width 0.2032)
		(layer "In7.Cu")
		(net "M_DDR3_NODE1_DQS4N")
	)
	(segment
		(start 74.40676 -45.84192)
		(end 74.40676 -45.548042)
		(width 0.2032)
		(layer "In7.Cu")
		(net "M_DDR3_NODE1_DQS4N")
	)
	(segment
		(start 70.68312 -58.572654)
		(end 70.61962 -58.509154)
		(width 0.09906)
		(layer "In7.Cu")
		(net "M_DDR3_NODE1_DQS4N")
	)
	(segment
		(start 76.455524 -42.002456)
		(end 76.749656 -42.002456)
		(width 0.2032)
		(layer "In7.Cu")
		(net "M_DDR3_NODE1_DQS4N")
	)
	(segment
		(start 77.838808 -38.863524)
		(end 78.240382 -38.46195)
		(width 0.2032)
		(layer "In7.Cu")
		(net "M_DDR3_NODE1_DQS4N")
	)
	(segment
		(start 131.70408 -111.52759)
		(end 131.553966 -111.677704)
		(width 0.1016)
		(layer "F.Cu")
		(net "CLK_25M_SATA_NODE1_R")
	)
	(segment
		(start 132.03936 -110.57382)
		(end 131.70408 -110.9091)
		(width 0.1016)
		(layer "F.Cu")
		(net "CLK_25M_SATA_NODE1_R")
	)
	(segment
		(start 132.03936 -110.269274)
		(end 132.03936 -110.57382)
		(width 0.1016)
		(layer "F.Cu")
		(net "CLK_25M_SATA_NODE1_R")
	)
	(segment
		(start 131.553712 -113.96472)
		(end 131.553712 -113.012982)
		(width 0.1016)
		(layer "F.Cu")
		(net "CLK_25M_SATA_NODE1_R")
	)
	(segment
		(start 131.784852 -111.90859)
		(end 131.553966 -111.677704)
		(width 0.1016)
		(layer "F.Cu")
		(net "CLK_25M_SATA_NODE1_R")
	)
	(segment
		(start 131.784852 -112.781842)
		(end 131.784852 -111.90859)
		(width 0.1016)
		(layer "F.Cu")
		(net "CLK_25M_SATA_NODE1_R")
	)
	(segment
		(start 131.70408 -110.9091)
		(end 131.70408 -111.52759)
		(width 0.1016)
		(layer "F.Cu")
		(net "CLK_25M_SATA_NODE1_R")
	)
	(segment
		(start 131.553712 -113.012982)
		(end 131.784852 -112.781842)
		(width 0.1016)
		(layer "F.Cu")
		(net "CLK_25M_SATA_NODE1_R")
	)
	(via
		(at 131.553966 -111.677704)
		(size 0.508)
		(drill 0.254)
		(layers "F.Cu" "B.Cu")
		(net "CLK_25M_SATA_NODE1_R")
	)
	(segment
		(start 41.63314 -131.36372)
		(end 41.63314 -131.191508)
		(width 0.1016)
		(layer "F.Cu")
		(net "BMC_NODE1_DDR_MA0")
	)
	(segment
		(start 43.260772 -131.111244)
		(end 43.71467 -131.565142)
		(width 0.1016)
		(layer "F.Cu")
		(net "BMC_NODE1_DDR_MA0")
	)
	(segment
		(start 56.801766 -132.859526)
		(end 56.737504 -132.923788)
		(width 0.1016)
		(layer "F.Cu")
		(net "BMC_NODE1_DDR_MA0")
	)
	(segment
		(start 43.260772 -130.22961)
		(end 43.260772 -131.111244)
		(width 0.1016)
		(layer "F.Cu")
		(net "BMC_NODE1_DDR_MA0")
	)
	(segment
		(start 42.094912 -130.729736)
		(end 42.094912 -130.086608)
		(width 0.1016)
		(layer "F.Cu")
		(net "BMC_NODE1_DDR_MA0")
	)
	(segment
		(start 57.34177 -132.859526)
		(end 56.801766 -132.859526)
		(width 0.1016)
		(layer "F.Cu")
		(net "BMC_NODE1_DDR_MA0")
	)
	(segment
		(start 42.285412 -129.896108)
		(end 42.92727 -129.896108)
		(width 0.1016)
		(layer "F.Cu")
		(net "BMC_NODE1_DDR_MA0")
	)
	(segment
		(start 42.92727 -129.896108)
		(end 43.260772 -130.22961)
		(width 0.1016)
		(layer "F.Cu")
		(net "BMC_NODE1_DDR_MA0")
	)
	(segment
		(start 43.71467 -131.565142)
		(end 43.71467 -131.957318)
		(width 0.1016)
		(layer "F.Cu")
		(net "BMC_NODE1_DDR_MA0")
	)
	(segment
		(start 41.63314 -131.191508)
		(end 42.094912 -130.729736)
		(width 0.1016)
		(layer "F.Cu")
		(net "BMC_NODE1_DDR_MA0")
	)
	(segment
		(start 42.094912 -130.086608)
		(end 42.285412 -129.896108)
		(width 0.1016)
		(layer "F.Cu")
		(net "BMC_NODE1_DDR_MA0")
	)
	(segment
		(start 43.71467 -131.957318)
		(end 43.782234 -132.024882)
		(width 0.1016)
		(layer "F.Cu")
		(net "BMC_NODE1_DDR_MA0")
	)
	(via
		(at 43.782234 -132.024882)
		(size 0.49022)
		(drill 0.254)
		(layers "F.Cu" "B.Cu")
		(net "BMC_NODE1_DDR_MA0")
	)
	(via
		(at 56.737504 -132.923788)
		(size 0.508)
		(drill 0.254)
		(layers "F.Cu" "B.Cu")
		(net "BMC_NODE1_DDR_MA0")
	)
	(segment
		(start 45.844206 -131.869942)
		(end 45.544486 -132.169662)
		(width 0.1143)
		(layer "In2.Cu")
		(net "BMC_NODE1_DDR_MA0")
	)
	(segment
		(start 56.737504 -132.923788)
		(end 56.610758 -132.923788)
		(width 0.1143)
		(layer "In2.Cu")
		(net "BMC_NODE1_DDR_MA0")
	)
	(segment
		(start 44.801536 -132.024882)
		(end 43.782234 -132.024882)
		(width 0.1143)
		(layer "In2.Cu")
		(net "BMC_NODE1_DDR_MA0")
	)
	(segment
		(start 55.945532 -132.258562)
		(end 53.306218 -132.258562)
		(width 0.1143)
		(layer "In2.Cu")
		(net "BMC_NODE1_DDR_MA0")
	)
	(segment
		(start 47.936658 -131.529328)
		(end 47.936658 -131.318762)
		(width 0.1143)
		(layer "In2.Cu")
		(net "BMC_NODE1_DDR_MA0")
	)
	(segment
		(start 47.144686 -131.204462)
		(end 46.479206 -131.869942)
		(width 0.1143)
		(layer "In2.Cu")
		(net "BMC_NODE1_DDR_MA0")
	)
	(segment
		(start 45.544486 -132.169662)
		(end 44.946316 -132.169662)
		(width 0.1143)
		(layer "In2.Cu")
		(net "BMC_NODE1_DDR_MA0")
	)
	(segment
		(start 47.936658 -131.318762)
		(end 47.822358 -131.204462)
		(width 0.1143)
		(layer "In2.Cu")
		(net "BMC_NODE1_DDR_MA0")
	)
	(segment
		(start 56.610758 -132.923788)
		(end 55.945532 -132.258562)
		(width 0.1143)
		(layer "In2.Cu")
		(net "BMC_NODE1_DDR_MA0")
	)
	(segment
		(start 48.11903 -131.7117)
		(end 47.936658 -131.529328)
		(width 0.1143)
		(layer "In2.Cu")
		(net "BMC_NODE1_DDR_MA0")
	)
	(segment
		(start 44.946316 -132.169662)
		(end 44.801536 -132.024882)
		(width 0.1143)
		(layer "In2.Cu")
		(net "BMC_NODE1_DDR_MA0")
	)
	(segment
		(start 46.479206 -131.869942)
		(end 45.844206 -131.869942)
		(width 0.1143)
		(layer "In2.Cu")
		(net "BMC_NODE1_DDR_MA0")
	)
	(segment
		(start 53.306218 -132.258562)
		(end 52.759356 -131.7117)
		(width 0.1143)
		(layer "In2.Cu")
		(net "BMC_NODE1_DDR_MA0")
	)
	(segment
		(start 47.822358 -131.204462)
		(end 47.144686 -131.204462)
		(width 0.1143)
		(layer "In2.Cu")
		(net "BMC_NODE1_DDR_MA0")
	)
	(segment
		(start 52.759356 -131.7117)
		(end 48.11903 -131.7117)
		(width 0.1143)
		(layer "In2.Cu")
		(net "BMC_NODE1_DDR_MA0")
	)
	(segment
		(start 71.4248 -24.985726)
		(end 72.150224 -24.260302)
		(width 0.2286)
		(layer "F.Cu")
		(net "M_DDR3_NODE1_MA5")
	)
	(segment
		(start 60.09894 -62.012068)
		(end 60.12434 -61.986668)
		(width 0.1016)
		(layer "F.Cu")
		(net "M_DDR3_NODE1_MA5")
	)
	(segment
		(start 60.09894 -62.951868)
		(end 60.09894 -62.012068)
		(width 0.1016)
		(layer "F.Cu")
		(net "M_DDR3_NODE1_MA5")
	)
	(segment
		(start 59.892184 -63.158624)
		(end 60.09894 -62.951868)
		(width 0.1016)
		(layer "F.Cu")
		(net "M_DDR3_NODE1_MA5")
	)
	(segment
		(start 72.150224 -24.260302)
		(end 72.150224 -20.94992)
		(width 0.2286)
		(layer "F.Cu")
		(net "M_DDR3_NODE1_MA5")
	)
	(via
		(at 60.12434 -61.986668)
		(size 0.508)
		(drill 0.254)
		(layers "F.Cu" "B.Cu")
		(net "M_DDR3_NODE1_MA5")
	)
	(via
		(at 71.4248 -24.985726)
		(size 0.508)
		(drill 0.254)
		(layers "F.Cu" "B.Cu")
		(net "M_DDR3_NODE1_MA5")
	)
	(segment
		(start 61.87694 -50.05705)
		(end 58.61558 -53.31841)
		(width 0.2286)
		(layer "In2.Cu")
		(net "M_DDR3_NODE1_MA5")
	)
	(segment
		(start 68.80606 -32.635698)
		(end 67.65036 -32.635698)
		(width 0.2286)
		(layer "In2.Cu")
		(net "M_DDR3_NODE1_MA5")
	)
	(segment
		(start 68.95846 -32.483298)
		(end 68.80606 -32.635698)
		(width 0.2286)
		(layer "In2.Cu")
		(net "M_DDR3_NODE1_MA5")
	)
	(segment
		(start 67.49796 -37.91204)
		(end 63.191644 -42.218356)
		(width 0.2286)
		(layer "In2.Cu")
		(net "M_DDR3_NODE1_MA5")
	)
	(segment
		(start 58.61558 -53.31841)
		(end 58.61558 -59.08421)
		(width 0.2286)
		(layer "In2.Cu")
		(net "M_DDR3_NODE1_MA5")
	)
	(segment
		(start 65.720214 -37.60597)
		(end 61.87694 -41.449244)
		(width 0.2286)
		(layer "In2.Cu")
		(net "M_DDR3_NODE1_MA5")
	)
	(segment
		(start 67.49796 -32.788098)
		(end 67.49796 -37.91204)
		(width 0.2286)
		(layer "In2.Cu")
		(net "M_DDR3_NODE1_MA5")
	)
	(segment
		(start 71.4248 -24.985726)
		(end 70.356222 -24.985726)
		(width 0.2286)
		(layer "In2.Cu")
		(net "M_DDR3_NODE1_MA5")
	)
	(segment
		(start 62.886844 -42.218102)
		(end 62.670944 -42.002202)
		(width 0.2286)
		(layer "In2.Cu")
		(net "M_DDR3_NODE1_MA5")
	)
	(segment
		(start 58.37428 -59.32551)
		(end 58.37428 -59.755278)
		(width 0.2286)
		(layer "In2.Cu")
		(net "M_DDR3_NODE1_MA5")
	)
	(segment
		(start 69.63664 -25.705308)
		(end 69.63664 -29.564838)
		(width 0.2286)
		(layer "In2.Cu")
		(net "M_DDR3_NODE1_MA5")
	)
	(segment
		(start 59.39028 -60.771278)
		(end 59.39028 -61.252608)
		(width 0.2286)
		(layer "In2.Cu")
		(net "M_DDR3_NODE1_MA5")
	)
	(segment
		(start 66.007742 -37.60597)
		(end 65.720214 -37.60597)
		(width 0.2286)
		(layer "In2.Cu")
		(net "M_DDR3_NODE1_MA5")
	)
	(segment
		(start 66.241168 -37.839396)
		(end 66.007742 -37.60597)
		(width 0.2286)
		(layer "In2.Cu")
		(net "M_DDR3_NODE1_MA5")
	)
	(segment
		(start 70.356222 -24.985726)
		(end 69.63664 -25.705308)
		(width 0.2286)
		(layer "In2.Cu")
		(net "M_DDR3_NODE1_MA5")
	)
	(segment
		(start 68.95846 -30.243018)
		(end 68.95846 -32.483298)
		(width 0.2286)
		(layer "In2.Cu")
		(net "M_DDR3_NODE1_MA5")
	)
	(segment
		(start 58.61558 -59.08421)
		(end 58.37428 -59.32551)
		(width 0.2286)
		(layer "In2.Cu")
		(net "M_DDR3_NODE1_MA5")
	)
	(segment
		(start 62.671198 -41.696894)
		(end 66.241168 -38.126924)
		(width 0.2286)
		(layer "In2.Cu")
		(net "M_DDR3_NODE1_MA5")
	)
	(segment
		(start 63.191644 -42.218356)
		(end 62.886844 -42.218102)
		(width 0.2286)
		(layer "In2.Cu")
		(net "M_DDR3_NODE1_MA5")
	)
	(segment
		(start 61.87694 -41.449244)
		(end 61.87694 -50.05705)
		(width 0.2286)
		(layer "In2.Cu")
		(net "M_DDR3_NODE1_MA5")
	)
	(segment
		(start 59.39028 -61.252608)
		(end 60.12434 -61.986668)
		(width 0.2286)
		(layer "In2.Cu")
		(net "M_DDR3_NODE1_MA5")
	)
	(segment
		(start 58.37428 -59.755278)
		(end 59.39028 -60.771278)
		(width 0.2286)
		(layer "In2.Cu")
		(net "M_DDR3_NODE1_MA5")
	)
	(segment
		(start 62.670944 -42.002202)
		(end 62.671198 -41.696894)
		(width 0.2286)
		(layer "In2.Cu")
		(net "M_DDR3_NODE1_MA5")
	)
	(segment
		(start 69.63664 -29.564838)
		(end 68.95846 -30.243018)
		(width 0.2286)
		(layer "In2.Cu")
		(net "M_DDR3_NODE1_MA5")
	)
	(segment
		(start 67.65036 -32.635698)
		(end 67.49796 -32.788098)
		(width 0.2286)
		(layer "In2.Cu")
		(net "M_DDR3_NODE1_MA5")
	)
	(segment
		(start 66.241168 -38.126924)
		(end 66.241168 -37.839396)
		(width 0.2286)
		(layer "In2.Cu")
		(net "M_DDR3_NODE1_MA5")
	)
	(segment
		(start 130.14452 -110.99165)
		(end 130.20802 -110.92815)
		(width 0.1016)
		(layer "F.Cu")
		(net "XTAL_CLK_NODE1_X1")
	)
	(segment
		(start 130.14452 -112.04575)
		(end 130.14452 -110.99165)
		(width 0.1016)
		(layer "F.Cu")
		(net "XTAL_CLK_NODE1_X1")
	)
	(segment
		(start 130.20802 -109.263942)
		(end 130.20802 -110.92815)
		(width 0.1016)
		(layer "F.Cu")
		(net "XTAL_CLK_NODE1_X1")
	)
	(segment
		(start 130.268218 -112.694466)
		(end 130.14452 -112.570768)
		(width 0.1016)
		(layer "F.Cu")
		(net "XTAL_CLK_NODE1_X1")
	)
	(segment
		(start 130.14452 -112.570768)
		(end 130.14452 -112.04575)
		(width 0.1016)
		(layer "F.Cu")
		(net "XTAL_CLK_NODE1_X1")
	)
	(segment
		(start 130.344418 -109.127544)
		(end 130.20802 -109.263942)
		(width 0.1016)
		(layer "F.Cu")
		(net "XTAL_CLK_NODE1_X1")
	)
	(segment
		(start 130.753866 -113.96472)
		(end 130.753866 -113.180114)
		(width 0.1016)
		(layer "F.Cu")
		(net "XTAL_CLK_NODE1_X1")
	)
	(segment
		(start 130.753866 -113.180114)
		(end 130.268218 -112.694466)
		(width 0.1016)
		(layer "F.Cu")
		(net "XTAL_CLK_NODE1_X1")
	)
	(via
		(at 130.268218 -112.694466)
		(size 0.508)
		(drill 0.254)
		(layers "F.Cu" "B.Cu")
		(net "XTAL_CLK_NODE1_X1")
	)
	(segment
		(start 170.860466 -122.36577)
		(end 170.389804 -122.836432)
		(width 0.1016)
		(layer "F.Cu")
		(net "FM_NODE1_DDR3_SYSPWRGD_L")
	)
	(segment
		(start 172.010324 -122.36577)
		(end 170.860466 -122.36577)
		(width 0.1016)
		(layer "F.Cu")
		(net "FM_NODE1_DDR3_SYSPWRGD_L")
	)
	(segment
		(start 167.364664 -121.57202)
		(end 168.410128 -122.617484)
		(width 0.1016)
		(layer "F.Cu")
		(net "FM_NODE1_DDR3_SYSPWRGD_L")
	)
	(segment
		(start 170.389804 -122.836432)
		(end 169.43578 -122.836432)
		(width 0.1016)
		(layer "F.Cu")
		(net "FM_NODE1_DDR3_SYSPWRGD_L")
	)
	(segment
		(start 168.410128 -122.617484)
		(end 169.216832 -122.617484)
		(width 0.1016)
		(layer "F.Cu")
		(net "FM_NODE1_DDR3_SYSPWRGD_L")
	)
	(segment
		(start 169.216832 -122.617484)
		(end 169.43578 -122.836432)
		(width 0.1016)
		(layer "F.Cu")
		(net "FM_NODE1_DDR3_SYSPWRGD_L")
	)
	(segment
		(start 167.115744 -121.57202)
		(end 167.364664 -121.57202)
		(width 0.1016)
		(layer "F.Cu")
		(net "FM_NODE1_DDR3_SYSPWRGD_L")
	)
	(via
		(at 169.43578 -122.836432)
		(size 0.508)
		(drill 0.254)
		(layers "F.Cu" "B.Cu")
		(net "FM_NODE1_DDR3_SYSPWRGD_L")
	)
	(segment
		(start 45.633894 -136.963658)
		(end 46.032928 -136.564624)
		(width 0.1016)
		(layer "F.Cu")
		(net "BMC_NODE1_DDR_D2")
	)
	(segment
		(start 54.129686 -136.868662)
		(end 53.715158 -136.868662)
		(width 0.1016)
		(layer "F.Cu")
		(net "BMC_NODE1_DDR_D2")
	)
	(segment
		(start 46.032928 -136.564624)
		(end 46.032928 -136.564116)
		(width 0.1016)
		(layer "F.Cu")
		(net "BMC_NODE1_DDR_D2")
	)
	(segment
		(start 54.802786 -136.195562)
		(end 54.129686 -136.868662)
		(width 0.1016)
		(layer "F.Cu")
		(net "BMC_NODE1_DDR_D2")
	)
	(segment
		(start 55.941976 -135.961628)
		(end 55.708042 -136.195562)
		(width 0.1016)
		(layer "F.Cu")
		(net "BMC_NODE1_DDR_D2")
	)
	(segment
		(start 57.113678 -135.259572)
		(end 56.411622 -135.961628)
		(width 0.1016)
		(layer "F.Cu")
		(net "BMC_NODE1_DDR_D2")
	)
	(segment
		(start 55.708042 -136.195562)
		(end 54.802786 -136.195562)
		(width 0.1016)
		(layer "F.Cu")
		(net "BMC_NODE1_DDR_D2")
	)
	(segment
		(start 56.411622 -135.961628)
		(end 55.941976 -135.961628)
		(width 0.1016)
		(layer "F.Cu")
		(net "BMC_NODE1_DDR_D2")
	)
	(segment
		(start 53.272944 -136.426448)
		(end 50.682906 -136.426448)
		(width 0.1016)
		(layer "F.Cu")
		(net "BMC_NODE1_DDR_D2")
	)
	(segment
		(start 45.633132 -136.963658)
		(end 45.633894 -136.963658)
		(width 0.1016)
		(layer "F.Cu")
		(net "BMC_NODE1_DDR_D2")
	)
	(segment
		(start 57.34177 -135.259572)
		(end 57.113678 -135.259572)
		(width 0.1016)
		(layer "F.Cu")
		(net "BMC_NODE1_DDR_D2")
	)
	(segment
		(start 53.715158 -136.868662)
		(end 53.272944 -136.426448)
		(width 0.1016)
		(layer "F.Cu")
		(net "BMC_NODE1_DDR_D2")
	)
	(via
		(at 46.032928 -136.564116)
		(size 0.49022)
		(drill 0.254)
		(layers "F.Cu" "B.Cu")
		(net "BMC_NODE1_DDR_D2")
	)
	(via
		(at 50.682906 -136.426448)
		(size 0.508)
		(drill 0.254)
		(layers "F.Cu" "B.Cu")
		(net "BMC_NODE1_DDR_D2")
	)
	(segment
		(start 47.220886 -136.284462)
		(end 47.043848 -136.107424)
		(width 0.1143)
		(layer "In7.Cu")
		(net "BMC_NODE1_DDR_D2")
	)
	(segment
		(start 48.680878 -134.101332)
		(end 48.86325 -134.283704)
		(width 0.1143)
		(layer "In7.Cu")
		(net "BMC_NODE1_DDR_D2")
	)
	(segment
		(start 49.068228 -135.020304)
		(end 49.068228 -135.414004)
		(width 0.1143)
		(layer "In7.Cu")
		(net "BMC_NODE1_DDR_D2")
	)
	(segment
		(start 48.680878 -133.843776)
		(end 48.680878 -134.101332)
		(width 0.1143)
		(layer "In7.Cu")
		(net "BMC_NODE1_DDR_D2")
	)
	(segment
		(start 49.562004 -135.642604)
		(end 49.562004 -135.970264)
		(width 0.1143)
		(layer "In7.Cu")
		(net "BMC_NODE1_DDR_D2")
	)
	(segment
		(start 49.182528 -135.528304)
		(end 49.447704 -135.528304)
		(width 0.1143)
		(layer "In7.Cu")
		(net "BMC_NODE1_DDR_D2")
	)
	(segment
		(start 48.86325 -134.283704)
		(end 49.447704 -134.283704)
		(width 0.1143)
		(layer "In7.Cu")
		(net "BMC_NODE1_DDR_D2")
	)
	(segment
		(start 49.562004 -134.398004)
		(end 49.562004 -134.791704)
		(width 0.1143)
		(layer "In7.Cu")
		(net "BMC_NODE1_DDR_D2")
	)
	(segment
		(start 48.739806 -136.193784)
		(end 48.68799 -136.141968)
		(width 0.1143)
		(layer "In7.Cu")
		(net "BMC_NODE1_DDR_D2")
	)
	(segment
		(start 49.447704 -135.528304)
		(end 49.562004 -135.642604)
		(width 0.1143)
		(layer "In7.Cu")
		(net "BMC_NODE1_DDR_D2")
	)
	(segment
		(start 49.447704 -134.906004)
		(end 49.182528 -134.906004)
		(width 0.1143)
		(layer "In7.Cu")
		(net "BMC_NODE1_DDR_D2")
	)
	(segment
		(start 50.184304 -135.927846)
		(end 50.184304 -133.801866)
		(width 0.1143)
		(layer "In7.Cu")
		(net "BMC_NODE1_DDR_D2")
	)
	(segment
		(start 49.182528 -134.906004)
		(end 49.068228 -135.020304)
		(width 0.1143)
		(layer "In7.Cu")
		(net "BMC_NODE1_DDR_D2")
	)
	(segment
		(start 49.447704 -134.283704)
		(end 49.562004 -134.398004)
		(width 0.1143)
		(layer "In7.Cu")
		(net "BMC_NODE1_DDR_D2")
	)
	(segment
		(start 46.032928 -136.367774)
		(end 46.032928 -136.564116)
		(width 0.1143)
		(layer "In7.Cu")
		(net "BMC_NODE1_DDR_D2")
	)
	(segment
		(start 49.562004 -135.970264)
		(end 49.338484 -136.193784)
		(width 0.1143)
		(layer "In7.Cu")
		(net "BMC_NODE1_DDR_D2")
	)
	(segment
		(start 50.184304 -133.801866)
		(end 50.043842 -133.661404)
		(width 0.1143)
		(layer "In7.Cu")
		(net "BMC_NODE1_DDR_D2")
	)
	(segment
		(start 49.338484 -136.193784)
		(end 48.739806 -136.193784)
		(width 0.1143)
		(layer "In7.Cu")
		(net "BMC_NODE1_DDR_D2")
	)
	(segment
		(start 46.293278 -136.107424)
		(end 46.032928 -136.367774)
		(width 0.1143)
		(layer "In7.Cu")
		(net "BMC_NODE1_DDR_D2")
	)
	(segment
		(start 47.76089 -136.141968)
		(end 47.618396 -136.284462)
		(width 0.1143)
		(layer "In7.Cu")
		(net "BMC_NODE1_DDR_D2")
	)
	(segment
		(start 49.562004 -134.791704)
		(end 49.447704 -134.906004)
		(width 0.1143)
		(layer "In7.Cu")
		(net "BMC_NODE1_DDR_D2")
	)
	(segment
		(start 48.86325 -133.661404)
		(end 48.680878 -133.843776)
		(width 0.1143)
		(layer "In7.Cu")
		(net "BMC_NODE1_DDR_D2")
	)
	(segment
		(start 50.682906 -136.426448)
		(end 50.184304 -135.927846)
		(width 0.1143)
		(layer "In7.Cu")
		(net "BMC_NODE1_DDR_D2")
	)
	(segment
		(start 47.043848 -136.107424)
		(end 46.293278 -136.107424)
		(width 0.1143)
		(layer "In7.Cu")
		(net "BMC_NODE1_DDR_D2")
	)
	(segment
		(start 50.043842 -133.661404)
		(end 48.86325 -133.661404)
		(width 0.1143)
		(layer "In7.Cu")
		(net "BMC_NODE1_DDR_D2")
	)
	(segment
		(start 47.618396 -136.284462)
		(end 47.220886 -136.284462)
		(width 0.1143)
		(layer "In7.Cu")
		(net "BMC_NODE1_DDR_D2")
	)
	(segment
		(start 49.068228 -135.414004)
		(end 49.182528 -135.528304)
		(width 0.1143)
		(layer "In7.Cu")
		(net "BMC_NODE1_DDR_D2")
	)
	(segment
		(start 48.68799 -136.141968)
		(end 47.76089 -136.141968)
		(width 0.1143)
		(layer "In7.Cu")
		(net "BMC_NODE1_DDR_D2")
	)
	(segment
		(start 10.566146 -13.40104)
		(end 11.178286 -14.01318)
		(width 0.254)
		(layer "F.Cu")
		(net "PV_VDDR_NODE1_VREF_LM321")
	)
	(segment
		(start 9.550146 -12.013946)
		(end 10.566146 -12.013946)
		(width 0.254)
		(layer "F.Cu")
		(net "PV_VDDR_NODE1_VREF_LM321")
	)
	(segment
		(start 33.918906 -19.453352)
		(end 33.291272 -19.453352)
		(width 0.254)
		(layer "F.Cu")
		(net "PV_VDDR_NODE1_VREF_LM321")
	)
	(segment
		(start 11.178286 -14.01318)
		(end 11.17854 -14.01318)
		(width 0.254)
		(layer "F.Cu")
		(net "PV_VDDR_NODE1_VREF_LM321")
	)
	(segment
		(start 10.566146 -12.013946)
		(end 10.566146 -13.40104)
		(width 0.254)
		(layer "F.Cu")
		(net "PV_VDDR_NODE1_VREF_LM321")
	)
	(via
		(at 11.17854 -14.01318)
		(size 0.508)
		(drill 0.254)
		(layers "F.Cu" "B.Cu")
		(net "PV_VDDR_NODE1_VREF_LM321")
	)
	(via
		(at 33.291272 -19.453352)
		(size 0.508)
		(drill 0.254)
		(layers "F.Cu" "B.Cu")
		(net "PV_VDDR_NODE1_VREF_LM321")
	)
	(segment
		(start 31.205424 -19.453352)
		(end 26.875994 -15.123922)
		(width 0.254)
		(layer "In2.Cu")
		(net "PV_VDDR_NODE1_VREF_LM321")
	)
	(segment
		(start 19.599656 -15.123922)
		(end 18.14068 -13.664946)
		(width 0.254)
		(layer "In2.Cu")
		(net "PV_VDDR_NODE1_VREF_LM321")
	)
	(segment
		(start 18.14068 -13.664946)
		(end 11.526774 -13.664946)
		(width 0.254)
		(layer "In2.Cu")
		(net "PV_VDDR_NODE1_VREF_LM321")
	)
	(segment
		(start 26.875994 -15.123922)
		(end 19.599656 -15.123922)
		(width 0.254)
		(layer "In2.Cu")
		(net "PV_VDDR_NODE1_VREF_LM321")
	)
	(segment
		(start 11.526774 -13.664946)
		(end 11.17854 -14.01318)
		(width 0.254)
		(layer "In2.Cu")
		(net "PV_VDDR_NODE1_VREF_LM321")
	)
	(segment
		(start 33.291272 -19.453352)
		(end 31.205424 -19.453352)
		(width 0.254)
		(layer "In2.Cu")
		(net "PV_VDDR_NODE1_VREF_LM321")
	)
	(segment
		(start 76.350114 -20.94992)
		(end 76.350114 -22.151086)
		(width 0.1651)
		(layer "F.Cu")
		(net "M_DDR3_NODE1_CK0N")
	)
	(segment
		(start 76.350114 -22.151086)
		(end 76.19619 -22.30501)
		(width 0.1651)
		(layer "F.Cu")
		(net "M_DDR3_NODE1_CK0N")
	)
	(segment
		(start 62.443106 -67.741038)
		(end 62.443106 -67.871086)
		(width 0.09906)
		(layer "F.Cu")
		(net "M_DDR3_NODE1_CK0N")
	)
	(segment
		(start 76.19619 -22.907498)
		(end 76.67498 -23.386288)
		(width 0.1651)
		(layer "F.Cu")
		(net "M_DDR3_NODE1_CK0N")
	)
	(segment
		(start 62.679326 -68.107306)
		(end 62.836806 -68.107306)
		(width 0.09906)
		(layer "F.Cu")
		(net "M_DDR3_NODE1_CK0N")
	)
	(segment
		(start 76.19619 -22.30501)
		(end 76.19619 -22.907498)
		(width 0.1651)
		(layer "F.Cu")
		(net "M_DDR3_NODE1_CK0N")
	)
	(segment
		(start 62.443106 -67.871086)
		(end 62.679326 -68.107306)
		(width 0.09906)
		(layer "F.Cu")
		(net "M_DDR3_NODE1_CK0N")
	)
	(via
		(at 62.836806 -68.107306)
		(size 0.508)
		(drill 0.254)
		(layers "F.Cu" "B.Cu")
		(net "M_DDR3_NODE1_CK0N")
	)
	(via
		(at 76.67498 -23.386288)
		(size 0.508)
		(drill 0.254)
		(layers "F.Cu" "B.Cu")
		(net "M_DDR3_NODE1_CK0N")
	)
	(segment
		(start 75.6539 -32.384746)
		(end 75.45578 -32.186626)
		(width 0.2032)
		(layer "In2.Cu")
		(net "M_DDR3_NODE1_CK0N")
	)
	(segment
		(start 62.41542 -67.59829)
		(end 63.84417 -67.59829)
		(width 0.09906)
		(layer "In2.Cu")
		(net "M_DDR3_NODE1_CK0N")
	)
	(segment
		(start 63.317882 -64.056514)
		(end 63.317882 -63.640716)
		(width 0.2032)
		(layer "In2.Cu")
		(net "M_DDR3_NODE1_CK0N")
	)
	(segment
		(start 71.105522 -49.684178)
		(end 71.105268 -49.116742)
		(width 0.2032)
		(layer "In2.Cu")
		(net "M_DDR3_NODE1_CK0N")
	)
	(segment
		(start 72.176132 -48.613568)
		(end 72.578976 -48.210724)
		(width 0.2032)
		(layer "In2.Cu")
		(net "M_DDR3_NODE1_CK0N")
	)
	(segment
		(start 76.05776 -43.448478)
		(end 76.05776 -34.606992)
		(width 0.2032)
		(layer "In2.Cu")
		(net "M_DDR3_NODE1_CK0N")
	)
	(segment
		(start 70.894702 -48.611536)
		(end 71.103236 -48.403002)
		(width 0.2032)
		(layer "In2.Cu")
		(net "M_DDR3_NODE1_CK0N")
	)
	(segment
		(start 62.256416 -67.757294)
		(end 62.41542 -67.59829)
		(width 0.09906)
		(layer "In2.Cu")
		(net "M_DDR3_NODE1_CK0N")
	)
	(segment
		(start 64.413892 -61.840618)
		(end 64.0334 -61.460126)
		(width 0.2032)
		(layer "In2.Cu")
		(net "M_DDR3_NODE1_CK0N")
	)
	(segment
		(start 62.256416 -67.996054)
		(end 62.256416 -67.757294)
		(width 0.09906)
		(layer "In2.Cu")
		(net "M_DDR3_NODE1_CK0N")
	)
	(segment
		(start 71.105268 -49.116742)
		(end 70.894702 -48.906176)
		(width 0.2032)
		(layer "In2.Cu")
		(net "M_DDR3_NODE1_CK0N")
	)
	(segment
		(start 75.97902 -24.547068)
		(end 76.218542 -24.307546)
		(width 0.2032)
		(layer "In2.Cu")
		(net "M_DDR3_NODE1_CK0N")
	)
	(segment
		(start 64.20358 -64.942212)
		(end 63.317882 -64.056514)
		(width 0.2032)
		(layer "In2.Cu")
		(net "M_DDR3_NODE1_CK0N")
	)
	(segment
		(start 64.20358 -66.815462)
		(end 64.20358 -64.942212)
		(width 0.2032)
		(layer "In2.Cu")
		(net "M_DDR3_NODE1_CK0N")
	)
	(segment
		(start 72.578976 -48.210724)
		(end 72.578722 -47.643288)
		(width 0.2032)
		(layer "In2.Cu")
		(net "M_DDR3_NODE1_CK0N")
	)
	(segment
		(start 62.836806 -68.107306)
		(end 62.367668 -68.107306)
		(width 0.09906)
		(layer "In2.Cu")
		(net "M_DDR3_NODE1_CK0N")
	)
	(segment
		(start 72.368156 -47.138082)
		(end 76.05776 -43.448478)
		(width 0.2032)
		(layer "In2.Cu")
		(net "M_DDR3_NODE1_CK0N")
	)
	(segment
		(start 66.39052 -62.99073)
		(end 66.39052 -62.186312)
		(width 0.2032)
		(layer "In2.Cu")
		(net "M_DDR3_NODE1_CK0N")
	)
	(segment
		(start 70.134734 -50.087276)
		(end 70.702678 -50.087022)
		(width 0.2032)
		(layer "In2.Cu")
		(net "M_DDR3_NODE1_CK0N")
	)
	(segment
		(start 76.38288 -29.35986)
		(end 76.38288 -25.783286)
		(width 0.2032)
		(layer "In2.Cu")
		(net "M_DDR3_NODE1_CK0N")
	)
	(segment
		(start 76.218542 -24.307546)
		(end 76.218542 -23.842726)
		(width 0.2032)
		(layer "In2.Cu")
		(net "M_DDR3_NODE1_CK0N")
	)
	(segment
		(start 75.45578 -30.28696)
		(end 76.38288 -29.35986)
		(width 0.2032)
		(layer "In2.Cu")
		(net "M_DDR3_NODE1_CK0N")
	)
	(segment
		(start 72.368156 -47.432722)
		(end 72.368156 -47.138082)
		(width 0.2032)
		(layer "In2.Cu")
		(net "M_DDR3_NODE1_CK0N")
	)
	(segment
		(start 71.397368 -48.403002)
		(end 71.608188 -48.613822)
		(width 0.2032)
		(layer "In2.Cu")
		(net "M_DDR3_NODE1_CK0N")
	)
	(segment
		(start 69.923914 -49.876456)
		(end 70.134734 -50.087276)
		(width 0.2032)
		(layer "In2.Cu")
		(net "M_DDR3_NODE1_CK0N")
	)
	(segment
		(start 64.14008 -67.30238)
		(end 64.14008 -66.90487)
		(width 0.09906)
		(layer "In2.Cu")
		(net "M_DDR3_NODE1_CK0N")
	)
	(segment
		(start 76.38288 -25.783286)
		(end 75.97902 -25.379426)
		(width 0.2032)
		(layer "In2.Cu")
		(net "M_DDR3_NODE1_CK0N")
	)
	(segment
		(start 70.702678 -50.087022)
		(end 71.105522 -49.684178)
		(width 0.2032)
		(layer "In2.Cu")
		(net "M_DDR3_NODE1_CK0N")
	)
	(segment
		(start 75.97902 -25.379426)
		(end 75.97902 -24.547068)
		(width 0.2032)
		(layer "In2.Cu")
		(net "M_DDR3_NODE1_CK0N")
	)
	(segment
		(start 71.608188 -48.613822)
		(end 72.176132 -48.613568)
		(width 0.2032)
		(layer "In2.Cu")
		(net "M_DDR3_NODE1_CK0N")
	)
	(segment
		(start 75.45578 -32.186626)
		(end 75.45578 -30.28696)
		(width 0.2032)
		(layer "In2.Cu")
		(net "M_DDR3_NODE1_CK0N")
	)
	(segment
		(start 76.05776 -34.606992)
		(end 75.6539 -34.203132)
		(width 0.2032)
		(layer "In2.Cu")
		(net "M_DDR3_NODE1_CK0N")
	)
	(segment
		(start 71.103236 -48.403002)
		(end 71.397368 -48.403002)
		(width 0.2032)
		(layer "In2.Cu")
		(net "M_DDR3_NODE1_CK0N")
	)
	(segment
		(start 63.317882 -63.640716)
		(end 63.622174 -63.336424)
		(width 0.2032)
		(layer "In2.Cu")
		(net "M_DDR3_NODE1_CK0N")
	)
	(segment
		(start 64.14008 -66.90487)
		(end 64.20358 -66.84137)
		(width 0.09906)
		(layer "In2.Cu")
		(net "M_DDR3_NODE1_CK0N")
	)
	(segment
		(start 66.044826 -61.840618)
		(end 64.413892 -61.840618)
		(width 0.2032)
		(layer "In2.Cu")
		(net "M_DDR3_NODE1_CK0N")
	)
	(segment
		(start 63.84417 -67.59829)
		(end 64.14008 -67.30238)
		(width 0.09906)
		(layer "In2.Cu")
		(net "M_DDR3_NODE1_CK0N")
	)
	(segment
		(start 72.578722 -47.643288)
		(end 72.368156 -47.432722)
		(width 0.2032)
		(layer "In2.Cu")
		(net "M_DDR3_NODE1_CK0N")
	)
	(segment
		(start 64.20358 -66.84137)
		(end 64.20358 -66.815462)
		(width 0.09906)
		(layer "In2.Cu")
		(net "M_DDR3_NODE1_CK0N")
	)
	(segment
		(start 62.367668 -68.107306)
		(end 62.256416 -67.996054)
		(width 0.09906)
		(layer "In2.Cu")
		(net "M_DDR3_NODE1_CK0N")
	)
	(segment
		(start 70.894702 -48.906176)
		(end 70.894702 -48.611536)
		(width 0.2032)
		(layer "In2.Cu")
		(net "M_DDR3_NODE1_CK0N")
	)
	(segment
		(start 75.6539 -34.203132)
		(end 75.6539 -32.384746)
		(width 0.2032)
		(layer "In2.Cu")
		(net "M_DDR3_NODE1_CK0N")
	)
	(segment
		(start 64.0334 -55.472838)
		(end 69.629782 -49.876456)
		(width 0.2032)
		(layer "In2.Cu")
		(net "M_DDR3_NODE1_CK0N")
	)
	(segment
		(start 64.0334 -61.460126)
		(end 64.0334 -55.472838)
		(width 0.2032)
		(layer "In2.Cu")
		(net "M_DDR3_NODE1_CK0N")
	)
	(segment
		(start 63.622174 -63.336424)
		(end 66.044826 -63.336424)
		(width 0.2032)
		(layer "In2.Cu")
		(net "M_DDR3_NODE1_CK0N")
	)
	(segment
		(start 66.044826 -63.336424)
		(end 66.39052 -62.99073)
		(width 0.2032)
		(layer "In2.Cu")
		(net "M_DDR3_NODE1_CK0N")
	)
	(segment
		(start 66.39052 -62.186312)
		(end 66.044826 -61.840618)
		(width 0.2032)
		(layer "In2.Cu")
		(net "M_DDR3_NODE1_CK0N")
	)
	(segment
		(start 76.218542 -23.842726)
		(end 76.67498 -23.386288)
		(width 0.2032)
		(layer "In2.Cu")
		(net "M_DDR3_NODE1_CK0N")
	)
	(segment
		(start 69.629782 -49.876456)
		(end 69.923914 -49.876456)
		(width 0.2032)
		(layer "In2.Cu")
		(net "M_DDR3_NODE1_CK0N")
	)
	(segment
		(start 137.52576 -112.19053)
		(end 137.195814 -112.520476)
		(width 0.1016)
		(layer "F.Cu")
		(net "CLK_14M_CPU_NODE1_R")
	)
	(segment
		(start 135.153654 -113.96472)
		(end 135.153654 -113.14684)
		(width 0.1016)
		(layer "F.Cu")
		(net "CLK_14M_CPU_NODE1_R")
	)
	(segment
		(start 137.52576 -111.183674)
		(end 137.52576 -112.19053)
		(width 0.1016)
		(layer "F.Cu")
		(net "CLK_14M_CPU_NODE1_R")
	)
	(segment
		(start 138.66876 -108.770674)
		(end 138.54176 -108.897674)
		(width 0.1016)
		(layer "F.Cu")
		(net "CLK_14M_CPU_NODE1_R")
	)
	(segment
		(start 138.54176 -110.929674)
		(end 138.28776 -111.183674)
		(width 0.1016)
		(layer "F.Cu")
		(net "CLK_14M_CPU_NODE1_R")
	)
	(segment
		(start 135.780018 -112.520476)
		(end 137.195814 -112.520476)
		(width 0.1016)
		(layer "F.Cu")
		(net "CLK_14M_CPU_NODE1_R")
	)
	(segment
		(start 138.54176 -108.897674)
		(end 138.54176 -110.929674)
		(width 0.1016)
		(layer "F.Cu")
		(net "CLK_14M_CPU_NODE1_R")
	)
	(segment
		(start 139.68476 -108.770674)
		(end 138.66876 -108.770674)
		(width 0.1016)
		(layer "F.Cu")
		(net "CLK_14M_CPU_NODE1_R")
	)
	(segment
		(start 138.28776 -111.183674)
		(end 137.52576 -111.183674)
		(width 0.1016)
		(layer "F.Cu")
		(net "CLK_14M_CPU_NODE1_R")
	)
	(segment
		(start 135.153654 -113.14684)
		(end 135.780018 -112.520476)
		(width 0.1016)
		(layer "F.Cu")
		(net "CLK_14M_CPU_NODE1_R")
	)
	(via
		(at 137.195814 -112.520476)
		(size 0.508)
		(drill 0.254)
		(layers "F.Cu" "B.Cu")
		(net "CLK_14M_CPU_NODE1_R")
	)
	(segment
		(start 41.399968 -133.28777)
		(end 41.511474 -133.399276)
		(width 0.1016)
		(layer "F.Cu")
		(net "BMC_NODE1_DDR_WE_L")
	)
	(segment
		(start 58.941716 -133.659118)
		(end 58.540904 -133.258306)
		(width 0.1016)
		(layer "F.Cu")
		(net "BMC_NODE1_DDR_WE_L")
	)
	(segment
		(start 42.376598 -133.63448)
		(end 42.376598 -132.965444)
		(width 0.1016)
		(layer "F.Cu")
		(net "BMC_NODE1_DDR_WE_L")
	)
	(segment
		(start 41.63314 -132.963666)
		(end 41.510204 -132.963666)
		(width 0.1016)
		(layer "F.Cu")
		(net "BMC_NODE1_DDR_WE_L")
	)
	(segment
		(start 41.511474 -133.399276)
		(end 41.783508 -133.399276)
		(width 0.1016)
		(layer "F.Cu")
		(net "BMC_NODE1_DDR_WE_L")
	)
	(segment
		(start 41.399968 -133.073902)
		(end 41.399968 -133.28777)
		(width 0.1016)
		(layer "F.Cu")
		(net "BMC_NODE1_DDR_WE_L")
	)
	(segment
		(start 42.09923 -133.714998)
		(end 42.29608 -133.714998)
		(width 0.1016)
		(layer "F.Cu")
		(net "BMC_NODE1_DDR_WE_L")
	)
	(segment
		(start 42.29608 -133.714998)
		(end 42.376598 -133.63448)
		(width 0.1016)
		(layer "F.Cu")
		(net "BMC_NODE1_DDR_WE_L")
	)
	(segment
		(start 58.941716 -133.659626)
		(end 58.941716 -133.659118)
		(width 0.1016)
		(layer "F.Cu")
		(net "BMC_NODE1_DDR_WE_L")
	)
	(segment
		(start 41.510204 -132.963666)
		(end 41.399968 -133.073902)
		(width 0.1016)
		(layer "F.Cu")
		(net "BMC_NODE1_DDR_WE_L")
	)
	(segment
		(start 41.783508 -133.399276)
		(end 42.09923 -133.714998)
		(width 0.1016)
		(layer "F.Cu")
		(net "BMC_NODE1_DDR_WE_L")
	)
	(via
		(at 42.376598 -132.965444)
		(size 0.508)
		(drill 0.254)
		(layers "F.Cu" "B.Cu")
		(net "BMC_NODE1_DDR_WE_L")
	)
	(via
		(at 58.540904 -133.258306)
		(size 0.49022)
		(drill 0.254)
		(layers "F.Cu" "B.Cu")
		(net "BMC_NODE1_DDR_WE_L")
	)
	(segment
		(start 48.83912 -132.8039)
		(end 48.698658 -132.944362)
		(width 0.1143)
		(layer "In2.Cu")
		(net "BMC_NODE1_DDR_WE_L")
	)
	(segment
		(start 52.909978 -133.362954)
		(end 52.350924 -132.8039)
		(width 0.1143)
		(layer "In2.Cu")
		(net "BMC_NODE1_DDR_WE_L")
	)
	(segment
		(start 57.765442 -133.258306)
		(end 56.588406 -134.435342)
		(width 0.1143)
		(layer "In2.Cu")
		(net "BMC_NODE1_DDR_WE_L")
	)
	(segment
		(start 55.829962 -133.362954)
		(end 52.909978 -133.362954)
		(width 0.1143)
		(layer "In2.Cu")
		(net "BMC_NODE1_DDR_WE_L")
	)
	(segment
		(start 56.588406 -134.435342)
		(end 56.4261 -134.435342)
		(width 0.1143)
		(layer "In2.Cu")
		(net "BMC_NODE1_DDR_WE_L")
	)
	(segment
		(start 56.083708 -133.6167)
		(end 55.829962 -133.362954)
		(width 0.1143)
		(layer "In2.Cu")
		(net "BMC_NODE1_DDR_WE_L")
	)
	(segment
		(start 46.382686 -133.058662)
		(end 44.793408 -133.058662)
		(width 0.1143)
		(layer "In2.Cu")
		(net "BMC_NODE1_DDR_WE_L")
	)
	(segment
		(start 47.740824 -132.8039)
		(end 46.637448 -132.8039)
		(width 0.1143)
		(layer "In2.Cu")
		(net "BMC_NODE1_DDR_WE_L")
	)
	(segment
		(start 58.540904 -133.258306)
		(end 57.765442 -133.258306)
		(width 0.1143)
		(layer "In2.Cu")
		(net "BMC_NODE1_DDR_WE_L")
	)
	(segment
		(start 56.4261 -134.435342)
		(end 56.083708 -134.09295)
		(width 0.1143)
		(layer "In2.Cu")
		(net "BMC_NODE1_DDR_WE_L")
	)
	(segment
		(start 44.793408 -133.058662)
		(end 44.504864 -132.770118)
		(width 0.1143)
		(layer "In2.Cu")
		(net "BMC_NODE1_DDR_WE_L")
	)
	(segment
		(start 47.881286 -132.944362)
		(end 47.740824 -132.8039)
		(width 0.1143)
		(layer "In2.Cu")
		(net "BMC_NODE1_DDR_WE_L")
	)
	(segment
		(start 44.504864 -132.770118)
		(end 42.571924 -132.770118)
		(width 0.1143)
		(layer "In2.Cu")
		(net "BMC_NODE1_DDR_WE_L")
	)
	(segment
		(start 52.350924 -132.8039)
		(end 48.83912 -132.8039)
		(width 0.1143)
		(layer "In2.Cu")
		(net "BMC_NODE1_DDR_WE_L")
	)
	(segment
		(start 42.571924 -132.770118)
		(end 42.376598 -132.965444)
		(width 0.1143)
		(layer "In2.Cu")
		(net "BMC_NODE1_DDR_WE_L")
	)
	(segment
		(start 48.698658 -132.944362)
		(end 47.881286 -132.944362)
		(width 0.1143)
		(layer "In2.Cu")
		(net "BMC_NODE1_DDR_WE_L")
	)
	(segment
		(start 56.083708 -134.09295)
		(end 56.083708 -133.6167)
		(width 0.1143)
		(layer "In2.Cu")
		(net "BMC_NODE1_DDR_WE_L")
	)
	(segment
		(start 46.637448 -132.8039)
		(end 46.382686 -133.058662)
		(width 0.1143)
		(layer "In2.Cu")
		(net "BMC_NODE1_DDR_WE_L")
	)
	(segment
		(start 10.09396 -7.127748)
		(end 9.569196 -7.127748)
		(width 0.381)
		(layer "F.Cu")
		(net "PV_VDDR_NODE1_VREF_RW")
	)
	(segment
		(start 8.819896 -7.725156)
		(end 8.74014 -7.725156)
		(width 0.381)
		(layer "F.Cu")
		(net "PV_VDDR_NODE1_VREF_RW")
	)
	(segment
		(start 8.819896 -7.725156)
		(end 9.293352 -8.198612)
		(width 0.381)
		(layer "F.Cu")
		(net "PV_VDDR_NODE1_VREF_RW")
	)
	(segment
		(start 8.971788 -7.725156)
		(end 8.819896 -7.725156)
		(width 0.381)
		(layer "F.Cu")
		(net "PV_VDDR_NODE1_VREF_RW")
	)
	(segment
		(start 8.722614 -5.272278)
		(end 8.722614 -6.69163)
		(width 0.254)
		(layer "F.Cu")
		(net "PV_VDDR_NODE1_VREF_RW")
	)
	(segment
		(start 9.050528 -6.709156)
		(end 8.74014 -6.709156)
		(width 0.381)
		(layer "F.Cu")
		(net "PV_VDDR_NODE1_VREF_RW")
	)
	(segment
		(start 9.359392 -6.400292)
		(end 9.050528 -6.709156)
		(width 0.381)
		(layer "F.Cu")
		(net "PV_VDDR_NODE1_VREF_RW")
	)
	(segment
		(start 8.722614 -6.69163)
		(end 8.74014 -6.709156)
		(width 0.254)
		(layer "F.Cu")
		(net "PV_VDDR_NODE1_VREF_RW")
	)
	(segment
		(start 9.569196 -7.127748)
		(end 8.971788 -7.725156)
		(width 0.381)
		(layer "F.Cu")
		(net "PV_VDDR_NODE1_VREF_RW")
	)
	(via
		(at 9.359392 -6.400292)
		(size 0.508)
		(drill 0.254)
		(layers "F.Cu" "B.Cu")
		(net "PV_VDDR_NODE1_VREF_RW")
	)
	(via
		(at 9.293352 -8.198612)
		(size 0.508)
		(drill 0.254)
		(layers "F.Cu" "B.Cu")
		(net "PV_VDDR_NODE1_VREF_RW")
	)
	(segment
		(start 9.359392 -6.400292)
		(end 9.359392 -8.132572)
		(width 0.254)
		(layer "In2.Cu")
		(net "PV_VDDR_NODE1_VREF_RW")
	)
	(segment
		(start 9.359392 -8.132572)
		(end 9.293352 -8.198612)
		(width 0.254)
		(layer "In2.Cu")
		(net "PV_VDDR_NODE1_VREF_RW")
	)
	(segment
		(start 45.418248 -67.384422)
		(end 46.126908 -66.714624)
		(width 0.127)
		(layer "F.Cu")
		(net "P2E_CPU_NIC2_NODE1_TX_C_DN")
	)
	(via
		(at 46.126908 -66.714624)
		(size 0.508)
		(drill 0.254)
		(layers "F.Cu" "B.Cu")
		(net "P2E_CPU_NIC2_NODE1_TX_C_DN")
	)
	(via
		(at 40.861996 -66.810636)
		(size 0.4064)
		(drill 0.2032)
		(layers "F.Cu" "B.Cu")
		(net "P2E_CPU_NIC2_NODE1_TX_C_DN")
	)
	(segment
		(start 42.01668 -66.810636)
		(end 42.658538 -66.810636)
		(width 0.127)
		(layer "B.Cu")
		(net "P2E_CPU_NIC2_NODE1_TX_C_DN")
	)
	(segment
		(start 41.348152 -66.810636)
		(end 41.491916 -66.666872)
		(width 0.127)
		(layer "B.Cu")
		(net "P2E_CPU_NIC2_NODE1_TX_C_DN")
	)
	(segment
		(start 45.707808 -67.28333)
		(end 45.989748 -67.28333)
		(width 0.127)
		(layer "B.Cu")
		(net "P2E_CPU_NIC2_NODE1_TX_C_DN")
	)
	(segment
		(start 45.601382 -67.176904)
		(end 45.707808 -67.28333)
		(width 0.127)
		(layer "B.Cu")
		(net "P2E_CPU_NIC2_NODE1_TX_C_DN")
	)
	(segment
		(start 36.624768 -66.810636)
		(end 36.247324 -66.433192)
		(width 0.127)
		(layer "B.Cu")
		(net "P2E_CPU_NIC2_NODE1_TX_C_DN")
	)
	(segment
		(start 45.989748 -67.28333)
		(end 46.126908 -67.14617)
		(width 0.127)
		(layer "B.Cu")
		(net "P2E_CPU_NIC2_NODE1_TX_C_DN")
	)
	(segment
		(start 46.126908 -67.14617)
		(end 46.126908 -66.714624)
		(width 0.127)
		(layer "B.Cu")
		(net "P2E_CPU_NIC2_NODE1_TX_C_DN")
	)
	(segment
		(start 42.658538 -66.810636)
		(end 43.024806 -67.176904)
		(width 0.127)
		(layer "B.Cu")
		(net "P2E_CPU_NIC2_NODE1_TX_C_DN")
	)
	(segment
		(start 40.861996 -66.810636)
		(end 36.624768 -66.810636)
		(width 0.127)
		(layer "B.Cu")
		(net "P2E_CPU_NIC2_NODE1_TX_C_DN")
	)
	(segment
		(start 43.024806 -67.176904)
		(end 45.601382 -67.176904)
		(width 0.127)
		(layer "B.Cu")
		(net "P2E_CPU_NIC2_NODE1_TX_C_DN")
	)
	(segment
		(start 41.491916 -66.666872)
		(end 41.872916 -66.666872)
		(width 0.127)
		(layer "B.Cu")
		(net "P2E_CPU_NIC2_NODE1_TX_C_DN")
	)
	(segment
		(start 40.861996 -66.810636)
		(end 41.348152 -66.810636)
		(width 0.127)
		(layer "B.Cu")
		(net "P2E_CPU_NIC2_NODE1_TX_C_DN")
	)
	(segment
		(start 41.872916 -66.666872)
		(end 42.01668 -66.810636)
		(width 0.127)
		(layer "B.Cu")
		(net "P2E_CPU_NIC2_NODE1_TX_C_DN")
	)
	(segment
		(start 57.382664 -62.85357)
		(end 57.178194 -62.6491)
		(width 0.1016)
		(layer "F.Cu")
		(net "M_DDR3_NODE1_BS2")
	)
	(segment
		(start 57.178194 -61.275214)
		(end 57.40654 -61.046868)
		(width 0.1016)
		(layer "F.Cu")
		(net "M_DDR3_NODE1_BS2")
	)
	(segment
		(start 70.257162 -23.398226)
		(end 69.750178 -22.891242)
		(width 0.2286)
		(layer "F.Cu")
		(net "M_DDR3_NODE1_BS2")
	)
	(segment
		(start 57.178194 -62.6491)
		(end 57.178194 -61.275214)
		(width 0.1016)
		(layer "F.Cu")
		(net "M_DDR3_NODE1_BS2")
	)
	(segment
		(start 57.382664 -63.047118)
		(end 57.382664 -62.85357)
		(width 0.1016)
		(layer "F.Cu")
		(net "M_DDR3_NODE1_BS2")
	)
	(segment
		(start 69.750178 -22.891242)
		(end 69.750178 -20.94992)
		(width 0.2286)
		(layer "F.Cu")
		(net "M_DDR3_NODE1_BS2")
	)
	(via
		(at 57.40654 -61.046868)
		(size 0.508)
		(drill 0.254)
		(layers "F.Cu" "B.Cu")
		(net "M_DDR3_NODE1_BS2")
	)
	(via
		(at 70.257162 -23.398226)
		(size 0.508)
		(drill 0.254)
		(layers "F.Cu" "B.Cu")
		(net "M_DDR3_NODE1_BS2")
	)
	(segment
		(start 65.75298 -33.789366)
		(end 65.95618 -33.586166)
		(width 0.2286)
		(layer "In2.Cu")
		(net "M_DDR3_NODE1_BS2")
	)
	(segment
		(start 64.894714 -32.316166)
		(end 65.11036 -32.10052)
		(width 0.2286)
		(layer "In2.Cu")
		(net "M_DDR3_NODE1_BS2")
	)
	(segment
		(start 60.47232 -44.293282)
		(end 60.47232 -43.987974)
		(width 0.2286)
		(layer "In2.Cu")
		(net "M_DDR3_NODE1_BS2")
	)
	(segment
		(start 65.95618 -33.255966)
		(end 65.75298 -33.052766)
		(width 0.2286)
		(layer "In2.Cu")
		(net "M_DDR3_NODE1_BS2")
	)
	(segment
		(start 64.612266 -33.052766)
		(end 64.39662 -32.83712)
		(width 0.2286)
		(layer "In2.Cu")
		(net "M_DDR3_NODE1_BS2")
	)
	(segment
		(start 60.47232 -45.766482)
		(end 60.47232 -45.461174)
		(width 0.2286)
		(layer "In2.Cu")
		(net "M_DDR3_NODE1_BS2")
	)
	(segment
		(start 71.298562 -24.065738)
		(end 71.864982 -23.499318)
		(width 0.2286)
		(layer "In2.Cu")
		(net "M_DDR3_NODE1_BS2")
	)
	(segment
		(start 64.612266 -32.316166)
		(end 64.894714 -32.316166)
		(width 0.2286)
		(layer "In2.Cu")
		(net "M_DDR3_NODE1_BS2")
	)
	(segment
		(start 67.7545 -26.926032)
		(end 68.27012 -26.410412)
		(width 0.2286)
		(layer "In2.Cu")
		(net "M_DDR3_NODE1_BS2")
	)
	(segment
		(start 67.22364 -29.939234)
		(end 67.7545 -29.408374)
		(width 0.2286)
		(layer "In2.Cu")
		(net "M_DDR3_NODE1_BS2")
	)
	(segment
		(start 64.783716 -30.137354)
		(end 67.051174 -30.137354)
		(width 0.2286)
		(layer "In2.Cu")
		(net "M_DDR3_NODE1_BS2")
	)
	(segment
		(start 56.97474 -60.615068)
		(end 56.97474 -59.036712)
		(width 0.1016)
		(layer "In2.Cu")
		(net "M_DDR3_NODE1_BS2")
	)
	(segment
		(start 60.47232 -42.514774)
		(end 60.256674 -42.299128)
		(width 0.2286)
		(layer "In2.Cu")
		(net "M_DDR3_NODE1_BS2")
	)
	(segment
		(start 60.47232 -38.483794)
		(end 64.39662 -34.559494)
		(width 0.2286)
		(layer "In2.Cu")
		(net "M_DDR3_NODE1_BS2")
	)
	(segment
		(start 60.47232 -49.590706)
		(end 60.47232 -46.934374)
		(width 0.2286)
		(layer "In2.Cu")
		(net "M_DDR3_NODE1_BS2")
	)
	(segment
		(start 59.64936 -42.083482)
		(end 59.64936 -41.778174)
		(width 0.2286)
		(layer "In2.Cu")
		(net "M_DDR3_NODE1_BS2")
	)
	(segment
		(start 64.612266 -31.579566)
		(end 64.39662 -31.36392)
		(width 0.2286)
		(layer "In2.Cu")
		(net "M_DDR3_NODE1_BS2")
	)
	(segment
		(start 60.256674 -45.982128)
		(end 60.47232 -45.766482)
		(width 0.2286)
		(layer "In2.Cu")
		(net "M_DDR3_NODE1_BS2")
	)
	(segment
		(start 70.927722 -22.716998)
		(end 70.927722 -23.012146)
		(width 0.2286)
		(layer "In2.Cu")
		(net "M_DDR3_NODE1_BS2")
	)
	(segment
		(start 60.47232 -42.820082)
		(end 60.47232 -42.514774)
		(width 0.2286)
		(layer "In2.Cu")
		(net "M_DDR3_NODE1_BS2")
	)
	(segment
		(start 60.256674 -44.508928)
		(end 60.47232 -44.293282)
		(width 0.2286)
		(layer "In2.Cu")
		(net "M_DDR3_NODE1_BS2")
	)
	(segment
		(start 59.64936 -46.197774)
		(end 59.865006 -45.982128)
		(width 0.2286)
		(layer "In2.Cu")
		(net "M_DDR3_NODE1_BS2")
	)
	(segment
		(start 64.39662 -34.005012)
		(end 64.612266 -33.789366)
		(width 0.2286)
		(layer "In2.Cu")
		(net "M_DDR3_NODE1_BS2")
	)
	(segment
		(start 71.864982 -22.671278)
		(end 71.66483 -22.471126)
		(width 0.2286)
		(layer "In2.Cu")
		(net "M_DDR3_NODE1_BS2")
	)
	(segment
		(start 70.927722 -23.012146)
		(end 70.541642 -23.398226)
		(width 0.2286)
		(layer "In2.Cu")
		(net "M_DDR3_NODE1_BS2")
	)
	(segment
		(start 64.39662 -31.36392)
		(end 64.39662 -30.52445)
		(width 0.2286)
		(layer "In2.Cu")
		(net "M_DDR3_NODE1_BS2")
	)
	(segment
		(start 65.11036 -32.10052)
		(end 65.11036 -31.795212)
		(width 0.2286)
		(layer "In2.Cu")
		(net "M_DDR3_NODE1_BS2")
	)
	(segment
		(start 68.26758 -25.023572)
		(end 69.225414 -24.065738)
		(width 0.2286)
		(layer "In2.Cu")
		(net "M_DDR3_NODE1_BS2")
	)
	(segment
		(start 67.051174 -30.137354)
		(end 67.22364 -29.964888)
		(width 0.2286)
		(layer "In2.Cu")
		(net "M_DDR3_NODE1_BS2")
	)
	(segment
		(start 64.894714 -31.579566)
		(end 64.612266 -31.579566)
		(width 0.2286)
		(layer "In2.Cu")
		(net "M_DDR3_NODE1_BS2")
	)
	(segment
		(start 57.29478 -58.716672)
		(end 57.29478 -58.485024)
		(width 0.1016)
		(layer "In2.Cu")
		(net "M_DDR3_NODE1_BS2")
	)
	(segment
		(start 60.256674 -46.718728)
		(end 59.865006 -46.718728)
		(width 0.2286)
		(layer "In2.Cu")
		(net "M_DDR3_NODE1_BS2")
	)
	(segment
		(start 64.39662 -34.559494)
		(end 64.39662 -34.005012)
		(width 0.2286)
		(layer "In2.Cu")
		(net "M_DDR3_NODE1_BS2")
	)
	(segment
		(start 64.39662 -30.52445)
		(end 64.783716 -30.137354)
		(width 0.2286)
		(layer "In2.Cu")
		(net "M_DDR3_NODE1_BS2")
	)
	(segment
		(start 59.865006 -44.508928)
		(end 60.256674 -44.508928)
		(width 0.2286)
		(layer "In2.Cu")
		(net "M_DDR3_NODE1_BS2")
	)
	(segment
		(start 60.47232 -45.461174)
		(end 60.256674 -45.245528)
		(width 0.2286)
		(layer "In2.Cu")
		(net "M_DDR3_NODE1_BS2")
	)
	(segment
		(start 70.541642 -23.398226)
		(end 70.257162 -23.398226)
		(width 0.2286)
		(layer "In2.Cu")
		(net "M_DDR3_NODE1_BS2")
	)
	(segment
		(start 68.27012 -26.410412)
		(end 68.231258 -26.410412)
		(width 0.2286)
		(layer "In2.Cu")
		(net "M_DDR3_NODE1_BS2")
	)
	(segment
		(start 60.256674 -43.772328)
		(end 59.865006 -43.772328)
		(width 0.2286)
		(layer "In2.Cu")
		(net "M_DDR3_NODE1_BS2")
	)
	(segment
		(start 59.865006 -41.562528)
		(end 60.256674 -41.562528)
		(width 0.2286)
		(layer "In2.Cu")
		(net "M_DDR3_NODE1_BS2")
	)
	(segment
		(start 59.64936 -43.251374)
		(end 59.865006 -43.035728)
		(width 0.2286)
		(layer "In2.Cu")
		(net "M_DDR3_NODE1_BS2")
	)
	(segment
		(start 59.865006 -45.245528)
		(end 59.64936 -45.029882)
		(width 0.2286)
		(layer "In2.Cu")
		(net "M_DDR3_NODE1_BS2")
	)
	(segment
		(start 60.256674 -42.299128)
		(end 59.865006 -42.299128)
		(width 0.2286)
		(layer "In2.Cu")
		(net "M_DDR3_NODE1_BS2")
	)
	(segment
		(start 57.40654 -61.046868)
		(end 56.97474 -60.615068)
		(width 0.1016)
		(layer "In2.Cu")
		(net "M_DDR3_NODE1_BS2")
	)
	(segment
		(start 59.865006 -45.982128)
		(end 60.256674 -45.982128)
		(width 0.2286)
		(layer "In2.Cu")
		(net "M_DDR3_NODE1_BS2")
	)
	(segment
		(start 64.39662 -32.531812)
		(end 64.612266 -32.316166)
		(width 0.2286)
		(layer "In2.Cu")
		(net "M_DDR3_NODE1_BS2")
	)
	(segment
		(start 64.39662 -32.83712)
		(end 64.39662 -32.531812)
		(width 0.2286)
		(layer "In2.Cu")
		(net "M_DDR3_NODE1_BS2")
	)
	(segment
		(start 57.29478 -58.485024)
		(end 57.29478 -52.768246)
		(width 0.2286)
		(layer "In2.Cu")
		(net "M_DDR3_NODE1_BS2")
	)
	(segment
		(start 59.64936 -46.503082)
		(end 59.64936 -46.197774)
		(width 0.2286)
		(layer "In2.Cu")
		(net "M_DDR3_NODE1_BS2")
	)
	(segment
		(start 60.256674 -41.562528)
		(end 60.47232 -41.346882)
		(width 0.2286)
		(layer "In2.Cu")
		(net "M_DDR3_NODE1_BS2")
	)
	(segment
		(start 60.47232 -43.987974)
		(end 60.256674 -43.772328)
		(width 0.2286)
		(layer "In2.Cu")
		(net "M_DDR3_NODE1_BS2")
	)
	(segment
		(start 57.29478 -52.768246)
		(end 60.47232 -49.590706)
		(width 0.2286)
		(layer "In2.Cu")
		(net "M_DDR3_NODE1_BS2")
	)
	(segment
		(start 71.864982 -23.499318)
		(end 71.864982 -22.671278)
		(width 0.2286)
		(layer "In2.Cu")
		(net "M_DDR3_NODE1_BS2")
	)
	(segment
		(start 69.225414 -24.065738)
		(end 71.298562 -24.065738)
		(width 0.2286)
		(layer "In2.Cu")
		(net "M_DDR3_NODE1_BS2")
	)
	(segment
		(start 59.865006 -42.299128)
		(end 59.64936 -42.083482)
		(width 0.2286)
		(layer "In2.Cu")
		(net "M_DDR3_NODE1_BS2")
	)
	(segment
		(start 59.64936 -43.556682)
		(end 59.64936 -43.251374)
		(width 0.2286)
		(layer "In2.Cu")
		(net "M_DDR3_NODE1_BS2")
	)
	(segment
		(start 65.11036 -31.795212)
		(end 64.894714 -31.579566)
		(width 0.2286)
		(layer "In2.Cu")
		(net "M_DDR3_NODE1_BS2")
	)
	(segment
		(start 56.97474 -59.036712)
		(end 57.29478 -58.716672)
		(width 0.1016)
		(layer "In2.Cu")
		(net "M_DDR3_NODE1_BS2")
	)
	(segment
		(start 65.95618 -33.586166)
		(end 65.95618 -33.255966)
		(width 0.2286)
		(layer "In2.Cu")
		(net "M_DDR3_NODE1_BS2")
	)
	(segment
		(start 65.75298 -33.052766)
		(end 64.612266 -33.052766)
		(width 0.2286)
		(layer "In2.Cu")
		(net "M_DDR3_NODE1_BS2")
	)
	(segment
		(start 60.256674 -45.245528)
		(end 59.865006 -45.245528)
		(width 0.2286)
		(layer "In2.Cu")
		(net "M_DDR3_NODE1_BS2")
	)
	(segment
		(start 59.64936 -41.778174)
		(end 59.865006 -41.562528)
		(width 0.2286)
		(layer "In2.Cu")
		(net "M_DDR3_NODE1_BS2")
	)
	(segment
		(start 71.66483 -22.471126)
		(end 71.173594 -22.471126)
		(width 0.2286)
		(layer "In2.Cu")
		(net "M_DDR3_NODE1_BS2")
	)
	(segment
		(start 60.256674 -43.035728)
		(end 60.47232 -42.820082)
		(width 0.2286)
		(layer "In2.Cu")
		(net "M_DDR3_NODE1_BS2")
	)
	(segment
		(start 67.7545 -29.408374)
		(end 67.7545 -26.926032)
		(width 0.2286)
		(layer "In2.Cu")
		(net "M_DDR3_NODE1_BS2")
	)
	(segment
		(start 67.22364 -29.964888)
		(end 67.22364 -29.939234)
		(width 0.2286)
		(layer "In2.Cu")
		(net "M_DDR3_NODE1_BS2")
	)
	(segment
		(start 59.64936 -45.029882)
		(end 59.64936 -44.724574)
		(width 0.2286)
		(layer "In2.Cu")
		(net "M_DDR3_NODE1_BS2")
	)
	(segment
		(start 64.612266 -33.789366)
		(end 65.75298 -33.789366)
		(width 0.2286)
		(layer "In2.Cu")
		(net "M_DDR3_NODE1_BS2")
	)
	(segment
		(start 60.47232 -46.934374)
		(end 60.256674 -46.718728)
		(width 0.2286)
		(layer "In2.Cu")
		(net "M_DDR3_NODE1_BS2")
	)
	(segment
		(start 60.47232 -41.346882)
		(end 60.47232 -38.483794)
		(width 0.2286)
		(layer "In2.Cu")
		(net "M_DDR3_NODE1_BS2")
	)
	(segment
		(start 71.173594 -22.471126)
		(end 70.927722 -22.716998)
		(width 0.2286)
		(layer "In2.Cu")
		(net "M_DDR3_NODE1_BS2")
	)
	(segment
		(start 59.865006 -43.035728)
		(end 60.256674 -43.035728)
		(width 0.2286)
		(layer "In2.Cu")
		(net "M_DDR3_NODE1_BS2")
	)
	(segment
		(start 59.865006 -46.718728)
		(end 59.64936 -46.503082)
		(width 0.2286)
		(layer "In2.Cu")
		(net "M_DDR3_NODE1_BS2")
	)
	(segment
		(start 68.231258 -26.410412)
		(end 68.26758 -26.37409)
		(width 0.2286)
		(layer "In2.Cu")
		(net "M_DDR3_NODE1_BS2")
	)
	(segment
		(start 59.64936 -44.724574)
		(end 59.865006 -44.508928)
		(width 0.2286)
		(layer "In2.Cu")
		(net "M_DDR3_NODE1_BS2")
	)
	(segment
		(start 59.865006 -43.772328)
		(end 59.64936 -43.556682)
		(width 0.2286)
		(layer "In2.Cu")
		(net "M_DDR3_NODE1_BS2")
	)
	(segment
		(start 68.26758 -26.37409)
		(end 68.26758 -25.023572)
		(width 0.2286)
		(layer "In2.Cu")
		(net "M_DDR3_NODE1_BS2")
	)
	(segment
		(start 49.209452 -131.003802)
		(end 49.316386 -130.896868)
		(width 0.1016)
		(layer "F.Cu")
		(net "BMC_NODE1_DDR_MA8")
	)
	(segment
		(start 49.272952 -129.944114)
		(end 49.416208 -129.944114)
		(width 0.1016)
		(layer "F.Cu")
		(net "BMC_NODE1_DDR_MA8")
	)
	(segment
		(start 50.795682 -130.46583)
		(end 50.795682 -130.791458)
		(width 0.1016)
		(layer "F.Cu")
		(net "BMC_NODE1_DDR_MA8")
	)
	(segment
		(start 52.052728 -131.690618)
		(end 51.644042 -131.690618)
		(width 0.1016)
		(layer "F.Cu")
		(net "BMC_NODE1_DDR_MA8")
	)
	(segment
		(start 50.795682 -130.791458)
		(end 50.690272 -130.896868)
		(width 0.1016)
		(layer "F.Cu")
		(net "BMC_NODE1_DDR_MA8")
	)
	(segment
		(start 49.030382 -130.186684)
		(end 49.272952 -129.944114)
		(width 0.1016)
		(layer "F.Cu")
		(net "BMC_NODE1_DDR_MA8")
	)
	(segment
		(start 50.61712 -130.287268)
		(end 50.795682 -130.46583)
		(width 0.1016)
		(layer "F.Cu")
		(net "BMC_NODE1_DDR_MA8")
	)
	(segment
		(start 51.459892 -131.506468)
		(end 49.480216 -131.506468)
		(width 0.1016)
		(layer "F.Cu")
		(net "BMC_NODE1_DDR_MA8")
	)
	(segment
		(start 45.633132 -128.574546)
		(end 46.180756 -128.026922)
		(width 0.1016)
		(layer "F.Cu")
		(net "BMC_NODE1_DDR_MA8")
	)
	(segment
		(start 46.180756 -128.026922)
		(end 47.90821 -128.026922)
		(width 0.1016)
		(layer "F.Cu")
		(net "BMC_NODE1_DDR_MA8")
	)
	(segment
		(start 45.633132 -128.963674)
		(end 45.633132 -128.574546)
		(width 0.1016)
		(layer "F.Cu")
		(net "BMC_NODE1_DDR_MA8")
	)
	(segment
		(start 49.480216 -131.506468)
		(end 49.209452 -131.235704)
		(width 0.1016)
		(layer "F.Cu")
		(net "BMC_NODE1_DDR_MA8")
	)
	(segment
		(start 48.673512 -129.681732)
		(end 48.673512 -130.032506)
		(width 0.1016)
		(layer "F.Cu")
		(net "BMC_NODE1_DDR_MA8")
	)
	(segment
		(start 51.644042 -131.690618)
		(end 51.459892 -131.506468)
		(width 0.1016)
		(layer "F.Cu")
		(net "BMC_NODE1_DDR_MA8")
	)
	(segment
		(start 48.827944 -130.186938)
		(end 49.030382 -130.186938)
		(width 0.1016)
		(layer "F.Cu")
		(net "BMC_NODE1_DDR_MA8")
	)
	(segment
		(start 49.416208 -129.944114)
		(end 49.759616 -130.287268)
		(width 0.1016)
		(layer "F.Cu")
		(net "BMC_NODE1_DDR_MA8")
	)
	(segment
		(start 49.030382 -130.186938)
		(end 49.030382 -130.186684)
		(width 0.1016)
		(layer "F.Cu")
		(net "BMC_NODE1_DDR_MA8")
	)
	(segment
		(start 48.841406 -129.513584)
		(end 48.673512 -129.681732)
		(width 0.1016)
		(layer "F.Cu")
		(net "BMC_NODE1_DDR_MA8")
	)
	(segment
		(start 48.841152 -129.370074)
		(end 48.841406 -129.513584)
		(width 0.1016)
		(layer "F.Cu")
		(net "BMC_NODE1_DDR_MA8")
	)
	(segment
		(start 57.34177 -131.25958)
		(end 56.754776 -131.25958)
		(width 0.1016)
		(layer "F.Cu")
		(net "BMC_NODE1_DDR_MA8")
	)
	(segment
		(start 47.90821 -128.026922)
		(end 48.841152 -128.95834)
		(width 0.1016)
		(layer "F.Cu")
		(net "BMC_NODE1_DDR_MA8")
	)
	(segment
		(start 49.209452 -131.235704)
		(end 49.209452 -131.003802)
		(width 0.1016)
		(layer "F.Cu")
		(net "BMC_NODE1_DDR_MA8")
	)
	(segment
		(start 55.724298 -130.229102)
		(end 53.514244 -130.229102)
		(width 0.1016)
		(layer "F.Cu")
		(net "BMC_NODE1_DDR_MA8")
	)
	(segment
		(start 49.759616 -130.287268)
		(end 50.61712 -130.287268)
		(width 0.1016)
		(layer "F.Cu")
		(net "BMC_NODE1_DDR_MA8")
	)
	(segment
		(start 53.514244 -130.229102)
		(end 52.052728 -131.690618)
		(width 0.1016)
		(layer "F.Cu")
		(net "BMC_NODE1_DDR_MA8")
	)
	(segment
		(start 56.754776 -131.25958)
		(end 55.724298 -130.229102)
		(width 0.1016)
		(layer "F.Cu")
		(net "BMC_NODE1_DDR_MA8")
	)
	(segment
		(start 48.673512 -130.032506)
		(end 48.827944 -130.186938)
		(width 0.1016)
		(layer "F.Cu")
		(net "BMC_NODE1_DDR_MA8")
	)
	(segment
		(start 48.841152 -128.95834)
		(end 48.841152 -129.370074)
		(width 0.1016)
		(layer "F.Cu")
		(net "BMC_NODE1_DDR_MA8")
	)
	(segment
		(start 50.690272 -130.896868)
		(end 50.014886 -130.896868)
		(width 0.1016)
		(layer "F.Cu")
		(net "BMC_NODE1_DDR_MA8")
	)
	(segment
		(start 49.316386 -130.896868)
		(end 50.014886 -130.896868)
		(width 0.1016)
		(layer "F.Cu")
		(net "BMC_NODE1_DDR_MA8")
	)
	(via
		(at 50.014886 -130.896868)
		(size 0.762)
		(drill 0.381)
		(layers "F.Cu" "B.Cu")
		(net "BMC_NODE1_DDR_MA8")
	)
	(via
		(at 12.67206 -7.719568)
		(size 0.508)
		(drill 0.254)
		(layers "F.Cu" "B.Cu")
		(net "PV_VDDR_NODE1_VREF_R")
	)
	(segment
		(start 79.160878 -93.490542)
		(end 79.558388 -95.054166)
		(width 0.1016)
		(layer "F.Cu")
		(net "CLK_33K_CPU_NODE1_SUSCLK")
	)
	(segment
		(start 180.010562 -120.365774)
		(end 180.010562 -120.372378)
		(width 0.1016)
		(layer "F.Cu")
		(net "CLK_33K_CPU_NODE1_SUSCLK")
	)
	(segment
		(start 77.49032 -92.033344)
		(end 77.49286 -92.033344)
		(width 0.1016)
		(layer "F.Cu")
		(net "CLK_33K_CPU_NODE1_SUSCLK")
	)
	(segment
		(start 75.806808 -86.483698)
		(end 75.694032 -86.596474)
		(width 0.1016)
		(layer "F.Cu")
		(net "CLK_33K_CPU_NODE1_SUSCLK")
	)
	(segment
		(start 75.694032 -90.233754)
		(end 77.0001 -91.539822)
		(width 0.1016)
		(layer "F.Cu")
		(net "CLK_33K_CPU_NODE1_SUSCLK")
	)
	(segment
		(start 79.558388 -95.054166)
		(end 79.558388 -96.261682)
		(width 0.1016)
		(layer "F.Cu")
		(net "CLK_33K_CPU_NODE1_SUSCLK")
	)
	(segment
		(start 180.010562 -120.372378)
		(end 180.535072 -120.896888)
		(width 0.1016)
		(layer "F.Cu")
		(net "CLK_33K_CPU_NODE1_SUSCLK")
	)
	(segment
		(start 77.0001 -91.543124)
		(end 77.49032 -92.033344)
		(width 0.1016)
		(layer "F.Cu")
		(net "CLK_33K_CPU_NODE1_SUSCLK")
	)
	(segment
		(start 77.49286 -92.033344)
		(end 77.7748 -92.315284)
		(width 0.1016)
		(layer "F.Cu")
		(net "CLK_33K_CPU_NODE1_SUSCLK")
	)
	(segment
		(start 77.7748 -92.315284)
		(end 77.98562 -92.315284)
		(width 0.1016)
		(layer "F.Cu")
		(net "CLK_33K_CPU_NODE1_SUSCLK")
	)
	(segment
		(start 75.694032 -86.596474)
		(end 75.694032 -90.233754)
		(width 0.1016)
		(layer "F.Cu")
		(net "CLK_33K_CPU_NODE1_SUSCLK")
	)
	(segment
		(start 77.98562 -92.315284)
		(end 79.160878 -93.490542)
		(width 0.1016)
		(layer "F.Cu")
		(net "CLK_33K_CPU_NODE1_SUSCLK")
	)
	(segment
		(start 77.0001 -91.539822)
		(end 77.0001 -91.543124)
		(width 0.1016)
		(layer "F.Cu")
		(net "CLK_33K_CPU_NODE1_SUSCLK")
	)
	(via
		(at 180.535072 -120.896888)
		(size 0.508)
		(drill 0.254)
		(layers "F.Cu" "B.Cu")
		(net "CLK_33K_CPU_NODE1_SUSCLK")
	)
	(via
		(at 79.558388 -95.054166)
		(size 0.508)
		(drill 0.254)
		(layers "F.Cu" "B.Cu")
		(net "CLK_33K_CPU_NODE1_SUSCLK")
	)
	(via
		(at 75.806808 -86.483698)
		(size 0.508)
		(drill 0.254)
		(layers "F.Cu" "B.Cu")
		(net "CLK_33K_CPU_NODE1_SUSCLK")
	)
	(segment
		(start 79.547974 -96.258634)
		(end 79.547974 -95.06458)
		(width 0.1016)
		(layer "B.Cu")
		(net "CLK_33K_CPU_NODE1_SUSCLK")
	)
	(segment
		(start 79.547974 -95.06458)
		(end 79.558388 -95.054166)
		(width 0.1016)
		(layer "B.Cu")
		(net "CLK_33K_CPU_NODE1_SUSCLK")
	)
	(segment
		(start 141.458188 -107.141264)
		(end 142.875254 -107.141264)
		(width 0.1143)
		(layer "In7.Cu")
		(net "CLK_33K_CPU_NODE1_SUSCLK")
	)
	(segment
		(start 125.570742 -103.613458)
		(end 137.850372 -103.613458)
		(width 0.1143)
		(layer "In7.Cu")
		(net "CLK_33K_CPU_NODE1_SUSCLK")
	)
	(segment
		(start 142.875254 -107.141264)
		(end 148.7424 -113.00841)
		(width 0.1143)
		(layer "In7.Cu")
		(net "CLK_33K_CPU_NODE1_SUSCLK")
	)
	(segment
		(start 78.10373 -87.516208)
		(end 78.43393 -87.846408)
		(width 0.1143)
		(layer "In7.Cu")
		(net "CLK_33K_CPU_NODE1_SUSCLK")
	)
	(segment
		(start 177.035714 -126.799594)
		(end 177.035714 -123.649232)
		(width 0.1143)
		(layer "In7.Cu")
		(net "CLK_33K_CPU_NODE1_SUSCLK")
	)
	(segment
		(start 82.133948 -87.717376)
		(end 85.871304 -87.717376)
		(width 0.1143)
		(layer "In7.Cu")
		(net "CLK_33K_CPU_NODE1_SUSCLK")
	)
	(segment
		(start 166.384478 -130.433572)
		(end 166.94658 -129.87147)
		(width 0.1143)
		(layer "In7.Cu")
		(net "CLK_33K_CPU_NODE1_SUSCLK")
	)
	(segment
		(start 141.457172 -107.140248)
		(end 141.458188 -107.141264)
		(width 0.1143)
		(layer "In7.Cu")
		(net "CLK_33K_CPU_NODE1_SUSCLK")
	)
	(segment
		(start 175.40097 -129.87147)
		(end 176.48174 -128.7907)
		(width 0.1143)
		(layer "In7.Cu")
		(net "CLK_33K_CPU_NODE1_SUSCLK")
	)
	(segment
		(start 75.806808 -86.483698)
		(end 76.839318 -87.516208)
		(width 0.1143)
		(layer "In7.Cu")
		(net "CLK_33K_CPU_NODE1_SUSCLK")
	)
	(segment
		(start 177.321718 -123.363228)
		(end 179.735226 -123.363228)
		(width 0.1143)
		(layer "In7.Cu")
		(net "CLK_33K_CPU_NODE1_SUSCLK")
	)
	(segment
		(start 148.7424 -113.00841)
		(end 148.7424 -117.20957)
		(width 0.1143)
		(layer "In7.Cu")
		(net "CLK_33K_CPU_NODE1_SUSCLK")
	)
	(segment
		(start 176.48174 -128.7907)
		(end 176.48174 -127.353568)
		(width 0.1143)
		(layer "In7.Cu")
		(net "CLK_33K_CPU_NODE1_SUSCLK")
	)
	(segment
		(start 161.73577 -129.69748)
		(end 164.99586 -129.69748)
		(width 0.1143)
		(layer "In7.Cu")
		(net "CLK_33K_CPU_NODE1_SUSCLK")
	)
	(segment
		(start 76.839318 -87.516208)
		(end 78.10373 -87.516208)
		(width 0.1143)
		(layer "In7.Cu")
		(net "CLK_33K_CPU_NODE1_SUSCLK")
	)
	(segment
		(start 97.816416 -85.1916)
		(end 99.81946 -87.194644)
		(width 0.1143)
		(layer "In7.Cu")
		(net "CLK_33K_CPU_NODE1_SUSCLK")
	)
	(segment
		(start 81.957926 -87.541354)
		(end 82.133948 -87.717376)
		(width 0.1143)
		(layer "In7.Cu")
		(net "CLK_33K_CPU_NODE1_SUSCLK")
	)
	(segment
		(start 166.94658 -129.87147)
		(end 175.40097 -129.87147)
		(width 0.1143)
		(layer "In7.Cu")
		(net "CLK_33K_CPU_NODE1_SUSCLK")
	)
	(segment
		(start 79.102204 -87.541354)
		(end 81.957926 -87.541354)
		(width 0.1143)
		(layer "In7.Cu")
		(net "CLK_33K_CPU_NODE1_SUSCLK")
	)
	(segment
		(start 176.48174 -127.353568)
		(end 177.035714 -126.799594)
		(width 0.1143)
		(layer "In7.Cu")
		(net "CLK_33K_CPU_NODE1_SUSCLK")
	)
	(segment
		(start 99.81946 -87.194644)
		(end 109.151928 -87.194644)
		(width 0.1143)
		(layer "In7.Cu")
		(net "CLK_33K_CPU_NODE1_SUSCLK")
	)
	(segment
		(start 165.731952 -130.433572)
		(end 166.384478 -130.433572)
		(width 0.1143)
		(layer "In7.Cu")
		(net "CLK_33K_CPU_NODE1_SUSCLK")
	)
	(segment
		(start 78.43393 -87.846408)
		(end 78.79715 -87.846408)
		(width 0.1143)
		(layer "In7.Cu")
		(net "CLK_33K_CPU_NODE1_SUSCLK")
	)
	(segment
		(start 85.871304 -87.717376)
		(end 88.39708 -85.1916)
		(width 0.1143)
		(layer "In7.Cu")
		(net "CLK_33K_CPU_NODE1_SUSCLK")
	)
	(segment
		(start 109.151928 -87.194644)
		(end 125.570742 -103.613458)
		(width 0.1143)
		(layer "In7.Cu")
		(net "CLK_33K_CPU_NODE1_SUSCLK")
	)
	(segment
		(start 88.39708 -85.1916)
		(end 97.816416 -85.1916)
		(width 0.1143)
		(layer "In7.Cu")
		(net "CLK_33K_CPU_NODE1_SUSCLK")
	)
	(segment
		(start 137.850372 -103.613458)
		(end 141.377162 -107.140248)
		(width 0.1143)
		(layer "In7.Cu")
		(net "CLK_33K_CPU_NODE1_SUSCLK")
	)
	(segment
		(start 180.00726 -121.4247)
		(end 180.535072 -120.896888)
		(width 0.1143)
		(layer "In7.Cu")
		(net "CLK_33K_CPU_NODE1_SUSCLK")
	)
	(segment
		(start 141.377162 -107.140248)
		(end 141.457172 -107.140248)
		(width 0.1143)
		(layer "In7.Cu")
		(net "CLK_33K_CPU_NODE1_SUSCLK")
	)
	(segment
		(start 160.4518 -128.91897)
		(end 160.95726 -128.91897)
		(width 0.1143)
		(layer "In7.Cu")
		(net "CLK_33K_CPU_NODE1_SUSCLK")
	)
	(segment
		(start 148.7424 -117.20957)
		(end 160.4518 -128.91897)
		(width 0.1143)
		(layer "In7.Cu")
		(net "CLK_33K_CPU_NODE1_SUSCLK")
	)
	(segment
		(start 160.95726 -128.91897)
		(end 161.73577 -129.69748)
		(width 0.1143)
		(layer "In7.Cu")
		(net "CLK_33K_CPU_NODE1_SUSCLK")
	)
	(segment
		(start 164.99586 -129.69748)
		(end 165.731952 -130.433572)
		(width 0.1143)
		(layer "In7.Cu")
		(net "CLK_33K_CPU_NODE1_SUSCLK")
	)
	(segment
		(start 179.735226 -123.363228)
		(end 180.00726 -123.091194)
		(width 0.1143)
		(layer "In7.Cu")
		(net "CLK_33K_CPU_NODE1_SUSCLK")
	)
	(segment
		(start 177.035714 -123.649232)
		(end 177.321718 -123.363228)
		(width 0.1143)
		(layer "In7.Cu")
		(net "CLK_33K_CPU_NODE1_SUSCLK")
	)
	(segment
		(start 78.79715 -87.846408)
		(end 79.102204 -87.541354)
		(width 0.1143)
		(layer "In7.Cu")
		(net "CLK_33K_CPU_NODE1_SUSCLK")
	)
	(segment
		(start 180.00726 -123.091194)
		(end 180.00726 -121.4247)
		(width 0.1143)
		(layer "In7.Cu")
		(net "CLK_33K_CPU_NODE1_SUSCLK")
	)
	(segment
		(start 46.765718 -67.43192)
		(end 46.765718 -67.272408)
		(width 0.127)
		(layer "F.Cu")
		(net "P2E_CPU_NIC2_NODE1_TX_C_DP")
	)
	(segment
		(start 46.635416 -67.562222)
		(end 46.765718 -67.43192)
		(width 0.127)
		(layer "F.Cu")
		(net "P2E_CPU_NIC2_NODE1_TX_C_DP")
	)
	(segment
		(start 46.180248 -67.384422)
		(end 46.358048 -67.562222)
		(width 0.127)
		(layer "F.Cu")
		(net "P2E_CPU_NIC2_NODE1_TX_C_DP")
	)
	(segment
		(start 46.358048 -67.562222)
		(end 46.635416 -67.562222)
		(width 0.127)
		(layer "F.Cu")
		(net "P2E_CPU_NIC2_NODE1_TX_C_DP")
	)
	(via
		(at 44.5008 -67.481704)
		(size 0.4064)
		(drill 0.2032)
		(layers "F.Cu" "B.Cu")
		(net "P2E_CPU_NIC2_NODE1_TX_C_DP")
	)
	(via
		(at 46.765718 -67.272408)
		(size 0.508)
		(drill 0.254)
		(layers "F.Cu" "B.Cu")
		(net "P2E_CPU_NIC2_NODE1_TX_C_DP")
	)
	(segment
		(start 46.431708 -67.272408)
		(end 46.765718 -67.272408)
		(width 0.127)
		(layer "B.Cu")
		(net "P2E_CPU_NIC2_NODE1_TX_C_DP")
	)
	(segment
		(start 46.431708 -67.272662)
		(end 46.431708 -67.272408)
		(width 0.127)
		(layer "B.Cu")
		(net "P2E_CPU_NIC2_NODE1_TX_C_DP")
	)
	(segment
		(start 42.532046 -67.115436)
		(end 42.898314 -67.481704)
		(width 0.127)
		(layer "B.Cu")
		(net "P2E_CPU_NIC2_NODE1_TX_C_DP")
	)
	(segment
		(start 45.47489 -67.481704)
		(end 45.581316 -67.58813)
		(width 0.127)
		(layer "B.Cu")
		(net "P2E_CPU_NIC2_NODE1_TX_C_DP")
	)
	(segment
		(start 36.70808 -67.115436)
		(end 42.532046 -67.115436)
		(width 0.127)
		(layer "B.Cu")
		(net "P2E_CPU_NIC2_NODE1_TX_C_DP")
	)
	(segment
		(start 36.247324 -67.576192)
		(end 36.70808 -67.115436)
		(width 0.127)
		(layer "B.Cu")
		(net "P2E_CPU_NIC2_NODE1_TX_C_DP")
	)
	(segment
		(start 42.898314 -67.481704)
		(end 44.5008 -67.481704)
		(width 0.127)
		(layer "B.Cu")
		(net "P2E_CPU_NIC2_NODE1_TX_C_DP")
	)
	(segment
		(start 44.5008 -67.481704)
		(end 45.47489 -67.481704)
		(width 0.127)
		(layer "B.Cu")
		(net "P2E_CPU_NIC2_NODE1_TX_C_DP")
	)
	(segment
		(start 45.581316 -67.58813)
		(end 46.11624 -67.58813)
		(width 0.127)
		(layer "B.Cu")
		(net "P2E_CPU_NIC2_NODE1_TX_C_DP")
	)
	(segment
		(start 46.11624 -67.58813)
		(end 46.431708 -67.272662)
		(width 0.127)
		(layer "B.Cu")
		(net "P2E_CPU_NIC2_NODE1_TX_C_DP")
	)
	(segment
		(start 52.050188 -27.771852)
		(end 52.050188 -29.149802)
		(width 0.1651)
		(layer "F.Cu")
		(net "M1_DQ_NODE1_DQ20")
	)
	(segment
		(start 54.781196 -65.455038)
		(end 54.994048 -65.66789)
		(width 0.1651)
		(layer "F.Cu")
		(net "M1_DQ_NODE1_DQ20")
	)
	(segment
		(start 54.994048 -65.66789)
		(end 54.994048 -65.65646)
		(width 0.1651)
		(layer "F.Cu")
		(net "M1_DQ_NODE1_DQ20")
	)
	(segment
		(start 53.162962 -26.659078)
		(end 52.050188 -27.771852)
		(width 0.1651)
		(layer "F.Cu")
		(net "M1_DQ_NODE1_DQ20")
	)
	(segment
		(start 53.955442 -26.659078)
		(end 53.162962 -26.659078)
		(width 0.1651)
		(layer "F.Cu")
		(net "M1_DQ_NODE1_DQ20")
	)
	(segment
		(start 54.497986 -65.455038)
		(end 54.781196 -65.455038)
		(width 0.1651)
		(layer "F.Cu")
		(net "M1_DQ_NODE1_DQ20")
	)
	(via
		(at 54.994048 -65.65646)
		(size 0.508)
		(drill 0.254)
		(layers "F.Cu" "B.Cu")
		(net "M1_DQ_NODE1_DQ20")
	)
	(via
		(at 53.955442 -26.659078)
		(size 0.508)
		(drill 0.254)
		(layers "F.Cu" "B.Cu")
		(net "M1_DQ_NODE1_DQ20")
	)
	(segment
		(start 47.94758 -48.067214)
		(end 47.7393 -48.275494)
		(width 0.2032)
		(layer "In7.Cu")
		(net "M1_DQ_NODE1_DQ20")
	)
	(segment
		(start 47.0281 -45.527722)
		(end 46.81982 -45.319442)
		(width 0.2032)
		(layer "In7.Cu")
		(net "M1_DQ_NODE1_DQ20")
	)
	(segment
		(start 46.81982 -43.185842)
		(end 47.0281 -42.977562)
		(width 0.2032)
		(layer "In7.Cu")
		(net "M1_DQ_NODE1_DQ20")
	)
	(segment
		(start 49.921414 -51.884834)
		(end 49.70526 -51.66868)
		(width 0.2032)
		(layer "In7.Cu")
		(net "M1_DQ_NODE1_DQ20")
	)
	(segment
		(start 46.81982 -44.608242)
		(end 47.0281 -44.399962)
		(width 0.2032)
		(layer "In7.Cu")
		(net "M1_DQ_NODE1_DQ20")
	)
	(segment
		(start 47.0281 -42.977562)
		(end 47.0281 -41.371774)
		(width 0.2032)
		(layer "In7.Cu")
		(net "M1_DQ_NODE1_DQ20")
	)
	(segment
		(start 47.0281 -44.105322)
		(end 46.81982 -43.897042)
		(width 0.2032)
		(layer "In7.Cu")
		(net "M1_DQ_NODE1_DQ20")
	)
	(segment
		(start 54.27726 -29.075888)
		(end 54.49062 -28.862528)
		(width 0.2032)
		(layer "In7.Cu")
		(net "M1_DQ_NODE1_DQ20")
	)
	(segment
		(start 54.49062 -28.862528)
		(end 54.49062 -28.505912)
		(width 0.2032)
		(layer "In7.Cu")
		(net "M1_DQ_NODE1_DQ20")
	)
	(segment
		(start 49.610772 -52.805076)
		(end 49.610772 -52.500276)
		(width 0.2032)
		(layer "In7.Cu")
		(net "M1_DQ_NODE1_DQ20")
	)
	(segment
		(start 45.13834 -43.688762)
		(end 45.13834 -43.394122)
		(width 0.2032)
		(layer "In7.Cu")
		(net "M1_DQ_NODE1_DQ20")
	)
	(segment
		(start 48.4505 -51.644804)
		(end 48.4505 -48.275494)
		(width 0.2032)
		(layer "In7.Cu")
		(net "M1_DQ_NODE1_DQ20")
	)
	(segment
		(start 46.47946 -44.816522)
		(end 46.68774 -44.608242)
		(width 0.2032)
		(layer "In7.Cu")
		(net "M1_DQ_NODE1_DQ20")
	)
	(segment
		(start 48.785018 -51.979322)
		(end 48.4505 -51.644804)
		(width 0.2032)
		(layer "In7.Cu")
		(net "M1_DQ_NODE1_DQ20")
	)
	(segment
		(start 53.75402 -57.8358)
		(end 53.75402 -56.948324)
		(width 0.2032)
		(layer "In7.Cu")
		(net "M1_DQ_NODE1_DQ20")
	)
	(segment
		(start 45.34662 -43.185842)
		(end 46.81982 -43.185842)
		(width 0.2032)
		(layer "In7.Cu")
		(net "M1_DQ_NODE1_DQ20")
	)
	(segment
		(start 54.27726 -29.787088)
		(end 53.68798 -29.787088)
		(width 0.2032)
		(layer "In7.Cu")
		(net "M1_DQ_NODE1_DQ20")
	)
	(segment
		(start 47.2313 -50.32756)
		(end 47.0281 -50.12436)
		(width 0.2032)
		(layer "In7.Cu")
		(net "M1_DQ_NODE1_DQ20")
	)
	(segment
		(start 49.921414 -52.189634)
		(end 49.921414 -51.884834)
		(width 0.2032)
		(layer "In7.Cu")
		(net "M1_DQ_NODE1_DQ20")
	)
	(segment
		(start 53.48478 -32.220916)
		(end 54.54396 -31.161736)
		(width 0.2032)
		(layer "In7.Cu")
		(net "M1_DQ_NODE1_DQ20")
	)
	(segment
		(start 48.4505 -48.275494)
		(end 48.24222 -48.067214)
		(width 0.2032)
		(layer "In7.Cu")
		(net "M1_DQ_NODE1_DQ20")
	)
	(segment
		(start 46.81982 -45.319442)
		(end 46.68774 -45.319442)
		(width 0.2032)
		(layer "In7.Cu")
		(net "M1_DQ_NODE1_DQ20")
	)
	(segment
		(start 53.68798 -29.075888)
		(end 54.27726 -29.075888)
		(width 0.2032)
		(layer "In7.Cu")
		(net "M1_DQ_NODE1_DQ20")
	)
	(segment
		(start 47.7393 -48.275494)
		(end 47.7393 -50.12436)
		(width 0.2032)
		(layer "In7.Cu")
		(net "M1_DQ_NODE1_DQ20")
	)
	(segment
		(start 49.70526 -51.66868)
		(end 49.40046 -51.66868)
		(width 0.2032)
		(layer "In7.Cu")
		(net "M1_DQ_NODE1_DQ20")
	)
	(segment
		(start 49.40046 -51.66868)
		(end 49.089818 -51.979322)
		(width 0.2032)
		(layer "In7.Cu")
		(net "M1_DQ_NODE1_DQ20")
	)
	(segment
		(start 45.13834 -43.394122)
		(end 45.34662 -43.185842)
		(width 0.2032)
		(layer "In7.Cu")
		(net "M1_DQ_NODE1_DQ20")
	)
	(segment
		(start 46.47946 -45.111162)
		(end 46.47946 -44.816522)
		(width 0.2032)
		(layer "In7.Cu")
		(net "M1_DQ_NODE1_DQ20")
	)
	(segment
		(start 49.089818 -51.979322)
		(end 48.785018 -51.979322)
		(width 0.2032)
		(layer "In7.Cu")
		(net "M1_DQ_NODE1_DQ20")
	)
	(segment
		(start 53.48478 -29.279088)
		(end 53.68798 -29.075888)
		(width 0.2032)
		(layer "In7.Cu")
		(net "M1_DQ_NODE1_DQ20")
	)
	(segment
		(start 54.49062 -28.505912)
		(end 54.153562 -28.168854)
		(width 0.2032)
		(layer "In7.Cu")
		(net "M1_DQ_NODE1_DQ20")
	)
	(segment
		(start 53.75402 -56.948324)
		(end 49.610772 -52.805076)
		(width 0.2032)
		(layer "In7.Cu")
		(net "M1_DQ_NODE1_DQ20")
	)
	(segment
		(start 54.54396 -31.161736)
		(end 54.54396 -30.053788)
		(width 0.2032)
		(layer "In7.Cu")
		(net "M1_DQ_NODE1_DQ20")
	)
	(segment
		(start 53.68798 -29.787088)
		(end 53.48478 -29.583888)
		(width 0.2032)
		(layer "In7.Cu")
		(net "M1_DQ_NODE1_DQ20")
	)
	(segment
		(start 54.994048 -65.65646)
		(end 54.994048 -64.862202)
		(width 0.1016)
		(layer "In7.Cu")
		(net "M1_DQ_NODE1_DQ20")
	)
	(segment
		(start 54.994048 -64.862202)
		(end 55.343044 -64.513206)
		(width 0.1016)
		(layer "In7.Cu")
		(net "M1_DQ_NODE1_DQ20")
	)
	(segment
		(start 48.24222 -48.067214)
		(end 47.94758 -48.067214)
		(width 0.2032)
		(layer "In7.Cu")
		(net "M1_DQ_NODE1_DQ20")
	)
	(segment
		(start 46.68774 -45.319442)
		(end 46.47946 -45.111162)
		(width 0.2032)
		(layer "In7.Cu")
		(net "M1_DQ_NODE1_DQ20")
	)
	(segment
		(start 47.0281 -41.371774)
		(end 53.48478 -34.915094)
		(width 0.2032)
		(layer "In7.Cu")
		(net "M1_DQ_NODE1_DQ20")
	)
	(segment
		(start 55.343044 -64.513206)
		(end 55.343044 -63.826898)
		(width 0.1016)
		(layer "In7.Cu")
		(net "M1_DQ_NODE1_DQ20")
	)
	(segment
		(start 47.0281 -44.399962)
		(end 47.0281 -44.105322)
		(width 0.2032)
		(layer "In7.Cu")
		(net "M1_DQ_NODE1_DQ20")
	)
	(segment
		(start 55.343044 -63.826898)
		(end 54.30266 -62.786514)
		(width 0.1016)
		(layer "In7.Cu")
		(net "M1_DQ_NODE1_DQ20")
	)
	(segment
		(start 54.30266 -58.38444)
		(end 53.75402 -57.8358)
		(width 0.2032)
		(layer "In7.Cu")
		(net "M1_DQ_NODE1_DQ20")
	)
	(segment
		(start 54.153562 -28.168854)
		(end 54.153562 -26.857198)
		(width 0.2032)
		(layer "In7.Cu")
		(net "M1_DQ_NODE1_DQ20")
	)
	(segment
		(start 54.153562 -26.857198)
		(end 53.955442 -26.659078)
		(width 0.2032)
		(layer "In7.Cu")
		(net "M1_DQ_NODE1_DQ20")
	)
	(segment
		(start 53.48478 -29.583888)
		(end 53.48478 -29.279088)
		(width 0.2032)
		(layer "In7.Cu")
		(net "M1_DQ_NODE1_DQ20")
	)
	(segment
		(start 54.54396 -30.053788)
		(end 54.27726 -29.787088)
		(width 0.2032)
		(layer "In7.Cu")
		(net "M1_DQ_NODE1_DQ20")
	)
	(segment
		(start 47.5361 -50.32756)
		(end 47.2313 -50.32756)
		(width 0.2032)
		(layer "In7.Cu")
		(net "M1_DQ_NODE1_DQ20")
	)
	(segment
		(start 49.610772 -52.500276)
		(end 49.921414 -52.189634)
		(width 0.2032)
		(layer "In7.Cu")
		(net "M1_DQ_NODE1_DQ20")
	)
	(segment
		(start 46.68774 -44.608242)
		(end 46.81982 -44.608242)
		(width 0.2032)
		(layer "In7.Cu")
		(net "M1_DQ_NODE1_DQ20")
	)
	(segment
		(start 47.7393 -50.12436)
		(end 47.5361 -50.32756)
		(width 0.2032)
		(layer "In7.Cu")
		(net "M1_DQ_NODE1_DQ20")
	)
	(segment
		(start 45.34662 -43.897042)
		(end 45.13834 -43.688762)
		(width 0.2032)
		(layer "In7.Cu")
		(net "M1_DQ_NODE1_DQ20")
	)
	(segment
		(start 53.48478 -34.915094)
		(end 53.48478 -32.220916)
		(width 0.2032)
		(layer "In7.Cu")
		(net "M1_DQ_NODE1_DQ20")
	)
	(segment
		(start 47.0281 -50.12436)
		(end 47.0281 -45.527722)
		(width 0.2032)
		(layer "In7.Cu")
		(net "M1_DQ_NODE1_DQ20")
	)
	(segment
		(start 54.30266 -62.786514)
		(end 54.30266 -58.38444)
		(width 0.1016)
		(layer "In7.Cu")
		(net "M1_DQ_NODE1_DQ20")
	)
	(segment
		(start 46.81982 -43.897042)
		(end 45.34662 -43.897042)
		(width 0.2032)
		(layer "In7.Cu")
		(net "M1_DQ_NODE1_DQ20")
	)
	(segment
		(start 143.265906 -104.8258)
		(end 143.58874 -104.8258)
		(width 0.1016)
		(layer "F.Cu")
		(net "CLK_14M_CPU_NODE1")
	)
	(segment
		(start 64.18961 -82.714846)
		(end 64.439292 -82.714846)
		(width 0.1016)
		(layer "F.Cu")
		(net "CLK_14M_CPU_NODE1")
	)
	(segment
		(start 140.121132 -107.970574)
		(end 143.265906 -104.8258)
		(width 0.1016)
		(layer "F.Cu")
		(net "CLK_14M_CPU_NODE1")
	)
	(segment
		(start 139.68476 -107.970574)
		(end 140.121132 -107.970574)
		(width 0.1016)
		(layer "F.Cu")
		(net "CLK_14M_CPU_NODE1")
	)
	(segment
		(start 64.439292 -82.714846)
		(end 64.676274 -82.477864)
		(width 0.1016)
		(layer "F.Cu")
		(net "CLK_14M_CPU_NODE1")
	)
	(via
		(at 143.58874 -104.8258)
		(size 0.508)
		(drill 0.254)
		(layers "F.Cu" "B.Cu")
		(net "CLK_14M_CPU_NODE1")
	)
	(via
		(at 64.676274 -82.477864)
		(size 0.508)
		(drill 0.254)
		(layers "F.Cu" "B.Cu")
		(net "CLK_14M_CPU_NODE1")
	)
	(segment
		(start 93.67266 -78.276704)
		(end 91.613736 -76.21778)
		(width 0.1143)
		(layer "In7.Cu")
		(net "CLK_14M_CPU_NODE1")
	)
	(segment
		(start 87.757 -77.465428)
		(end 87.757 -77.835252)
		(width 0.1143)
		(layer "In7.Cu")
		(net "CLK_14M_CPU_NODE1")
	)
	(segment
		(start 84.871306 -78.90891)
		(end 79.021178 -78.90891)
		(width 0.1143)
		(layer "In7.Cu")
		(net "CLK_14M_CPU_NODE1")
	)
	(segment
		(start 79.021178 -78.90891)
		(end 78.046326 -79.883762)
		(width 0.1143)
		(layer "In7.Cu")
		(net "CLK_14M_CPU_NODE1")
	)
	(segment
		(start 96.059498 -78.276704)
		(end 93.67266 -78.276704)
		(width 0.1143)
		(layer "In7.Cu")
		(net "CLK_14M_CPU_NODE1")
	)
	(segment
		(start 109.685582 -85.21827)
		(end 103.001064 -85.21827)
		(width 0.1143)
		(layer "In7.Cu")
		(net "CLK_14M_CPU_NODE1")
	)
	(segment
		(start 126.217426 -101.750114)
		(end 109.685582 -85.21827)
		(width 0.1143)
		(layer "In7.Cu")
		(net "CLK_14M_CPU_NODE1")
	)
	(segment
		(start 85.336888 -78.443328)
		(end 84.871306 -78.90891)
		(width 0.1143)
		(layer "In7.Cu")
		(net "CLK_14M_CPU_NODE1")
	)
	(segment
		(start 87.757 -77.835252)
		(end 87.148924 -78.443328)
		(width 0.1143)
		(layer "In7.Cu")
		(net "CLK_14M_CPU_NODE1")
	)
	(segment
		(start 78.046326 -79.883762)
		(end 66.044064 -79.883762)
		(width 0.1143)
		(layer "In7.Cu")
		(net "CLK_14M_CPU_NODE1")
	)
	(segment
		(start 143.58874 -104.738932)
		(end 140.599922 -101.750114)
		(width 0.1143)
		(layer "In7.Cu")
		(net "CLK_14M_CPU_NODE1")
	)
	(segment
		(start 140.599922 -101.750114)
		(end 126.217426 -101.750114)
		(width 0.1143)
		(layer "In7.Cu")
		(net "CLK_14M_CPU_NODE1")
	)
	(segment
		(start 87.148924 -78.443328)
		(end 85.336888 -78.443328)
		(width 0.1143)
		(layer "In7.Cu")
		(net "CLK_14M_CPU_NODE1")
	)
	(segment
		(start 66.044064 -79.883762)
		(end 64.676274 -81.251552)
		(width 0.1143)
		(layer "In7.Cu")
		(net "CLK_14M_CPU_NODE1")
	)
	(segment
		(start 103.001064 -85.21827)
		(end 96.059498 -78.276704)
		(width 0.1143)
		(layer "In7.Cu")
		(net "CLK_14M_CPU_NODE1")
	)
	(segment
		(start 89.004648 -76.21778)
		(end 87.757 -77.465428)
		(width 0.1143)
		(layer "In7.Cu")
		(net "CLK_14M_CPU_NODE1")
	)
	(segment
		(start 91.613736 -76.21778)
		(end 89.004648 -76.21778)
		(width 0.1143)
		(layer "In7.Cu")
		(net "CLK_14M_CPU_NODE1")
	)
	(segment
		(start 143.58874 -104.8258)
		(end 143.58874 -104.738932)
		(width 0.1143)
		(layer "In7.Cu")
		(net "CLK_14M_CPU_NODE1")
	)
	(segment
		(start 64.676274 -81.251552)
		(end 64.676274 -82.477864)
		(width 0.1143)
		(layer "In7.Cu")
		(net "CLK_14M_CPU_NODE1")
	)
	(segment
		(start 172.676312 -123.858528)
		(end 171.20108 -123.858528)
		(width 0.1016)
		(layer "F.Cu")
		(net "FM_CPLD_NODE1_JTAG_POK_L")
	)
	(segment
		(start 170.024298 -125.03531)
		(end 167.92321 -125.03531)
		(width 0.1016)
		(layer "F.Cu")
		(net "FM_CPLD_NODE1_JTAG_POK_L")
	)
	(segment
		(start 173.010322 -123.524518)
		(end 172.676312 -123.858528)
		(width 0.1016)
		(layer "F.Cu")
		(net "FM_CPLD_NODE1_JTAG_POK_L")
	)
	(segment
		(start 173.010322 -123.365768)
		(end 173.010322 -123.524518)
		(width 0.1016)
		(layer "F.Cu")
		(net "FM_CPLD_NODE1_JTAG_POK_L")
	)
	(segment
		(start 167.92321 -125.03531)
		(end 167.771572 -125.186948)
		(width 0.1016)
		(layer "F.Cu")
		(net "FM_CPLD_NODE1_JTAG_POK_L")
	)
	(segment
		(start 167.467534 -124.88291)
		(end 167.771572 -125.186948)
		(width 0.1016)
		(layer "F.Cu")
		(net "FM_CPLD_NODE1_JTAG_POK_L")
	)
	(segment
		(start 171.20108 -123.858528)
		(end 170.024298 -125.03531)
		(width 0.1016)
		(layer "F.Cu")
		(net "FM_CPLD_NODE1_JTAG_POK_L")
	)
	(segment
		(start 167.13327 -124.88291)
		(end 167.467534 -124.88291)
		(width 0.1016)
		(layer "F.Cu")
		(net "FM_CPLD_NODE1_JTAG_POK_L")
	)
	(via
		(at 167.771572 -125.186948)
		(size 0.508)
		(drill 0.254)
		(layers "F.Cu" "B.Cu")
		(net "FM_CPLD_NODE1_JTAG_POK_L")
	)
	(segment
		(start 59.741816 -132.059426)
		(end 59.741816 -132.058918)
		(width 0.1016)
		(layer "F.Cu")
		(net "BMC_NODE1_DDR_MA1")
	)
	(segment
		(start 45.23232 -130.163824)
		(end 45.23359 -130.163824)
		(width 0.1016)
		(layer "F.Cu")
		(net "BMC_NODE1_DDR_MA1")
	)
	(segment
		(start 44.833032 -130.563112)
		(end 45.23232 -130.163824)
		(width 0.1016)
		(layer "F.Cu")
		(net "BMC_NODE1_DDR_MA1")
	)
	(segment
		(start 59.741816 -132.058918)
		(end 59.341004 -131.658106)
		(width 0.1016)
		(layer "F.Cu")
		(net "BMC_NODE1_DDR_MA1")
	)
	(segment
		(start 44.833032 -130.56362)
		(end 44.833032 -130.563112)
		(width 0.1016)
		(layer "F.Cu")
		(net "BMC_NODE1_DDR_MA1")
	)
	(via
		(at 59.341004 -131.658106)
		(size 0.49022)
		(drill 0.254)
		(layers "F.Cu" "B.Cu")
		(net "BMC_NODE1_DDR_MA1")
	)
	(via
		(at 45.23359 -130.163824)
		(size 0.508)
		(drill 0.254)
		(layers "F.Cu" "B.Cu")
		(net "BMC_NODE1_DDR_MA1")
	)
	(segment
		(start 45.378624 -130.308858)
		(end 45.23359 -130.163824)
		(width 0.1143)
		(layer "In2.Cu")
		(net "BMC_NODE1_DDR_MA1")
	)
	(segment
		(start 52.3113 -128.625092)
		(end 51.843432 -128.625092)
		(width 0.1143)
		(layer "In2.Cu")
		(net "BMC_NODE1_DDR_MA1")
	)
	(segment
		(start 58.943494 -132.055616)
		(end 57.01284 -132.055616)
		(width 0.1016)
		(layer "In2.Cu")
		(net "BMC_NODE1_DDR_MA1")
	)
	(segment
		(start 44.687998 -130.789426)
		(end 45.266102 -130.789426)
		(width 0.1143)
		(layer "In2.Cu")
		(net "BMC_NODE1_DDR_MA1")
	)
	(segment
		(start 44.525692 -130.62712)
		(end 44.687998 -130.789426)
		(width 0.1143)
		(layer "In2.Cu")
		(net "BMC_NODE1_DDR_MA1")
	)
	(segment
		(start 59.341004 -131.658106)
		(end 58.943494 -132.055616)
		(width 0.1016)
		(layer "In2.Cu")
		(net "BMC_NODE1_DDR_MA1")
	)
	(segment
		(start 45.378624 -130.676904)
		(end 45.378624 -130.308858)
		(width 0.1143)
		(layer "In2.Cu")
		(net "BMC_NODE1_DDR_MA1")
	)
	(segment
		(start 54.30774 -129.999994)
		(end 53.409596 -129.10185)
		(width 0.1143)
		(layer "In2.Cu")
		(net "BMC_NODE1_DDR_MA1")
	)
	(segment
		(start 51.843432 -128.625092)
		(end 51.442366 -128.224026)
		(width 0.1143)
		(layer "In2.Cu")
		(net "BMC_NODE1_DDR_MA1")
	)
	(segment
		(start 45.266102 -130.789426)
		(end 45.378624 -130.676904)
		(width 0.1143)
		(layer "In2.Cu")
		(net "BMC_NODE1_DDR_MA1")
	)
	(segment
		(start 57.01284 -132.055616)
		(end 54.957218 -129.999994)
		(width 0.1143)
		(layer "In2.Cu")
		(net "BMC_NODE1_DDR_MA1")
	)
	(segment
		(start 46.12386 -128.224026)
		(end 44.525692 -129.822194)
		(width 0.1143)
		(layer "In2.Cu")
		(net "BMC_NODE1_DDR_MA1")
	)
	(segment
		(start 52.788058 -129.10185)
		(end 52.3113 -128.625092)
		(width 0.1143)
		(layer "In2.Cu")
		(net "BMC_NODE1_DDR_MA1")
	)
	(segment
		(start 53.409596 -129.10185)
		(end 52.788058 -129.10185)
		(width 0.1143)
		(layer "In2.Cu")
		(net "BMC_NODE1_DDR_MA1")
	)
	(segment
		(start 54.957218 -129.999994)
		(end 54.30774 -129.999994)
		(width 0.1143)
		(layer "In2.Cu")
		(net "BMC_NODE1_DDR_MA1")
	)
	(segment
		(start 51.442366 -128.224026)
		(end 46.12386 -128.224026)
		(width 0.1143)
		(layer "In2.Cu")
		(net "BMC_NODE1_DDR_MA1")
	)
	(segment
		(start 44.525692 -129.822194)
		(end 44.525692 -130.62712)
		(width 0.1143)
		(layer "In2.Cu")
		(net "BMC_NODE1_DDR_MA1")
	)
	(segment
		(start 153.428192 -153.51125)
		(end 152.987756 -153.070814)
		(width 0.127)
		(layer "F.Cu")
		(net "P2E_CPU_NIC2_NODE1_TX_DP")
	)
	(segment
		(start 155.66898 -153.401522)
		(end 155.559252 -153.51125)
		(width 0.127)
		(layer "F.Cu")
		(net "P2E_CPU_NIC2_NODE1_TX_DP")
	)
	(segment
		(start 155.988004 -153.401522)
		(end 155.66898 -153.401522)
		(width 0.127)
		(layer "F.Cu")
		(net "P2E_CPU_NIC2_NODE1_TX_DP")
	)
	(segment
		(start 155.559252 -153.51125)
		(end 153.428192 -153.51125)
		(width 0.127)
		(layer "F.Cu")
		(net "P2E_CPU_NIC2_NODE1_TX_DP")
	)
	(segment
		(start 156.470096 -153.347166)
		(end 156.04236 -153.347166)
		(width 0.127)
		(layer "F.Cu")
		(net "P2E_CPU_NIC2_NODE1_TX_DP")
	)
	(segment
		(start 156.04236 -153.347166)
		(end 155.988004 -153.401522)
		(width 0.127)
		(layer "F.Cu")
		(net "P2E_CPU_NIC2_NODE1_TX_DP")
	)
	(via
		(at 32.75584 -72.058784)
		(size 0.508)
		(drill 0.254)
		(layers "F.Cu" "B.Cu")
		(net "P2E_CPU_NIC2_NODE1_TX_DP")
	)
	(via
		(at 152.987756 -153.070814)
		(size 0.508)
		(drill 0.254)
		(layers "F.Cu" "B.Cu")
		(net "P2E_CPU_NIC2_NODE1_TX_DP")
	)
	(segment
		(start 32.296608 -72.058784)
		(end 32.75584 -72.058784)
		(width 0.127)
		(layer "B.Cu")
		(net "P2E_CPU_NIC2_NODE1_TX_DP")
	)
	(segment
		(start 32.12084 -69.114162)
		(end 32.24784 -69.241162)
		(width 0.127)
		(layer "B.Cu")
		(net "P2E_CPU_NIC2_NODE1_TX_DP")
	)
	(segment
		(start 35.447224 -67.576192)
		(end 35.028124 -67.157092)
		(width 0.127)
		(layer "B.Cu")
		(net "P2E_CPU_NIC2_NODE1_TX_DP")
	)
	(segment
		(start 32.24784 -69.622162)
		(end 32.12084 -69.749162)
		(width 0.127)
		(layer "B.Cu")
		(net "P2E_CPU_NIC2_NODE1_TX_DP")
	)
	(segment
		(start 33.429448 -67.157092)
		(end 32.12084 -68.4657)
		(width 0.127)
		(layer "B.Cu")
		(net "P2E_CPU_NIC2_NODE1_TX_DP")
	)
	(segment
		(start 32.24784 -70.257162)
		(end 32.24784 -70.638162)
		(width 0.127)
		(layer "B.Cu")
		(net "P2E_CPU_NIC2_NODE1_TX_DP")
	)
	(segment
		(start 32.12084 -69.749162)
		(end 32.12084 -70.130162)
		(width 0.127)
		(layer "B.Cu")
		(net "P2E_CPU_NIC2_NODE1_TX_DP")
	)
	(segment
		(start 32.24784 -69.241162)
		(end 32.24784 -69.622162)
		(width 0.127)
		(layer "B.Cu")
		(net "P2E_CPU_NIC2_NODE1_TX_DP")
	)
	(segment
		(start 32.12084 -70.130162)
		(end 32.24784 -70.257162)
		(width 0.127)
		(layer "B.Cu")
		(net "P2E_CPU_NIC2_NODE1_TX_DP")
	)
	(segment
		(start 32.12084 -70.765162)
		(end 32.12084 -71.883016)
		(width 0.127)
		(layer "B.Cu")
		(net "P2E_CPU_NIC2_NODE1_TX_DP")
	)
	(segment
		(start 35.028124 -67.157092)
		(end 33.429448 -67.157092)
		(width 0.127)
		(layer "B.Cu")
		(net "P2E_CPU_NIC2_NODE1_TX_DP")
	)
	(segment
		(start 32.12084 -71.883016)
		(end 32.296608 -72.058784)
		(width 0.127)
		(layer "B.Cu")
		(net "P2E_CPU_NIC2_NODE1_TX_DP")
	)
	(segment
		(start 32.12084 -68.4657)
		(end 32.12084 -69.114162)
		(width 0.127)
		(layer "B.Cu")
		(net "P2E_CPU_NIC2_NODE1_TX_DP")
	)
	(segment
		(start 32.24784 -70.638162)
		(end 32.12084 -70.765162)
		(width 0.127)
		(layer "B.Cu")
		(net "P2E_CPU_NIC2_NODE1_TX_DP")
	)
	(segment
		(start 155.421076 -147.8915)
		(end 155.666694 -147.599908)
		(width 0.127)
		(layer "In7.Cu")
		(net "P2E_CPU_NIC2_NODE1_TX_DP")
	)
	(segment
		(start 156.002736 -146.516598)
		(end 156.144976 -146.393154)
		(width 0.127)
		(layer "In7.Cu")
		(net "P2E_CPU_NIC2_NODE1_TX_DP")
	)
	(segment
		(start 155.224226 -147.90801)
		(end 155.421076 -147.8915)
		(width 0.127)
		(layer "In7.Cu")
		(net "P2E_CPU_NIC2_NODE1_TX_DP")
	)
	(segment
		(start 72.950832 -115.544092)
		(end 67.979798 -114.869722)
		(width 0.127)
		(layer "In7.Cu")
		(net "P2E_CPU_NIC2_NODE1_TX_DP")
	)
	(segment
		(start 31.858712 -75.869038)
		(end 32.052768 -73.985374)
		(width 0.127)
		(layer "In7.Cu")
		(net "P2E_CPU_NIC2_NODE1_TX_DP")
	)
	(segment
		(start 152.13584 -153.3144)
		(end 152.15616 -152.7302)
		(width 0.127)
		(layer "In7.Cu")
		(net "P2E_CPU_NIC2_NODE1_TX_DP")
	)
	(segment
		(start 100.934774 -108.97743)
		(end 98.84918 -109.559598)
		(width 0.127)
		(layer "In7.Cu")
		(net "P2E_CPU_NIC2_NODE1_TX_DP")
	)
	(segment
		(start 129.46888 -131.011676)
		(end 127.101854 -129.22504)
		(width 0.127)
		(layer "In7.Cu")
		(net "P2E_CPU_NIC2_NODE1_TX_DP")
	)
	(segment
		(start 65.60693 -115.020344)
		(end 62.170056 -113.84788)
		(width 0.127)
		(layer "In7.Cu")
		(net "P2E_CPU_NIC2_NODE1_TX_DP")
	)
	(segment
		(start 153.113994 -152.242012)
		(end 153.478992 -152.130506)
		(width 0.127)
		(layer "In7.Cu")
		(net "P2E_CPU_NIC2_NODE1_TX_DP")
	)
	(segment
		(start 154.695652 -151.23414)
		(end 154.818842 -150.214076)
		(width 0.127)
		(layer "In7.Cu")
		(net "P2E_CPU_NIC2_NODE1_TX_DP")
	)
	(segment
		(start 126.4031 -127.773176)
		(end 126.727204 -122.34545)
		(width 0.127)
		(layer "In7.Cu")
		(net "P2E_CPU_NIC2_NODE1_TX_DP")
	)
	(segment
		(start 50.39741 -115.490752)
		(end 48.495712 -117.29847)
		(width 0.127)
		(layer "In7.Cu")
		(net "P2E_CPU_NIC2_NODE1_TX_DP")
	)
	(segment
		(start 155.966414 -147.027138)
		(end 156.002736 -146.516598)
		(width 0.127)
		(layer "In7.Cu")
		(net "P2E_CPU_NIC2_NODE1_TX_DP")
	)
	(segment
		(start 154.355546 -151.72563)
		(end 154.554428 -151.437848)
		(width 0.127)
		(layer "In7.Cu")
		(net "P2E_CPU_NIC2_NODE1_TX_DP")
	)
	(segment
		(start 156.244798 -144.987264)
		(end 156.120846 -144.845532)
		(width 0.127)
		(layer "In7.Cu")
		(net "P2E_CPU_NIC2_NODE1_TX_DP")
	)
	(segment
		(start 38.50767 -102.0699)
		(end 34.198814 -97.593912)
		(width 0.127)
		(layer "In7.Cu")
		(net "P2E_CPU_NIC2_NODE1_TX_DP")
	)
	(segment
		(start 46.00448 -117.614446)
		(end 43.06062 -117.206268)
		(width 0.127)
		(layer "In7.Cu")
		(net "P2E_CPU_NIC2_NODE1_TX_DP")
	)
	(segment
		(start 32.052768 -73.985374)
		(end 32.264858 -72.592946)
		(width 0.127)
		(layer "In7.Cu")
		(net "P2E_CPU_NIC2_NODE1_TX_DP")
	)
	(segment
		(start 40.060626 -113.715038)
		(end 39.885112 -113.511838)
		(width 0.127)
		(layer "In7.Cu")
		(net "P2E_CPU_NIC2_NODE1_TX_DP")
	)
	(segment
		(start 67.979798 -114.869722)
		(end 65.60693 -115.020344)
		(width 0.127)
		(layer "In7.Cu")
		(net "P2E_CPU_NIC2_NODE1_TX_DP")
	)
	(segment
		(start 156.21762 -145.367502)
		(end 156.244798 -144.987264)
		(width 0.127)
		(layer "In7.Cu")
		(net "P2E_CPU_NIC2_NODE1_TX_DP")
	)
	(segment
		(start 127.101854 -129.22504)
		(end 126.4031 -127.773176)
		(width 0.127)
		(layer "In7.Cu")
		(net "P2E_CPU_NIC2_NODE1_TX_DP")
	)
	(segment
		(start 34.198814 -97.593912)
		(end 33.53943 -95.754952)
		(width 0.127)
		(layer "In7.Cu")
		(net "P2E_CPU_NIC2_NODE1_TX_DP")
	)
	(segment
		(start 40.260778 -113.891822)
		(end 40.060626 -113.715038)
		(width 0.127)
		(layer "In7.Cu")
		(net "P2E_CPU_NIC2_NODE1_TX_DP")
	)
	(segment
		(start 31.86303 -86.143084)
		(end 32.008826 -77.178408)
		(width 0.127)
		(layer "In7.Cu")
		(net "P2E_CPU_NIC2_NODE1_TX_DP")
	)
	(segment
		(start 32.26816 -72.546464)
		(end 32.75584 -72.058784)
		(width 0.127)
		(layer "In7.Cu")
		(net "P2E_CPU_NIC2_NODE1_TX_DP")
	)
	(segment
		(start 156.172662 -144.108424)
		(end 155.968954 -140.202412)
		(width 0.127)
		(layer "In7.Cu")
		(net "P2E_CPU_NIC2_NODE1_TX_DP")
	)
	(segment
		(start 56.798464 -114.674142)
		(end 52.808632 -114.508788)
		(width 0.127)
		(layer "In7.Cu")
		(net "P2E_CPU_NIC2_NODE1_TX_DP")
	)
	(segment
		(start 156.172154 -146.012916)
		(end 156.048202 -145.871184)
		(width 0.127)
		(layer "In7.Cu")
		(net "P2E_CPU_NIC2_NODE1_TX_DP")
	)
	(segment
		(start 32.008826 -77.178408)
		(end 31.858712 -75.869038)
		(width 0.127)
		(layer "In7.Cu")
		(net "P2E_CPU_NIC2_NODE1_TX_DP")
	)
	(segment
		(start 124.747782 -118.80596)
		(end 124.645674 -117.740684)
		(width 0.127)
		(layer "In7.Cu")
		(net "P2E_CPU_NIC2_NODE1_TX_DP")
	)
	(segment
		(start 98.84918 -109.559598)
		(end 96.80194 -110.270798)
		(width 0.127)
		(layer "In7.Cu")
		(net "P2E_CPU_NIC2_NODE1_TX_DP")
	)
	(segment
		(start 151.735536 -137.533634)
		(end 147.514818 -132.67182)
		(width 0.127)
		(layer "In7.Cu")
		(net "P2E_CPU_NIC2_NODE1_TX_DP")
	)
	(segment
		(start 101.019102 -108.967016)
		(end 100.934774 -108.97743)
		(width 0.127)
		(layer "In7.Cu")
		(net "P2E_CPU_NIC2_NODE1_TX_DP")
	)
	(segment
		(start 115.14201 -108.82376)
		(end 115.123976 -108.824522)
		(width 0.127)
		(layer "In7.Cu")
		(net "P2E_CPU_NIC2_NODE1_TX_DP")
	)
	(segment
		(start 126.727204 -122.34545)
		(end 125.100842 -120.818402)
		(width 0.127)
		(layer "In7.Cu")
		(net "P2E_CPU_NIC2_NODE1_TX_DP")
	)
	(segment
		(start 39.885112 -113.511838)
		(end 38.94328 -112.396524)
		(width 0.127)
		(layer "In7.Cu")
		(net "P2E_CPU_NIC2_NODE1_TX_DP")
	)
	(segment
		(start 43.06062 -117.206268)
		(end 42.114978 -116.315998)
		(width 0.127)
		(layer "In7.Cu")
		(net "P2E_CPU_NIC2_NODE1_TX_DP")
	)
	(segment
		(start 152.15616 -152.7302)
		(end 152.404318 -152.319736)
		(width 0.127)
		(layer "In7.Cu")
		(net "P2E_CPU_NIC2_NODE1_TX_DP")
	)
	(segment
		(start 120.843802 -110.396528)
		(end 119.268494 -109.40415)
		(width 0.127)
		(layer "In7.Cu")
		(net "P2E_CPU_NIC2_NODE1_TX_DP")
	)
	(segment
		(start 153.566622 -151.965914)
		(end 154.355546 -151.72563)
		(width 0.127)
		(layer "In7.Cu")
		(net "P2E_CPU_NIC2_NODE1_TX_DP")
	)
	(segment
		(start 117.605302 -109.047534)
		(end 115.14201 -108.82376)
		(width 0.127)
		(layer "In7.Cu")
		(net "P2E_CPU_NIC2_NODE1_TX_DP")
	)
	(segment
		(start 125.100842 -120.818402)
		(end 124.7902 -119.432324)
		(width 0.127)
		(layer "In7.Cu")
		(net "P2E_CPU_NIC2_NODE1_TX_DP")
	)
	(segment
		(start 124.7902 -119.432324)
		(end 124.747782 -118.80596)
		(width 0.127)
		(layer "In7.Cu")
		(net "P2E_CPU_NIC2_NODE1_TX_DP")
	)
	(segment
		(start 108.63199 -109.112812)
		(end 101.019102 -108.967016)
		(width 0.127)
		(layer "In7.Cu")
		(net "P2E_CPU_NIC2_NODE1_TX_DP")
	)
	(segment
		(start 154.778964 -149.040596)
		(end 155.03398 -148.133816)
		(width 0.127)
		(layer "In7.Cu")
		(net "P2E_CPU_NIC2_NODE1_TX_DP")
	)
	(segment
		(start 122.66676 -113.486438)
		(end 120.843802 -110.396528)
		(width 0.127)
		(layer "In7.Cu")
		(net "P2E_CPU_NIC2_NODE1_TX_DP")
	)
	(segment
		(start 124.267214 -116.6876)
		(end 122.66676 -113.486438)
		(width 0.127)
		(layer "In7.Cu")
		(net "P2E_CPU_NIC2_NODE1_TX_DP")
	)
	(segment
		(start 90.45448 -110.886494)
		(end 86.312502 -110.8329)
		(width 0.127)
		(layer "In7.Cu")
		(net "P2E_CPU_NIC2_NODE1_TX_DP")
	)
	(segment
		(start 155.03398 -148.133816)
		(end 155.224226 -147.90801)
		(width 0.127)
		(layer "In7.Cu")
		(net "P2E_CPU_NIC2_NODE1_TX_DP")
	)
	(segment
		(start 33.53943 -95.754952)
		(end 31.86303 -86.143084)
		(width 0.127)
		(layer "In7.Cu")
		(net "P2E_CPU_NIC2_NODE1_TX_DP")
	)
	(segment
		(start 152.949656 -152.15362)
		(end 153.113994 -152.242012)
		(width 0.127)
		(layer "In7.Cu")
		(net "P2E_CPU_NIC2_NODE1_TX_DP")
	)
	(segment
		(start 143.04899 -131.793996)
		(end 138.295126 -131.74472)
		(width 0.127)
		(layer "In7.Cu")
		(net "P2E_CPU_NIC2_NODE1_TX_DP")
	)
	(segment
		(start 86.312502 -110.8329)
		(end 85.893656 -110.852712)
		(width 0.127)
		(layer "In7.Cu")
		(net "P2E_CPU_NIC2_NODE1_TX_DP")
	)
	(segment
		(start 52.808632 -114.508788)
		(end 50.39741 -115.490752)
		(width 0.127)
		(layer "In7.Cu")
		(net "P2E_CPU_NIC2_NODE1_TX_DP")
	)
	(segment
		(start 152.404318 -152.319736)
		(end 152.949656 -152.15362)
		(width 0.127)
		(layer "In7.Cu")
		(net "P2E_CPU_NIC2_NODE1_TX_DP")
	)
	(segment
		(start 156.048202 -145.871184)
		(end 156.07538 -145.490946)
		(width 0.127)
		(layer "In7.Cu")
		(net "P2E_CPU_NIC2_NODE1_TX_DP")
	)
	(segment
		(start 130.691128 -131.42468)
		(end 129.46888 -131.011676)
		(width 0.127)
		(layer "In7.Cu")
		(net "P2E_CPU_NIC2_NODE1_TX_DP")
	)
	(segment
		(start 156.144976 -146.393154)
		(end 156.172154 -146.012916)
		(width 0.127)
		(layer "In7.Cu")
		(net "P2E_CPU_NIC2_NODE1_TX_DP")
	)
	(segment
		(start 152.987756 -153.070814)
		(end 152.498806 -153.559764)
		(width 0.127)
		(layer "In7.Cu")
		(net "P2E_CPU_NIC2_NODE1_TX_DP")
	)
	(segment
		(start 83.46567 -111.591852)
		(end 82.260694 -112.989614)
		(width 0.127)
		(layer "In7.Cu")
		(net "P2E_CPU_NIC2_NODE1_TX_DP")
	)
	(segment
		(start 155.42133 -139.434316)
		(end 151.735536 -137.533634)
		(width 0.127)
		(layer "In7.Cu")
		(net "P2E_CPU_NIC2_NODE1_TX_DP")
	)
	(segment
		(start 138.295126 -131.74472)
		(end 133.77799 -131.168648)
		(width 0.127)
		(layer "In7.Cu")
		(net "P2E_CPU_NIC2_NODE1_TX_DP")
	)
	(segment
		(start 85.893656 -110.852712)
		(end 85.88883 -110.852712)
		(width 0.127)
		(layer "In7.Cu")
		(net "P2E_CPU_NIC2_NODE1_TX_DP")
	)
	(segment
		(start 152.498806 -153.559764)
		(end 152.371806 -153.559764)
		(width 0.127)
		(layer "In7.Cu")
		(net "P2E_CPU_NIC2_NODE1_TX_DP")
	)
	(segment
		(start 32.264858 -72.592946)
		(end 32.26816 -72.546464)
		(width 0.127)
		(layer "In7.Cu")
		(net "P2E_CPU_NIC2_NODE1_TX_DP")
	)
	(segment
		(start 82.260694 -112.989614)
		(end 78.862936 -114.64417)
		(width 0.127)
		(layer "In7.Cu")
		(net "P2E_CPU_NIC2_NODE1_TX_DP")
	)
	(segment
		(start 40.479726 -114.08537)
		(end 40.260778 -113.891822)
		(width 0.127)
		(layer "In7.Cu")
		(net "P2E_CPU_NIC2_NODE1_TX_DP")
	)
	(segment
		(start 95.137986 -110.203996)
		(end 90.45448 -110.886494)
		(width 0.127)
		(layer "In7.Cu")
		(net "P2E_CPU_NIC2_NODE1_TX_DP")
	)
	(segment
		(start 133.77799 -131.168648)
		(end 130.691128 -131.42468)
		(width 0.127)
		(layer "In7.Cu")
		(net "P2E_CPU_NIC2_NODE1_TX_DP")
	)
	(segment
		(start 115.122198 -108.824522)
		(end 108.63199 -109.112812)
		(width 0.127)
		(layer "In7.Cu")
		(net "P2E_CPU_NIC2_NODE1_TX_DP")
	)
	(segment
		(start 124.645674 -117.740684)
		(end 124.267214 -116.6876)
		(width 0.127)
		(layer "In7.Cu")
		(net "P2E_CPU_NIC2_NODE1_TX_DP")
	)
	(segment
		(start 156.07538 -145.490946)
		(end 156.21762 -145.367502)
		(width 0.127)
		(layer "In7.Cu")
		(net "P2E_CPU_NIC2_NODE1_TX_DP")
	)
	(segment
		(start 154.554428 -151.437848)
		(end 154.695652 -151.23414)
		(width 0.127)
		(layer "In7.Cu")
		(net "P2E_CPU_NIC2_NODE1_TX_DP")
	)
	(segment
		(start 119.268494 -109.40415)
		(end 117.665246 -109.047534)
		(width 0.127)
		(layer "In7.Cu")
		(net "P2E_CPU_NIC2_NODE1_TX_DP")
	)
	(segment
		(start 147.514818 -132.67182)
		(end 145.67535 -131.821428)
		(width 0.127)
		(layer "In7.Cu")
		(net "P2E_CPU_NIC2_NODE1_TX_DP")
	)
	(segment
		(start 117.665246 -109.047534)
		(end 117.605302 -109.047534)
		(width 0.127)
		(layer "In7.Cu")
		(net "P2E_CPU_NIC2_NODE1_TX_DP")
	)
	(segment
		(start 152.371806 -153.559764)
		(end 152.13584 -153.3144)
		(width 0.127)
		(layer "In7.Cu")
		(net "P2E_CPU_NIC2_NODE1_TX_DP")
	)
	(segment
		(start 145.612104 -131.820412)
		(end 143.04899 -131.793996)
		(width 0.127)
		(layer "In7.Cu")
		(net "P2E_CPU_NIC2_NODE1_TX_DP")
	)
	(segment
		(start 154.818842 -150.214076)
		(end 154.778964 -149.040596)
		(width 0.127)
		(layer "In7.Cu")
		(net "P2E_CPU_NIC2_NODE1_TX_DP")
	)
	(segment
		(start 115.123976 -108.824522)
		(end 115.122198 -108.824522)
		(width 0.127)
		(layer "In7.Cu")
		(net "P2E_CPU_NIC2_NODE1_TX_DP")
	)
	(segment
		(start 42.114978 -116.315998)
		(end 40.479726 -114.08537)
		(width 0.127)
		(layer "In7.Cu")
		(net "P2E_CPU_NIC2_NODE1_TX_DP")
	)
	(segment
		(start 38.94328 -112.396524)
		(end 38.50767 -102.0699)
		(width 0.127)
		(layer "In7.Cu")
		(net "P2E_CPU_NIC2_NODE1_TX_DP")
	)
	(segment
		(start 155.666694 -147.599908)
		(end 155.649676 -147.403058)
		(width 0.127)
		(layer "In7.Cu")
		(net "P2E_CPU_NIC2_NODE1_TX_DP")
	)
	(segment
		(start 153.478992 -152.130506)
		(end 153.566622 -151.965914)
		(width 0.127)
		(layer "In7.Cu")
		(net "P2E_CPU_NIC2_NODE1_TX_DP")
	)
	(segment
		(start 96.80194 -110.270798)
		(end 95.137986 -110.203996)
		(width 0.127)
		(layer "In7.Cu")
		(net "P2E_CPU_NIC2_NODE1_TX_DP")
	)
	(segment
		(start 62.170056 -113.84788)
		(end 56.798464 -114.674142)
		(width 0.127)
		(layer "In7.Cu")
		(net "P2E_CPU_NIC2_NODE1_TX_DP")
	)
	(segment
		(start 85.88375 -110.84814)
		(end 83.46567 -111.591852)
		(width 0.127)
		(layer "In7.Cu")
		(net "P2E_CPU_NIC2_NODE1_TX_DP")
	)
	(segment
		(start 145.67535 -131.821428)
		(end 145.612358 -131.820666)
		(width 0.127)
		(layer "In7.Cu")
		(net "P2E_CPU_NIC2_NODE1_TX_DP")
	)
	(segment
		(start 155.649676 -147.403058)
		(end 155.966414 -147.027138)
		(width 0.127)
		(layer "In7.Cu")
		(net "P2E_CPU_NIC2_NODE1_TX_DP")
	)
	(segment
		(start 48.495712 -117.29847)
		(end 46.00448 -117.614446)
		(width 0.127)
		(layer "In7.Cu")
		(net "P2E_CPU_NIC2_NODE1_TX_DP")
	)
	(segment
		(start 155.968954 -140.202412)
		(end 155.42133 -139.434316)
		(width 0.127)
		(layer "In7.Cu")
		(net "P2E_CPU_NIC2_NODE1_TX_DP")
	)
	(segment
		(start 78.862936 -114.64417)
		(end 72.950832 -115.544092)
		(width 0.127)
		(layer "In7.Cu")
		(net "P2E_CPU_NIC2_NODE1_TX_DP")
	)
	(segment
		(start 145.612358 -131.820666)
		(end 145.612104 -131.820412)
		(width 0.127)
		(layer "In7.Cu")
		(net "P2E_CPU_NIC2_NODE1_TX_DP")
	)
	(segment
		(start 85.88883 -110.852712)
		(end 85.88375 -110.84814)
		(width 0.127)
		(layer "In7.Cu")
		(net "P2E_CPU_NIC2_NODE1_TX_DP")
	)
	(segment
		(start 156.120846 -144.845532)
		(end 156.172662 -144.108424)
		(width 0.127)
		(layer "In7.Cu")
		(net "P2E_CPU_NIC2_NODE1_TX_DP")
	)
	(segment
		(start 53.945536 -60.688474)
		(end 53.83149 -60.574428)
		(width 0.09906)
		(layer "F.Cu")
		(net "M_DDR3_NODE1_DQS3P")
	)
	(segment
		(start 54.29504 -63.05931)
		(end 54.15661 -63.05931)
		(width 0.09906)
		(layer "F.Cu")
		(net "M_DDR3_NODE1_DQS3P")
	)
	(segment
		(start 58.4962 -30.781498)
		(end 58.728102 -31.0134)
		(width 0.1651)
		(layer "F.Cu")
		(net "M_DDR3_NODE1_DQS3P")
	)
	(segment
		(start 58.650124 -29.149802)
		(end 58.650124 -30.350968)
		(width 0.1651)
		(layer "F.Cu")
		(net "M_DDR3_NODE1_DQS3P")
	)
	(segment
		(start 53.83149 -60.574428)
		(end 53.83149 -60.29579)
		(width 0.09906)
		(layer "F.Cu")
		(net "M_DDR3_NODE1_DQS3P")
	)
	(segment
		(start 58.4962 -30.504892)
		(end 58.4962 -30.781498)
		(width 0.1651)
		(layer "F.Cu")
		(net "M_DDR3_NODE1_DQS3P")
	)
	(segment
		(start 54.260242 -60.688474)
		(end 53.945536 -60.688474)
		(width 0.09906)
		(layer "F.Cu")
		(net "M_DDR3_NODE1_DQS3P")
	)
	(segment
		(start 58.650124 -30.350968)
		(end 58.4962 -30.504892)
		(width 0.1651)
		(layer "F.Cu")
		(net "M_DDR3_NODE1_DQS3P")
	)
	(segment
		(start 54.486048 -60.91428)
		(end 54.260242 -60.688474)
		(width 0.09906)
		(layer "F.Cu")
		(net "M_DDR3_NODE1_DQS3P")
	)
	(segment
		(start 54.15661 -63.05931)
		(end 54.083458 -62.986158)
		(width 0.09906)
		(layer "F.Cu")
		(net "M_DDR3_NODE1_DQS3P")
	)
	(segment
		(start 54.360572 -62.993778)
		(end 54.29504 -63.05931)
		(width 0.09906)
		(layer "F.Cu")
		(net "M_DDR3_NODE1_DQS3P")
	)
	(segment
		(start 54.486048 -62.396878)
		(end 54.486048 -60.91428)
		(width 0.09906)
		(layer "F.Cu")
		(net "M_DDR3_NODE1_DQS3P")
	)
	(segment
		(start 54.083458 -62.799468)
		(end 54.486048 -62.396878)
		(width 0.09906)
		(layer "F.Cu")
		(net "M_DDR3_NODE1_DQS3P")
	)
	(segment
		(start 54.083458 -62.986158)
		(end 54.083458 -62.799468)
		(width 0.09906)
		(layer "F.Cu")
		(net "M_DDR3_NODE1_DQS3P")
	)
	(segment
		(start 58.728102 -31.464758)
		(end 59.217052 -31.953708)
		(width 0.1651)
		(layer "F.Cu")
		(net "M_DDR3_NODE1_DQS3P")
	)
	(segment
		(start 58.728102 -31.0134)
		(end 58.728102 -31.464758)
		(width 0.1651)
		(layer "F.Cu")
		(net "M_DDR3_NODE1_DQS3P")
	)
	(via
		(at 53.83149 -60.29579)
		(size 0.508)
		(drill 0.254)
		(layers "F.Cu" "B.Cu")
		(net "M_DDR3_NODE1_DQS3P")
	)
	(via
		(at 59.217052 -31.953708)
		(size 0.508)
		(drill 0.254)
		(layers "F.Cu" "B.Cu")
		(net "M_DDR3_NODE1_DQS3P")
	)
	(segment
		(start 51.45532 -47.597314)
		(end 51.56962 -47.711614)
		(width 0.2032)
		(layer "In2.Cu")
		(net "M_DDR3_NODE1_DQS3P")
	)
	(segment
		(start 49.37252 -48.10379)
		(end 49.581054 -48.312324)
		(width 0.2032)
		(layer "In2.Cu")
		(net "M_DDR3_NODE1_DQS3P")
	)
	(segment
		(start 51.45532 -48.229774)
		(end 51.45532 -48.816514)
		(width 0.2032)
		(layer "In2.Cu")
		(net "M_DDR3_NODE1_DQS3P")
	)
	(segment
		(start 49.581054 -48.312324)
		(end 49.875186 -48.312324)
		(width 0.2032)
		(layer "In2.Cu")
		(net "M_DDR3_NODE1_DQS3P")
	)
	(segment
		(start 52.25923 -52.86502)
		(end 49.55286 -50.15865)
		(width 0.2032)
		(layer "In2.Cu")
		(net "M_DDR3_NODE1_DQS3P")
	)
	(segment
		(start 49.37252 -42.51198)
		(end 49.37252 -48.10379)
		(width 0.2032)
		(layer "In2.Cu")
		(net "M_DDR3_NODE1_DQS3P")
	)
	(segment
		(start 49.049178 -50.367438)
		(end 49.049178 -50.661824)
		(width 0.2032)
		(layer "In2.Cu")
		(net "M_DDR3_NODE1_DQS3P")
	)
	(segment
		(start 51.053746 -43.249596)
		(end 51.45532 -43.65117)
		(width 0.2032)
		(layer "In2.Cu")
		(net "M_DDR3_NODE1_DQS3P")
	)
	(segment
		(start 50.485294 -43.249596)
		(end 51.053746 -43.249596)
		(width 0.2032)
		(layer "In2.Cu")
		(net "M_DDR3_NODE1_DQS3P")
	)
	(segment
		(start 51.45532 -50.121058)
		(end 53.229256 -51.894994)
		(width 0.2032)
		(layer "In2.Cu")
		(net "M_DDR3_NODE1_DQS3P")
	)
	(segment
		(start 51.45532 -49.448974)
		(end 51.45532 -50.121058)
		(width 0.2032)
		(layer "In2.Cu")
		(net "M_DDR3_NODE1_DQS3P")
	)
	(segment
		(start 49.55286 -50.15865)
		(end 49.25822 -50.15865)
		(width 0.2032)
		(layer "In2.Cu")
		(net "M_DDR3_NODE1_DQS3P")
	)
	(segment
		(start 51.45532 -48.816514)
		(end 51.56962 -48.930814)
		(width 0.2032)
		(layer "In2.Cu")
		(net "M_DDR3_NODE1_DQS3P")
	)
	(segment
		(start 59.217052 -31.953708)
		(end 58.76798 -32.40278)
		(width 0.2032)
		(layer "In2.Cu")
		(net "M_DDR3_NODE1_DQS3P")
	)
	(segment
		(start 53.274214 -60.62599)
		(end 53.50129 -60.62599)
		(width 0.09906)
		(layer "In2.Cu")
		(net "M_DDR3_NODE1_DQS3P")
	)
	(segment
		(start 51.56962 -49.334674)
		(end 51.45532 -49.448974)
		(width 0.2032)
		(layer "In2.Cu")
		(net "M_DDR3_NODE1_DQS3P")
	)
	(segment
		(start 49.25822 -50.15865)
		(end 49.049178 -50.367438)
		(width 0.2032)
		(layer "In2.Cu")
		(net "M_DDR3_NODE1_DQS3P")
	)
	(segment
		(start 49.049178 -50.661824)
		(end 53.22316 -54.835806)
		(width 0.2032)
		(layer "In2.Cu")
		(net "M_DDR3_NODE1_DQS3P")
	)
	(segment
		(start 53.229256 -51.894994)
		(end 53.229256 -52.463446)
		(width 0.2032)
		(layer "In2.Cu")
		(net "M_DDR3_NODE1_DQS3P")
	)
	(segment
		(start 58.76798 -32.40278)
		(end 58.76798 -33.11652)
		(width 0.2032)
		(layer "In2.Cu")
		(net "M_DDR3_NODE1_DQS3P")
	)
	(segment
		(start 51.45532 -43.65117)
		(end 51.45532 -47.597314)
		(width 0.2032)
		(layer "In2.Cu")
		(net "M_DDR3_NODE1_DQS3P")
	)
	(segment
		(start 53.22316 -56.844184)
		(end 53.22316 -56.870092)
		(width 0.09906)
		(layer "In2.Cu")
		(net "M_DDR3_NODE1_DQS3P")
	)
	(segment
		(start 51.56962 -47.711614)
		(end 51.56962 -48.115474)
		(width 0.2032)
		(layer "In2.Cu")
		(net "M_DDR3_NODE1_DQS3P")
	)
	(segment
		(start 52.9209 -57.899046)
		(end 52.9209 -60.272676)
		(width 0.09906)
		(layer "In2.Cu")
		(net "M_DDR3_NODE1_DQS3P")
	)
	(segment
		(start 49.875186 -48.312324)
		(end 50.08372 -48.10379)
		(width 0.2032)
		(layer "In2.Cu")
		(net "M_DDR3_NODE1_DQS3P")
	)
	(segment
		(start 52.827682 -52.86502)
		(end 52.25923 -52.86502)
		(width 0.2032)
		(layer "In2.Cu")
		(net "M_DDR3_NODE1_DQS3P")
	)
	(segment
		(start 53.15966 -57.660286)
		(end 52.9209 -57.899046)
		(width 0.09906)
		(layer "In2.Cu")
		(net "M_DDR3_NODE1_DQS3P")
	)
	(segment
		(start 53.22316 -54.835806)
		(end 53.22316 -56.844184)
		(width 0.2032)
		(layer "In2.Cu")
		(net "M_DDR3_NODE1_DQS3P")
	)
	(segment
		(start 50.08372 -43.65117)
		(end 50.485294 -43.249596)
		(width 0.2032)
		(layer "In2.Cu")
		(net "M_DDR3_NODE1_DQS3P")
	)
	(segment
		(start 53.15966 -56.933592)
		(end 53.15966 -57.660286)
		(width 0.09906)
		(layer "In2.Cu")
		(net "M_DDR3_NODE1_DQS3P")
	)
	(segment
		(start 58.76798 -33.11652)
		(end 49.37252 -42.51198)
		(width 0.2032)
		(layer "In2.Cu")
		(net "M_DDR3_NODE1_DQS3P")
	)
	(segment
		(start 52.9209 -60.272676)
		(end 53.274214 -60.62599)
		(width 0.09906)
		(layer "In2.Cu")
		(net "M_DDR3_NODE1_DQS3P")
	)
	(segment
		(start 50.08372 -48.10379)
		(end 50.08372 -43.65117)
		(width 0.2032)
		(layer "In2.Cu")
		(net "M_DDR3_NODE1_DQS3P")
	)
	(segment
		(start 51.56962 -48.930814)
		(end 51.56962 -49.334674)
		(width 0.2032)
		(layer "In2.Cu")
		(net "M_DDR3_NODE1_DQS3P")
	)
	(segment
		(start 53.50129 -60.62599)
		(end 53.83149 -60.29579)
		(width 0.09906)
		(layer "In2.Cu")
		(net "M_DDR3_NODE1_DQS3P")
	)
	(segment
		(start 53.22316 -56.870092)
		(end 53.15966 -56.933592)
		(width 0.09906)
		(layer "In2.Cu")
		(net "M_DDR3_NODE1_DQS3P")
	)
	(segment
		(start 53.229256 -52.463446)
		(end 52.827682 -52.86502)
		(width 0.2032)
		(layer "In2.Cu")
		(net "M_DDR3_NODE1_DQS3P")
	)
	(segment
		(start 51.56962 -48.115474)
		(end 51.45532 -48.229774)
		(width 0.2032)
		(layer "In2.Cu")
		(net "M_DDR3_NODE1_DQS3P")
	)
	(segment
		(start 165.296342 -121.57202)
		(end 164.571934 -120.847612)
		(width 0.1016)
		(layer "F.Cu")
		(net "FM_NODE1_DDR3_SYSPWRGD_R_L")
	)
	(segment
		(start 166.315644 -121.57202)
		(end 165.296342 -121.57202)
		(width 0.1016)
		(layer "F.Cu")
		(net "FM_NODE1_DDR3_SYSPWRGD_R_L")
	)
	(segment
		(start 163.252404 -119.684546)
		(end 163.408868 -119.684546)
		(width 0.1016)
		(layer "F.Cu")
		(net "FM_NODE1_DDR3_SYSPWRGD_R_L")
	)
	(segment
		(start 163.408868 -119.684546)
		(end 164.571934 -120.847612)
		(width 0.1016)
		(layer "F.Cu")
		(net "FM_NODE1_DDR3_SYSPWRGD_R_L")
	)
	(via
		(at 164.571934 -120.847612)
		(size 0.508)
		(drill 0.254)
		(layers "F.Cu" "B.Cu")
		(net "FM_NODE1_DDR3_SYSPWRGD_R_L")
	)
	(segment
		(start 45.633132 -132.163566)
		(end 45.633132 -132.163312)
		(width 0.3556)
		(layer "F.Cu")
		(net "P0V75_BMC_VTTREF_NODE1")
	)
	(segment
		(start 40.032432 -135.364474)
		(end 39.59987 -135.364474)
		(width 0.3556)
		(layer "F.Cu")
		(net "P0V75_BMC_VTTREF_NODE1")
	)
	(segment
		(start 39.59987 -135.364474)
		(end 39.4716 -135.492744)
		(width 0.3556)
		(layer "F.Cu")
		(net "P0V75_BMC_VTTREF_NODE1")
	)
	(segment
		(start 60.541916 -133.659118)
		(end 60.141104 -133.258306)
		(width 0.3556)
		(layer "F.Cu")
		(net "P0V75_BMC_VTTREF_NODE1")
	)
	(segment
		(start 38.14572 -135.492744)
		(end 39.4716 -135.492744)
		(width 0.381)
		(layer "F.Cu")
		(net "P0V75_BMC_VTTREF_NODE1")
	)
	(segment
		(start 37.967158 -135.314182)
		(end 38.14572 -135.492744)
		(width 0.381)
		(layer "F.Cu")
		(net "P0V75_BMC_VTTREF_NODE1")
	)
	(segment
		(start 40.033194 -135.363712)
		(end 40.032432 -135.364474)
		(width 0.3556)
		(layer "F.Cu")
		(net "P0V75_BMC_VTTREF_NODE1")
	)
	(segment
		(start 45.633132 -132.163312)
		(end 45.23359 -131.76377)
		(width 0.3556)
		(layer "F.Cu")
		(net "P0V75_BMC_VTTREF_NODE1")
	)
	(segment
		(start 60.541916 -133.659626)
		(end 60.541916 -133.659118)
		(width 0.3556)
		(layer "F.Cu")
		(net "P0V75_BMC_VTTREF_NODE1")
	)
	(via
		(at 37.175694 -141.068298)
		(size 0.6604)
		(drill 0.3302)
		(layers "F.Cu" "B.Cu")
		(net "P0V75_BMC_VTTREF_NODE1")
	)
	(via
		(at 36.60648 -139.084558)
		(size 0.508)
		(drill 0.254)
		(layers "F.Cu" "B.Cu")
		(net "P0V75_BMC_VTTREF_NODE1")
	)
	(via
		(at 57.634886 -134.125462)
		(size 0.6604)
		(drill 0.3302)
		(layers "F.Cu" "B.Cu")
		(net "P0V75_BMC_VTTREF_NODE1")
	)
	(via
		(at 39.4716 -135.492744)
		(size 0.49022)
		(drill 0.254)
		(layers "F.Cu" "B.Cu")
		(net "P0V75_BMC_VTTREF_NODE1")
	)
	(via
		(at 37.967158 -135.314182)
		(size 0.508)
		(drill 0.254)
		(layers "F.Cu" "B.Cu")
		(net "P0V75_BMC_VTTREF_NODE1")
	)
	(via
		(at 36.459922 -135.134096)
		(size 0.6604)
		(drill 0.3302)
		(layers "F.Cu" "B.Cu")
		(net "P0V75_BMC_VTTREF_NODE1")
	)
	(via
		(at 36.040822 -138.378946)
		(size 0.6604)
		(drill 0.3302)
		(layers "F.Cu" "B.Cu")
		(net "P0V75_BMC_VTTREF_NODE1")
	)
	(via
		(at 45.23359 -131.76377)
		(size 0.49022)
		(drill 0.254)
		(layers "F.Cu" "B.Cu")
		(net "P0V75_BMC_VTTREF_NODE1")
	)
	(via
		(at 36.090098 -136.68883)
		(size 0.6604)
		(drill 0.3302)
		(layers "F.Cu" "B.Cu")
		(net "P0V75_BMC_VTTREF_NODE1")
	)
	(via
		(at 60.141104 -133.258306)
		(size 0.49022)
		(drill 0.254)
		(layers "F.Cu" "B.Cu")
		(net "P0V75_BMC_VTTREF_NODE1")
	)
	(via
		(at 37.31768 -139.109958)
		(size 0.508)
		(drill 0.254)
		(layers "F.Cu" "B.Cu")
		(net "P0V75_BMC_VTTREF_NODE1")
	)
	(via
		(at 39.178484 -133.976872)
		(size 0.49022)
		(drill 0.254)
		(layers "F.Cu" "B.Cu")
		(net "P0V75_BMC_VTTREF_NODE1")
	)
	(segment
		(start 59.743086 -132.804662)
		(end 59.743086 -132.182616)
		(width 0.1016)
		(layer "B.Cu")
		(net "P0V75_BMC_VTTREF_NODE1")
	)
	(segment
		(start 59.616086 -132.055616)
		(end 58.092086 -132.055616)
		(width 0.1016)
		(layer "B.Cu")
		(net "P0V75_BMC_VTTREF_NODE1")
	)
	(segment
		(start 45.881036 -132.093462)
		(end 45.563282 -132.093462)
		(width 0.381)
		(layer "B.Cu")
		(net "P0V75_BMC_VTTREF_NODE1")
	)
	(segment
		(start 59.61634 -133.660642)
		(end 58.170826 -133.660642)
		(width 0.1016)
		(layer "B.Cu")
		(net "P0V75_BMC_VTTREF_NODE1")
	)
	(segment
		(start 58.092086 -132.860796)
		(end 59.616086 -132.860796)
		(width 0.1016)
		(layer "B.Cu")
		(net "P0V75_BMC_VTTREF_NODE1")
	)
	(segment
		(start 59.743086 -132.182616)
		(end 59.616086 -132.055616)
		(width 0.1016)
		(layer "B.Cu")
		(net "P0V75_BMC_VTTREF_NODE1")
	)
	(segment
		(start 59.743086 -133.820662)
		(end 59.743086 -134.582662)
		(width 0.1016)
		(layer "B.Cu")
		(net "P0V75_BMC_VTTREF_NODE1")
	)
	(segment
		(start 45.563282 -132.093462)
		(end 45.23359 -131.76377)
		(width 0.381)
		(layer "B.Cu")
		(net "P0V75_BMC_VTTREF_NODE1")
	)
	(segment
		(start 58.120534 -133.655816)
		(end 59.50585 -133.655816)
		(width 0.1016)
		(layer "In7.Cu")
		(net "P0V75_BMC_VTTREF_NODE1")
	)
	(segment
		(start 58.066686 -131.260596)
		(end 60.355988 -131.260596)
		(width 0.1016)
		(layer "In7.Cu")
		(net "P0V75_BMC_VTTREF_NODE1")
	)
	(segment
		(start 59.76874 -132.055616)
		(end 58.092086 -132.055616)
		(width 0.1016)
		(layer "In7.Cu")
		(net "P0V75_BMC_VTTREF_NODE1")
	)
	(segment
		(start 59.743086 -132.08127)
		(end 59.76874 -132.055616)
		(width 0.1016)
		(layer "In7.Cu")
		(net "P0V75_BMC_VTTREF_NODE1")
	)
	(segment
		(start 59.50585 -133.655816)
		(end 59.57951 -133.582156)
		(width 0.1016)
		(layer "In7.Cu")
		(net "P0V75_BMC_VTTREF_NODE1")
	)
	(segment
		(start 59.57951 -133.582156)
		(end 59.745118 -133.582156)
		(width 0.1016)
		(layer "In7.Cu")
		(net "P0V75_BMC_VTTREF_NODE1")
	)
	(segment
		(start 60.538614 -132.051298)
		(end 60.538614 -132.822188)
		(width 0.1016)
		(layer "In7.Cu")
		(net "P0V75_BMC_VTTREF_NODE1")
	)
	(segment
		(start 60.538614 -131.443222)
		(end 60.538614 -132.051298)
		(width 0.1016)
		(layer "In7.Cu")
		(net "P0V75_BMC_VTTREF_NODE1")
	)
	(segment
		(start 60.534296 -132.055616)
		(end 60.538614 -132.051298)
		(width 0.1016)
		(layer "In7.Cu")
		(net "P0V75_BMC_VTTREF_NODE1")
	)
	(segment
		(start 57.878472 -133.413754)
		(end 58.120534 -133.655816)
		(width 0.1016)
		(layer "In7.Cu")
		(net "P0V75_BMC_VTTREF_NODE1")
	)
	(segment
		(start 58.066686 -132.858002)
		(end 59.629548 -132.858002)
		(width 0.1016)
		(layer "In7.Cu")
		(net "P0V75_BMC_VTTREF_NODE1")
	)
	(segment
		(start 59.743086 -132.744464)
		(end 59.743086 -132.08127)
		(width 0.1016)
		(layer "In7.Cu")
		(net "P0V75_BMC_VTTREF_NODE1")
	)
	(segment
		(start 60.538614 -132.822188)
		(end 60.423806 -132.936996)
		(width 0.1016)
		(layer "In7.Cu")
		(net "P0V75_BMC_VTTREF_NODE1")
	)
	(segment
		(start 59.629548 -132.858002)
		(end 59.743086 -132.744464)
		(width 0.1016)
		(layer "In7.Cu")
		(net "P0V75_BMC_VTTREF_NODE1")
	)
	(segment
		(start 59.76874 -132.055616)
		(end 60.534296 -132.055616)
		(width 0.1016)
		(layer "In7.Cu")
		(net "P0V75_BMC_VTTREF_NODE1")
	)
	(segment
		(start 60.355988 -131.260596)
		(end 60.538614 -131.443222)
		(width 0.1016)
		(layer "In7.Cu")
		(net "P0V75_BMC_VTTREF_NODE1")
	)
	(segment
		(start 156.470096 -153.847292)
		(end 156.10078 -153.847292)
		(width 0.127)
		(layer "F.Cu")
		(net "P2E_CPU_NIC2_NODE1_TX_DN")
	)
	(segment
		(start 155.795472 -153.706322)
		(end 155.685744 -153.81605)
		(width 0.127)
		(layer "F.Cu")
		(net "P2E_CPU_NIC2_NODE1_TX_DN")
	)
	(segment
		(start 155.685744 -153.81605)
		(end 153.51252 -153.81605)
		(width 0.127)
		(layer "F.Cu")
		(net "P2E_CPU_NIC2_NODE1_TX_DN")
	)
	(segment
		(start 155.95981 -153.706322)
		(end 155.795472 -153.706322)
		(width 0.127)
		(layer "F.Cu")
		(net "P2E_CPU_NIC2_NODE1_TX_DN")
	)
	(segment
		(start 156.10078 -153.847292)
		(end 155.95981 -153.706322)
		(width 0.127)
		(layer "F.Cu")
		(net "P2E_CPU_NIC2_NODE1_TX_DN")
	)
	(segment
		(start 153.51252 -153.81605)
		(end 152.987756 -154.340814)
		(width 0.127)
		(layer "F.Cu")
		(net "P2E_CPU_NIC2_NODE1_TX_DN")
	)
	(via
		(at 152.987756 -154.340814)
		(size 0.508)
		(drill 0.254)
		(layers "F.Cu" "B.Cu")
		(net "P2E_CPU_NIC2_NODE1_TX_DN")
	)
	(via
		(at 31.48584 -72.058784)
		(size 0.508)
		(drill 0.254)
		(layers "F.Cu" "B.Cu")
		(net "P2E_CPU_NIC2_NODE1_TX_DN")
	)
	(segment
		(start 31.81604 -68.339208)
		(end 31.81604 -71.883016)
		(width 0.127)
		(layer "B.Cu")
		(net "P2E_CPU_NIC2_NODE1_TX_DN")
	)
	(segment
		(start 33.302956 -66.852292)
		(end 31.81604 -68.339208)
		(width 0.127)
		(layer "B.Cu")
		(net "P2E_CPU_NIC2_NODE1_TX_DN")
	)
	(segment
		(start 35.447224 -66.433192)
		(end 35.028124 -66.852292)
		(width 0.127)
		(layer "B.Cu")
		(net "P2E_CPU_NIC2_NODE1_TX_DN")
	)
	(segment
		(start 35.028124 -66.852292)
		(end 33.302956 -66.852292)
		(width 0.127)
		(layer "B.Cu")
		(net "P2E_CPU_NIC2_NODE1_TX_DN")
	)
	(segment
		(start 31.81604 -71.883016)
		(end 31.640272 -72.058784)
		(width 0.127)
		(layer "B.Cu")
		(net "P2E_CPU_NIC2_NODE1_TX_DN")
	)
	(segment
		(start 31.640272 -72.058784)
		(end 31.48584 -72.058784)
		(width 0.127)
		(layer "B.Cu")
		(net "P2E_CPU_NIC2_NODE1_TX_DN")
	)
	(segment
		(start 108.6358 -109.405166)
		(end 101.013514 -109.259116)
		(width 0.127)
		(layer "In7.Cu")
		(net "P2E_CPU_NIC2_NODE1_TX_DN")
	)
	(segment
		(start 130.65506 -131.720844)
		(end 129.33045 -131.27355)
		(width 0.127)
		(layer "In7.Cu")
		(net "P2E_CPU_NIC2_NODE1_TX_DN")
	)
	(segment
		(start 38.655498 -112.508792)
		(end 38.220396 -102.192836)
		(width 0.127)
		(layer "In7.Cu")
		(net "P2E_CPU_NIC2_NODE1_TX_DN")
	)
	(segment
		(start 85.902292 -111.144558)
		(end 85.89772 -111.149638)
		(width 0.127)
		(layer "In7.Cu")
		(net "P2E_CPU_NIC2_NODE1_TX_DN")
	)
	(segment
		(start 155.68168 -146.911568)
		(end 155.8798 -144.10563)
		(width 0.127)
		(layer "In7.Cu")
		(net "P2E_CPU_NIC2_NODE1_TX_DN")
	)
	(segment
		(start 41.895014 -116.510562)
		(end 40.262556 -114.28349)
		(width 0.127)
		(layer "In7.Cu")
		(net "P2E_CPU_NIC2_NODE1_TX_DN")
	)
	(segment
		(start 124.835158 -120.97004)
		(end 124.500132 -119.474488)
		(width 0.127)
		(layer "In7.Cu")
		(net "P2E_CPU_NIC2_NODE1_TX_DN")
	)
	(segment
		(start 145.609564 -132.11302)
		(end 145.60931 -132.112766)
		(width 0.127)
		(layer "In7.Cu")
		(net "P2E_CPU_NIC2_NODE1_TX_DN")
	)
	(segment
		(start 119.155464 -109.67847)
		(end 117.632988 -109.339634)
		(width 0.127)
		(layer "In7.Cu")
		(net "P2E_CPU_NIC2_NODE1_TX_DN")
	)
	(segment
		(start 65.56756 -115.315746)
		(end 62.14364 -114.1476)
		(width 0.127)
		(layer "In7.Cu")
		(net "P2E_CPU_NIC2_NODE1_TX_DN")
	)
	(segment
		(start 82.442812 -113.226088)
		(end 78.95082 -114.926364)
		(width 0.127)
		(layer "In7.Cu")
		(net "P2E_CPU_NIC2_NODE1_TX_DN")
	)
	(segment
		(start 145.48993 -132.111496)
		(end 145.489676 -132.111496)
		(width 0.127)
		(layer "In7.Cu")
		(net "P2E_CPU_NIC2_NODE1_TX_DN")
	)
	(segment
		(start 31.716218 -77.192632)
		(end 31.564834 -75.870816)
		(width 0.127)
		(layer "In7.Cu")
		(net "P2E_CPU_NIC2_NODE1_TX_DN")
	)
	(segment
		(start 154.17292 -151.475694)
		(end 154.314144 -151.271478)
		(width 0.127)
		(layer "In7.Cu")
		(net "P2E_CPU_NIC2_NODE1_TX_DN")
	)
	(segment
		(start 52.85994 -114.803428)
		(end 50.5587 -115.740688)
		(width 0.127)
		(layer "In7.Cu")
		(net "P2E_CPU_NIC2_NODE1_TX_DN")
	)
	(segment
		(start 50.5587 -115.740688)
		(end 48.627538 -117.576346)
		(width 0.127)
		(layer "In7.Cu")
		(net "P2E_CPU_NIC2_NODE1_TX_DN")
	)
	(segment
		(start 83.63204 -111.84636)
		(end 82.442812 -113.226088)
		(width 0.127)
		(layer "In7.Cu")
		(net "P2E_CPU_NIC2_NODE1_TX_DN")
	)
	(segment
		(start 154.52598 -150.201376)
		(end 154.48534 -149.005036)
		(width 0.127)
		(layer "In7.Cu")
		(net "P2E_CPU_NIC2_NODE1_TX_DN")
	)
	(segment
		(start 31.570422 -86.165944)
		(end 31.716218 -77.192632)
		(width 0.127)
		(layer "In7.Cu")
		(net "P2E_CPU_NIC2_NODE1_TX_DN")
	)
	(segment
		(start 90.473784 -111.179102)
		(end 86.317582 -111.125254)
		(width 0.127)
		(layer "In7.Cu")
		(net "P2E_CPU_NIC2_NODE1_TX_DN")
	)
	(segment
		(start 33.944814 -97.751646)
		(end 33.255966 -95.829882)
		(width 0.127)
		(layer "In7.Cu")
		(net "P2E_CPU_NIC2_NODE1_TX_DN")
	)
	(segment
		(start 120.627902 -110.606078)
		(end 119.155464 -109.67847)
		(width 0.127)
		(layer "In7.Cu")
		(net "P2E_CPU_NIC2_NODE1_TX_DN")
	)
	(segment
		(start 151.8666 -152.64384)
		(end 152.212294 -152.072848)
		(width 0.127)
		(layer "In7.Cu")
		(net "P2E_CPU_NIC2_NODE1_TX_DN")
	)
	(segment
		(start 155.68168 -140.302742)
		(end 155.22448 -139.661646)
		(width 0.127)
		(layer "In7.Cu")
		(net "P2E_CPU_NIC2_NODE1_TX_DN")
	)
	(segment
		(start 78.95082 -114.926364)
		(end 72.953118 -115.83924)
		(width 0.127)
		(layer "In7.Cu")
		(net "P2E_CPU_NIC2_NODE1_TX_DN")
	)
	(segment
		(start 39.852092 -113.921032)
		(end 39.750492 -113.80343)
		(width 0.127)
		(layer "In7.Cu")
		(net "P2E_CPU_NIC2_NODE1_TX_DN")
	)
	(segment
		(start 48.627538 -117.576346)
		(end 46.002702 -117.90934)
		(width 0.127)
		(layer "In7.Cu")
		(net "P2E_CPU_NIC2_NODE1_TX_DN")
	)
	(segment
		(start 33.255966 -95.829882)
		(end 31.570422 -86.165944)
		(width 0.127)
		(layer "In7.Cu")
		(net "P2E_CPU_NIC2_NODE1_TX_DN")
	)
	(segment
		(start 72.953118 -115.83924)
		(end 67.969384 -115.163092)
		(width 0.127)
		(layer "In7.Cu")
		(net "P2E_CPU_NIC2_NODE1_TX_DN")
	)
	(segment
		(start 115.135152 -109.116622)
		(end 108.6358 -109.405166)
		(width 0.127)
		(layer "In7.Cu")
		(net "P2E_CPU_NIC2_NODE1_TX_DN")
	)
	(segment
		(start 152.987756 -154.340814)
		(end 152.498806 -153.851864)
		(width 0.127)
		(layer "In7.Cu")
		(net "P2E_CPU_NIC2_NODE1_TX_DN")
	)
	(segment
		(start 126.42723 -122.46483)
		(end 124.835158 -120.97004)
		(width 0.127)
		(layer "In7.Cu")
		(net "P2E_CPU_NIC2_NODE1_TX_DN")
	)
	(segment
		(start 31.564834 -75.870816)
		(end 31.7627 -73.94829)
		(width 0.127)
		(layer "In7.Cu")
		(net "P2E_CPU_NIC2_NODE1_TX_DN")
	)
	(segment
		(start 117.632988 -109.339634)
		(end 117.59184 -109.339634)
		(width 0.127)
		(layer "In7.Cu")
		(net "P2E_CPU_NIC2_NODE1_TX_DN")
	)
	(segment
		(start 152.212294 -152.072848)
		(end 154.17292 -151.475694)
		(width 0.127)
		(layer "In7.Cu")
		(net "P2E_CPU_NIC2_NODE1_TX_DN")
	)
	(segment
		(start 155.8798 -144.10563)
		(end 155.68168 -140.302742)
		(width 0.127)
		(layer "In7.Cu")
		(net "P2E_CPU_NIC2_NODE1_TX_DN")
	)
	(segment
		(start 67.969384 -115.163092)
		(end 65.56756 -115.315746)
		(width 0.127)
		(layer "In7.Cu")
		(net "P2E_CPU_NIC2_NODE1_TX_DN")
	)
	(segment
		(start 56.81472 -114.967258)
		(end 52.85994 -114.803428)
		(width 0.127)
		(layer "In7.Cu")
		(net "P2E_CPU_NIC2_NODE1_TX_DN")
	)
	(segment
		(start 124.358146 -117.804946)
		(end 123.997974 -116.802916)
		(width 0.127)
		(layer "In7.Cu")
		(net "P2E_CPU_NIC2_NODE1_TX_DN")
	)
	(segment
		(start 152.247346 -153.851864)
		(end 151.839422 -153.427938)
		(width 0.127)
		(layer "In7.Cu")
		(net "P2E_CPU_NIC2_NODE1_TX_DN")
	)
	(segment
		(start 151.55164 -137.767568)
		(end 147.33524 -132.910834)
		(width 0.127)
		(layer "In7.Cu")
		(net "P2E_CPU_NIC2_NODE1_TX_DN")
	)
	(segment
		(start 123.997974 -116.802916)
		(end 122.409966 -113.626138)
		(width 0.127)
		(layer "In7.Cu")
		(net "P2E_CPU_NIC2_NODE1_TX_DN")
	)
	(segment
		(start 98.936556 -109.83849)
		(end 96.845628 -110.56493)
		(width 0.127)
		(layer "In7.Cu")
		(net "P2E_CPU_NIC2_NODE1_TX_DN")
	)
	(segment
		(start 145.489676 -132.111496)
		(end 143.045942 -132.086096)
		(width 0.127)
		(layer "In7.Cu")
		(net "P2E_CPU_NIC2_NODE1_TX_DN")
	)
	(segment
		(start 95.153226 -110.497112)
		(end 90.473784 -111.179102)
		(width 0.127)
		(layer "In7.Cu")
		(net "P2E_CPU_NIC2_NODE1_TX_DN")
	)
	(segment
		(start 62.14364 -114.1476)
		(end 56.81472 -114.967258)
		(width 0.127)
		(layer "In7.Cu")
		(net "P2E_CPU_NIC2_NODE1_TX_DN")
	)
	(segment
		(start 101.013514 -109.259116)
		(end 98.936556 -109.83849)
		(width 0.127)
		(layer "In7.Cu")
		(net "P2E_CPU_NIC2_NODE1_TX_DN")
	)
	(segment
		(start 147.33524 -132.910834)
		(end 145.609564 -132.11302)
		(width 0.127)
		(layer "In7.Cu")
		(net "P2E_CPU_NIC2_NODE1_TX_DN")
	)
	(segment
		(start 86.317582 -111.125254)
		(end 85.907372 -111.144558)
		(width 0.127)
		(layer "In7.Cu")
		(net "P2E_CPU_NIC2_NODE1_TX_DN")
	)
	(segment
		(start 152.498806 -153.851864)
		(end 152.247346 -153.851864)
		(width 0.127)
		(layer "In7.Cu")
		(net "P2E_CPU_NIC2_NODE1_TX_DN")
	)
	(segment
		(start 143.045942 -132.086096)
		(end 138.27506 -132.03682)
		(width 0.127)
		(layer "In7.Cu")
		(net "P2E_CPU_NIC2_NODE1_TX_DN")
	)
	(segment
		(start 133.771386 -131.462526)
		(end 130.65506 -131.720844)
		(width 0.127)
		(layer "In7.Cu")
		(net "P2E_CPU_NIC2_NODE1_TX_DN")
	)
	(segment
		(start 154.314144 -151.271478)
		(end 154.41422 -151.127206)
		(width 0.127)
		(layer "In7.Cu")
		(net "P2E_CPU_NIC2_NODE1_TX_DN")
	)
	(segment
		(start 40.262556 -114.28349)
		(end 40.06723 -114.111024)
		(width 0.127)
		(layer "In7.Cu")
		(net "P2E_CPU_NIC2_NODE1_TX_DN")
	)
	(segment
		(start 138.27506 -132.03682)
		(end 133.771386 -131.462526)
		(width 0.127)
		(layer "In7.Cu")
		(net "P2E_CPU_NIC2_NODE1_TX_DN")
	)
	(segment
		(start 39.95293 -114.010186)
		(end 39.852092 -113.921032)
		(width 0.127)
		(layer "In7.Cu")
		(net "P2E_CPU_NIC2_NODE1_TX_DN")
	)
	(segment
		(start 124.500132 -119.474488)
		(end 124.456444 -118.829836)
		(width 0.127)
		(layer "In7.Cu")
		(net "P2E_CPU_NIC2_NODE1_TX_DN")
	)
	(segment
		(start 124.456444 -118.829836)
		(end 124.358146 -117.804946)
		(width 0.127)
		(layer "In7.Cu")
		(net "P2E_CPU_NIC2_NODE1_TX_DN")
	)
	(segment
		(start 122.409966 -113.626138)
		(end 120.627902 -110.606078)
		(width 0.127)
		(layer "In7.Cu")
		(net "P2E_CPU_NIC2_NODE1_TX_DN")
	)
	(segment
		(start 40.06723 -114.111024)
		(end 39.95293 -114.010186)
		(width 0.127)
		(layer "In7.Cu")
		(net "P2E_CPU_NIC2_NODE1_TX_DN")
	)
	(segment
		(start 42.928286 -117.482874)
		(end 41.895014 -116.510562)
		(width 0.127)
		(layer "In7.Cu")
		(net "P2E_CPU_NIC2_NODE1_TX_DN")
	)
	(segment
		(start 151.839422 -153.427938)
		(end 151.8666 -152.64384)
		(width 0.127)
		(layer "In7.Cu")
		(net "P2E_CPU_NIC2_NODE1_TX_DN")
	)
	(segment
		(start 46.002702 -117.90934)
		(end 42.928286 -117.482874)
		(width 0.127)
		(layer "In7.Cu")
		(net "P2E_CPU_NIC2_NODE1_TX_DN")
	)
	(segment
		(start 154.48534 -149.005036)
		(end 154.76982 -147.993862)
		(width 0.127)
		(layer "In7.Cu")
		(net "P2E_CPU_NIC2_NODE1_TX_DN")
	)
	(segment
		(start 126.106936 -127.831596)
		(end 126.42723 -122.46483)
		(width 0.127)
		(layer "In7.Cu")
		(net "P2E_CPU_NIC2_NODE1_TX_DN")
	)
	(segment
		(start 154.76982 -147.993862)
		(end 155.68168 -146.911568)
		(width 0.127)
		(layer "In7.Cu")
		(net "P2E_CPU_NIC2_NODE1_TX_DN")
	)
	(segment
		(start 126.86919 -129.415794)
		(end 126.106936 -127.831596)
		(width 0.127)
		(layer "In7.Cu")
		(net "P2E_CPU_NIC2_NODE1_TX_DN")
	)
	(segment
		(start 31.974282 -72.560434)
		(end 31.975044 -72.547988)
		(width 0.127)
		(layer "In7.Cu")
		(net "P2E_CPU_NIC2_NODE1_TX_DN")
	)
	(segment
		(start 85.907372 -111.144558)
		(end 85.902292 -111.144558)
		(width 0.127)
		(layer "In7.Cu")
		(net "P2E_CPU_NIC2_NODE1_TX_DN")
	)
	(segment
		(start 38.220396 -102.192836)
		(end 33.944814 -97.751646)
		(width 0.127)
		(layer "In7.Cu")
		(net "P2E_CPU_NIC2_NODE1_TX_DN")
	)
	(segment
		(start 39.662862 -113.70183)
		(end 38.655498 -112.508792)
		(width 0.127)
		(layer "In7.Cu")
		(net "P2E_CPU_NIC2_NODE1_TX_DN")
	)
	(segment
		(start 31.975044 -72.547988)
		(end 31.48584 -72.058784)
		(width 0.127)
		(layer "In7.Cu")
		(net "P2E_CPU_NIC2_NODE1_TX_DN")
	)
	(segment
		(start 31.7627 -73.94829)
		(end 31.974282 -72.560434)
		(width 0.127)
		(layer "In7.Cu")
		(net "P2E_CPU_NIC2_NODE1_TX_DN")
	)
	(segment
		(start 85.89772 -111.149638)
		(end 83.63204 -111.84636)
		(width 0.127)
		(layer "In7.Cu")
		(net "P2E_CPU_NIC2_NODE1_TX_DN")
	)
	(segment
		(start 96.845628 -110.56493)
		(end 95.153226 -110.497112)
		(width 0.127)
		(layer "In7.Cu")
		(net "P2E_CPU_NIC2_NODE1_TX_DN")
	)
	(segment
		(start 155.22448 -139.661646)
		(end 151.55164 -137.767568)
		(width 0.127)
		(layer "In7.Cu")
		(net "P2E_CPU_NIC2_NODE1_TX_DN")
	)
	(segment
		(start 154.41422 -151.127206)
		(end 154.52598 -150.201376)
		(width 0.127)
		(layer "In7.Cu")
		(net "P2E_CPU_NIC2_NODE1_TX_DN")
	)
	(segment
		(start 117.59184 -109.339634)
		(end 115.135152 -109.116622)
		(width 0.127)
		(layer "In7.Cu")
		(net "P2E_CPU_NIC2_NODE1_TX_DN")
	)
	(segment
		(start 39.750492 -113.80343)
		(end 39.662862 -113.70183)
		(width 0.127)
		(layer "In7.Cu")
		(net "P2E_CPU_NIC2_NODE1_TX_DN")
	)
	(segment
		(start 145.60931 -132.112766)
		(end 145.48993 -132.111496)
		(width 0.127)
		(layer "In7.Cu")
		(net "P2E_CPU_NIC2_NODE1_TX_DN")
	)
	(segment
		(start 129.33045 -131.27355)
		(end 126.86919 -129.415794)
		(width 0.127)
		(layer "In7.Cu")
		(net "P2E_CPU_NIC2_NODE1_TX_DN")
	)
	(segment
		(start 49.180242 -63.870332)
		(end 49.562004 -63.48857)
		(width 0.1016)
		(layer "F.Cu")
		(net "M1_DQ_NODE1_DQ14")
	)
	(segment
		(start 50.25009 -27.172666)
		(end 49.909222 -26.831798)
		(width 0.1651)
		(layer "F.Cu")
		(net "M1_DQ_NODE1_DQ14")
	)
	(segment
		(start 50.25009 -29.149802)
		(end 50.25009 -27.172666)
		(width 0.1651)
		(layer "F.Cu")
		(net "M1_DQ_NODE1_DQ14")
	)
	(segment
		(start 48.729646 -64.004698)
		(end 48.864012 -63.870332)
		(width 0.1016)
		(layer "F.Cu")
		(net "M1_DQ_NODE1_DQ14")
	)
	(segment
		(start 48.429672 -64.004698)
		(end 48.729646 -64.004698)
		(width 0.1016)
		(layer "F.Cu")
		(net "M1_DQ_NODE1_DQ14")
	)
	(segment
		(start 48.864012 -63.870332)
		(end 49.180242 -63.870332)
		(width 0.1016)
		(layer "F.Cu")
		(net "M1_DQ_NODE1_DQ14")
	)
	(via
		(at 49.909222 -26.831798)
		(size 0.508)
		(drill 0.254)
		(layers "F.Cu" "B.Cu")
		(net "M1_DQ_NODE1_DQ14")
	)
	(via
		(at 49.562004 -63.48857)
		(size 0.508)
		(drill 0.254)
		(layers "F.Cu" "B.Cu")
		(net "M1_DQ_NODE1_DQ14")
	)
	(segment
		(start 49.94656 -29.961586)
		(end 50.15484 -29.753306)
		(width 0.2032)
		(layer "In2.Cu")
		(net "M1_DQ_NODE1_DQ14")
	)
	(segment
		(start 50.2539 -28.345638)
		(end 50.2539 -27.172412)
		(width 0.2032)
		(layer "In2.Cu")
		(net "M1_DQ_NODE1_DQ14")
	)
	(segment
		(start 46.073822 -56.841136)
		(end 45.27677 -56.044084)
		(width 0.2032)
		(layer "In2.Cu")
		(net "M1_DQ_NODE1_DQ14")
	)
	(segment
		(start 38.27018 -52.916328)
		(end 38.27018 -39.597584)
		(width 0.2032)
		(layer "In2.Cu")
		(net "M1_DQ_NODE1_DQ14")
	)
	(segment
		(start 48.61052 -58.64479)
		(end 47.144178 -57.178448)
		(width 0.1016)
		(layer "In2.Cu")
		(net "M1_DQ_NODE1_DQ14")
	)
	(segment
		(start 50.91176 -29.003498)
		(end 50.2539 -28.345638)
		(width 0.2032)
		(layer "In2.Cu")
		(net "M1_DQ_NODE1_DQ14")
	)
	(segment
		(start 50.15484 -29.753306)
		(end 50.70348 -29.753306)
		(width 0.2032)
		(layer "In2.Cu")
		(net "M1_DQ_NODE1_DQ14")
	)
	(segment
		(start 41.399968 -37.178996)
		(end 41.399968 -37.473636)
		(width 0.2032)
		(layer "In2.Cu")
		(net "M1_DQ_NODE1_DQ14")
	)
	(segment
		(start 49.94656 -30.256226)
		(end 49.94656 -29.961586)
		(width 0.2032)
		(layer "In2.Cu")
		(net "M1_DQ_NODE1_DQ14")
	)
	(segment
		(start 49.909222 -26.83256)
		(end 49.909222 -26.831798)
		(width 0.2032)
		(layer "In2.Cu")
		(net "M1_DQ_NODE1_DQ14")
	)
	(segment
		(start 42.714672 -54.997096)
		(end 40.350948 -54.997096)
		(width 0.2032)
		(layer "In2.Cu")
		(net "M1_DQ_NODE1_DQ14")
	)
	(segment
		(start 50.70348 -29.753306)
		(end 50.91176 -29.545026)
		(width 0.2032)
		(layer "In2.Cu")
		(net "M1_DQ_NODE1_DQ14")
	)
	(segment
		(start 39.619174 -40.26027)
		(end 43.033188 -36.846256)
		(width 0.2032)
		(layer "In2.Cu")
		(net "M1_DQ_NODE1_DQ14")
	)
	(segment
		(start 50.15484 -30.464506)
		(end 49.94656 -30.256226)
		(width 0.2032)
		(layer "In2.Cu")
		(net "M1_DQ_NODE1_DQ14")
	)
	(segment
		(start 48.61052 -59.916568)
		(end 48.61052 -58.64479)
		(width 0.1016)
		(layer "In2.Cu")
		(net "M1_DQ_NODE1_DQ14")
	)
	(segment
		(start 46.389036 -36.846256)
		(end 50.91176 -32.323532)
		(width 0.2032)
		(layer "In2.Cu")
		(net "M1_DQ_NODE1_DQ14")
	)
	(segment
		(start 50.70348 -30.464506)
		(end 50.15484 -30.464506)
		(width 0.2032)
		(layer "In2.Cu")
		(net "M1_DQ_NODE1_DQ14")
	)
	(segment
		(start 43.033188 -36.846256)
		(end 46.389036 -36.846256)
		(width 0.2032)
		(layer "In2.Cu")
		(net "M1_DQ_NODE1_DQ14")
	)
	(segment
		(start 41.399968 -37.473636)
		(end 39.116254 -39.75735)
		(width 0.2032)
		(layer "In2.Cu")
		(net "M1_DQ_NODE1_DQ14")
	)
	(segment
		(start 38.27018 -39.597584)
		(end 40.897048 -36.970716)
		(width 0.2032)
		(layer "In2.Cu")
		(net "M1_DQ_NODE1_DQ14")
	)
	(segment
		(start 39.116254 -39.75735)
		(end 39.116254 -40.05199)
		(width 0.2032)
		(layer "In2.Cu")
		(net "M1_DQ_NODE1_DQ14")
	)
	(segment
		(start 40.897048 -36.970716)
		(end 41.191688 -36.970716)
		(width 0.2032)
		(layer "In2.Cu")
		(net "M1_DQ_NODE1_DQ14")
	)
	(segment
		(start 46.411134 -57.178448)
		(end 46.073822 -56.841136)
		(width 0.1016)
		(layer "In2.Cu")
		(net "M1_DQ_NODE1_DQ14")
	)
	(segment
		(start 49.770792 -63.488062)
		(end 50.901092 -62.357762)
		(width 0.1016)
		(layer "In2.Cu")
		(net "M1_DQ_NODE1_DQ14")
	)
	(segment
		(start 50.91176 -32.323532)
		(end 50.91176 -30.672786)
		(width 0.2032)
		(layer "In2.Cu")
		(net "M1_DQ_NODE1_DQ14")
	)
	(segment
		(start 39.116254 -40.05199)
		(end 39.324534 -40.26027)
		(width 0.2032)
		(layer "In2.Cu")
		(net "M1_DQ_NODE1_DQ14")
	)
	(segment
		(start 50.2539 -27.172412)
		(end 49.914048 -26.83256)
		(width 0.2032)
		(layer "In2.Cu")
		(net "M1_DQ_NODE1_DQ14")
	)
	(segment
		(start 50.91176 -29.545026)
		(end 50.91176 -29.003498)
		(width 0.2032)
		(layer "In2.Cu")
		(net "M1_DQ_NODE1_DQ14")
	)
	(segment
		(start 50.901092 -61.85281)
		(end 50.622962 -61.57468)
		(width 0.1016)
		(layer "In2.Cu")
		(net "M1_DQ_NODE1_DQ14")
	)
	(segment
		(start 40.350948 -54.997096)
		(end 38.27018 -52.916328)
		(width 0.2032)
		(layer "In2.Cu")
		(net "M1_DQ_NODE1_DQ14")
	)
	(segment
		(start 49.562512 -63.488062)
		(end 49.770792 -63.488062)
		(width 0.1016)
		(layer "In2.Cu")
		(net "M1_DQ_NODE1_DQ14")
	)
	(segment
		(start 49.914048 -26.83256)
		(end 49.909222 -26.83256)
		(width 0.2032)
		(layer "In2.Cu")
		(net "M1_DQ_NODE1_DQ14")
	)
	(segment
		(start 39.324534 -40.26027)
		(end 39.619174 -40.26027)
		(width 0.2032)
		(layer "In2.Cu")
		(net "M1_DQ_NODE1_DQ14")
	)
	(segment
		(start 50.622962 -61.57468)
		(end 50.268632 -61.57468)
		(width 0.1016)
		(layer "In2.Cu")
		(net "M1_DQ_NODE1_DQ14")
	)
	(segment
		(start 45.27677 -56.044084)
		(end 43.76166 -56.044084)
		(width 0.2032)
		(layer "In2.Cu")
		(net "M1_DQ_NODE1_DQ14")
	)
	(segment
		(start 50.901092 -62.357762)
		(end 50.901092 -61.85281)
		(width 0.1016)
		(layer "In2.Cu")
		(net "M1_DQ_NODE1_DQ14")
	)
	(segment
		(start 41.191688 -36.970716)
		(end 41.399968 -37.178996)
		(width 0.2032)
		(layer "In2.Cu")
		(net "M1_DQ_NODE1_DQ14")
	)
	(segment
		(start 43.76166 -56.044084)
		(end 42.714672 -54.997096)
		(width 0.2032)
		(layer "In2.Cu")
		(net "M1_DQ_NODE1_DQ14")
	)
	(segment
		(start 50.91176 -30.672786)
		(end 50.70348 -30.464506)
		(width 0.2032)
		(layer "In2.Cu")
		(net "M1_DQ_NODE1_DQ14")
	)
	(segment
		(start 47.144178 -57.178448)
		(end 46.411134 -57.178448)
		(width 0.1016)
		(layer "In2.Cu")
		(net "M1_DQ_NODE1_DQ14")
	)
	(segment
		(start 49.562004 -63.48857)
		(end 49.562512 -63.488062)
		(width 0.1016)
		(layer "In2.Cu")
		(net "M1_DQ_NODE1_DQ14")
	)
	(segment
		(start 50.268632 -61.57468)
		(end 48.61052 -59.916568)
		(width 0.1016)
		(layer "In2.Cu")
		(net "M1_DQ_NODE1_DQ14")
	)
	(segment
		(start 41.63314 -133.848602)
		(end 41.91254 -134.128002)
		(width 0.1016)
		(layer "F.Cu")
		(net "BMC_NODE1_DDR_CAS_L")
	)
	(segment
		(start 41.63314 -133.763766)
		(end 41.63314 -133.848602)
		(width 0.1016)
		(layer "F.Cu")
		(net "BMC_NODE1_DDR_CAS_L")
	)
	(segment
		(start 43.470068 -133.532626)
		(end 43.470068 -133.11759)
		(width 0.1016)
		(layer "F.Cu")
		(net "BMC_NODE1_DDR_CAS_L")
	)
	(segment
		(start 55.372 -133.751066)
		(end 55.372 -133.979666)
		(width 0.1016)
		(layer "F.Cu")
		(net "BMC_NODE1_DDR_CAS_L")
	)
	(segment
		(start 42.828718 -133.11759)
		(end 42.828718 -133.542024)
		(width 0.1016)
		(layer "F.Cu")
		(net "BMC_NODE1_DDR_CAS_L")
	)
	(segment
		(start 55.372 -133.979666)
		(end 55.709312 -134.316978)
		(width 0.1016)
		(layer "F.Cu")
		(net "BMC_NODE1_DDR_CAS_L")
	)
	(segment
		(start 43.016678 -132.92963)
		(end 42.828718 -133.11759)
		(width 0.1016)
		(layer "F.Cu")
		(net "BMC_NODE1_DDR_CAS_L")
	)
	(segment
		(start 41.91254 -134.128002)
		(end 42.874692 -134.128002)
		(width 0.1016)
		(layer "F.Cu")
		(net "BMC_NODE1_DDR_CAS_L")
	)
	(segment
		(start 43.470068 -133.11759)
		(end 43.282108 -132.92963)
		(width 0.1016)
		(layer "F.Cu")
		(net "BMC_NODE1_DDR_CAS_L")
	)
	(segment
		(start 55.46344 -133.659626)
		(end 55.372 -133.751066)
		(width 0.1016)
		(layer "F.Cu")
		(net "BMC_NODE1_DDR_CAS_L")
	)
	(segment
		(start 57.34177 -133.659626)
		(end 55.46344 -133.659626)
		(width 0.1016)
		(layer "F.Cu")
		(net "BMC_NODE1_DDR_CAS_L")
	)
	(segment
		(start 42.874692 -134.128002)
		(end 43.470068 -133.532626)
		(width 0.1016)
		(layer "F.Cu")
		(net "BMC_NODE1_DDR_CAS_L")
	)
	(segment
		(start 43.282108 -132.92963)
		(end 43.016678 -132.92963)
		(width 0.1016)
		(layer "F.Cu")
		(net "BMC_NODE1_DDR_CAS_L")
	)
	(segment
		(start 55.709312 -134.316978)
		(end 55.709312 -134.321042)
		(width 0.1016)
		(layer "F.Cu")
		(net "BMC_NODE1_DDR_CAS_L")
	)
	(via
		(at 42.828718 -133.542024)
		(size 0.49022)
		(drill 0.254)
		(layers "F.Cu" "B.Cu")
		(net "BMC_NODE1_DDR_CAS_L")
	)
	(via
		(at 55.709312 -134.321042)
		(size 0.508)
		(drill 0.254)
		(layers "F.Cu" "B.Cu")
		(net "BMC_NODE1_DDR_CAS_L")
	)
	(segment
		(start 52.148486 -133.363462)
		(end 44.737528 -133.363462)
		(width 0.1143)
		(layer "In2.Cu")
		(net "BMC_NODE1_DDR_CAS_L")
	)
	(segment
		(start 43.184318 -133.186424)
		(end 42.828718 -133.542024)
		(width 0.1143)
		(layer "In2.Cu")
		(net "BMC_NODE1_DDR_CAS_L")
	)
	(segment
		(start 44.737528 -133.363462)
		(end 44.56049 -133.186424)
		(width 0.1143)
		(layer "In2.Cu")
		(net "BMC_NODE1_DDR_CAS_L")
	)
	(segment
		(start 52.57165 -133.786626)
		(end 52.148486 -133.363462)
		(width 0.1143)
		(layer "In2.Cu")
		(net "BMC_NODE1_DDR_CAS_L")
	)
	(segment
		(start 44.56049 -133.186424)
		(end 43.184318 -133.186424)
		(width 0.1143)
		(layer "In2.Cu")
		(net "BMC_NODE1_DDR_CAS_L")
	)
	(segment
		(start 55.703216 -134.321042)
		(end 55.1688 -133.786626)
		(width 0.1143)
		(layer "In2.Cu")
		(net "BMC_NODE1_DDR_CAS_L")
	)
	(segment
		(start 55.709312 -134.321042)
		(end 55.703216 -134.321042)
		(width 0.1143)
		(layer "In2.Cu")
		(net "BMC_NODE1_DDR_CAS_L")
	)
	(segment
		(start 55.1688 -133.786626)
		(end 52.57165 -133.786626)
		(width 0.1143)
		(layer "In2.Cu")
		(net "BMC_NODE1_DDR_CAS_L")
	)
	(segment
		(start 69.8246 -63.160402)
		(end 70.037452 -63.373254)
		(width 0.1016)
		(layer "F.Cu")
		(net "M1_DQ_NODE1_DQ35")
	)
	(segment
		(start 70.037452 -63.373254)
		(end 70.037452 -63.671196)
		(width 0.1016)
		(layer "F.Cu")
		(net "M1_DQ_NODE1_DQ35")
	)
	(segment
		(start 86.550246 -22.464014)
		(end 86.497922 -22.516338)
		(width 0.1651)
		(layer "F.Cu")
		(net "M1_DQ_NODE1_DQ35")
	)
	(segment
		(start 70.037452 -63.671196)
		(end 70.172072 -63.805816)
		(width 0.1016)
		(layer "F.Cu")
		(net "M1_DQ_NODE1_DQ35")
	)
	(segment
		(start 70.172072 -63.805816)
		(end 70.172072 -63.986156)
		(width 0.1016)
		(layer "F.Cu")
		(net "M1_DQ_NODE1_DQ35")
	)
	(segment
		(start 70.172072 -63.986156)
		(end 70.333616 -64.1477)
		(width 0.1016)
		(layer "F.Cu")
		(net "M1_DQ_NODE1_DQ35")
	)
	(segment
		(start 86.550246 -20.94992)
		(end 86.550246 -22.464014)
		(width 0.1651)
		(layer "F.Cu")
		(net "M1_DQ_NODE1_DQ35")
	)
	(via
		(at 70.333616 -64.1477)
		(size 0.508)
		(drill 0.254)
		(layers "F.Cu" "B.Cu")
		(net "M1_DQ_NODE1_DQ35")
	)
	(via
		(at 86.497922 -22.516338)
		(size 0.508)
		(drill 0.254)
		(layers "F.Cu" "B.Cu")
		(net "M1_DQ_NODE1_DQ35")
	)
	(segment
		(start 76.052172 -49.141888)
		(end 75.757532 -49.141888)
		(width 0.2032)
		(layer "In7.Cu")
		(net "M1_DQ_NODE1_DQ35")
	)
	(segment
		(start 85.91296 -25.470104)
		(end 86.497922 -24.885142)
		(width 0.2032)
		(layer "In7.Cu")
		(net "M1_DQ_NODE1_DQ35")
	)
	(segment
		(start 70.333616 -64.1477)
		(end 71.065644 -63.415672)
		(width 0.1016)
		(layer "In7.Cu")
		(net "M1_DQ_NODE1_DQ35")
	)
	(segment
		(start 73.38441 -59.23534)
		(end 73.23582 -59.08675)
		(width 0.2032)
		(layer "In7.Cu")
		(net "M1_DQ_NODE1_DQ35")
	)
	(segment
		(start 71.065644 -63.415672)
		(end 72.452992 -63.415672)
		(width 0.1016)
		(layer "In7.Cu")
		(net "M1_DQ_NODE1_DQ35")
	)
	(segment
		(start 73.23582 -52.962556)
		(end 75.7428 -50.455576)
		(width 0.2032)
		(layer "In7.Cu")
		(net "M1_DQ_NODE1_DQ35")
	)
	(segment
		(start 73.38441 -61.529976)
		(end 73.38441 -59.23534)
		(width 0.2032)
		(layer "In7.Cu")
		(net "M1_DQ_NODE1_DQ35")
	)
	(segment
		(start 86.497922 -24.885142)
		(end 86.497922 -22.516338)
		(width 0.2032)
		(layer "In7.Cu")
		(net "M1_DQ_NODE1_DQ35")
	)
	(segment
		(start 78.417928 -47.070772)
		(end 78.123288 -47.070772)
		(width 0.2032)
		(layer "In7.Cu")
		(net "M1_DQ_NODE1_DQ35")
	)
	(segment
		(start 75.744324 -50.455576)
		(end 78.626208 -47.573692)
		(width 0.2032)
		(layer "In7.Cu")
		(net "M1_DQ_NODE1_DQ35")
	)
	(segment
		(start 85.702902 -29.95295)
		(end 86.43112 -29.224732)
		(width 0.2032)
		(layer "In7.Cu")
		(net "M1_DQ_NODE1_DQ35")
	)
	(segment
		(start 85.91296 -26.144474)
		(end 85.91296 -25.470104)
		(width 0.2032)
		(layer "In7.Cu")
		(net "M1_DQ_NODE1_DQ35")
	)
	(segment
		(start 73.283064 -62.5856)
		(end 73.283064 -61.631322)
		(width 0.1016)
		(layer "In7.Cu")
		(net "M1_DQ_NODE1_DQ35")
	)
	(segment
		(start 75.549252 -48.638968)
		(end 85.702902 -38.485318)
		(width 0.2032)
		(layer "In7.Cu")
		(net "M1_DQ_NODE1_DQ35")
	)
	(segment
		(start 78.123288 -47.070772)
		(end 76.052172 -49.141888)
		(width 0.2032)
		(layer "In7.Cu")
		(net "M1_DQ_NODE1_DQ35")
	)
	(segment
		(start 75.549252 -48.933608)
		(end 75.549252 -48.638968)
		(width 0.2032)
		(layer "In7.Cu")
		(net "M1_DQ_NODE1_DQ35")
	)
	(segment
		(start 86.43112 -29.224732)
		(end 86.43112 -26.662634)
		(width 0.2032)
		(layer "In7.Cu")
		(net "M1_DQ_NODE1_DQ35")
	)
	(segment
		(start 75.757532 -49.141888)
		(end 75.549252 -48.933608)
		(width 0.2032)
		(layer "In7.Cu")
		(net "M1_DQ_NODE1_DQ35")
	)
	(segment
		(start 78.626208 -47.279052)
		(end 78.417928 -47.070772)
		(width 0.2032)
		(layer "In7.Cu")
		(net "M1_DQ_NODE1_DQ35")
	)
	(segment
		(start 75.7428 -50.455576)
		(end 75.744324 -50.455576)
		(width 0.2032)
		(layer "In7.Cu")
		(net "M1_DQ_NODE1_DQ35")
	)
	(segment
		(start 85.702902 -38.485318)
		(end 85.702902 -29.95295)
		(width 0.2032)
		(layer "In7.Cu")
		(net "M1_DQ_NODE1_DQ35")
	)
	(segment
		(start 86.43112 -26.662634)
		(end 85.91296 -26.144474)
		(width 0.2032)
		(layer "In7.Cu")
		(net "M1_DQ_NODE1_DQ35")
	)
	(segment
		(start 73.283064 -61.631322)
		(end 73.38441 -61.529976)
		(width 0.1016)
		(layer "In7.Cu")
		(net "M1_DQ_NODE1_DQ35")
	)
	(segment
		(start 72.452992 -63.415672)
		(end 73.283064 -62.5856)
		(width 0.1016)
		(layer "In7.Cu")
		(net "M1_DQ_NODE1_DQ35")
	)
	(segment
		(start 73.23582 -59.08675)
		(end 73.23582 -52.962556)
		(width 0.2032)
		(layer "In7.Cu")
		(net "M1_DQ_NODE1_DQ35")
	)
	(segment
		(start 78.626208 -47.573692)
		(end 78.626208 -47.279052)
		(width 0.2032)
		(layer "In7.Cu")
		(net "M1_DQ_NODE1_DQ35")
	)
	(segment
		(start 166.33317 -125.425708)
		(end 165.335458 -126.42342)
		(width 0.1016)
		(layer "F.Cu")
		(net "FM_CPLD_NODE1_JTAG_POK_R_L")
	)
	(segment
		(start 165.335458 -126.42342)
		(end 165.30066 -126.42342)
		(width 0.1016)
		(layer "F.Cu")
		(net "FM_CPLD_NODE1_JTAG_POK_R_L")
	)
	(segment
		(start 166.33317 -124.88291)
		(end 166.33317 -125.425708)
		(width 0.1016)
		(layer "F.Cu")
		(net "FM_CPLD_NODE1_JTAG_POK_R_L")
	)
	(segment
		(start 163.235894 -126.42342)
		(end 165.30066 -126.42342)
		(width 0.1016)
		(layer "F.Cu")
		(net "FM_CPLD_NODE1_JTAG_POK_R_L")
	)
	(via
		(at 165.30066 -126.42342)
		(size 0.508)
		(drill 0.254)
		(layers "F.Cu" "B.Cu")
		(net "FM_CPLD_NODE1_JTAG_POK_R_L")
	)
	(segment
		(start 41.63314 -140.96365)
		(end 43.038776 -141.924278)
		(width 0.1016)
		(layer "F.Cu")
		(net "BMC_NODE1_DDR_D14")
	)
	(segment
		(start 58.941716 -137.659618)
		(end 58.93943 -137.659618)
		(width 0.1016)
		(layer "F.Cu")
		(net "BMC_NODE1_DDR_D14")
	)
	(segment
		(start 58.93943 -137.659618)
		(end 58.540904 -138.058144)
		(width 0.1016)
		(layer "F.Cu")
		(net "BMC_NODE1_DDR_D14")
	)
	(via
		(at 58.540904 -138.058144)
		(size 0.49022)
		(drill 0.254)
		(layers "F.Cu" "B.Cu")
		(net "BMC_NODE1_DDR_D14")
	)
	(via
		(at 43.038776 -141.924278)
		(size 0.508)
		(drill 0.254)
		(layers "F.Cu" "B.Cu")
		(net "BMC_NODE1_DDR_D14")
	)
	(segment
		(start 54.790594 -142.451582)
		(end 55.368952 -141.873224)
		(width 0.1143)
		(layer "In7.Cu")
		(net "BMC_NODE1_DDR_D14")
	)
	(segment
		(start 56.230266 -140.6779)
		(end 57.584086 -138.799062)
		(width 0.1143)
		(layer "In7.Cu")
		(net "BMC_NODE1_DDR_D14")
	)
	(segment
		(start 52.201572 -142.451582)
		(end 54.790594 -142.451582)
		(width 0.1143)
		(layer "In7.Cu")
		(net "BMC_NODE1_DDR_D14")
	)
	(segment
		(start 57.584086 -138.799062)
		(end 58.325004 -138.058144)
		(width 0.1143)
		(layer "In7.Cu")
		(net "BMC_NODE1_DDR_D14")
	)
	(segment
		(start 51.732942 -142.920212)
		(end 52.201572 -142.451582)
		(width 0.1143)
		(layer "In7.Cu")
		(net "BMC_NODE1_DDR_D14")
	)
	(segment
		(start 43.928792 -142.296388)
		(end 45.715682 -142.920212)
		(width 0.1143)
		(layer "In7.Cu")
		(net "BMC_NODE1_DDR_D14")
	)
	(segment
		(start 45.715682 -142.920212)
		(end 51.732942 -142.920212)
		(width 0.1143)
		(layer "In7.Cu")
		(net "BMC_NODE1_DDR_D14")
	)
	(segment
		(start 43.038776 -141.924278)
		(end 43.928792 -142.296388)
		(width 0.1143)
		(layer "In7.Cu")
		(net "BMC_NODE1_DDR_D14")
	)
	(segment
		(start 58.325004 -138.058144)
		(end 58.540904 -138.058144)
		(width 0.1143)
		(layer "In7.Cu")
		(net "BMC_NODE1_DDR_D14")
	)
	(segment
		(start 55.368952 -141.873224)
		(end 56.230266 -140.6779)
		(width 0.1143)
		(layer "In7.Cu")
		(net "BMC_NODE1_DDR_D14")
	)
	(segment
		(start 68.374768 -63.126112)
		(end 68.374768 -63.045086)
		(width 0.09906)
		(layer "F.Cu")
		(net "M_DDR3_NODE1_DQS4P")
	)
	(segment
		(start 84.750148 -20.94992)
		(end 84.750148 -22.151086)
		(width 0.1651)
		(layer "F.Cu")
		(net "M_DDR3_NODE1_DQS4P")
	)
	(segment
		(start 84.775802 -22.767798)
		(end 84.775802 -23.092918)
		(width 0.1651)
		(layer "F.Cu")
		(net "M_DDR3_NODE1_DQS4P")
	)
	(segment
		(start 68.904104 -63.898526)
		(end 68.904104 -63.655448)
		(width 0.09906)
		(layer "F.Cu")
		(net "M_DDR3_NODE1_DQS4P")
	)
	(segment
		(start 84.596224 -22.30501)
		(end 84.596224 -22.58822)
		(width 0.1651)
		(layer "F.Cu")
		(net "M_DDR3_NODE1_DQS4P")
	)
	(segment
		(start 84.596224 -22.58822)
		(end 84.775802 -22.767798)
		(width 0.1651)
		(layer "F.Cu")
		(net "M_DDR3_NODE1_DQS4P")
	)
	(segment
		(start 84.750148 -22.151086)
		(end 84.596224 -22.30501)
		(width 0.1651)
		(layer "F.Cu")
		(net "M_DDR3_NODE1_DQS4P")
	)
	(segment
		(start 84.775802 -23.092918)
		(end 85.259672 -23.576788)
		(width 0.1651)
		(layer "F.Cu")
		(net "M_DDR3_NODE1_DQS4P")
	)
	(segment
		(start 68.904104 -63.655448)
		(end 68.374768 -63.126112)
		(width 0.09906)
		(layer "F.Cu")
		(net "M_DDR3_NODE1_DQS4P")
	)
	(via
		(at 68.374768 -63.045086)
		(size 0.508)
		(drill 0.254)
		(layers "F.Cu" "B.Cu")
		(net "M_DDR3_NODE1_DQS4P")
	)
	(via
		(at 85.259672 -23.576788)
		(size 0.508)
		(drill 0.254)
		(layers "F.Cu" "B.Cu")
		(net "M_DDR3_NODE1_DQS4P")
	)
	(segment
		(start 78.762606 -40.456612)
		(end 78.762606 -39.888668)
		(width 0.2032)
		(layer "In7.Cu")
		(net "M_DDR3_NODE1_DQS4P")
	)
	(segment
		(start 78.377288 -38.79215)
		(end 78.671928 -38.79215)
		(width 0.2032)
		(layer "In7.Cu")
		(net "M_DDR3_NODE1_DQS4P")
	)
	(segment
		(start 74.73696 -45.411136)
		(end 74.41946 -45.09389)
		(width 0.2032)
		(layer "In7.Cu")
		(net "M_DDR3_NODE1_DQS4P")
	)
	(segment
		(start 71.317866 -61.474096)
		(end 71.708264 -61.083698)
		(width 0.09906)
		(layer "In7.Cu")
		(net "M_DDR3_NODE1_DQS4P")
	)
	(segment
		(start 76.116942 -42.13098)
		(end 76.318618 -42.332656)
		(width 0.2032)
		(layer "In7.Cu")
		(net "M_DDR3_NODE1_DQS4P")
	)
	(segment
		(start 75.614022 -42.33926)
		(end 75.822302 -42.13098)
		(width 0.2032)
		(layer "In7.Cu")
		(net "M_DDR3_NODE1_DQS4P")
	)
	(segment
		(start 78.671928 -38.79215)
		(end 79.265526 -39.385748)
		(width 0.2032)
		(layer "In7.Cu")
		(net "M_DDR3_NODE1_DQS4P")
	)
	(segment
		(start 79.83347 -39.385748)
		(end 82.240882 -36.978336)
		(width 0.2032)
		(layer "In7.Cu")
		(net "M_DDR3_NODE1_DQS4P")
	)
	(segment
		(start 74.41946 -45.09389)
		(end 74.41946 -44.799758)
		(width 0.2032)
		(layer "In7.Cu")
		(net "M_DDR3_NODE1_DQS4P")
	)
	(segment
		(start 85.053932 -23.576788)
		(end 85.259672 -23.576788)
		(width 0.2032)
		(layer "In7.Cu")
		(net "M_DDR3_NODE1_DQS4P")
	)
	(segment
		(start 78.169008 -39.29507)
		(end 78.169008 -39.00043)
		(width 0.2032)
		(layer "In7.Cu")
		(net "M_DDR3_NODE1_DQS4P")
	)
	(segment
		(start 75.815698 -42.835576)
		(end 75.614022 -42.6339)
		(width 0.2032)
		(layer "In7.Cu")
		(net "M_DDR3_NODE1_DQS4P")
	)
	(segment
		(start 68.37553 -63.044324)
		(end 69.563742 -63.044324)
		(width 0.09906)
		(layer "In7.Cu")
		(net "M_DDR3_NODE1_DQS4P")
	)
	(segment
		(start 70.417436 -61.474096)
		(end 71.317866 -61.474096)
		(width 0.09906)
		(layer "In7.Cu")
		(net "M_DDR3_NODE1_DQS4P")
	)
	(segment
		(start 75.614022 -42.6339)
		(end 75.614022 -42.33926)
		(width 0.2032)
		(layer "In7.Cu")
		(net "M_DDR3_NODE1_DQS4P")
	)
	(segment
		(start 75.815698 -43.40352)
		(end 75.815698 -42.835576)
		(width 0.2032)
		(layer "In7.Cu")
		(net "M_DDR3_NODE1_DQS4P")
	)
	(segment
		(start 76.886562 -42.332656)
		(end 77.289152 -41.930066)
		(width 0.2032)
		(layer "In7.Cu")
		(net "M_DDR3_NODE1_DQS4P")
	)
	(segment
		(start 73.449434 -46.063916)
		(end 73.766172 -46.380908)
		(width 0.2032)
		(layer "In7.Cu")
		(net "M_DDR3_NODE1_DQS4P")
	)
	(segment
		(start 70.88632 -59.100212)
		(end 70.88632 -58.572654)
		(width 0.09906)
		(layer "In7.Cu")
		(net "M_DDR3_NODE1_DQS4P")
	)
	(segment
		(start 84.829142 -23.801578)
		(end 85.053932 -23.576788)
		(width 0.2032)
		(layer "In7.Cu")
		(net "M_DDR3_NODE1_DQS4P")
	)
	(segment
		(start 71.97598 -47.53737)
		(end 72.410574 -47.97171)
		(width 0.2032)
		(layer "In7.Cu")
		(net "M_DDR3_NODE1_DQS4P")
	)
	(segment
		(start 72.410574 -47.97171)
		(end 72.978518 -47.971456)
		(width 0.2032)
		(layer "In7.Cu")
		(net "M_DDR3_NODE1_DQS4P")
	)
	(segment
		(start 71.681848 -47.53737)
		(end 71.97598 -47.53737)
		(width 0.2032)
		(layer "In7.Cu")
		(net "M_DDR3_NODE1_DQS4P")
	)
	(segment
		(start 83.007962 -31.431738)
		(end 83.007962 -29.729938)
		(width 0.2032)
		(layer "In7.Cu")
		(net "M_DDR3_NODE1_DQS4P")
	)
	(segment
		(start 83.0072 -29.028898)
		(end 84.21624 -27.819858)
		(width 0.2032)
		(layer "In7.Cu")
		(net "M_DDR3_NODE1_DQS4P")
	)
	(segment
		(start 84.21624 -27.819858)
		(end 84.21624 -24.86914)
		(width 0.2032)
		(layer "In7.Cu")
		(net "M_DDR3_NODE1_DQS4P")
	)
	(segment
		(start 77.289152 -41.362122)
		(end 76.695554 -40.768524)
		(width 0.2032)
		(layer "In7.Cu")
		(net "M_DDR3_NODE1_DQS4P")
	)
	(segment
		(start 72.978518 -47.971456)
		(end 73.380092 -47.569882)
		(width 0.2032)
		(layer "In7.Cu")
		(net "M_DDR3_NODE1_DQS4P")
	)
	(segment
		(start 70.94982 -58.483246)
		(end 70.94982 -48.269398)
		(width 0.2032)
		(layer "In7.Cu")
		(net "M_DDR3_NODE1_DQS4P")
	)
	(segment
		(start 70.08114 -61.810392)
		(end 70.417436 -61.474096)
		(width 0.09906)
		(layer "In7.Cu")
		(net "M_DDR3_NODE1_DQS4P")
	)
	(segment
		(start 84.21624 -24.86914)
		(end 84.829142 -24.256238)
		(width 0.2032)
		(layer "In7.Cu")
		(net "M_DDR3_NODE1_DQS4P")
	)
	(segment
		(start 73.380092 -47.569882)
		(end 73.380346 -47.001938)
		(width 0.2032)
		(layer "In7.Cu")
		(net "M_DDR3_NODE1_DQS4P")
	)
	(segment
		(start 76.695554 -40.768524)
		(end 76.695554 -40.473884)
		(width 0.2032)
		(layer "In7.Cu")
		(net "M_DDR3_NODE1_DQS4P")
	)
	(segment
		(start 76.695554 -40.473884)
		(end 76.903834 -40.265604)
		(width 0.2032)
		(layer "In7.Cu")
		(net "M_DDR3_NODE1_DQS4P")
	)
	(segment
		(start 74.33437 -46.381162)
		(end 74.73696 -45.978826)
		(width 0.2032)
		(layer "In7.Cu")
		(net "M_DDR3_NODE1_DQS4P")
	)
	(segment
		(start 77.198474 -40.265604)
		(end 77.792072 -40.859202)
		(width 0.2032)
		(layer "In7.Cu")
		(net "M_DDR3_NODE1_DQS4P")
	)
	(segment
		(start 76.318618 -42.332656)
		(end 76.886562 -42.332656)
		(width 0.2032)
		(layer "In7.Cu")
		(net "M_DDR3_NODE1_DQS4P")
	)
	(segment
		(start 83.0072 -29.729938)
		(end 83.0072 -29.028898)
		(width 0.2032)
		(layer "In7.Cu")
		(net "M_DDR3_NODE1_DQS4P")
	)
	(segment
		(start 83.007962 -29.729938)
		(end 83.0072 -29.729938)
		(width 0.2032)
		(layer "In7.Cu")
		(net "M_DDR3_NODE1_DQS4P")
	)
	(segment
		(start 70.88632 -58.572654)
		(end 70.94982 -58.509154)
		(width 0.09906)
		(layer "In7.Cu")
		(net "M_DDR3_NODE1_DQS4P")
	)
	(segment
		(start 76.903834 -40.265604)
		(end 77.198474 -40.265604)
		(width 0.2032)
		(layer "In7.Cu")
		(net "M_DDR3_NODE1_DQS4P")
	)
	(segment
		(start 78.762606 -39.888668)
		(end 78.169008 -39.29507)
		(width 0.2032)
		(layer "In7.Cu")
		(net "M_DDR3_NODE1_DQS4P")
	)
	(segment
		(start 68.374768 -63.045086)
		(end 68.37553 -63.044324)
		(width 0.09906)
		(layer "In7.Cu")
		(net "M_DDR3_NODE1_DQS4P")
	)
	(segment
		(start 73.380346 -47.001938)
		(end 72.946006 -46.567344)
		(width 0.2032)
		(layer "In7.Cu")
		(net "M_DDR3_NODE1_DQS4P")
	)
	(segment
		(start 74.41946 -44.799758)
		(end 75.815698 -43.40352)
		(width 0.2032)
		(layer "In7.Cu")
		(net "M_DDR3_NODE1_DQS4P")
	)
	(segment
		(start 78.169008 -39.00043)
		(end 78.377288 -38.79215)
		(width 0.2032)
		(layer "In7.Cu")
		(net "M_DDR3_NODE1_DQS4P")
	)
	(segment
		(start 69.563742 -63.044324)
		(end 70.08114 -62.526926)
		(width 0.09906)
		(layer "In7.Cu")
		(net "M_DDR3_NODE1_DQS4P")
	)
	(segment
		(start 72.946006 -46.273212)
		(end 73.155302 -46.063916)
		(width 0.2032)
		(layer "In7.Cu")
		(net "M_DDR3_NODE1_DQS4P")
	)
	(segment
		(start 70.94982 -48.269398)
		(end 71.681848 -47.53737)
		(width 0.2032)
		(layer "In7.Cu")
		(net "M_DDR3_NODE1_DQS4P")
	)
	(segment
		(start 77.289152 -41.930066)
		(end 77.289152 -41.362122)
		(width 0.2032)
		(layer "In7.Cu")
		(net "M_DDR3_NODE1_DQS4P")
	)
	(segment
		(start 73.155302 -46.063916)
		(end 73.449434 -46.063916)
		(width 0.2032)
		(layer "In7.Cu")
		(net "M_DDR3_NODE1_DQS4P")
	)
	(segment
		(start 71.708264 -59.922156)
		(end 70.88632 -59.100212)
		(width 0.09906)
		(layer "In7.Cu")
		(net "M_DDR3_NODE1_DQS4P")
	)
	(segment
		(start 70.08114 -62.526926)
		(end 70.08114 -61.810392)
		(width 0.09906)
		(layer "In7.Cu")
		(net "M_DDR3_NODE1_DQS4P")
	)
	(segment
		(start 74.73696 -45.978826)
		(end 74.73696 -45.411136)
		(width 0.2032)
		(layer "In7.Cu")
		(net "M_DDR3_NODE1_DQS4P")
	)
	(segment
		(start 84.829142 -24.256238)
		(end 84.829142 -23.801578)
		(width 0.2032)
		(layer "In7.Cu")
		(net "M_DDR3_NODE1_DQS4P")
	)
	(segment
		(start 70.94982 -58.509154)
		(end 70.94982 -58.483246)
		(width 0.09906)
		(layer "In7.Cu")
		(net "M_DDR3_NODE1_DQS4P")
	)
	(segment
		(start 71.708264 -61.083698)
		(end 71.708264 -59.922156)
		(width 0.09906)
		(layer "In7.Cu")
		(net "M_DDR3_NODE1_DQS4P")
	)
	(segment
		(start 78.360016 -40.859202)
		(end 78.762606 -40.456612)
		(width 0.2032)
		(layer "In7.Cu")
		(net "M_DDR3_NODE1_DQS4P")
	)
	(segment
		(start 73.766172 -46.380908)
		(end 74.33437 -46.381162)
		(width 0.2032)
		(layer "In7.Cu")
		(net "M_DDR3_NODE1_DQS4P")
	)
	(segment
		(start 75.822302 -42.13098)
		(end 76.116942 -42.13098)
		(width 0.2032)
		(layer "In7.Cu")
		(net "M_DDR3_NODE1_DQS4P")
	)
	(segment
		(start 77.792072 -40.859202)
		(end 78.360016 -40.859202)
		(width 0.2032)
		(layer "In7.Cu")
		(net "M_DDR3_NODE1_DQS4P")
	)
	(segment
		(start 79.265526 -39.385748)
		(end 79.83347 -39.385748)
		(width 0.2032)
		(layer "In7.Cu")
		(net "M_DDR3_NODE1_DQS4P")
	)
	(segment
		(start 82.240882 -36.978336)
		(end 82.240882 -32.198818)
		(width 0.2032)
		(layer "In7.Cu")
		(net "M_DDR3_NODE1_DQS4P")
	)
	(segment
		(start 82.240882 -32.198818)
		(end 83.007962 -31.431738)
		(width 0.2032)
		(layer "In7.Cu")
		(net "M_DDR3_NODE1_DQS4P")
	)
	(segment
		(start 72.946006 -46.567344)
		(end 72.946006 -46.273212)
		(width 0.2032)
		(layer "In7.Cu")
		(net "M_DDR3_NODE1_DQS4P")
	)
	(segment
		(start 115.023646 -135.217154)
		(end 115.021614 -135.219186)
		(width 0.254)
		(layer "F.Cu")
		(net "VR_PVCCP_NODE1_COMP_RC")
	)
	(segment
		(start 116.007388 -135.217154)
		(end 115.023646 -135.217154)
		(width 0.254)
		(layer "F.Cu")
		(net "VR_PVCCP_NODE1_COMP_RC")
	)
	(segment
		(start 116.007388 -134.502144)
		(end 116.007388 -135.217154)
		(width 0.254)
		(layer "F.Cu")
		(net "VR_PVCCP_NODE1_COMP_RC")
	)
	(via
		(at 116.007388 -134.502144)
		(size 0.508)
		(drill 0.254)
		(layers "F.Cu" "B.Cu")
		(net "VR_PVCCP_NODE1_COMP_RC")
	)
	(segment
		(start 41.627044 -137.763758)
		(end 41.23309 -138.157712)
		(width 0.1016)
		(layer "F.Cu")
		(net "BMC_NODE1_DDR_D7")
	)
	(segment
		(start 58.941716 -136.059418)
		(end 58.93943 -136.059418)
		(width 0.1016)
		(layer "F.Cu")
		(net "BMC_NODE1_DDR_D7")
	)
	(segment
		(start 58.93943 -136.059418)
		(end 58.540904 -136.457944)
		(width 0.1016)
		(layer "F.Cu")
		(net "BMC_NODE1_DDR_D7")
	)
	(segment
		(start 41.63314 -137.763758)
		(end 41.627044 -137.763758)
		(width 0.1016)
		(layer "F.Cu")
		(net "BMC_NODE1_DDR_D7")
	)
	(segment
		(start 41.23309 -138.157712)
		(end 41.23309 -138.164316)
		(width 0.1016)
		(layer "F.Cu")
		(net "BMC_NODE1_DDR_D7")
	)
	(via
		(at 58.540904 -136.457944)
		(size 0.49022)
		(drill 0.254)
		(layers "F.Cu" "B.Cu")
		(net "BMC_NODE1_DDR_D7")
	)
	(via
		(at 41.23309 -138.164316)
		(size 0.508)
		(drill 0.254)
		(layers "F.Cu" "B.Cu")
		(net "BMC_NODE1_DDR_D7")
	)
	(segment
		(start 43.1292 -138.770106)
		(end 43.888406 -139.529312)
		(width 0.1143)
		(layer "In7.Cu")
		(net "BMC_NODE1_DDR_D7")
	)
	(segment
		(start 58.325004 -136.457944)
		(end 58.540904 -136.457944)
		(width 0.1143)
		(layer "In7.Cu")
		(net "BMC_NODE1_DDR_D7")
	)
	(segment
		(start 41.23309 -138.164316)
		(end 42.61866 -138.770106)
		(width 0.1143)
		(layer "In7.Cu")
		(net "BMC_NODE1_DDR_D7")
	)
	(segment
		(start 43.888406 -139.529312)
		(end 44.51223 -139.90701)
		(width 0.1143)
		(layer "In7.Cu")
		(net "BMC_NODE1_DDR_D7")
	)
	(segment
		(start 42.61866 -138.770106)
		(end 43.1292 -138.770106)
		(width 0.1143)
		(layer "In7.Cu")
		(net "BMC_NODE1_DDR_D7")
	)
	(segment
		(start 54.730396 -140.000482)
		(end 55.374032 -139.520676)
		(width 0.1143)
		(layer "In7.Cu")
		(net "BMC_NODE1_DDR_D7")
	)
	(segment
		(start 44.966382 -141.016482)
		(end 53.067966 -141.016482)
		(width 0.1143)
		(layer "In7.Cu")
		(net "BMC_NODE1_DDR_D7")
	)
	(segment
		(start 56.060086 -138.722862)
		(end 58.325004 -136.457944)
		(width 0.1143)
		(layer "In7.Cu")
		(net "BMC_NODE1_DDR_D7")
	)
	(segment
		(start 54.543706 -140.139674)
		(end 54.730396 -140.000482)
		(width 0.1143)
		(layer "In7.Cu")
		(net "BMC_NODE1_DDR_D7")
	)
	(segment
		(start 44.51223 -139.90701)
		(end 44.745148 -140.795248)
		(width 0.1143)
		(layer "In7.Cu")
		(net "BMC_NODE1_DDR_D7")
	)
	(segment
		(start 44.745148 -140.795248)
		(end 44.966382 -141.016482)
		(width 0.1143)
		(layer "In7.Cu")
		(net "BMC_NODE1_DDR_D7")
	)
	(segment
		(start 53.067966 -141.016482)
		(end 54.543706 -140.139674)
		(width 0.1143)
		(layer "In7.Cu")
		(net "BMC_NODE1_DDR_D7")
	)
	(segment
		(start 55.374032 -139.520168)
		(end 56.060086 -138.722862)
		(width 0.1143)
		(layer "In7.Cu")
		(net "BMC_NODE1_DDR_D7")
	)
	(segment
		(start 55.374032 -139.520676)
		(end 55.374032 -139.520168)
		(width 0.1143)
		(layer "In7.Cu")
		(net "BMC_NODE1_DDR_D7")
	)
	(segment
		(start 67.535044 -75.569318)
		(end 67.535044 -75.559412)
		(width 0.1016)
		(layer "F.Cu")
		(net "FM_CPU_NODE1_OWDTOUT")
	)
	(segment
		(start 173.84522 -132.190998)
		(end 173.84522 -134.909306)
		(width 0.1016)
		(layer "F.Cu")
		(net "FM_CPU_NODE1_OWDTOUT")
	)
	(segment
		(start 173.99762 -135.061706)
		(end 175.605186 -135.061706)
		(width 0.1016)
		(layer "F.Cu")
		(net "FM_CPU_NODE1_OWDTOUT")
	)
	(segment
		(start 173.84522 -134.909306)
		(end 173.99762 -135.061706)
		(width 0.1016)
		(layer "F.Cu")
		(net "FM_CPU_NODE1_OWDTOUT")
	)
	(segment
		(start 67.898518 -75.195938)
		(end 67.916044 -75.195938)
		(width 0.1016)
		(layer "F.Cu")
		(net "FM_CPU_NODE1_OWDTOUT")
	)
	(segment
		(start 67.535044 -75.559412)
		(end 67.898518 -75.195938)
		(width 0.1016)
		(layer "F.Cu")
		(net "FM_CPU_NODE1_OWDTOUT")
	)
	(segment
		(start 176.242472 -134.42442)
		(end 177.515774 -134.42442)
		(width 0.1016)
		(layer "F.Cu")
		(net "FM_CPU_NODE1_OWDTOUT")
	)
	(segment
		(start 175.605186 -135.061706)
		(end 176.242472 -134.42442)
		(width 0.1016)
		(layer "F.Cu")
		(net "FM_CPU_NODE1_OWDTOUT")
	)
	(segment
		(start 172.3263 -129.143252)
		(end 172.3263 -130.672078)
		(width 0.1016)
		(layer "F.Cu")
		(net "FM_CPU_NODE1_OWDTOUT")
	)
	(segment
		(start 172.3263 -130.672078)
		(end 173.84522 -132.190998)
		(width 0.1016)
		(layer "F.Cu")
		(net "FM_CPU_NODE1_OWDTOUT")
	)
	(via
		(at 67.916044 -75.195938)
		(size 0.508)
		(drill 0.254)
		(layers "F.Cu" "B.Cu")
		(net "FM_CPU_NODE1_OWDTOUT")
	)
	(via
		(at 172.3263 -129.143252)
		(size 0.508)
		(drill 0.254)
		(layers "F.Cu" "B.Cu")
		(net "FM_CPU_NODE1_OWDTOUT")
	)
	(via
		(at 86.790022 -72.64654)
		(size 0.508)
		(drill 0.254)
		(layers "F.Cu" "B.Cu")
		(net "FM_CPU_NODE1_OWDTOUT")
	)
	(segment
		(start 79.229458 -72.64654)
		(end 77.234034 -74.641964)
		(width 0.1016)
		(layer "B.Cu")
		(net "FM_CPU_NODE1_OWDTOUT")
	)
	(segment
		(start 69.667374 -74.621898)
		(end 69.33057 -74.621898)
		(width 0.1016)
		(layer "B.Cu")
		(net "FM_CPU_NODE1_OWDTOUT")
	)
	(segment
		(start 68.75653 -75.195938)
		(end 67.916044 -75.195938)
		(width 0.1016)
		(layer "B.Cu")
		(net "FM_CPU_NODE1_OWDTOUT")
	)
	(segment
		(start 69.33057 -74.621898)
		(end 68.75653 -75.195938)
		(width 0.1016)
		(layer "B.Cu")
		(net "FM_CPU_NODE1_OWDTOUT")
	)
	(segment
		(start 69.68744 -74.641964)
		(end 69.667374 -74.621898)
		(width 0.1016)
		(layer "B.Cu")
		(net "FM_CPU_NODE1_OWDTOUT")
	)
	(segment
		(start 77.234034 -74.641964)
		(end 69.68744 -74.641964)
		(width 0.1016)
		(layer "B.Cu")
		(net "FM_CPU_NODE1_OWDTOUT")
	)
	(segment
		(start 86.790022 -72.64654)
		(end 79.229458 -72.64654)
		(width 0.1016)
		(layer "B.Cu")
		(net "FM_CPU_NODE1_OWDTOUT")
	)
	(segment
		(start 87.52332 -71.913496)
		(end 86.790276 -72.64654)
		(width 0.1143)
		(layer "In7.Cu")
		(net "FM_CPU_NODE1_OWDTOUT")
	)
	(segment
		(start 96.78162 -71.913496)
		(end 87.52332 -71.913496)
		(width 0.1143)
		(layer "In7.Cu")
		(net "FM_CPU_NODE1_OWDTOUT")
	)
	(segment
		(start 148.25218 -106.730546)
		(end 141.375384 -99.85375)
		(width 0.1143)
		(layer "In7.Cu")
		(net "FM_CPU_NODE1_OWDTOUT")
	)
	(segment
		(start 161.629344 -123.753626)
		(end 159.362648 -123.753626)
		(width 0.1143)
		(layer "In7.Cu")
		(net "FM_CPU_NODE1_OWDTOUT")
	)
	(segment
		(start 165.827964 -127.084836)
		(end 164.960554 -127.084836)
		(width 0.1143)
		(layer "In7.Cu")
		(net "FM_CPU_NODE1_OWDTOUT")
	)
	(segment
		(start 111.199422 -80.968596)
		(end 105.83672 -80.968596)
		(width 0.1143)
		(layer "In7.Cu")
		(net "FM_CPU_NODE1_OWDTOUT")
	)
	(segment
		(start 167.88638 -129.143252)
		(end 165.827964 -127.084836)
		(width 0.1143)
		(layer "In7.Cu")
		(net "FM_CPU_NODE1_OWDTOUT")
	)
	(segment
		(start 172.3263 -129.143252)
		(end 167.88638 -129.143252)
		(width 0.1143)
		(layer "In7.Cu")
		(net "FM_CPU_NODE1_OWDTOUT")
	)
	(segment
		(start 130.084576 -99.85375)
		(end 111.199422 -80.968596)
		(width 0.1143)
		(layer "In7.Cu")
		(net "FM_CPU_NODE1_OWDTOUT")
	)
	(segment
		(start 148.25218 -107.75061)
		(end 148.25218 -106.730546)
		(width 0.1143)
		(layer "In7.Cu")
		(net "FM_CPU_NODE1_OWDTOUT")
	)
	(segment
		(start 153.43378 -117.824758)
		(end 153.43378 -112.93221)
		(width 0.1143)
		(layer "In7.Cu")
		(net "FM_CPU_NODE1_OWDTOUT")
	)
	(segment
		(start 86.790276 -72.64654)
		(end 86.790022 -72.64654)
		(width 0.1143)
		(layer "In7.Cu")
		(net "FM_CPU_NODE1_OWDTOUT")
	)
	(segment
		(start 159.362648 -123.753626)
		(end 153.43378 -117.824758)
		(width 0.1143)
		(layer "In7.Cu")
		(net "FM_CPU_NODE1_OWDTOUT")
	)
	(segment
		(start 164.960554 -127.084836)
		(end 161.629344 -123.753626)
		(width 0.1143)
		(layer "In7.Cu")
		(net "FM_CPU_NODE1_OWDTOUT")
	)
	(segment
		(start 141.375384 -99.85375)
		(end 130.084576 -99.85375)
		(width 0.1143)
		(layer "In7.Cu")
		(net "FM_CPU_NODE1_OWDTOUT")
	)
	(segment
		(start 153.43378 -112.93221)
		(end 148.25218 -107.75061)
		(width 0.1143)
		(layer "In7.Cu")
		(net "FM_CPU_NODE1_OWDTOUT")
	)
	(segment
		(start 105.83672 -80.968596)
		(end 96.78162 -71.913496)
		(width 0.1143)
		(layer "In7.Cu")
		(net "FM_CPU_NODE1_OWDTOUT")
	)
	(segment
		(start 68.797424 -56.30418)
		(end 68.60032 -56.501284)
		(width 0.1651)
		(layer "F.Cu")
		(net "M_DDR3_NODE1_ODT0")
	)
	(segment
		(start 80.24876 -29.149802)
		(end 80.24876 -32.356552)
		(width 0.1651)
		(layer "F.Cu")
		(net "M_DDR3_NODE1_ODT0")
	)
	(segment
		(start 70.73392 -57.174384)
		(end 70.73392 -57.453276)
		(width 0.1651)
		(layer "F.Cu")
		(net "M_DDR3_NODE1_ODT0")
	)
	(segment
		(start 71.6026 -56.30418)
		(end 68.797424 -56.30418)
		(width 0.1651)
		(layer "F.Cu")
		(net "M_DDR3_NODE1_ODT0")
	)
	(segment
		(start 80.4418 -41.742868)
		(end 80.4418 -42.02176)
		(width 0.1651)
		(layer "F.Cu")
		(net "M_DDR3_NODE1_ODT0")
	)
	(segment
		(start 68.061078 -57.65038)
		(end 67.863974 -57.453276)
		(width 0.1651)
		(layer "F.Cu")
		(net "M_DDR3_NODE1_ODT0")
	)
	(segment
		(start 80.24876 -33.42386)
		(end 80.24876 -33.75152)
		(width 0.1651)
		(layer "F.Cu")
		(net "M_DDR3_NODE1_ODT0")
	)
	(segment
		(start 66.55562 -58.098944)
		(end 66.55562 -61.056012)
		(width 0.1651)
		(layer "F.Cu")
		(net "M_DDR3_NODE1_ODT0")
	)
	(segment
		(start 80.4418 -42.02176)
		(end 80.638904 -42.218864)
		(width 0.1651)
		(layer "F.Cu")
		(net "M_DDR3_NODE1_ODT0")
	)
	(segment
		(start 81.35112 -35.09772)
		(end 81.35112 -35.738308)
		(width 0.1651)
		(layer "F.Cu")
		(net "M_DDR3_NODE1_ODT0")
	)
	(segment
		(start 81.00568 -40.00246)
		(end 80.808576 -40.199564)
		(width 0.1651)
		(layer "F.Cu")
		(net "M_DDR3_NODE1_ODT0")
	)
	(segment
		(start 81.24444 -32.68218)
		(end 81.24444 -33.023556)
		(width 0.1651)
		(layer "F.Cu")
		(net "M_DDR3_NODE1_ODT0")
	)
	(segment
		(start 80.1624 -48.210978)
		(end 79.695802 -48.210978)
		(width 0.1651)
		(layer "F.Cu")
		(net "M_DDR3_NODE1_ODT0")
	)
	(segment
		(start 80.808576 -42.891964)
		(end 80.651604 -42.891964)
		(width 0.1651)
		(layer "F.Cu")
		(net "M_DDR3_NODE1_ODT0")
	)
	(segment
		(start 80.808576 -40.199564)
		(end 80.677004 -40.199564)
		(width 0.1651)
		(layer "F.Cu")
		(net "M_DDR3_NODE1_ODT0")
	)
	(segment
		(start 80.628744 -46.257464)
		(end 80.808576 -46.257464)
		(width 0.1651)
		(layer "F.Cu")
		(net "M_DDR3_NODE1_ODT0")
	)
	(segment
		(start 80.43164 -45.781468)
		(end 80.43164 -46.06036)
		(width 0.1651)
		(layer "F.Cu")
		(net "M_DDR3_NODE1_ODT0")
	)
	(segment
		(start 81.00568 -45.38726)
		(end 80.808576 -45.584364)
		(width 0.1651)
		(layer "F.Cu")
		(net "M_DDR3_NODE1_ODT0")
	)
	(segment
		(start 80.824578 -48.542956)
		(end 80.4926 -48.542956)
		(width 0.1651)
		(layer "F.Cu")
		(net "M_DDR3_NODE1_ODT0")
	)
	(segment
		(start 81.00568 -43.762168)
		(end 81.00568 -44.04106)
		(width 0.1651)
		(layer "F.Cu")
		(net "M_DDR3_NODE1_ODT0")
	)
	(segment
		(start 80.42656 -44.435268)
		(end 80.42656 -44.71416)
		(width 0.1651)
		(layer "F.Cu")
		(net "M_DDR3_NODE1_ODT0")
	)
	(segment
		(start 80.808576 -45.584364)
		(end 80.628744 -45.584364)
		(width 0.1651)
		(layer "F.Cu")
		(net "M_DDR3_NODE1_ODT0")
	)
	(segment
		(start 81.47304 -47.59579)
		(end 81.47304 -47.894494)
		(width 0.1651)
		(layer "F.Cu")
		(net "M_DDR3_NODE1_ODT0")
	)
	(segment
		(start 80.4799 -40.396668)
		(end 80.4799 -40.67556)
		(width 0.1651)
		(layer "F.Cu")
		(net "M_DDR3_NODE1_ODT0")
	)
	(segment
		(start 67.1703 -57.429654)
		(end 67.1703 -57.708546)
		(width 0.1651)
		(layer "F.Cu")
		(net "M_DDR3_NODE1_ODT0")
	)
	(segment
		(start 68.797424 -56.97728)
		(end 70.536816 -56.97728)
		(width 0.1651)
		(layer "F.Cu")
		(net "M_DDR3_NODE1_ODT0")
	)
	(segment
		(start 80.1624 -48.212756)
		(end 80.1624 -48.210978)
		(width 0.1651)
		(layer "F.Cu")
		(net "M_DDR3_NODE1_ODT0")
	)
	(segment
		(start 81.35112 -36.708588)
		(end 81.35112 -37.936424)
		(width 0.1651)
		(layer "F.Cu")
		(net "M_DDR3_NODE1_ODT0")
	)
	(segment
		(start 81.35112 -35.738308)
		(end 81.6483 -36.035488)
		(width 0.1651)
		(layer "F.Cu")
		(net "M_DDR3_NODE1_ODT0")
	)
	(segment
		(start 81.00568 -42.69486)
		(end 80.808576 -42.891964)
		(width 0.1651)
		(layer "F.Cu")
		(net "M_DDR3_NODE1_ODT0")
	)
	(segment
		(start 81.00568 -42.415968)
		(end 81.00568 -42.69486)
		(width 0.1651)
		(layer "F.Cu")
		(net "M_DDR3_NODE1_ODT0")
	)
	(segment
		(start 80.4926 -48.542956)
		(end 80.1624 -48.212756)
		(width 0.1651)
		(layer "F.Cu")
		(net "M_DDR3_NODE1_ODT0")
	)
	(segment
		(start 80.99552 -46.444408)
		(end 80.99552 -47.11827)
		(width 0.1651)
		(layer "F.Cu")
		(net "M_DDR3_NODE1_ODT0")
	)
	(segment
		(start 80.42656 -44.71416)
		(end 80.623664 -44.911264)
		(width 0.1651)
		(layer "F.Cu")
		(net "M_DDR3_NODE1_ODT0")
	)
	(segment
		(start 70.536816 -57.65038)
		(end 68.061078 -57.65038)
		(width 0.1651)
		(layer "F.Cu")
		(net "M_DDR3_NODE1_ODT0")
	)
	(segment
		(start 70.73392 -57.453276)
		(end 70.536816 -57.65038)
		(width 0.1651)
		(layer "F.Cu")
		(net "M_DDR3_NODE1_ODT0")
	)
	(segment
		(start 80.99552 -47.11827)
		(end 81.47304 -47.59579)
		(width 0.1651)
		(layer "F.Cu")
		(net "M_DDR3_NODE1_ODT0")
	)
	(segment
		(start 65.7733 -56.960516)
		(end 66.045334 -57.23255)
		(width 0.1651)
		(layer "F.Cu")
		(net "M_DDR3_NODE1_ODT0")
	)
	(segment
		(start 80.753966 -39.526464)
		(end 80.808576 -39.526464)
		(width 0.1651)
		(layer "F.Cu")
		(net "M_DDR3_NODE1_ODT0")
	)
	(segment
		(start 79.695802 -48.210978)
		(end 71.6026 -56.30418)
		(width 0.1651)
		(layer "F.Cu")
		(net "M_DDR3_NODE1_ODT0")
	)
	(segment
		(start 66.973196 -57.23255)
		(end 67.1703 -57.429654)
		(width 0.1651)
		(layer "F.Cu")
		(net "M_DDR3_NODE1_ODT0")
	)
	(segment
		(start 80.371188 -32.47898)
		(end 81.04124 -32.47898)
		(width 0.1651)
		(layer "F.Cu")
		(net "M_DDR3_NODE1_ODT0")
	)
	(segment
		(start 80.628744 -45.584364)
		(end 80.43164 -45.781468)
		(width 0.1651)
		(layer "F.Cu")
		(net "M_DDR3_NODE1_ODT0")
	)
	(segment
		(start 80.651604 -43.565064)
		(end 80.808576 -43.565064)
		(width 0.1651)
		(layer "F.Cu")
		(net "M_DDR3_NODE1_ODT0")
	)
	(segment
		(start 67.1703 -57.708546)
		(end 66.907918 -57.970928)
		(width 0.1651)
		(layer "F.Cu")
		(net "M_DDR3_NODE1_ODT0")
	)
	(segment
		(start 66.907918 -57.970928)
		(end 66.683636 -57.970928)
		(width 0.1651)
		(layer "F.Cu")
		(net "M_DDR3_NODE1_ODT0")
	)
	(segment
		(start 80.623664 -44.911264)
		(end 80.808576 -44.911264)
		(width 0.1651)
		(layer "F.Cu")
		(net "M_DDR3_NODE1_ODT0")
	)
	(segment
		(start 66.683636 -57.970928)
		(end 66.55562 -58.098944)
		(width 0.1651)
		(layer "F.Cu")
		(net "M_DDR3_NODE1_ODT0")
	)
	(segment
		(start 81.00568 -41.34866)
		(end 80.808576 -41.545764)
		(width 0.1651)
		(layer "F.Cu")
		(net "M_DDR3_NODE1_ODT0")
	)
	(segment
		(start 66.55562 -61.162184)
		(end 64.987424 -62.73038)
		(width 0.1016)
		(layer "F.Cu")
		(net "M_DDR3_NODE1_ODT0")
	)
	(segment
		(start 66.045334 -57.23255)
		(end 66.973196 -57.23255)
		(width 0.1651)
		(layer "F.Cu")
		(net "M_DDR3_NODE1_ODT0")
	)
	(segment
		(start 80.651604 -42.891964)
		(end 80.4545 -43.089068)
		(width 0.1651)
		(layer "F.Cu")
		(net "M_DDR3_NODE1_ODT0")
	)
	(segment
		(start 80.556862 -38.730682)
		(end 80.556862 -39.32936)
		(width 0.1651)
		(layer "F.Cu")
		(net "M_DDR3_NODE1_ODT0")
	)
	(segment
		(start 80.445864 -33.226756)
		(end 80.24876 -33.42386)
		(width 0.1651)
		(layer "F.Cu")
		(net "M_DDR3_NODE1_ODT0")
	)
	(segment
		(start 66.045334 -56.30418)
		(end 65.7733 -56.576214)
		(width 0.1651)
		(layer "F.Cu")
		(net "M_DDR3_NODE1_ODT0")
	)
	(segment
		(start 81.473294 -33.931098)
		(end 81.704688 -34.162492)
		(width 0.1651)
		(layer "F.Cu")
		(net "M_DDR3_NODE1_ODT0")
	)
	(segment
		(start 80.808576 -46.257464)
		(end 80.99552 -46.444408)
		(width 0.1651)
		(layer "F.Cu")
		(net "M_DDR3_NODE1_ODT0")
	)
	(segment
		(start 80.4545 -43.36796)
		(end 80.651604 -43.565064)
		(width 0.1651)
		(layer "F.Cu")
		(net "M_DDR3_NODE1_ODT0")
	)
	(segment
		(start 80.808576 -41.545764)
		(end 80.638904 -41.545764)
		(width 0.1651)
		(layer "F.Cu")
		(net "M_DDR3_NODE1_ODT0")
	)
	(segment
		(start 81.00568 -41.069768)
		(end 81.00568 -41.34866)
		(width 0.1651)
		(layer "F.Cu")
		(net "M_DDR3_NODE1_ODT0")
	)
	(segment
		(start 81.6483 -36.035488)
		(end 81.6483 -36.411408)
		(width 0.1651)
		(layer "F.Cu")
		(net "M_DDR3_NODE1_ODT0")
	)
	(segment
		(start 81.04124 -33.226756)
		(end 80.445864 -33.226756)
		(width 0.1651)
		(layer "F.Cu")
		(net "M_DDR3_NODE1_ODT0")
	)
	(segment
		(start 80.623664 -44.238164)
		(end 80.42656 -44.435268)
		(width 0.1651)
		(layer "F.Cu")
		(net "M_DDR3_NODE1_ODT0")
	)
	(segment
		(start 67.863974 -56.55437)
		(end 67.613784 -56.30418)
		(width 0.1651)
		(layer "F.Cu")
		(net "M_DDR3_NODE1_ODT0")
	)
	(segment
		(start 65.7733 -56.576214)
		(end 65.7733 -56.960516)
		(width 0.1651)
		(layer "F.Cu")
		(net "M_DDR3_NODE1_ODT0")
	)
	(segment
		(start 70.536816 -56.97728)
		(end 70.73392 -57.174384)
		(width 0.1651)
		(layer "F.Cu")
		(net "M_DDR3_NODE1_ODT0")
	)
	(segment
		(start 81.704688 -34.162492)
		(end 81.704688 -34.744152)
		(width 0.1651)
		(layer "F.Cu")
		(net "M_DDR3_NODE1_ODT0")
	)
	(segment
		(start 80.638904 -42.218864)
		(end 80.808576 -42.218864)
		(width 0.1651)
		(layer "F.Cu")
		(net "M_DDR3_NODE1_ODT0")
	)
	(segment
		(start 81.704688 -34.744152)
		(end 81.35112 -35.09772)
		(width 0.1651)
		(layer "F.Cu")
		(net "M_DDR3_NODE1_ODT0")
	)
	(segment
		(start 80.808576 -43.565064)
		(end 81.00568 -43.762168)
		(width 0.1651)
		(layer "F.Cu")
		(net "M_DDR3_NODE1_ODT0")
	)
	(segment
		(start 80.677004 -40.199564)
		(end 80.4799 -40.396668)
		(width 0.1651)
		(layer "F.Cu")
		(net "M_DDR3_NODE1_ODT0")
	)
	(segment
		(start 81.47304 -47.894494)
		(end 80.824578 -48.542956)
		(width 0.1651)
		(layer "F.Cu")
		(net "M_DDR3_NODE1_ODT0")
	)
	(segment
		(start 80.677004 -40.872664)
		(end 80.808576 -40.872664)
		(width 0.1651)
		(layer "F.Cu")
		(net "M_DDR3_NODE1_ODT0")
	)
	(segment
		(start 68.60032 -56.501284)
		(end 68.60032 -56.780176)
		(width 0.1651)
		(layer "F.Cu")
		(net "M_DDR3_NODE1_ODT0")
	)
	(segment
		(start 80.4799 -40.67556)
		(end 80.677004 -40.872664)
		(width 0.1651)
		(layer "F.Cu")
		(net "M_DDR3_NODE1_ODT0")
	)
	(segment
		(start 80.250284 -29.149802)
		(end 80.24876 -29.149802)
		(width 0.1651)
		(layer "F.Cu")
		(net "M_DDR3_NODE1_ODT0")
	)
	(segment
		(start 80.556862 -39.32936)
		(end 80.753966 -39.526464)
		(width 0.1651)
		(layer "F.Cu")
		(net "M_DDR3_NODE1_ODT0")
	)
	(segment
		(start 81.35112 -37.936424)
		(end 80.556862 -38.730682)
		(width 0.1651)
		(layer "F.Cu")
		(net "M_DDR3_NODE1_ODT0")
	)
	(segment
		(start 80.24876 -32.356552)
		(end 80.371188 -32.47898)
		(width 0.1651)
		(layer "F.Cu")
		(net "M_DDR3_NODE1_ODT0")
	)
	(segment
		(start 64.987424 -63.595758)
		(end 65.290192 -63.898526)
		(width 0.1016)
		(layer "F.Cu")
		(net "M_DDR3_NODE1_ODT0")
	)
	(segment
		(start 80.808576 -44.911264)
		(end 81.00568 -45.108368)
		(width 0.1651)
		(layer "F.Cu")
		(net "M_DDR3_NODE1_ODT0")
	)
	(segment
		(start 80.428338 -33.931098)
		(end 81.473294 -33.931098)
		(width 0.1651)
		(layer "F.Cu")
		(net "M_DDR3_NODE1_ODT0")
	)
	(segment
		(start 80.24876 -33.75152)
		(end 80.428338 -33.931098)
		(width 0.1651)
		(layer "F.Cu")
		(net "M_DDR3_NODE1_ODT0")
	)
	(segment
		(start 80.43164 -46.06036)
		(end 80.628744 -46.257464)
		(width 0.1651)
		(layer "F.Cu")
		(net "M_DDR3_NODE1_ODT0")
	)
	(segment
		(start 81.04124 -32.47898)
		(end 81.24444 -32.68218)
		(width 0.1651)
		(layer "F.Cu")
		(net "M_DDR3_NODE1_ODT0")
	)
	(segment
		(start 81.24444 -33.023556)
		(end 81.04124 -33.226756)
		(width 0.1651)
		(layer "F.Cu")
		(net "M_DDR3_NODE1_ODT0")
	)
	(segment
		(start 67.863974 -57.453276)
		(end 67.863974 -56.55437)
		(width 0.1651)
		(layer "F.Cu")
		(net "M_DDR3_NODE1_ODT0")
	)
	(segment
		(start 80.808576 -39.526464)
		(end 81.00568 -39.723568)
		(width 0.1651)
		(layer "F.Cu")
		(net "M_DDR3_NODE1_ODT0")
	)
	(segment
		(start 67.613784 -56.30418)
		(end 66.045334 -56.30418)
		(width 0.1651)
		(layer "F.Cu")
		(net "M_DDR3_NODE1_ODT0")
	)
	(segment
		(start 80.638904 -41.545764)
		(end 80.4418 -41.742868)
		(width 0.1651)
		(layer "F.Cu")
		(net "M_DDR3_NODE1_ODT0")
	)
	(segment
		(start 66.55562 -61.056012)
		(end 66.55562 -61.162184)
		(width 0.1016)
		(layer "F.Cu")
		(net "M_DDR3_NODE1_ODT0")
	)
	(segment
		(start 80.808576 -40.872664)
		(end 81.00568 -41.069768)
		(width 0.1651)
		(layer "F.Cu")
		(net "M_DDR3_NODE1_ODT0")
	)
	(segment
		(start 80.4545 -43.089068)
		(end 80.4545 -43.36796)
		(width 0.1651)
		(layer "F.Cu")
		(net "M_DDR3_NODE1_ODT0")
	)
	(segment
		(start 80.808576 -44.238164)
		(end 80.623664 -44.238164)
		(width 0.1651)
		(layer "F.Cu")
		(net "M_DDR3_NODE1_ODT0")
	)
	(segment
		(start 81.00568 -44.04106)
		(end 80.808576 -44.238164)
		(width 0.1651)
		(layer "F.Cu")
		(net "M_DDR3_NODE1_ODT0")
	)
	(segment
		(start 81.6483 -36.411408)
		(end 81.35112 -36.708588)
		(width 0.1651)
		(layer "F.Cu")
		(net "M_DDR3_NODE1_ODT0")
	)
	(segment
		(start 81.00568 -39.723568)
		(end 81.00568 -40.00246)
		(width 0.1651)
		(layer "F.Cu")
		(net "M_DDR3_NODE1_ODT0")
	)
	(segment
		(start 64.987424 -62.73038)
		(end 64.987424 -63.595758)
		(width 0.1016)
		(layer "F.Cu")
		(net "M_DDR3_NODE1_ODT0")
	)
	(segment
		(start 68.60032 -56.780176)
		(end 68.797424 -56.97728)
		(width 0.1651)
		(layer "F.Cu")
		(net "M_DDR3_NODE1_ODT0")
	)
	(segment
		(start 80.808576 -42.218864)
		(end 81.00568 -42.415968)
		(width 0.1651)
		(layer "F.Cu")
		(net "M_DDR3_NODE1_ODT0")
	)
	(segment
		(start 81.00568 -45.108368)
		(end 81.00568 -45.38726)
		(width 0.1651)
		(layer "F.Cu")
		(net "M_DDR3_NODE1_ODT0")
	)
	(via
		(at 80.1624 -48.210978)
		(size 0.762)
		(drill 0.381)
		(layers "F.Cu" "B.Cu")
		(net "M_DDR3_NODE1_ODT0")
	)
	(via
		(at 76.081382 -100.090224)
		(size 0.508)
		(drill 0.254)
		(layers "F.Cu" "B.Cu")
		(net "FM_OSC_NODE1_OSC_NC")
	)
	(segment
		(start 57.74436 -137.257028)
		(end 57.025286 -137.257028)
		(width 0.1016)
		(layer "F.Cu")
		(net "BMC_NODE1_DDR_D10")
	)
	(segment
		(start 57.025286 -137.257028)
		(end 56.102504 -138.17981)
		(width 0.1016)
		(layer "F.Cu")
		(net "BMC_NODE1_DDR_D10")
	)
	(segment
		(start 44.660566 -140.96365)
		(end 43.983402 -140.286486)
		(width 0.1016)
		(layer "F.Cu")
		(net "BMC_NODE1_DDR_D10")
	)
	(segment
		(start 44.833032 -140.96365)
		(end 44.660566 -140.96365)
		(width 0.1016)
		(layer "F.Cu")
		(net "BMC_NODE1_DDR_D10")
	)
	(segment
		(start 56.102504 -138.17981)
		(end 55.608474 -138.17981)
		(width 0.1016)
		(layer "F.Cu")
		(net "BMC_NODE1_DDR_D10")
	)
	(segment
		(start 43.983402 -140.286486)
		(end 43.983402 -140.183362)
		(width 0.1016)
		(layer "F.Cu")
		(net "BMC_NODE1_DDR_D10")
	)
	(segment
		(start 55.608474 -138.17981)
		(end 55.562754 -138.13409)
		(width 0.1016)
		(layer "F.Cu")
		(net "BMC_NODE1_DDR_D10")
	)
	(segment
		(start 58.14187 -136.859518)
		(end 57.74436 -137.257028)
		(width 0.1016)
		(layer "F.Cu")
		(net "BMC_NODE1_DDR_D10")
	)
	(via
		(at 55.562754 -138.13409)
		(size 0.49022)
		(drill 0.254)
		(layers "F.Cu" "B.Cu")
		(net "BMC_NODE1_DDR_D10")
	)
	(via
		(at 43.983402 -140.183362)
		(size 0.508)
		(drill 0.254)
		(layers "F.Cu" "B.Cu")
		(net "BMC_NODE1_DDR_D10")
	)
	(segment
		(start 43.983402 -140.311378)
		(end 45.531532 -141.859508)
		(width 0.1143)
		(layer "In2.Cu")
		(net "BMC_NODE1_DDR_D10")
	)
	(segment
		(start 50.179224 -142.66291)
		(end 52.686712 -141.356334)
		(width 0.1143)
		(layer "In2.Cu")
		(net "BMC_NODE1_DDR_D10")
	)
	(segment
		(start 52.686712 -141.356334)
		(end 54.376574 -140.018008)
		(width 0.1143)
		(layer "In2.Cu")
		(net "BMC_NODE1_DDR_D10")
	)
	(segment
		(start 45.531532 -141.859508)
		(end 47.31258 -142.66291)
		(width 0.1143)
		(layer "In2.Cu")
		(net "BMC_NODE1_DDR_D10")
	)
	(segment
		(start 47.31258 -142.66291)
		(end 50.179224 -142.66291)
		(width 0.1143)
		(layer "In2.Cu")
		(net "BMC_NODE1_DDR_D10")
	)
	(segment
		(start 54.730396 -139.664186)
		(end 55.562754 -138.832082)
		(width 0.1143)
		(layer "In2.Cu")
		(net "BMC_NODE1_DDR_D10")
	)
	(segment
		(start 54.376574 -140.018008)
		(end 54.730396 -139.664186)
		(width 0.1143)
		(layer "In2.Cu")
		(net "BMC_NODE1_DDR_D10")
	)
	(segment
		(start 43.983402 -140.183362)
		(end 43.983402 -140.311378)
		(width 0.1143)
		(layer "In2.Cu")
		(net "BMC_NODE1_DDR_D10")
	)
	(segment
		(start 55.562754 -138.832082)
		(end 55.562754 -138.13409)
		(width 0.1143)
		(layer "In2.Cu")
		(net "BMC_NODE1_DDR_D10")
	)
	(segment
		(start 43.796204 -73.804526)
		(end 43.996864 -73.603866)
		(width 0.1143)
		(layer "F.Cu")
		(net "PD_CPU_NODE1_AL5")
	)
	(segment
		(start 43.996864 -73.603866)
		(end 44.109132 -73.603866)
		(width 0.1143)
		(layer "F.Cu")
		(net "PD_CPU_NODE1_AL5")
	)
	(segment
		(start 44.109132 -73.603866)
		(end 44.233592 -73.479406)
		(width 0.1143)
		(layer "F.Cu")
		(net "PD_CPU_NODE1_AL5")
	)
	(via
		(at 44.233592 -73.479406)
		(size 0.508)
		(drill 0.254)
		(layers "F.Cu" "B.Cu")
		(net "PD_CPU_NODE1_AL5")
	)
	(segment
		(start 42.951908 -73.494138)
		(end 44.233592 -73.479406)
		(width 0.1016)
		(layer "B.Cu")
		(net "PD_CPU_NODE1_AL5")
	)
	(segment
		(start 47.975774 -65.24498)
		(end 47.919132 -65.24498)
		(width 0.1016)
		(layer "F.Cu")
		(net "M1_DQ_NODE1_DQ2")
	)
	(segment
		(start 48.539146 -65.806828)
		(end 48.085502 -65.353184)
		(width 0.1016)
		(layer "F.Cu")
		(net "M1_DQ_NODE1_DQ2")
	)
	(segment
		(start 43.950128 -22.094952)
		(end 43.950128 -20.94992)
		(width 0.1651)
		(layer "F.Cu")
		(net "M1_DQ_NODE1_DQ2")
	)
	(segment
		(start 43.323002 -24.774652)
		(end 43.323002 -22.722078)
		(width 0.1651)
		(layer "F.Cu")
		(net "M1_DQ_NODE1_DQ2")
	)
	(segment
		(start 43.323002 -22.722078)
		(end 43.950128 -22.094952)
		(width 0.1651)
		(layer "F.Cu")
		(net "M1_DQ_NODE1_DQ2")
	)
	(segment
		(start 42.8879 -25.209754)
		(end 43.323002 -24.774652)
		(width 0.1651)
		(layer "F.Cu")
		(net "M1_DQ_NODE1_DQ2")
	)
	(segment
		(start 48.539146 -65.836038)
		(end 48.539146 -65.806828)
		(width 0.1016)
		(layer "F.Cu")
		(net "M1_DQ_NODE1_DQ2")
	)
	(segment
		(start 48.085502 -65.353184)
		(end 48.083978 -65.353184)
		(width 0.1016)
		(layer "F.Cu")
		(net "M1_DQ_NODE1_DQ2")
	)
	(segment
		(start 48.083978 -65.353184)
		(end 47.975774 -65.24498)
		(width 0.1016)
		(layer "F.Cu")
		(net "M1_DQ_NODE1_DQ2")
	)
	(via
		(at 47.919132 -65.24498)
		(size 0.508)
		(drill 0.254)
		(layers "F.Cu" "B.Cu")
		(net "M1_DQ_NODE1_DQ2")
	)
	(via
		(at 42.8879 -25.209754)
		(size 0.508)
		(drill 0.254)
		(layers "F.Cu" "B.Cu")
		(net "M1_DQ_NODE1_DQ2")
	)
	(segment
		(start 35.319716 -30.030928)
		(end 35.625024 -30.030928)
		(width 0.2032)
		(layer "In7.Cu")
		(net "M1_DQ_NODE1_DQ2")
	)
	(segment
		(start 47.919132 -65.24498)
		(end 47.83074 -65.24498)
		(width 0.1016)
		(layer "In7.Cu")
		(net "M1_DQ_NODE1_DQ2")
	)
	(segment
		(start 39.52367 -29.495242)
		(end 39.52367 -29.815282)
		(width 0.2032)
		(layer "In7.Cu")
		(net "M1_DQ_NODE1_DQ2")
	)
	(segment
		(start 37.834824 -29.279596)
		(end 38.05047 -29.495242)
		(width 0.2032)
		(layer "In7.Cu")
		(net "M1_DQ_NODE1_DQ2")
	)
	(segment
		(start 35.10407 -29.815282)
		(end 35.319716 -30.030928)
		(width 0.2032)
		(layer "In7.Cu")
		(net "M1_DQ_NODE1_DQ2")
	)
	(segment
		(start 34.36747 -29.495242)
		(end 34.583116 -29.279596)
		(width 0.2032)
		(layer "In7.Cu")
		(net "M1_DQ_NODE1_DQ2")
	)
	(segment
		(start 42.09542 -26.643584)
		(end 42.49674 -26.242264)
		(width 0.2032)
		(layer "In7.Cu")
		(net "M1_DQ_NODE1_DQ2")
	)
	(segment
		(start 39.308024 -29.279596)
		(end 39.52367 -29.495242)
		(width 0.2032)
		(layer "In7.Cu")
		(net "M1_DQ_NODE1_DQ2")
	)
	(segment
		(start 46.817026 -64.67729)
		(end 46.060614 -63.920878)
		(width 0.1016)
		(layer "In7.Cu")
		(net "M1_DQ_NODE1_DQ2")
	)
	(segment
		(start 37.31387 -29.495242)
		(end 37.529516 -29.279596)
		(width 0.2032)
		(layer "In7.Cu")
		(net "M1_DQ_NODE1_DQ2")
	)
	(segment
		(start 42.74058 -61.360304)
		(end 42.131996 -61.360304)
		(width 0.1016)
		(layer "In7.Cu")
		(net "M1_DQ_NODE1_DQ2")
	)
	(segment
		(start 42.49674 -25.600914)
		(end 42.8879 -25.209754)
		(width 0.2032)
		(layer "In7.Cu")
		(net "M1_DQ_NODE1_DQ2")
	)
	(segment
		(start 35.625024 -30.030928)
		(end 35.84067 -29.815282)
		(width 0.2032)
		(layer "In7.Cu")
		(net "M1_DQ_NODE1_DQ2")
	)
	(segment
		(start 34.888424 -29.279596)
		(end 35.10407 -29.495242)
		(width 0.2032)
		(layer "In7.Cu")
		(net "M1_DQ_NODE1_DQ2")
	)
	(segment
		(start 38.78707 -29.495242)
		(end 39.002716 -29.279596)
		(width 0.2032)
		(layer "In7.Cu")
		(net "M1_DQ_NODE1_DQ2")
	)
	(segment
		(start 39.52367 -29.815282)
		(end 39.739316 -30.030928)
		(width 0.2032)
		(layer "In7.Cu")
		(net "M1_DQ_NODE1_DQ2")
	)
	(segment
		(start 36.361624 -29.279596)
		(end 36.57727 -29.495242)
		(width 0.2032)
		(layer "In7.Cu")
		(net "M1_DQ_NODE1_DQ2")
	)
	(segment
		(start 41.29024 -60.744608)
		(end 39.984426 -59.438794)
		(width 0.2032)
		(layer "In7.Cu")
		(net "M1_DQ_NODE1_DQ2")
	)
	(segment
		(start 40.310816 -30.030928)
		(end 42.09542 -28.246324)
		(width 0.2032)
		(layer "In7.Cu")
		(net "M1_DQ_NODE1_DQ2")
	)
	(segment
		(start 34.151824 -30.030928)
		(end 34.36747 -29.815282)
		(width 0.2032)
		(layer "In7.Cu")
		(net "M1_DQ_NODE1_DQ2")
	)
	(segment
		(start 37.31387 -29.815282)
		(end 37.31387 -29.495242)
		(width 0.2032)
		(layer "In7.Cu")
		(net "M1_DQ_NODE1_DQ2")
	)
	(segment
		(start 36.056316 -29.279596)
		(end 36.361624 -29.279596)
		(width 0.2032)
		(layer "In7.Cu")
		(net "M1_DQ_NODE1_DQ2")
	)
	(segment
		(start 39.002716 -29.279596)
		(end 39.308024 -29.279596)
		(width 0.2032)
		(layer "In7.Cu")
		(net "M1_DQ_NODE1_DQ2")
	)
	(segment
		(start 34.583116 -29.279596)
		(end 34.888424 -29.279596)
		(width 0.2032)
		(layer "In7.Cu")
		(net "M1_DQ_NODE1_DQ2")
	)
	(segment
		(start 36.792916 -30.030928)
		(end 37.098224 -30.030928)
		(width 0.2032)
		(layer "In7.Cu")
		(net "M1_DQ_NODE1_DQ2")
	)
	(segment
		(start 31.57728 -54.43728)
		(end 31.57728 -31.933134)
		(width 0.2032)
		(layer "In7.Cu")
		(net "M1_DQ_NODE1_DQ2")
	)
	(segment
		(start 44.681648 -63.920878)
		(end 43.031664 -62.270894)
		(width 0.1016)
		(layer "In7.Cu")
		(net "M1_DQ_NODE1_DQ2")
	)
	(segment
		(start 38.05047 -29.495242)
		(end 38.05047 -29.815282)
		(width 0.2032)
		(layer "In7.Cu")
		(net "M1_DQ_NODE1_DQ2")
	)
	(segment
		(start 39.739316 -30.030928)
		(end 40.310816 -30.030928)
		(width 0.2032)
		(layer "In7.Cu")
		(net "M1_DQ_NODE1_DQ2")
	)
	(segment
		(start 38.571424 -30.030928)
		(end 38.78707 -29.815282)
		(width 0.2032)
		(layer "In7.Cu")
		(net "M1_DQ_NODE1_DQ2")
	)
	(segment
		(start 43.031664 -61.651388)
		(end 42.74058 -61.360304)
		(width 0.1016)
		(layer "In7.Cu")
		(net "M1_DQ_NODE1_DQ2")
	)
	(segment
		(start 33.479486 -30.030928)
		(end 34.151824 -30.030928)
		(width 0.2032)
		(layer "In7.Cu")
		(net "M1_DQ_NODE1_DQ2")
	)
	(segment
		(start 38.05047 -29.815282)
		(end 38.266116 -30.030928)
		(width 0.2032)
		(layer "In7.Cu")
		(net "M1_DQ_NODE1_DQ2")
	)
	(segment
		(start 42.49674 -26.242264)
		(end 42.49674 -25.600914)
		(width 0.2032)
		(layer "In7.Cu")
		(net "M1_DQ_NODE1_DQ2")
	)
	(segment
		(start 31.57728 -31.933134)
		(end 33.479486 -30.030928)
		(width 0.2032)
		(layer "In7.Cu")
		(net "M1_DQ_NODE1_DQ2")
	)
	(segment
		(start 38.266116 -30.030928)
		(end 38.571424 -30.030928)
		(width 0.2032)
		(layer "In7.Cu")
		(net "M1_DQ_NODE1_DQ2")
	)
	(segment
		(start 35.84067 -29.495242)
		(end 36.056316 -29.279596)
		(width 0.2032)
		(layer "In7.Cu")
		(net "M1_DQ_NODE1_DQ2")
	)
	(segment
		(start 41.5163 -60.744608)
		(end 41.29024 -60.744608)
		(width 0.2032)
		(layer "In7.Cu")
		(net "M1_DQ_NODE1_DQ2")
	)
	(segment
		(start 42.09542 -28.246324)
		(end 42.09542 -26.643584)
		(width 0.2032)
		(layer "In7.Cu")
		(net "M1_DQ_NODE1_DQ2")
	)
	(segment
		(start 39.984426 -59.438794)
		(end 36.578794 -59.438794)
		(width 0.2032)
		(layer "In7.Cu")
		(net "M1_DQ_NODE1_DQ2")
	)
	(segment
		(start 42.131996 -61.360304)
		(end 41.5163 -60.744608)
		(width 0.1016)
		(layer "In7.Cu")
		(net "M1_DQ_NODE1_DQ2")
	)
	(segment
		(start 47.26305 -64.67729)
		(end 46.817026 -64.67729)
		(width 0.1016)
		(layer "In7.Cu")
		(net "M1_DQ_NODE1_DQ2")
	)
	(segment
		(start 34.36747 -29.815282)
		(end 34.36747 -29.495242)
		(width 0.2032)
		(layer "In7.Cu")
		(net "M1_DQ_NODE1_DQ2")
	)
	(segment
		(start 35.84067 -29.815282)
		(end 35.84067 -29.495242)
		(width 0.2032)
		(layer "In7.Cu")
		(net "M1_DQ_NODE1_DQ2")
	)
	(segment
		(start 36.57727 -29.495242)
		(end 36.57727 -29.815282)
		(width 0.2032)
		(layer "In7.Cu")
		(net "M1_DQ_NODE1_DQ2")
	)
	(segment
		(start 36.578794 -59.438794)
		(end 31.57728 -54.43728)
		(width 0.2032)
		(layer "In7.Cu")
		(net "M1_DQ_NODE1_DQ2")
	)
	(segment
		(start 37.098224 -30.030928)
		(end 37.31387 -29.815282)
		(width 0.2032)
		(layer "In7.Cu")
		(net "M1_DQ_NODE1_DQ2")
	)
	(segment
		(start 36.57727 -29.815282)
		(end 36.792916 -30.030928)
		(width 0.2032)
		(layer "In7.Cu")
		(net "M1_DQ_NODE1_DQ2")
	)
	(segment
		(start 43.031664 -62.270894)
		(end 43.031664 -61.651388)
		(width 0.1016)
		(layer "In7.Cu")
		(net "M1_DQ_NODE1_DQ2")
	)
	(segment
		(start 47.83074 -65.24498)
		(end 47.26305 -64.67729)
		(width 0.1016)
		(layer "In7.Cu")
		(net "M1_DQ_NODE1_DQ2")
	)
	(segment
		(start 35.10407 -29.495242)
		(end 35.10407 -29.815282)
		(width 0.2032)
		(layer "In7.Cu")
		(net "M1_DQ_NODE1_DQ2")
	)
	(segment
		(start 46.060614 -63.920878)
		(end 44.681648 -63.920878)
		(width 0.1016)
		(layer "In7.Cu")
		(net "M1_DQ_NODE1_DQ2")
	)
	(segment
		(start 37.529516 -29.279596)
		(end 37.834824 -29.279596)
		(width 0.2032)
		(layer "In7.Cu")
		(net "M1_DQ_NODE1_DQ2")
	)
	(segment
		(start 38.78707 -29.815282)
		(end 38.78707 -29.495242)
		(width 0.2032)
		(layer "In7.Cu")
		(net "M1_DQ_NODE1_DQ2")
	)
	(segment
		(start 44.432728 -138.964924)
		(end 44.43222 -138.964924)
		(width 0.1016)
		(layer "F.Cu")
		(net "BMC_NODE1_DDR_D8")
	)
	(segment
		(start 60.541916 -136.059418)
		(end 60.53963 -136.059418)
		(width 0.1016)
		(layer "F.Cu")
		(net "BMC_NODE1_DDR_D8")
	)
	(segment
		(start 44.833032 -138.563604)
		(end 44.833032 -138.56462)
		(width 0.1016)
		(layer "F.Cu")
		(net "BMC_NODE1_DDR_D8")
	)
	(segment
		(start 44.833032 -138.56462)
		(end 44.432728 -138.964924)
		(width 0.1016)
		(layer "F.Cu")
		(net "BMC_NODE1_DDR_D8")
	)
	(segment
		(start 60.53963 -136.059418)
		(end 60.141104 -136.457944)
		(width 0.1016)
		(layer "F.Cu")
		(net "BMC_NODE1_DDR_D8")
	)
	(via
		(at 44.43222 -138.964924)
		(size 0.508)
		(drill 0.254)
		(layers "F.Cu" "B.Cu")
		(net "BMC_NODE1_DDR_D8")
	)
	(via
		(at 60.141104 -136.457944)
		(size 0.49022)
		(drill 0.254)
		(layers "F.Cu" "B.Cu")
		(net "BMC_NODE1_DDR_D8")
	)
	(segment
		(start 57.8358 -136.058148)
		(end 58.475626 -136.058148)
		(width 0.1143)
		(layer "In2.Cu")
		(net "BMC_NODE1_DDR_D8")
	)
	(segment
		(start 58.475626 -136.058148)
		(end 58.765694 -136.058148)
		(width 0.1016)
		(layer "In2.Cu")
		(net "BMC_NODE1_DDR_D8")
	)
	(segment
		(start 53.627782 -138.106912)
		(end 54.878478 -136.856216)
		(width 0.1143)
		(layer "In2.Cu")
		(net "BMC_NODE1_DDR_D8")
	)
	(segment
		(start 49.72812 -138.106912)
		(end 53.627782 -138.106912)
		(width 0.1143)
		(layer "In2.Cu")
		(net "BMC_NODE1_DDR_D8")
	)
	(segment
		(start 57.037732 -136.856216)
		(end 57.8358 -136.058148)
		(width 0.1143)
		(layer "In2.Cu")
		(net "BMC_NODE1_DDR_D8")
	)
	(segment
		(start 44.43222 -138.964924)
		(end 43.309286 -137.84199)
		(width 0.1143)
		(layer "In2.Cu")
		(net "BMC_NODE1_DDR_D8")
	)
	(segment
		(start 59.741308 -136.058148)
		(end 60.141104 -136.457944)
		(width 0.1143)
		(layer "In2.Cu")
		(net "BMC_NODE1_DDR_D8")
	)
	(segment
		(start 43.309286 -137.84199)
		(end 43.309286 -137.453878)
		(width 0.1143)
		(layer "In2.Cu")
		(net "BMC_NODE1_DDR_D8")
	)
	(segment
		(start 58.765694 -136.058148)
		(end 59.24169 -136.058148)
		(width 0.1143)
		(layer "In2.Cu")
		(net "BMC_NODE1_DDR_D8")
	)
	(segment
		(start 54.878478 -136.856216)
		(end 57.037732 -136.856216)
		(width 0.1143)
		(layer "In2.Cu")
		(net "BMC_NODE1_DDR_D8")
	)
	(segment
		(start 43.309286 -137.453878)
		(end 43.68038 -137.082784)
		(width 0.1143)
		(layer "In2.Cu")
		(net "BMC_NODE1_DDR_D8")
	)
	(segment
		(start 59.517026 -136.058148)
		(end 59.741308 -136.058148)
		(width 0.1143)
		(layer "In2.Cu")
		(net "BMC_NODE1_DDR_D8")
	)
	(segment
		(start 43.68038 -137.082784)
		(end 48.703992 -137.082784)
		(width 0.1143)
		(layer "In2.Cu")
		(net "BMC_NODE1_DDR_D8")
	)
	(segment
		(start 59.24169 -136.058148)
		(end 59.517026 -136.058148)
		(width 0.1016)
		(layer "In2.Cu")
		(net "BMC_NODE1_DDR_D8")
	)
	(segment
		(start 48.703992 -137.082784)
		(end 49.72812 -138.106912)
		(width 0.1143)
		(layer "In2.Cu")
		(net "BMC_NODE1_DDR_D8")
	)
	(segment
		(start 101.606604 -133.119114)
		(end 101.193092 -133.119114)
		(width 0.1016)
		(layer "F.Cu")
		(net "SVID_CPU_NODE1_PVCCP_CLK")
	)
	(segment
		(start 101.558598 -132.369052)
		(end 101.461316 -132.466334)
		(width 0.1016)
		(layer "F.Cu")
		(net "SVID_CPU_NODE1_PVCCP_CLK")
	)
	(segment
		(start 101.558598 -131.939538)
		(end 101.558598 -132.369052)
		(width 0.1016)
		(layer "F.Cu")
		(net "SVID_CPU_NODE1_PVCCP_CLK")
	)
	(segment
		(start 101.193092 -133.119114)
		(end 100.725732 -132.651754)
		(width 0.1016)
		(layer "F.Cu")
		(net "SVID_CPU_NODE1_PVCCP_CLK")
	)
	(segment
		(start 101.461316 -132.466334)
		(end 100.911152 -132.466334)
		(width 0.1016)
		(layer "F.Cu")
		(net "SVID_CPU_NODE1_PVCCP_CLK")
	)
	(segment
		(start 71.997824 -78.287118)
		(end 71.713598 -78.287118)
		(width 0.1016)
		(layer "F.Cu")
		(net "SVID_CPU_NODE1_PVCCP_CLK")
	)
	(segment
		(start 100.911152 -132.466334)
		(end 100.725732 -132.651754)
		(width 0.1016)
		(layer "F.Cu")
		(net "SVID_CPU_NODE1_PVCCP_CLK")
	)
	(segment
		(start 72.205088 -78.494382)
		(end 71.997824 -78.287118)
		(width 0.1016)
		(layer "F.Cu")
		(net "SVID_CPU_NODE1_PVCCP_CLK")
	)
	(via
		(at 100.725732 -132.651754)
		(size 0.508)
		(drill 0.254)
		(layers "F.Cu" "B.Cu")
		(net "SVID_CPU_NODE1_PVCCP_CLK")
	)
	(via
		(at 71.713598 -78.287118)
		(size 0.508)
		(drill 0.254)
		(layers "F.Cu" "B.Cu")
		(net "SVID_CPU_NODE1_PVCCP_CLK")
	)
	(segment
		(start 100.725732 -132.362956)
		(end 100.725732 -132.651754)
		(width 0.1016)
		(layer "B.Cu")
		(net "SVID_CPU_NODE1_PVCCP_CLK")
	)
	(segment
		(start 94.75216 -85.753194)
		(end 94.75216 -90.743786)
		(width 0.1016)
		(layer "B.Cu")
		(net "SVID_CPU_NODE1_PVCCP_CLK")
	)
	(segment
		(start 100.07346 -131.710684)
		(end 100.725732 -132.362956)
		(width 0.1016)
		(layer "B.Cu")
		(net "SVID_CPU_NODE1_PVCCP_CLK")
	)
	(segment
		(start 82.111342 -78.990698)
		(end 82.533744 -79.4131)
		(width 0.1016)
		(layer "B.Cu")
		(net "SVID_CPU_NODE1_PVCCP_CLK")
	)
	(segment
		(start 100.095304 -119.414798)
		(end 100.095304 -119.837962)
		(width 0.1016)
		(layer "B.Cu")
		(net "SVID_CPU_NODE1_PVCCP_CLK")
	)
	(segment
		(start 78.655164 -78.990698)
		(end 82.111342 -78.990698)
		(width 0.1016)
		(layer "B.Cu")
		(net "SVID_CPU_NODE1_PVCCP_CLK")
	)
	(segment
		(start 91.53779 -82.538824)
		(end 94.75216 -85.753194)
		(width 0.1016)
		(layer "B.Cu")
		(net "SVID_CPU_NODE1_PVCCP_CLK")
	)
	(segment
		(start 94.75216 -90.743786)
		(end 97.68332 -93.674946)
		(width 0.1016)
		(layer "B.Cu")
		(net "SVID_CPU_NODE1_PVCCP_CLK")
	)
	(segment
		(start 71.797164 -78.287118)
		(end 72.187308 -78.677262)
		(width 0.1016)
		(layer "B.Cu")
		(net "SVID_CPU_NODE1_PVCCP_CLK")
	)
	(segment
		(start 71.713598 -78.287118)
		(end 71.797164 -78.287118)
		(width 0.1016)
		(layer "B.Cu")
		(net "SVID_CPU_NODE1_PVCCP_CLK")
	)
	(segment
		(start 83.689698 -81.637124)
		(end 87.401908 -81.637124)
		(width 0.1016)
		(layer "B.Cu")
		(net "SVID_CPU_NODE1_PVCCP_CLK")
	)
	(segment
		(start 78.239874 -79.405988)
		(end 78.655164 -78.990698)
		(width 0.1016)
		(layer "B.Cu")
		(net "SVID_CPU_NODE1_PVCCP_CLK")
	)
	(segment
		(start 88.303608 -82.538824)
		(end 91.53779 -82.538824)
		(width 0.1016)
		(layer "B.Cu")
		(net "SVID_CPU_NODE1_PVCCP_CLK")
	)
	(segment
		(start 97.68332 -103.986076)
		(end 98.91014 -105.212896)
		(width 0.1016)
		(layer "B.Cu")
		(net "SVID_CPU_NODE1_PVCCP_CLK")
	)
	(segment
		(start 98.91014 -105.212896)
		(end 98.91014 -118.229634)
		(width 0.1016)
		(layer "B.Cu")
		(net "SVID_CPU_NODE1_PVCCP_CLK")
	)
	(segment
		(start 82.533744 -80.48117)
		(end 83.689698 -81.637124)
		(width 0.1016)
		(layer "B.Cu")
		(net "SVID_CPU_NODE1_PVCCP_CLK")
	)
	(segment
		(start 82.533744 -79.4131)
		(end 82.533744 -80.48117)
		(width 0.1016)
		(layer "B.Cu")
		(net "SVID_CPU_NODE1_PVCCP_CLK")
	)
	(segment
		(start 100.07346 -119.859806)
		(end 100.07346 -131.710684)
		(width 0.1016)
		(layer "B.Cu")
		(net "SVID_CPU_NODE1_PVCCP_CLK")
	)
	(segment
		(start 97.68332 -93.674946)
		(end 97.68332 -103.986076)
		(width 0.1016)
		(layer "B.Cu")
		(net "SVID_CPU_NODE1_PVCCP_CLK")
	)
	(segment
		(start 98.91014 -118.229634)
		(end 100.095304 -119.414798)
		(width 0.1016)
		(layer "B.Cu")
		(net "SVID_CPU_NODE1_PVCCP_CLK")
	)
	(segment
		(start 72.187308 -78.677262)
		(end 73.319132 -78.677262)
		(width 0.1016)
		(layer "B.Cu")
		(net "SVID_CPU_NODE1_PVCCP_CLK")
	)
	(segment
		(start 100.095304 -119.837962)
		(end 100.07346 -119.859806)
		(width 0.1016)
		(layer "B.Cu")
		(net "SVID_CPU_NODE1_PVCCP_CLK")
	)
	(segment
		(start 73.319132 -78.677262)
		(end 74.047858 -79.405988)
		(width 0.1016)
		(layer "B.Cu")
		(net "SVID_CPU_NODE1_PVCCP_CLK")
	)
	(segment
		(start 74.047858 -79.405988)
		(end 78.239874 -79.405988)
		(width 0.1016)
		(layer "B.Cu")
		(net "SVID_CPU_NODE1_PVCCP_CLK")
	)
	(segment
		(start 87.401908 -81.637124)
		(end 88.303608 -82.538824)
		(width 0.1016)
		(layer "B.Cu")
		(net "SVID_CPU_NODE1_PVCCP_CLK")
	)
	(segment
		(start 97.050098 -29.149802)
		(end 97.049082 -29.149802)
		(width 0.1651)
		(layer "F.Cu")
		(net "M1_DQ_NODE1_DQ61")
	)
	(segment
		(start 73.752202 -72.605646)
		(end 73.752202 -72.664828)
		(width 0.1016)
		(layer "F.Cu")
		(net "M1_DQ_NODE1_DQ61")
	)
	(segment
		(start 73.226422 -72.079866)
		(end 73.752202 -72.605646)
		(width 0.1016)
		(layer "F.Cu")
		(net "M1_DQ_NODE1_DQ61")
	)
	(segment
		(start 97.049082 -29.149802)
		(end 97.049082 -26.326338)
		(width 0.1651)
		(layer "F.Cu")
		(net "M1_DQ_NODE1_DQ61")
	)
	(segment
		(start 97.049082 -26.326338)
		(end 97.050098 -26.326338)
		(width 0.1651)
		(layer "F.Cu")
		(net "M1_DQ_NODE1_DQ61")
	)
	(segment
		(start 72.752204 -72.079866)
		(end 73.226422 -72.079866)
		(width 0.1016)
		(layer "F.Cu")
		(net "M1_DQ_NODE1_DQ61")
	)
	(via
		(at 97.050098 -26.326338)
		(size 0.508)
		(drill 0.254)
		(layers "F.Cu" "B.Cu")
		(net "M1_DQ_NODE1_DQ61")
	)
	(via
		(at 73.752202 -72.664828)
		(size 0.508)
		(drill 0.254)
		(layers "F.Cu" "B.Cu")
		(net "M1_DQ_NODE1_DQ61")
	)
	(segment
		(start 82.55889 -64.62268)
		(end 82.76717 -64.83096)
		(width 0.2032)
		(layer "In7.Cu")
		(net "M1_DQ_NODE1_DQ61")
	)
	(segment
		(start 89.731342 -54.471062)
		(end 89.43721 -54.471062)
		(width 0.2032)
		(layer "In7.Cu")
		(net "M1_DQ_NODE1_DQ61")
	)
	(segment
		(start 77.598778 -68.43776)
		(end 76.57973 -69.456808)
		(width 0.2032)
		(layer "In7.Cu")
		(net "M1_DQ_NODE1_DQ61")
	)
	(segment
		(start 74.200512 -72.216518)
		(end 73.752202 -72.664828)
		(width 0.2032)
		(layer "In7.Cu")
		(net "M1_DQ_NODE1_DQ61")
	)
	(segment
		(start 83.04276 -65.54216)
		(end 82.76717 -65.54216)
		(width 0.2032)
		(layer "In7.Cu")
		(net "M1_DQ_NODE1_DQ61")
	)
	(segment
		(start 97.050098 -26.326338)
		(end 97.050098 -26.825702)
		(width 0.2032)
		(layer "In7.Cu")
		(net "M1_DQ_NODE1_DQ61")
	)
	(segment
		(start 97.052638 -26.828242)
		(end 97.054162 -26.828242)
		(width 0.2032)
		(layer "In7.Cu")
		(net "M1_DQ_NODE1_DQ61")
	)
	(segment
		(start 97.6122 -34.857436)
		(end 97.6122 -46.295818)
		(width 0.2032)
		(layer "In7.Cu")
		(net "M1_DQ_NODE1_DQ61")
	)
	(segment
		(start 75.921616 -69.456808)
		(end 75.69454 -69.683884)
		(width 0.2032)
		(layer "In7.Cu")
		(net "M1_DQ_NODE1_DQ61")
	)
	(segment
		(start 90.70848 -53.199538)
		(end 90.709242 -53.2003)
		(width 0.2032)
		(layer "In7.Cu")
		(net "M1_DQ_NODE1_DQ61")
	)
	(segment
		(start 97.318322 -30.176978)
		(end 97.318322 -34.563558)
		(width 0.2032)
		(layer "In7.Cu")
		(net "M1_DQ_NODE1_DQ61")
	)
	(segment
		(start 90.709242 -53.2003)
		(end 90.709242 -55.210964)
		(width 0.2032)
		(layer "In7.Cu")
		(net "M1_DQ_NODE1_DQ61")
	)
	(segment
		(start 76.57973 -69.456808)
		(end 75.921616 -69.456808)
		(width 0.2032)
		(layer "In7.Cu")
		(net "M1_DQ_NODE1_DQ61")
	)
	(segment
		(start 82.55889 -66.811906)
		(end 80.933036 -68.43776)
		(width 0.2032)
		(layer "In7.Cu")
		(net "M1_DQ_NODE1_DQ61")
	)
	(segment
		(start 75.69454 -69.683884)
		(end 75.69454 -70.054724)
		(width 0.2032)
		(layer "In7.Cu")
		(net "M1_DQ_NODE1_DQ61")
	)
	(segment
		(start 85.156802 -60.469018)
		(end 84.948268 -60.260484)
		(width 0.2032)
		(layer "In7.Cu")
		(net "M1_DQ_NODE1_DQ61")
	)
	(segment
		(start 82.55889 -65.75044)
		(end 82.55889 -66.811906)
		(width 0.2032)
		(layer "In7.Cu")
		(net "M1_DQ_NODE1_DQ61")
	)
	(segment
		(start 74.200512 -70.692772)
		(end 74.200512 -72.216518)
		(width 0.2032)
		(layer "In7.Cu")
		(net "M1_DQ_NODE1_DQ61")
	)
	(segment
		(start 89.939876 -54.974236)
		(end 89.939876 -54.679596)
		(width 0.2032)
		(layer "In7.Cu")
		(net "M1_DQ_NODE1_DQ61")
	)
	(segment
		(start 84.948268 -60.260484)
		(end 84.948268 -59.965844)
		(width 0.2032)
		(layer "In7.Cu")
		(net "M1_DQ_NODE1_DQ61")
	)
	(segment
		(start 85.451188 -60.469018)
		(end 85.156802 -60.469018)
		(width 0.2032)
		(layer "In7.Cu")
		(net "M1_DQ_NODE1_DQ61")
	)
	(segment
		(start 89.43721 -54.471062)
		(end 82.55889 -61.349128)
		(width 0.2032)
		(layer "In7.Cu")
		(net "M1_DQ_NODE1_DQ61")
	)
	(segment
		(start 83.25104 -65.33388)
		(end 83.04276 -65.54216)
		(width 0.2032)
		(layer "In7.Cu")
		(net "M1_DQ_NODE1_DQ61")
	)
	(segment
		(start 82.55889 -61.349128)
		(end 82.55889 -64.62268)
		(width 0.2032)
		(layer "In7.Cu")
		(net "M1_DQ_NODE1_DQ61")
	)
	(segment
		(start 97.087182 -26.861262)
		(end 97.087182 -29.945838)
		(width 0.2032)
		(layer "In7.Cu")
		(net "M1_DQ_NODE1_DQ61")
	)
	(segment
		(start 75.25258 -70.496684)
		(end 74.3966 -70.496684)
		(width 0.2032)
		(layer "In7.Cu")
		(net "M1_DQ_NODE1_DQ61")
	)
	(segment
		(start 82.76717 -64.83096)
		(end 83.04276 -64.83096)
		(width 0.2032)
		(layer "In7.Cu")
		(net "M1_DQ_NODE1_DQ61")
	)
	(segment
		(start 90.709242 -55.210964)
		(end 85.451188 -60.469018)
		(width 0.2032)
		(layer "In7.Cu")
		(net "M1_DQ_NODE1_DQ61")
	)
	(segment
		(start 75.69454 -70.054724)
		(end 75.25258 -70.496684)
		(width 0.2032)
		(layer "In7.Cu")
		(net "M1_DQ_NODE1_DQ61")
	)
	(segment
		(start 97.318322 -34.563558)
		(end 97.6122 -34.857436)
		(width 0.2032)
		(layer "In7.Cu")
		(net "M1_DQ_NODE1_DQ61")
	)
	(segment
		(start 80.933036 -68.43776)
		(end 77.598778 -68.43776)
		(width 0.2032)
		(layer "In7.Cu")
		(net "M1_DQ_NODE1_DQ61")
	)
	(segment
		(start 82.76717 -65.54216)
		(end 82.55889 -65.75044)
		(width 0.2032)
		(layer "In7.Cu")
		(net "M1_DQ_NODE1_DQ61")
	)
	(segment
		(start 74.3966 -70.496684)
		(end 74.200512 -70.692772)
		(width 0.2032)
		(layer "In7.Cu")
		(net "M1_DQ_NODE1_DQ61")
	)
	(segment
		(start 97.087182 -29.945838)
		(end 97.318322 -30.176978)
		(width 0.2032)
		(layer "In7.Cu")
		(net "M1_DQ_NODE1_DQ61")
	)
	(segment
		(start 89.939876 -54.679596)
		(end 89.731342 -54.471062)
		(width 0.2032)
		(layer "In7.Cu")
		(net "M1_DQ_NODE1_DQ61")
	)
	(segment
		(start 97.054162 -26.828242)
		(end 97.087182 -26.861262)
		(width 0.2032)
		(layer "In7.Cu")
		(net "M1_DQ_NODE1_DQ61")
	)
	(segment
		(start 84.948268 -59.965844)
		(end 89.939876 -54.974236)
		(width 0.2032)
		(layer "In7.Cu")
		(net "M1_DQ_NODE1_DQ61")
	)
	(segment
		(start 97.6122 -46.295818)
		(end 90.70848 -53.199538)
		(width 0.2032)
		(layer "In7.Cu")
		(net "M1_DQ_NODE1_DQ61")
	)
	(segment
		(start 97.050098 -26.825702)
		(end 97.052638 -26.828242)
		(width 0.2032)
		(layer "In7.Cu")
		(net "M1_DQ_NODE1_DQ61")
	)
	(segment
		(start 83.04276 -64.83096)
		(end 83.25104 -65.03924)
		(width 0.2032)
		(layer "In7.Cu")
		(net "M1_DQ_NODE1_DQ61")
	)
	(segment
		(start 83.25104 -65.03924)
		(end 83.25104 -65.33388)
		(width 0.2032)
		(layer "In7.Cu")
		(net "M1_DQ_NODE1_DQ61")
	)
	(segment
		(start 160.949894 -124.02058)
		(end 161.261298 -124.02058)
		(width 0.1016)
		(layer "F.Cu")
		(net "PWRGD_NODE1_DDR3_DRAM_POK")
	)
	(segment
		(start 160.12668 -124.843794)
		(end 160.949894 -124.02058)
		(width 0.1016)
		(layer "F.Cu")
		(net "PWRGD_NODE1_DDR3_DRAM_POK")
	)
	(segment
		(start 62.443106 -65.455038)
		(end 62.809374 -65.821306)
		(width 0.1016)
		(layer "F.Cu")
		(net "PWRGD_NODE1_DDR3_DRAM_POK")
	)
	(segment
		(start 62.809374 -65.821306)
		(end 62.836806 -65.821306)
		(width 0.1016)
		(layer "F.Cu")
		(net "PWRGD_NODE1_DDR3_DRAM_POK")
	)
	(via
		(at 62.836806 -65.821306)
		(size 0.508)
		(drill 0.254)
		(layers "F.Cu" "B.Cu")
		(net "PWRGD_NODE1_DDR3_DRAM_POK")
	)
	(via
		(at 160.12668 -124.843794)
		(size 0.508)
		(drill 0.254)
		(layers "F.Cu" "B.Cu")
		(net "PWRGD_NODE1_DDR3_DRAM_POK")
	)
	(segment
		(start 62.137036 -66.815208)
		(end 62.137036 -66.521076)
		(width 0.1016)
		(layer "B.Cu")
		(net "PWRGD_NODE1_DDR3_DRAM_POK")
	)
	(segment
		(start 62.137036 -66.521076)
		(end 62.836806 -65.821306)
		(width 0.1016)
		(layer "B.Cu")
		(net "PWRGD_NODE1_DDR3_DRAM_POK")
	)
	(segment
		(start 67.95389 -73.210674)
		(end 67.542156 -73.622408)
		(width 0.1143)
		(layer "In7.Cu")
		(net "PWRGD_NODE1_DDR3_DRAM_POK")
	)
	(segment
		(start 69.759322 -73.210674)
		(end 67.95389 -73.210674)
		(width 0.1143)
		(layer "In7.Cu")
		(net "PWRGD_NODE1_DDR3_DRAM_POK")
	)
	(segment
		(start 141.016228 -100.38715)
		(end 126.637796 -100.38715)
		(width 0.1143)
		(layer "In7.Cu")
		(net "PWRGD_NODE1_DDR3_DRAM_POK")
	)
	(segment
		(start 100.18522 -79.757016)
		(end 94.33687 -73.908666)
		(width 0.1143)
		(layer "In7.Cu")
		(net "PWRGD_NODE1_DDR3_DRAM_POK")
	)
	(segment
		(start 88.488774 -73.908666)
		(end 86.39937 -75.99807)
		(width 0.1143)
		(layer "In7.Cu")
		(net "PWRGD_NODE1_DDR3_DRAM_POK")
	)
	(segment
		(start 126.637796 -100.38715)
		(end 123.471432 -97.220786)
		(width 0.1143)
		(layer "In7.Cu")
		(net "PWRGD_NODE1_DDR3_DRAM_POK")
	)
	(segment
		(start 63.657988 -70.467728)
		(end 62.144656 -68.954396)
		(width 0.1143)
		(layer "In7.Cu")
		(net "PWRGD_NODE1_DDR3_DRAM_POK")
	)
	(segment
		(start 66.210434 -71.05142)
		(end 65.626742 -70.467728)
		(width 0.1143)
		(layer "In7.Cu")
		(net "PWRGD_NODE1_DDR3_DRAM_POK")
	)
	(segment
		(start 85.678518 -75.99807)
		(end 85.068156 -76.608432)
		(width 0.1143)
		(layer "In7.Cu")
		(net "PWRGD_NODE1_DDR3_DRAM_POK")
	)
	(segment
		(start 110.540292 -83.28533)
		(end 102.955852 -83.28533)
		(width 0.1143)
		(layer "In7.Cu")
		(net "PWRGD_NODE1_DDR3_DRAM_POK")
	)
	(segment
		(start 73.383394 -76.834746)
		(end 69.759322 -73.210674)
		(width 0.1143)
		(layer "In7.Cu")
		(net "PWRGD_NODE1_DDR3_DRAM_POK")
	)
	(segment
		(start 123.471432 -97.220786)
		(end 123.471432 -96.21647)
		(width 0.1143)
		(layer "In7.Cu")
		(net "PWRGD_NODE1_DDR3_DRAM_POK")
	)
	(segment
		(start 66.210434 -73.230994)
		(end 66.210434 -71.05142)
		(width 0.1143)
		(layer "In7.Cu")
		(net "PWRGD_NODE1_DDR3_DRAM_POK")
	)
	(segment
		(start 65.626742 -70.467728)
		(end 63.657988 -70.467728)
		(width 0.1143)
		(layer "In7.Cu")
		(net "PWRGD_NODE1_DDR3_DRAM_POK")
	)
	(segment
		(start 94.33687 -73.908666)
		(end 88.488774 -73.908666)
		(width 0.1143)
		(layer "In7.Cu")
		(net "PWRGD_NODE1_DDR3_DRAM_POK")
	)
	(segment
		(start 85.068156 -76.608432)
		(end 76.950824 -76.608432)
		(width 0.1143)
		(layer "In7.Cu")
		(net "PWRGD_NODE1_DDR3_DRAM_POK")
	)
	(segment
		(start 66.601848 -73.622408)
		(end 66.210434 -73.230994)
		(width 0.1143)
		(layer "In7.Cu")
		(net "PWRGD_NODE1_DDR3_DRAM_POK")
	)
	(segment
		(start 152.90038 -113.15319)
		(end 147.71878 -107.97159)
		(width 0.1143)
		(layer "In7.Cu")
		(net "PWRGD_NODE1_DDR3_DRAM_POK")
	)
	(segment
		(start 159.668718 -124.843794)
		(end 152.90038 -118.075456)
		(width 0.1143)
		(layer "In7.Cu")
		(net "PWRGD_NODE1_DDR3_DRAM_POK")
	)
	(segment
		(start 67.542156 -73.622408)
		(end 66.601848 -73.622408)
		(width 0.1143)
		(layer "In7.Cu")
		(net "PWRGD_NODE1_DDR3_DRAM_POK")
	)
	(segment
		(start 76.950824 -76.608432)
		(end 76.72451 -76.834746)
		(width 0.1143)
		(layer "In7.Cu")
		(net "PWRGD_NODE1_DDR3_DRAM_POK")
	)
	(segment
		(start 102.955852 -83.28533)
		(end 100.18522 -80.514698)
		(width 0.1143)
		(layer "In7.Cu")
		(net "PWRGD_NODE1_DDR3_DRAM_POK")
	)
	(segment
		(start 160.12668 -124.843794)
		(end 159.668718 -124.843794)
		(width 0.1143)
		(layer "In7.Cu")
		(net "PWRGD_NODE1_DDR3_DRAM_POK")
	)
	(segment
		(start 62.144656 -68.954396)
		(end 62.144656 -66.513456)
		(width 0.1143)
		(layer "In7.Cu")
		(net "PWRGD_NODE1_DDR3_DRAM_POK")
	)
	(segment
		(start 123.471432 -96.21647)
		(end 110.540292 -83.28533)
		(width 0.1143)
		(layer "In7.Cu")
		(net "PWRGD_NODE1_DDR3_DRAM_POK")
	)
	(segment
		(start 147.71878 -107.089702)
		(end 141.016228 -100.38715)
		(width 0.1143)
		(layer "In7.Cu")
		(net "PWRGD_NODE1_DDR3_DRAM_POK")
	)
	(segment
		(start 86.39937 -75.99807)
		(end 85.678518 -75.99807)
		(width 0.1143)
		(layer "In7.Cu")
		(net "PWRGD_NODE1_DDR3_DRAM_POK")
	)
	(segment
		(start 62.144656 -66.513456)
		(end 62.836806 -65.821306)
		(width 0.1143)
		(layer "In7.Cu")
		(net "PWRGD_NODE1_DDR3_DRAM_POK")
	)
	(segment
		(start 76.72451 -76.834746)
		(end 73.383394 -76.834746)
		(width 0.1143)
		(layer "In7.Cu")
		(net "PWRGD_NODE1_DDR3_DRAM_POK")
	)
	(segment
		(start 147.71878 -107.97159)
		(end 147.71878 -107.089702)
		(width 0.1143)
		(layer "In7.Cu")
		(net "PWRGD_NODE1_DDR3_DRAM_POK")
	)
	(segment
		(start 100.18522 -80.514698)
		(end 100.18522 -79.757016)
		(width 0.1143)
		(layer "In7.Cu")
		(net "PWRGD_NODE1_DDR3_DRAM_POK")
	)
	(segment
		(start 152.90038 -118.075456)
		(end 152.90038 -113.15319)
		(width 0.1143)
		(layer "In7.Cu")
		(net "PWRGD_NODE1_DDR3_DRAM_POK")
	)
	(segment
		(start 111.209328 -141.318996)
		(end 110.81766 -140.927328)
		(width 0.254)
		(layer "F.Cu")
		(net "VR_PVCCP_NODE1_SETINI")
	)
	(segment
		(start 110.799626 -141.728698)
		(end 111.209328 -141.318996)
		(width 0.254)
		(layer "F.Cu")
		(net "VR_PVCCP_NODE1_SETINI")
	)
	(segment
		(start 109.710728 -138.245342)
		(end 109.469428 -138.004042)
		(width 0.254)
		(layer "F.Cu")
		(net "VR_PVCCP_NODE1_SETINI")
	)
	(segment
		(start 109.469428 -138.004042)
		(end 109.271562 -137.806176)
		(width 0.1778)
		(layer "F.Cu")
		(net "VR_PVCCP_NODE1_SETINI")
	)
	(segment
		(start 110.81766 -140.927328)
		(end 110.81766 -140.547598)
		(width 0.254)
		(layer "F.Cu")
		(net "VR_PVCCP_NODE1_SETINI")
	)
	(segment
		(start 110.81766 -140.547598)
		(end 110.624874 -140.547598)
		(width 0.254)
		(layer "F.Cu")
		(net "VR_PVCCP_NODE1_SETINI")
	)
	(segment
		(start 110.330234 -140.252958)
		(end 110.330234 -139.518898)
		(width 0.254)
		(layer "F.Cu")
		(net "VR_PVCCP_NODE1_SETINI")
	)
	(segment
		(start 109.271562 -137.806176)
		(end 109.271562 -137.44067)
		(width 0.1778)
		(layer "F.Cu")
		(net "VR_PVCCP_NODE1_SETINI")
	)
	(segment
		(start 110.624874 -140.547598)
		(end 110.330234 -140.252958)
		(width 0.254)
		(layer "F.Cu")
		(net "VR_PVCCP_NODE1_SETINI")
	)
	(segment
		(start 110.330234 -139.518898)
		(end 109.710728 -138.899392)
		(width 0.254)
		(layer "F.Cu")
		(net "VR_PVCCP_NODE1_SETINI")
	)
	(segment
		(start 109.710728 -138.899392)
		(end 109.710728 -138.245342)
		(width 0.254)
		(layer "F.Cu")
		(net "VR_PVCCP_NODE1_SETINI")
	)
	(segment
		(start 110.799626 -142.019782)
		(end 110.799626 -141.728698)
		(width 0.254)
		(layer "F.Cu")
		(net "VR_PVCCP_NODE1_SETINI")
	)
	(via
		(at 111.209328 -141.318996)
		(size 0.508)
		(drill 0.254)
		(layers "F.Cu" "B.Cu")
		(net "VR_PVCCP_NODE1_SETINI")
	)
	(via
		(at 14.730476 -73.06437)
		(size 0.508)
		(drill 0.254)
		(layers "F.Cu" "B.Cu")
		(net "N21581564")
	)
	(segment
		(start 60.541916 -136.859518)
		(end 60.53963 -136.859518)
		(width 0.1016)
		(layer "F.Cu")
		(net "BMC_NODE1_DDR_D13")
	)
	(segment
		(start 46.152816 -138.96213)
		(end 46.800262 -138.96213)
		(width 0.1016)
		(layer "F.Cu")
		(net "BMC_NODE1_DDR_D13")
	)
	(segment
		(start 60.53963 -136.859518)
		(end 60.141104 -137.258044)
		(width 0.1016)
		(layer "F.Cu")
		(net "BMC_NODE1_DDR_D13")
	)
	(segment
		(start 47.237904 -138.524488)
		(end 47.457614 -138.524488)
		(width 0.1016)
		(layer "F.Cu")
		(net "BMC_NODE1_DDR_D13")
	)
	(segment
		(start 45.633132 -139.363704)
		(end 45.751242 -139.363704)
		(width 0.1016)
		(layer "F.Cu")
		(net "BMC_NODE1_DDR_D13")
	)
	(segment
		(start 46.800262 -138.96213)
		(end 47.237904 -138.524488)
		(width 0.1016)
		(layer "F.Cu")
		(net "BMC_NODE1_DDR_D13")
	)
	(segment
		(start 45.751242 -139.363704)
		(end 46.152816 -138.96213)
		(width 0.1016)
		(layer "F.Cu")
		(net "BMC_NODE1_DDR_D13")
	)
	(via
		(at 47.457614 -138.524488)
		(size 0.508)
		(drill 0.254)
		(layers "F.Cu" "B.Cu")
		(net "BMC_NODE1_DDR_D13")
	)
	(via
		(at 60.141104 -137.258044)
		(size 0.49022)
		(drill 0.254)
		(layers "F.Cu" "B.Cu")
		(net "BMC_NODE1_DDR_D13")
	)
	(segment
		(start 57.507632 -137.275316)
		(end 55.149496 -137.275316)
		(width 0.1143)
		(layer "In2.Cu")
		(net "BMC_NODE1_DDR_D13")
	)
	(segment
		(start 45.477176 -137.997692)
		(end 45.477176 -138.274044)
		(width 0.1143)
		(layer "In2.Cu")
		(net "BMC_NODE1_DDR_D13")
	)
	(segment
		(start 57.92724 -136.855708)
		(end 57.507632 -137.275316)
		(width 0.1143)
		(layer "In2.Cu")
		(net "BMC_NODE1_DDR_D13")
	)
	(segment
		(start 52.554886 -138.741912)
		(end 52.440586 -138.627612)
		(width 0.1143)
		(layer "In2.Cu")
		(net "BMC_NODE1_DDR_D13")
	)
	(segment
		(start 52.994814 -139.03706)
		(end 52.737258 -139.03706)
		(width 0.1143)
		(layer "In2.Cu")
		(net "BMC_NODE1_DDR_D13")
	)
	(segment
		(start 53.177186 -138.854688)
		(end 52.994814 -139.03706)
		(width 0.1143)
		(layer "In2.Cu")
		(net "BMC_NODE1_DDR_D13")
	)
	(segment
		(start 53.291486 -138.627612)
		(end 53.177186 -138.741912)
		(width 0.1143)
		(layer "In2.Cu")
		(net "BMC_NODE1_DDR_D13")
	)
	(segment
		(start 60.141104 -137.258044)
		(end 59.738768 -136.855708)
		(width 0.1143)
		(layer "In2.Cu")
		(net "BMC_NODE1_DDR_D13")
	)
	(segment
		(start 45.477176 -138.274044)
		(end 45.782738 -138.579606)
		(width 0.1143)
		(layer "In2.Cu")
		(net "BMC_NODE1_DDR_D13")
	)
	(segment
		(start 49.505616 -138.627612)
		(end 48.504856 -137.626852)
		(width 0.1143)
		(layer "In2.Cu")
		(net "BMC_NODE1_DDR_D13")
	)
	(segment
		(start 52.737258 -139.03706)
		(end 52.554886 -138.854688)
		(width 0.1143)
		(layer "In2.Cu")
		(net "BMC_NODE1_DDR_D13")
	)
	(segment
		(start 52.440586 -138.627612)
		(end 49.505616 -138.627612)
		(width 0.1143)
		(layer "In2.Cu")
		(net "BMC_NODE1_DDR_D13")
	)
	(segment
		(start 48.504856 -137.626852)
		(end 45.848016 -137.626852)
		(width 0.1143)
		(layer "In2.Cu")
		(net "BMC_NODE1_DDR_D13")
	)
	(segment
		(start 58.44667 -136.855708)
		(end 57.92724 -136.855708)
		(width 0.1143)
		(layer "In2.Cu")
		(net "BMC_NODE1_DDR_D13")
	)
	(segment
		(start 58.756804 -136.855708)
		(end 58.44667 -136.855708)
		(width 0.1016)
		(layer "In2.Cu")
		(net "BMC_NODE1_DDR_D13")
	)
	(segment
		(start 54.24424 -138.180572)
		(end 54.24424 -138.328908)
		(width 0.1143)
		(layer "In2.Cu")
		(net "BMC_NODE1_DDR_D13")
	)
	(segment
		(start 47.402496 -138.579606)
		(end 47.457614 -138.524488)
		(width 0.1143)
		(layer "In2.Cu")
		(net "BMC_NODE1_DDR_D13")
	)
	(segment
		(start 53.945536 -138.627612)
		(end 53.291486 -138.627612)
		(width 0.1143)
		(layer "In2.Cu")
		(net "BMC_NODE1_DDR_D13")
	)
	(segment
		(start 53.177186 -138.741912)
		(end 53.177186 -138.854688)
		(width 0.1143)
		(layer "In2.Cu")
		(net "BMC_NODE1_DDR_D13")
	)
	(segment
		(start 45.848016 -137.626852)
		(end 45.477176 -137.997692)
		(width 0.1143)
		(layer "In2.Cu")
		(net "BMC_NODE1_DDR_D13")
	)
	(segment
		(start 45.782738 -138.579606)
		(end 47.402496 -138.579606)
		(width 0.1143)
		(layer "In2.Cu")
		(net "BMC_NODE1_DDR_D13")
	)
	(segment
		(start 55.149496 -137.275316)
		(end 54.24424 -138.180572)
		(width 0.1143)
		(layer "In2.Cu")
		(net "BMC_NODE1_DDR_D13")
	)
	(segment
		(start 59.455812 -136.855708)
		(end 59.202574 -136.855708)
		(width 0.1016)
		(layer "In2.Cu")
		(net "BMC_NODE1_DDR_D13")
	)
	(segment
		(start 59.738768 -136.855708)
		(end 59.455812 -136.855708)
		(width 0.1143)
		(layer "In2.Cu")
		(net "BMC_NODE1_DDR_D13")
	)
	(segment
		(start 52.554886 -138.854688)
		(end 52.554886 -138.741912)
		(width 0.1143)
		(layer "In2.Cu")
		(net "BMC_NODE1_DDR_D13")
	)
	(segment
		(start 54.24424 -138.328908)
		(end 53.945536 -138.627612)
		(width 0.1143)
		(layer "In2.Cu")
		(net "BMC_NODE1_DDR_D13")
	)
	(segment
		(start 59.202574 -136.855708)
		(end 58.756804 -136.855708)
		(width 0.1143)
		(layer "In2.Cu")
		(net "BMC_NODE1_DDR_D13")
	)
	(segment
		(start 56.24449 -85.762846)
		(end 56.381142 -85.762846)
		(width 0.1016)
		(layer "F.Cu")
		(net "FM_NODE1_DFX_GPIO_GRP05")
	)
	(segment
		(start 182.01132 -135.89762)
		(end 181.93004 -135.81634)
		(width 0.1016)
		(layer "F.Cu")
		(net "FM_NODE1_DFX_GPIO_GRP05")
	)
	(segment
		(start 56.381142 -85.762846)
		(end 56.684164 -86.065868)
		(width 0.1016)
		(layer "F.Cu")
		(net "FM_NODE1_DFX_GPIO_GRP05")
	)
	(segment
		(start 181.93004 -135.81634)
		(end 181.93004 -133.42493)
		(width 0.1016)
		(layer "F.Cu")
		(net "FM_NODE1_DFX_GPIO_GRP05")
	)
	(segment
		(start 182.012844 -135.89762)
		(end 182.01132 -135.89762)
		(width 0.1016)
		(layer "F.Cu")
		(net "FM_NODE1_DFX_GPIO_GRP05")
	)
	(via
		(at 56.684164 -86.065868)
		(size 0.508)
		(drill 0.254)
		(layers "F.Cu" "B.Cu")
		(net "FM_NODE1_DFX_GPIO_GRP05")
	)
	(via
		(at 56.635396 -90.458036)
		(size 0.508)
		(drill 0.254)
		(layers "F.Cu" "B.Cu")
		(net "FM_NODE1_DFX_GPIO_GRP05")
	)
	(via
		(at 181.93004 -133.42493)
		(size 0.508)
		(drill 0.254)
		(layers "F.Cu" "B.Cu")
		(net "FM_NODE1_DFX_GPIO_GRP05")
	)
	(segment
		(start 56.635396 -90.458036)
		(end 57.108598 -89.984834)
		(width 0.1016)
		(layer "B.Cu")
		(net "FM_NODE1_DFX_GPIO_GRP05")
	)
	(segment
		(start 57.108598 -89.984834)
		(end 57.108598 -86.494366)
		(width 0.1016)
		(layer "B.Cu")
		(net "FM_NODE1_DFX_GPIO_GRP05")
	)
	(segment
		(start 56.684164 -86.069932)
		(end 56.684164 -86.065868)
		(width 0.1016)
		(layer "B.Cu")
		(net "FM_NODE1_DFX_GPIO_GRP05")
	)
	(segment
		(start 57.108598 -86.494366)
		(end 56.684164 -86.069932)
		(width 0.1016)
		(layer "B.Cu")
		(net "FM_NODE1_DFX_GPIO_GRP05")
	)
	(segment
		(start 98.836988 -88.451944)
		(end 96.999044 -86.614)
		(width 0.1143)
		(layer "In7.Cu")
		(net "FM_NODE1_DFX_GPIO_GRP05")
	)
	(segment
		(start 89.190576 -86.614)
		(end 88.17102 -87.633556)
		(width 0.1143)
		(layer "In7.Cu")
		(net "FM_NODE1_DFX_GPIO_GRP05")
	)
	(segment
		(start 181.93004 -133.42493)
		(end 181.068472 -132.563362)
		(width 0.1143)
		(layer "In7.Cu")
		(net "FM_NODE1_DFX_GPIO_GRP05")
	)
	(segment
		(start 59.451748 -89.212928)
		(end 58.511694 -90.152982)
		(width 0.1143)
		(layer "In7.Cu")
		(net "FM_NODE1_DFX_GPIO_GRP05")
	)
	(segment
		(start 81.403444 -90.42527)
		(end 81.37906 -90.449654)
		(width 0.1143)
		(layer "In7.Cu")
		(net "FM_NODE1_DFX_GPIO_GRP05")
	)
	(segment
		(start 177.850546 -132.563362)
		(end 177.60188 -132.314696)
		(width 0.1143)
		(layer "In7.Cu")
		(net "FM_NODE1_DFX_GPIO_GRP05")
	)
	(segment
		(start 159.871664 -131.112768)
		(end 147.48256 -118.723664)
		(width 0.1143)
		(layer "In7.Cu")
		(net "FM_NODE1_DFX_GPIO_GRP05")
	)
	(segment
		(start 140.703554 -108.398564)
		(end 137.201402 -104.896412)
		(width 0.1143)
		(layer "In7.Cu")
		(net "FM_NODE1_DFX_GPIO_GRP05")
	)
	(segment
		(start 88.17102 -87.633556)
		(end 88.17102 -87.751412)
		(width 0.1143)
		(layer "In7.Cu")
		(net "FM_NODE1_DFX_GPIO_GRP05")
	)
	(segment
		(start 147.48256 -118.723664)
		(end 147.48256 -113.680748)
		(width 0.1143)
		(layer "In7.Cu")
		(net "FM_NODE1_DFX_GPIO_GRP05")
	)
	(segment
		(start 56.94045 -90.152982)
		(end 56.635396 -90.458036)
		(width 0.1143)
		(layer "In7.Cu")
		(net "FM_NODE1_DFX_GPIO_GRP05")
	)
	(segment
		(start 69.58838 -90.101166)
		(end 68.700142 -89.212928)
		(width 0.1143)
		(layer "In7.Cu")
		(net "FM_NODE1_DFX_GPIO_GRP05")
	)
	(segment
		(start 81.799938 -90.42527)
		(end 81.403444 -90.42527)
		(width 0.1143)
		(layer "In7.Cu")
		(net "FM_NODE1_DFX_GPIO_GRP05")
	)
	(segment
		(start 88.17102 -87.751412)
		(end 85.445092 -90.47734)
		(width 0.1143)
		(layer "In7.Cu")
		(net "FM_NODE1_DFX_GPIO_GRP05")
	)
	(segment
		(start 73.630028 -90.449654)
		(end 73.28154 -90.101166)
		(width 0.1143)
		(layer "In7.Cu")
		(net "FM_NODE1_DFX_GPIO_GRP05")
	)
	(segment
		(start 81.37906 -90.449654)
		(end 73.630028 -90.449654)
		(width 0.1143)
		(layer "In7.Cu")
		(net "FM_NODE1_DFX_GPIO_GRP05")
	)
	(segment
		(start 96.999044 -86.614)
		(end 89.190576 -86.614)
		(width 0.1143)
		(layer "In7.Cu")
		(net "FM_NODE1_DFX_GPIO_GRP05")
	)
	(segment
		(start 147.48256 -113.680748)
		(end 142.200376 -108.398564)
		(width 0.1143)
		(layer "In7.Cu")
		(net "FM_NODE1_DFX_GPIO_GRP05")
	)
	(segment
		(start 85.445092 -90.47734)
		(end 81.852008 -90.47734)
		(width 0.1143)
		(layer "In7.Cu")
		(net "FM_NODE1_DFX_GPIO_GRP05")
	)
	(segment
		(start 58.511694 -90.152982)
		(end 56.94045 -90.152982)
		(width 0.1143)
		(layer "In7.Cu")
		(net "FM_NODE1_DFX_GPIO_GRP05")
	)
	(segment
		(start 160.838896 -131.112768)
		(end 159.871664 -131.112768)
		(width 0.1143)
		(layer "In7.Cu")
		(net "FM_NODE1_DFX_GPIO_GRP05")
	)
	(segment
		(start 73.28154 -90.101166)
		(end 69.58838 -90.101166)
		(width 0.1143)
		(layer "In7.Cu")
		(net "FM_NODE1_DFX_GPIO_GRP05")
	)
	(segment
		(start 68.700142 -89.212928)
		(end 59.451748 -89.212928)
		(width 0.1143)
		(layer "In7.Cu")
		(net "FM_NODE1_DFX_GPIO_GRP05")
	)
	(segment
		(start 108.627164 -88.451944)
		(end 98.836988 -88.451944)
		(width 0.1143)
		(layer "In7.Cu")
		(net "FM_NODE1_DFX_GPIO_GRP05")
	)
	(segment
		(start 162.040824 -132.314696)
		(end 160.838896 -131.112768)
		(width 0.1143)
		(layer "In7.Cu")
		(net "FM_NODE1_DFX_GPIO_GRP05")
	)
	(segment
		(start 137.201402 -104.896412)
		(end 125.071632 -104.896412)
		(width 0.1143)
		(layer "In7.Cu")
		(net "FM_NODE1_DFX_GPIO_GRP05")
	)
	(segment
		(start 81.852008 -90.47734)
		(end 81.799938 -90.42527)
		(width 0.1143)
		(layer "In7.Cu")
		(net "FM_NODE1_DFX_GPIO_GRP05")
	)
	(segment
		(start 125.071632 -104.896412)
		(end 108.627164 -88.451944)
		(width 0.1143)
		(layer "In7.Cu")
		(net "FM_NODE1_DFX_GPIO_GRP05")
	)
	(segment
		(start 142.200376 -108.398564)
		(end 140.703554 -108.398564)
		(width 0.1143)
		(layer "In7.Cu")
		(net "FM_NODE1_DFX_GPIO_GRP05")
	)
	(segment
		(start 181.068472 -132.563362)
		(end 177.850546 -132.563362)
		(width 0.1143)
		(layer "In7.Cu")
		(net "FM_NODE1_DFX_GPIO_GRP05")
	)
	(segment
		(start 177.60188 -132.314696)
		(end 162.040824 -132.314696)
		(width 0.1143)
		(layer "In7.Cu")
		(net "FM_NODE1_DFX_GPIO_GRP05")
	)
	(segment
		(start 70.19036 -24.199596)
		(end 69.589142 -24.800814)
		(width 0.2286)
		(layer "F.Cu")
		(net "M_DDR3_NODE1_MA12")
	)
	(segment
		(start 69.589142 -24.800814)
		(end 69.589142 -24.80183)
		(width 0.2286)
		(layer "F.Cu")
		(net "M_DDR3_NODE1_MA12")
	)
	(segment
		(start 57.743852 -63.87846)
		(end 57.617614 -64.004698)
		(width 0.1016)
		(layer "F.Cu")
		(net "M_DDR3_NODE1_MA12")
	)
	(segment
		(start 70.950074 -23.85187)
		(end 70.602348 -24.199596)
		(width 0.2286)
		(layer "F.Cu")
		(net "M_DDR3_NODE1_MA12")
	)
	(segment
		(start 57.721246 -63.188342)
		(end 57.490106 -63.419482)
		(width 0.1016)
		(layer "F.Cu")
		(net "M_DDR3_NODE1_MA12")
	)
	(segment
		(start 57.84215 -60.87745)
		(end 57.84215 -61.323982)
		(width 0.1016)
		(layer "F.Cu")
		(net "M_DDR3_NODE1_MA12")
	)
	(segment
		(start 57.40654 -60.44184)
		(end 57.84215 -60.87745)
		(width 0.1016)
		(layer "F.Cu")
		(net "M_DDR3_NODE1_MA12")
	)
	(segment
		(start 70.602348 -24.199596)
		(end 70.19036 -24.199596)
		(width 0.2286)
		(layer "F.Cu")
		(net "M_DDR3_NODE1_MA12")
	)
	(segment
		(start 57.40654 -59.319668)
		(end 57.40654 -60.44184)
		(width 0.1016)
		(layer "F.Cu")
		(net "M_DDR3_NODE1_MA12")
	)
	(segment
		(start 57.382156 -61.783976)
		(end 57.382156 -62.489334)
		(width 0.1016)
		(layer "F.Cu")
		(net "M_DDR3_NODE1_MA12")
	)
	(segment
		(start 57.617614 -64.004698)
		(end 57.435496 -64.004698)
		(width 0.1016)
		(layer "F.Cu")
		(net "M_DDR3_NODE1_MA12")
	)
	(segment
		(start 57.382156 -62.489334)
		(end 57.721246 -62.828424)
		(width 0.1016)
		(layer "F.Cu")
		(net "M_DDR3_NODE1_MA12")
	)
	(segment
		(start 57.490106 -63.525654)
		(end 57.743852 -63.7794)
		(width 0.1016)
		(layer "F.Cu")
		(net "M_DDR3_NODE1_MA12")
	)
	(segment
		(start 57.84215 -61.323982)
		(end 57.382156 -61.783976)
		(width 0.1016)
		(layer "F.Cu")
		(net "M_DDR3_NODE1_MA12")
	)
	(segment
		(start 57.743852 -63.7794)
		(end 57.743852 -63.87846)
		(width 0.1016)
		(layer "F.Cu")
		(net "M_DDR3_NODE1_MA12")
	)
	(segment
		(start 57.721246 -62.828424)
		(end 57.721246 -63.188342)
		(width 0.1016)
		(layer "F.Cu")
		(net "M_DDR3_NODE1_MA12")
	)
	(segment
		(start 57.490106 -63.419482)
		(end 57.490106 -63.525654)
		(width 0.1016)
		(layer "F.Cu")
		(net "M_DDR3_NODE1_MA12")
	)
	(segment
		(start 70.950074 -20.94992)
		(end 70.950074 -23.85187)
		(width 0.2286)
		(layer "F.Cu")
		(net "M_DDR3_NODE1_MA12")
	)
	(via
		(at 57.40654 -59.319668)
		(size 0.508)
		(drill 0.254)
		(layers "F.Cu" "B.Cu")
		(net "M_DDR3_NODE1_MA12")
	)
	(via
		(at 69.589142 -24.80183)
		(size 0.508)
		(drill 0.254)
		(layers "F.Cu" "B.Cu")
		(net "M_DDR3_NODE1_MA12")
	)
	(segment
		(start 57.40654 -59.319668)
		(end 57.95518 -58.771028)
		(width 0.2286)
		(layer "In2.Cu")
		(net "M_DDR3_NODE1_MA12")
	)
	(segment
		(start 67.82308 -31.26359)
		(end 67.82308 -30.273752)
		(width 0.2286)
		(layer "In2.Cu")
		(net "M_DDR3_NODE1_MA12")
	)
	(segment
		(start 67.82308 -30.273752)
		(end 68.93052 -29.166312)
		(width 0.2286)
		(layer "In2.Cu")
		(net "M_DDR3_NODE1_MA12")
	)
	(segment
		(start 67.327526 -31.759144)
		(end 67.82308 -31.26359)
		(width 0.2286)
		(layer "In2.Cu")
		(net "M_DDR3_NODE1_MA12")
	)
	(segment
		(start 66.67754 -35.511232)
		(end 66.67754 -32.409384)
		(width 0.2286)
		(layer "In2.Cu")
		(net "M_DDR3_NODE1_MA12")
	)
	(segment
		(start 62.508384 -39.680388)
		(end 66.67754 -35.511232)
		(width 0.2286)
		(layer "In2.Cu")
		(net "M_DDR3_NODE1_MA12")
	)
	(segment
		(start 61.98743 -39.464742)
		(end 62.203076 -39.680388)
		(width 0.2286)
		(layer "In2.Cu")
		(net "M_DDR3_NODE1_MA12")
	)
	(segment
		(start 57.95518 -58.771028)
		(end 57.95518 -53.04282)
		(width 0.2286)
		(layer "In2.Cu")
		(net "M_DDR3_NODE1_MA12")
	)
	(segment
		(start 68.93052 -29.166312)
		(end 68.93052 -25.460452)
		(width 0.2286)
		(layer "In2.Cu")
		(net "M_DDR3_NODE1_MA12")
	)
	(segment
		(start 68.93052 -25.460452)
		(end 69.589142 -24.80183)
		(width 0.2286)
		(layer "In2.Cu")
		(net "M_DDR3_NODE1_MA12")
	)
	(segment
		(start 57.95518 -53.04282)
		(end 61.21654 -49.78146)
		(width 0.2286)
		(layer "In2.Cu")
		(net "M_DDR3_NODE1_MA12")
	)
	(segment
		(start 61.21654 -38.888416)
		(end 65.35293 -34.752026)
		(width 0.2286)
		(layer "In2.Cu")
		(net "M_DDR3_NODE1_MA12")
	)
	(segment
		(start 65.65773 -34.752026)
		(end 65.873884 -34.96818)
		(width 0.2286)
		(layer "In2.Cu")
		(net "M_DDR3_NODE1_MA12")
	)
	(segment
		(start 62.203076 -39.680388)
		(end 62.508384 -39.680388)
		(width 0.2286)
		(layer "In2.Cu")
		(net "M_DDR3_NODE1_MA12")
	)
	(segment
		(start 61.21654 -49.78146)
		(end 61.21654 -38.888416)
		(width 0.2286)
		(layer "In2.Cu")
		(net "M_DDR3_NODE1_MA12")
	)
	(segment
		(start 61.98743 -39.159434)
		(end 61.98743 -39.464742)
		(width 0.2286)
		(layer "In2.Cu")
		(net "M_DDR3_NODE1_MA12")
	)
	(segment
		(start 65.873884 -34.96818)
		(end 65.873884 -35.27298)
		(width 0.2286)
		(layer "In2.Cu")
		(net "M_DDR3_NODE1_MA12")
	)
	(segment
		(start 65.35293 -34.752026)
		(end 65.65773 -34.752026)
		(width 0.2286)
		(layer "In2.Cu")
		(net "M_DDR3_NODE1_MA12")
	)
	(segment
		(start 65.873884 -35.27298)
		(end 61.98743 -39.159434)
		(width 0.2286)
		(layer "In2.Cu")
		(net "M_DDR3_NODE1_MA12")
	)
	(segment
		(start 66.67754 -32.409384)
		(end 67.327526 -31.759144)
		(width 0.2286)
		(layer "In2.Cu")
		(net "M_DDR3_NODE1_MA12")
	)
	(segment
		(start 109.763052 -142.814548)
		(end 108.72724 -142.814548)
		(width 0.381)
		(layer "F.Cu")
		(net "VR_PVCCP_NODE1_VCC")
	)
	(segment
		(start 109.996478 -136.297924)
		(end 110.48238 -136.297924)
		(width 0.1778)
		(layer "F.Cu")
		(net "VR_PVCCP_NODE1_VCC")
	)
	(segment
		(start 104.466644 -120.961404)
		(end 104.761792 -120.961404)
		(width 0.254)
		(layer "F.Cu")
		(net "VR_PVCCP_NODE1_VCC")
	)
	(segment
		(start 102.998016 -121.674636)
		(end 103.753412 -121.674636)
		(width 0.254)
		(layer "F.Cu")
		(net "VR_PVCCP_NODE1_VCC")
	)
	(segment
		(start 106.871516 -137.42289)
		(end 106.871516 -138.481562)
		(width 0.1778)
		(layer "F.Cu")
		(net "VR_PVCCP_NODE1_VCC")
	)
	(segment
		(start 110.743492 -136.559036)
		(end 110.743492 -137.090404)
		(width 0.1778)
		(layer "F.Cu")
		(net "VR_PVCCP_NODE1_VCC")
	)
	(segment
		(start 100.97008 -123.702572)
		(end 102.998016 -121.674636)
		(width 0.254)
		(layer "F.Cu")
		(net "VR_PVCCP_NODE1_VCC")
	)
	(segment
		(start 105.666794 -139.218924)
		(end 105.79481 -139.090908)
		(width 0.4572)
		(layer "F.Cu")
		(net "VR_PVCCP_NODE1_VCC")
	)
	(segment
		(start 103.753412 -121.674636)
		(end 104.466644 -120.961404)
		(width 0.254)
		(layer "F.Cu")
		(net "VR_PVCCP_NODE1_VCC")
	)
	(segment
		(start 106.871516 -138.481562)
		(end 106.26217 -139.090908)
		(width 0.1778)
		(layer "F.Cu")
		(net "VR_PVCCP_NODE1_VCC")
	)
	(segment
		(start 107.794298 -145.093436)
		(end 102.955598 -145.093436)
		(width 0.254)
		(layer "F.Cu")
		(net "VR_PVCCP_NODE1_VCC")
	)
	(segment
		(start 108.578396 -144.309338)
		(end 107.794298 -145.093436)
		(width 0.254)
		(layer "F.Cu")
		(net "VR_PVCCP_NODE1_VCC")
	)
	(segment
		(start 109.766608 -142.810992)
		(end 109.763052 -142.814548)
		(width 0.381)
		(layer "F.Cu")
		(net "VR_PVCCP_NODE1_VCC")
	)
	(segment
		(start 102.955598 -145.093436)
		(end 100.73386 -142.871698)
		(width 0.254)
		(layer "F.Cu")
		(net "VR_PVCCP_NODE1_VCC")
	)
	(segment
		(start 108.72724 -142.814548)
		(end 108.72724 -143.646906)
		(width 0.381)
		(layer "F.Cu")
		(net "VR_PVCCP_NODE1_VCC")
	)
	(segment
		(start 108.72724 -143.646906)
		(end 108.578396 -143.79575)
		(width 0.381)
		(layer "F.Cu")
		(net "VR_PVCCP_NODE1_VCC")
	)
	(segment
		(start 109.766608 -142.810992)
		(end 110.790736 -142.810992)
		(width 0.381)
		(layer "F.Cu")
		(net "VR_PVCCP_NODE1_VCC")
	)
	(segment
		(start 110.790736 -142.810992)
		(end 110.799626 -142.819882)
		(width 0.381)
		(layer "F.Cu")
		(net "VR_PVCCP_NODE1_VCC")
	)
	(segment
		(start 101.957378 -128.499362)
		(end 100.97008 -127.512064)
		(width 0.254)
		(layer "F.Cu")
		(net "VR_PVCCP_NODE1_VCC")
	)
	(segment
		(start 100.73386 -142.871698)
		(end 100.73386 -139.52474)
		(width 0.254)
		(layer "F.Cu")
		(net "VR_PVCCP_NODE1_VCC")
	)
	(segment
		(start 110.48238 -136.297924)
		(end 110.743492 -136.559036)
		(width 0.1778)
		(layer "F.Cu")
		(net "VR_PVCCP_NODE1_VCC")
	)
	(segment
		(start 110.799626 -142.819882)
		(end 111.731298 -142.819882)
		(width 0.381)
		(layer "F.Cu")
		(net "VR_PVCCP_NODE1_VCC")
	)
	(segment
		(start 105.666794 -139.786868)
		(end 105.666794 -139.218924)
		(width 0.4572)
		(layer "F.Cu")
		(net "VR_PVCCP_NODE1_VCC")
	)
	(segment
		(start 102.224332 -128.499362)
		(end 101.957378 -128.499362)
		(width 0.254)
		(layer "F.Cu")
		(net "VR_PVCCP_NODE1_VCC")
	)
	(segment
		(start 112.096804 -142.454376)
		(end 112.096804 -141.2367)
		(width 0.381)
		(layer "F.Cu")
		(net "VR_PVCCP_NODE1_VCC")
	)
	(segment
		(start 106.26217 -139.090908)
		(end 105.79481 -139.090908)
		(width 0.1778)
		(layer "F.Cu")
		(net "VR_PVCCP_NODE1_VCC")
	)
	(segment
		(start 108.578396 -143.79575)
		(end 108.578396 -144.309338)
		(width 0.254)
		(layer "F.Cu")
		(net "VR_PVCCP_NODE1_VCC")
	)
	(segment
		(start 100.97008 -127.512064)
		(end 100.97008 -123.702572)
		(width 0.254)
		(layer "F.Cu")
		(net "VR_PVCCP_NODE1_VCC")
	)
	(segment
		(start 111.731298 -142.819882)
		(end 112.096804 -142.454376)
		(width 0.381)
		(layer "F.Cu")
		(net "VR_PVCCP_NODE1_VCC")
	)
	(via
		(at 110.743492 -137.090404)
		(size 0.508)
		(drill 0.254)
		(layers "F.Cu" "B.Cu")
		(net "VR_PVCCP_NODE1_VCC")
	)
	(via
		(at 100.73386 -139.52474)
		(size 0.508)
		(drill 0.254)
		(layers "F.Cu" "B.Cu")
		(net "VR_PVCCP_NODE1_VCC")
	)
	(via
		(at 105.79481 -139.090908)
		(size 0.508)
		(drill 0.254)
		(layers "F.Cu" "B.Cu")
		(net "VR_PVCCP_NODE1_VCC")
	)
	(via
		(at 102.224332 -128.499362)
		(size 0.508)
		(drill 0.254)
		(layers "F.Cu" "B.Cu")
		(net "VR_PVCCP_NODE1_VCC")
	)
	(via
		(at 110.287562 -137.895838)
		(size 0.508)
		(drill 0.254)
		(layers "F.Cu" "B.Cu")
		(net "VR_PVCCP_NODE1_VCC")
	)
	(via
		(at 112.096804 -141.2367)
		(size 0.508)
		(drill 0.254)
		(layers "F.Cu" "B.Cu")
		(net "VR_PVCCP_NODE1_VCC")
	)
	(segment
		(start 101.39934 -138.567414)
		(end 100.73386 -139.232894)
		(width 0.254)
		(layer "In2.Cu")
		(net "VR_PVCCP_NODE1_VCC")
	)
	(segment
		(start 102.224332 -128.499362)
		(end 101.672898 -128.499362)
		(width 0.254)
		(layer "In2.Cu")
		(net "VR_PVCCP_NODE1_VCC")
	)
	(segment
		(start 101.39934 -129.752344)
		(end 101.39934 -138.567414)
		(width 0.254)
		(layer "In2.Cu")
		(net "VR_PVCCP_NODE1_VCC")
	)
	(segment
		(start 110.287562 -139.055348)
		(end 110.287562 -137.895838)
		(width 0.508)
		(layer "In2.Cu")
		(net "VR_PVCCP_NODE1_VCC")
	)
	(segment
		(start 101.231954 -128.95453)
		(end 101.2317 -128.95453)
		(width 0.254)
		(layer "In2.Cu")
		(net "VR_PVCCP_NODE1_VCC")
	)
	(segment
		(start 109.402372 -139.940538)
		(end 110.287562 -139.055348)
		(width 0.508)
		(layer "In2.Cu")
		(net "VR_PVCCP_NODE1_VCC")
	)
	(segment
		(start 101.57714 -128.609344)
		(end 101.231954 -128.95453)
		(width 0.254)
		(layer "In2.Cu")
		(net "VR_PVCCP_NODE1_VCC")
	)
	(segment
		(start 101.672898 -128.499362)
		(end 101.57714 -128.59512)
		(width 0.254)
		(layer "In2.Cu")
		(net "VR_PVCCP_NODE1_VCC")
	)
	(segment
		(start 110.287562 -137.895838)
		(end 111.031274 -138.63955)
		(width 0.508)
		(layer "In2.Cu")
		(net "VR_PVCCP_NODE1_VCC")
	)
	(segment
		(start 101.2317 -129.585466)
		(end 101.398578 -129.752344)
		(width 0.254)
		(layer "In2.Cu")
		(net "VR_PVCCP_NODE1_VCC")
	)
	(segment
		(start 111.031274 -138.63955)
		(end 111.031274 -140.17117)
		(width 0.508)
		(layer "In2.Cu")
		(net "VR_PVCCP_NODE1_VCC")
	)
	(segment
		(start 101.57714 -128.59512)
		(end 101.57714 -128.609344)
		(width 0.254)
		(layer "In2.Cu")
		(net "VR_PVCCP_NODE1_VCC")
	)
	(segment
		(start 105.79481 -139.090908)
		(end 106.64444 -139.940538)
		(width 0.508)
		(layer "In2.Cu")
		(net "VR_PVCCP_NODE1_VCC")
	)
	(segment
		(start 101.2317 -128.95453)
		(end 101.2317 -129.585466)
		(width 0.254)
		(layer "In2.Cu")
		(net "VR_PVCCP_NODE1_VCC")
	)
	(segment
		(start 101.398578 -129.752344)
		(end 101.39934 -129.752344)
		(width 0.254)
		(layer "In2.Cu")
		(net "VR_PVCCP_NODE1_VCC")
	)
	(segment
		(start 111.031274 -140.17117)
		(end 112.096804 -141.2367)
		(width 0.508)
		(layer "In2.Cu")
		(net "VR_PVCCP_NODE1_VCC")
	)
	(segment
		(start 106.64444 -139.940538)
		(end 109.402372 -139.940538)
		(width 0.508)
		(layer "In2.Cu")
		(net "VR_PVCCP_NODE1_VCC")
	)
	(segment
		(start 100.73386 -139.232894)
		(end 100.73386 -139.52474)
		(width 0.254)
		(layer "In2.Cu")
		(net "VR_PVCCP_NODE1_VCC")
	)
	(segment
		(start 25.768046 -48.213264)
		(end 25.768046 -49.369472)
		(width 0.1016)
		(layer "F.Cu")
		(net "N21581283")
	)
	(segment
		(start 25.0698 -59.6011)
		(end 25.0698 -59.606942)
		(width 0.1016)
		(layer "F.Cu")
		(net "N21581283")
	)
	(segment
		(start 20.258024 -61.961776)
		(end 20.419314 -61.800486)
		(width 0.1016)
		(layer "F.Cu")
		(net "N21581283")
	)
	(segment
		(start 23.478744 -61.197998)
		(end 22.03069 -61.197998)
		(width 0.1016)
		(layer "F.Cu")
		(net "N21581283")
	)
	(segment
		(start 20.419314 -61.80074)
		(end 20.419314 -61.800486)
		(width 0.1016)
		(layer "F.Cu")
		(net "N21581283")
	)
	(segment
		(start 25.0698 -59.606942)
		(end 23.478744 -61.197998)
		(width 0.1016)
		(layer "F.Cu")
		(net "N21581283")
	)
	(segment
		(start 22.03069 -61.197998)
		(end 21.427948 -61.80074)
		(width 0.1016)
		(layer "F.Cu")
		(net "N21581283")
	)
	(segment
		(start 21.427948 -61.80074)
		(end 20.419314 -61.80074)
		(width 0.1016)
		(layer "F.Cu")
		(net "N21581283")
	)
	(segment
		(start 18.992596 -61.961776)
		(end 20.258024 -61.961776)
		(width 0.1016)
		(layer "F.Cu")
		(net "N21581283")
	)
	(via
		(at 25.0698 -59.6011)
		(size 0.508)
		(drill 0.254)
		(layers "F.Cu" "B.Cu")
		(net "N21581283")
	)
	(via
		(at 25.768046 -49.369472)
		(size 0.508)
		(drill 0.254)
		(layers "F.Cu" "B.Cu")
		(net "N21581283")
	)
	(segment
		(start 25.0698 -59.6011)
		(end 25.0698 -58.905394)
		(width 0.1143)
		(layer "In2.Cu")
		(net "N21581283")
	)
	(segment
		(start 25.0698 -58.905394)
		(end 26.17978 -57.795414)
		(width 0.1143)
		(layer "In2.Cu")
		(net "N21581283")
	)
	(segment
		(start 25.768046 -55.714138)
		(end 25.768046 -49.369472)
		(width 0.1143)
		(layer "In2.Cu")
		(net "N21581283")
	)
	(segment
		(start 26.17978 -56.125872)
		(end 25.768046 -55.714138)
		(width 0.1143)
		(layer "In2.Cu")
		(net "N21581283")
	)
	(segment
		(start 26.17978 -57.795414)
		(end 26.17978 -56.125872)
		(width 0.1143)
		(layer "In2.Cu")
		(net "N21581283")
	)
	(segment
		(start 42.191178 -134.563612)
		(end 42.662602 -135.035036)
		(width 0.1016)
		(layer "F.Cu")
		(net "BMC_NODE1_DDR_RAS_L")
	)
	(segment
		(start 42.662602 -135.695944)
		(end 42.893488 -135.92683)
		(width 0.1016)
		(layer "F.Cu")
		(net "BMC_NODE1_DDR_RAS_L")
	)
	(segment
		(start 59.741816 -133.648958)
		(end 59.351164 -133.258306)
		(width 0.1016)
		(layer "F.Cu")
		(net "BMC_NODE1_DDR_RAS_L")
	)
	(segment
		(start 43.220386 -135.92683)
		(end 43.451272 -135.695944)
		(width 0.1016)
		(layer "F.Cu")
		(net "BMC_NODE1_DDR_RAS_L")
	)
	(segment
		(start 42.662602 -135.035036)
		(end 42.662602 -135.695944)
		(width 0.1016)
		(layer "F.Cu")
		(net "BMC_NODE1_DDR_RAS_L")
	)
	(segment
		(start 59.741816 -133.659626)
		(end 59.741816 -133.648958)
		(width 0.1016)
		(layer "F.Cu")
		(net "BMC_NODE1_DDR_RAS_L")
	)
	(segment
		(start 41.63314 -134.563612)
		(end 42.191178 -134.563612)
		(width 0.1016)
		(layer "F.Cu")
		(net "BMC_NODE1_DDR_RAS_L")
	)
	(segment
		(start 43.451272 -135.695944)
		(end 43.451272 -134.944866)
		(width 0.1016)
		(layer "F.Cu")
		(net "BMC_NODE1_DDR_RAS_L")
	)
	(segment
		(start 42.893488 -135.92683)
		(end 43.220386 -135.92683)
		(width 0.1016)
		(layer "F.Cu")
		(net "BMC_NODE1_DDR_RAS_L")
	)
	(segment
		(start 43.451272 -134.944866)
		(end 43.050714 -134.544308)
		(width 0.1016)
		(layer "F.Cu")
		(net "BMC_NODE1_DDR_RAS_L")
	)
	(segment
		(start 59.351164 -133.258306)
		(end 59.341004 -133.258306)
		(width 0.1016)
		(layer "F.Cu")
		(net "BMC_NODE1_DDR_RAS_L")
	)
	(via
		(at 43.050714 -134.544308)
		(size 0.508)
		(drill 0.254)
		(layers "F.Cu" "B.Cu")
		(net "BMC_NODE1_DDR_RAS_L")
	)
	(via
		(at 59.341004 -133.258306)
		(size 0.49022)
		(drill 0.254)
		(layers "F.Cu" "B.Cu")
		(net "BMC_NODE1_DDR_RAS_L")
	)
	(segment
		(start 51.28133 -134.303262)
		(end 51.932332 -134.954264)
		(width 0.1143)
		(layer "In2.Cu")
		(net "BMC_NODE1_DDR_RAS_L")
	)
	(segment
		(start 56.577484 -134.954264)
		(end 57.874408 -133.65734)
		(width 0.1143)
		(layer "In2.Cu")
		(net "BMC_NODE1_DDR_RAS_L")
	)
	(segment
		(start 45.525944 -134.62508)
		(end 46.365668 -134.62508)
		(width 0.1143)
		(layer "In2.Cu")
		(net "BMC_NODE1_DDR_RAS_L")
	)
	(segment
		(start 58.68416 -133.65734)
		(end 58.94197 -133.65734)
		(width 0.1143)
		(layer "In2.Cu")
		(net "BMC_NODE1_DDR_RAS_L")
	)
	(segment
		(start 46.687486 -134.303262)
		(end 51.28133 -134.303262)
		(width 0.1143)
		(layer "In2.Cu")
		(net "BMC_NODE1_DDR_RAS_L")
	)
	(segment
		(start 46.365668 -134.62508)
		(end 46.687486 -134.303262)
		(width 0.1143)
		(layer "In2.Cu")
		(net "BMC_NODE1_DDR_RAS_L")
	)
	(segment
		(start 58.372502 -133.65734)
		(end 58.68416 -133.65734)
		(width 0.1016)
		(layer "In2.Cu")
		(net "BMC_NODE1_DDR_RAS_L")
	)
	(segment
		(start 57.874408 -133.65734)
		(end 58.372502 -133.65734)
		(width 0.1143)
		(layer "In2.Cu")
		(net "BMC_NODE1_DDR_RAS_L")
	)
	(segment
		(start 45.462444 -134.56158)
		(end 45.525944 -134.62508)
		(width 0.1143)
		(layer "In2.Cu")
		(net "BMC_NODE1_DDR_RAS_L")
	)
	(segment
		(start 51.932332 -134.954264)
		(end 56.577484 -134.954264)
		(width 0.1143)
		(layer "In2.Cu")
		(net "BMC_NODE1_DDR_RAS_L")
	)
	(segment
		(start 58.94197 -133.65734)
		(end 59.341004 -133.258306)
		(width 0.1143)
		(layer "In2.Cu")
		(net "BMC_NODE1_DDR_RAS_L")
	)
	(segment
		(start 44.47667 -134.544308)
		(end 45.462444 -134.56158)
		(width 0.1016)
		(layer "In2.Cu")
		(net "BMC_NODE1_DDR_RAS_L")
	)
	(segment
		(start 43.050714 -134.544308)
		(end 44.47667 -134.544308)
		(width 0.1016)
		(layer "In2.Cu")
		(net "BMC_NODE1_DDR_RAS_L")
	)
	(segment
		(start 38.85946 -63.016384)
		(end 39.403274 -63.016384)
		(width 0.1143)
		(layer "F.Cu")
		(net "TP_CPU_NODE1_RP0_PLLMON1")
	)
	(segment
		(start 42.282618 -62.137798)
		(end 42.282618 -63.081408)
		(width 0.1143)
		(layer "F.Cu")
		(net "TP_CPU_NODE1_RP0_PLLMON1")
	)
	(segment
		(start 42.282618 -63.081408)
		(end 42.70248 -63.50127)
		(width 0.1143)
		(layer "F.Cu")
		(net "TP_CPU_NODE1_RP0_PLLMON1")
	)
	(segment
		(start 39.403274 -63.016384)
		(end 40.85971 -61.559948)
		(width 0.1143)
		(layer "F.Cu")
		(net "TP_CPU_NODE1_RP0_PLLMON1")
	)
	(segment
		(start 41.704768 -61.559948)
		(end 42.282618 -62.137798)
		(width 0.1143)
		(layer "F.Cu")
		(net "TP_CPU_NODE1_RP0_PLLMON1")
	)
	(segment
		(start 40.85971 -61.559948)
		(end 41.704768 -61.559948)
		(width 0.1143)
		(layer "F.Cu")
		(net "TP_CPU_NODE1_RP0_PLLMON1")
	)
	(via
		(at 38.85946 -63.016384)
		(size 0.508)
		(drill 0.254)
		(layers "F.Cu" "B.Cu")
		(net "TP_CPU_NODE1_RP0_PLLMON1")
	)
	(segment
		(start 73.116694 -74.99985)
		(end 73.41616 -74.99985)
		(width 0.1016)
		(layer "F.Cu")
		(net "M1_DQ_NODE1_DQ62")
	)
	(segment
		(start 75.274424 -74.992484)
		(end 75.721718 -74.6887)
		(width 0.1016)
		(layer "F.Cu")
		(net "M1_DQ_NODE1_DQ62")
	)
	(segment
		(start 76.178918 -74.377804)
		(end 76.492354 -74.164698)
		(width 0.1016)
		(layer "F.Cu")
		(net "M1_DQ_NODE1_DQ62")
	)
	(segment
		(start 72.651112 -74.534268)
		(end 73.116694 -74.99985)
		(width 0.1016)
		(layer "F.Cu")
		(net "M1_DQ_NODE1_DQ62")
	)
	(segment
		(start 72.651112 -74.437494)
		(end 72.651112 -74.534268)
		(width 0.1016)
		(layer "F.Cu")
		(net "M1_DQ_NODE1_DQ62")
	)
	(segment
		(start 101.473762 -25.190958)
		(end 101.641402 -25.190958)
		(width 0.1651)
		(layer "F.Cu")
		(net "M1_DQ_NODE1_DQ62")
	)
	(segment
		(start 73.41616 -74.99985)
		(end 73.55332 -74.86269)
		(width 0.1016)
		(layer "F.Cu")
		(net "M1_DQ_NODE1_DQ62")
	)
	(segment
		(start 75.721718 -74.6887)
		(end 76.178918 -74.377804)
		(width 0.1016)
		(layer "F.Cu")
		(net "M1_DQ_NODE1_DQ62")
	)
	(segment
		(start 73.950068 -74.86269)
		(end 74.079862 -74.992484)
		(width 0.1016)
		(layer "F.Cu")
		(net "M1_DQ_NODE1_DQ62")
	)
	(segment
		(start 72.205088 -73.99147)
		(end 72.651112 -74.437494)
		(width 0.1016)
		(layer "F.Cu")
		(net "M1_DQ_NODE1_DQ62")
	)
	(segment
		(start 100.050092 -26.614628)
		(end 101.473762 -25.190958)
		(width 0.1651)
		(layer "F.Cu")
		(net "M1_DQ_NODE1_DQ62")
	)
	(segment
		(start 74.079862 -74.992484)
		(end 75.274424 -74.992484)
		(width 0.1016)
		(layer "F.Cu")
		(net "M1_DQ_NODE1_DQ62")
	)
	(segment
		(start 100.050092 -29.149802)
		(end 100.050092 -26.614628)
		(width 0.1651)
		(layer "F.Cu")
		(net "M1_DQ_NODE1_DQ62")
	)
	(segment
		(start 76.492354 -74.164698)
		(end 76.500228 -74.159364)
		(width 0.1016)
		(layer "F.Cu")
		(net "M1_DQ_NODE1_DQ62")
	)
	(segment
		(start 73.55332 -74.86269)
		(end 73.950068 -74.86269)
		(width 0.1016)
		(layer "F.Cu")
		(net "M1_DQ_NODE1_DQ62")
	)
	(via
		(at 76.500228 -74.159364)
		(size 0.508)
		(drill 0.254)
		(layers "F.Cu" "B.Cu")
		(net "M1_DQ_NODE1_DQ62")
	)
	(via
		(at 101.641402 -25.190958)
		(size 0.508)
		(drill 0.254)
		(layers "F.Cu" "B.Cu")
		(net "M1_DQ_NODE1_DQ62")
	)
	(segment
		(start 103.54056 -26.516584)
		(end 103.54056 -26.222452)
		(width 0.2032)
		(layer "In7.Cu")
		(net "M1_DQ_NODE1_DQ62")
	)
	(segment
		(start 90.304112 -70.588124)
		(end 97.22612 -63.666116)
		(width 0.2032)
		(layer "In7.Cu")
		(net "M1_DQ_NODE1_DQ62")
	)
	(segment
		(start 103.759 -40.539924)
		(end 105.92816 -38.370764)
		(width 0.2032)
		(layer "In7.Cu")
		(net "M1_DQ_NODE1_DQ62")
	)
	(segment
		(start 78.165452 -74.159364)
		(end 78.30312 -74.021696)
		(width 0.1016)
		(layer "In7.Cu")
		(net "M1_DQ_NODE1_DQ62")
	)
	(segment
		(start 87.244682 -70.588124)
		(end 90.304112 -70.588124)
		(width 0.2032)
		(layer "In7.Cu")
		(net "M1_DQ_NODE1_DQ62")
	)
	(segment
		(start 103.54056 -26.222452)
		(end 103.779574 -25.983692)
		(width 0.2032)
		(layer "In7.Cu")
		(net "M1_DQ_NODE1_DQ62")
	)
	(segment
		(start 104.28224 -26.486866)
		(end 104.043734 -26.725372)
		(width 0.2032)
		(layer "In7.Cu")
		(net "M1_DQ_NODE1_DQ62")
	)
	(segment
		(start 103.749348 -26.725372)
		(end 103.54056 -26.516584)
		(width 0.2032)
		(layer "In7.Cu")
		(net "M1_DQ_NODE1_DQ62")
	)
	(segment
		(start 78.30312 -74.021696)
		(end 83.81111 -74.021696)
		(width 0.2032)
		(layer "In7.Cu")
		(net "M1_DQ_NODE1_DQ62")
	)
	(segment
		(start 97.22612 -63.666116)
		(end 97.22612 -58.383678)
		(width 0.2032)
		(layer "In7.Cu")
		(net "M1_DQ_NODE1_DQ62")
	)
	(segment
		(start 83.81111 -74.021696)
		(end 87.244682 -70.588124)
		(width 0.2032)
		(layer "In7.Cu")
		(net "M1_DQ_NODE1_DQ62")
	)
	(segment
		(start 105.92816 -27.838146)
		(end 104.57688 -26.486866)
		(width 0.2032)
		(layer "In7.Cu")
		(net "M1_DQ_NODE1_DQ62")
	)
	(segment
		(start 76.500228 -74.159364)
		(end 78.165452 -74.159364)
		(width 0.1016)
		(layer "In7.Cu")
		(net "M1_DQ_NODE1_DQ62")
	)
	(segment
		(start 105.92816 -38.370764)
		(end 105.92816 -27.838146)
		(width 0.2032)
		(layer "In7.Cu")
		(net "M1_DQ_NODE1_DQ62")
	)
	(segment
		(start 104.57688 -26.486866)
		(end 104.28224 -26.486866)
		(width 0.2032)
		(layer "In7.Cu")
		(net "M1_DQ_NODE1_DQ62")
	)
	(segment
		(start 103.779574 -25.983692)
		(end 103.779574 -25.68956)
		(width 0.2032)
		(layer "In7.Cu")
		(net "M1_DQ_NODE1_DQ62")
	)
	(segment
		(start 104.043734 -26.725372)
		(end 103.749348 -26.725372)
		(width 0.2032)
		(layer "In7.Cu")
		(net "M1_DQ_NODE1_DQ62")
	)
	(segment
		(start 103.779574 -25.68956)
		(end 103.280972 -25.190958)
		(width 0.2032)
		(layer "In7.Cu")
		(net "M1_DQ_NODE1_DQ62")
	)
	(segment
		(start 103.280972 -25.190958)
		(end 101.641402 -25.190958)
		(width 0.2032)
		(layer "In7.Cu")
		(net "M1_DQ_NODE1_DQ62")
	)
	(segment
		(start 103.759 -51.850798)
		(end 103.759 -40.539924)
		(width 0.2032)
		(layer "In7.Cu")
		(net "M1_DQ_NODE1_DQ62")
	)
	(segment
		(start 97.22612 -58.383678)
		(end 103.759 -51.850798)
		(width 0.2032)
		(layer "In7.Cu")
		(net "M1_DQ_NODE1_DQ62")
	)
	(segment
		(start 110.70209 -133.497828)
		(end 111.16564 -133.034278)
		(width 0.1778)
		(layer "F.Cu")
		(net "VR_PVCCP_NODE1_TONSET")
	)
	(segment
		(start 111.16564 -133.034278)
		(end 111.699548 -133.034278)
		(width 0.1778)
		(layer "F.Cu")
		(net "VR_PVCCP_NODE1_TONSET")
	)
	(segment
		(start 109.996478 -133.497828)
		(end 110.70209 -133.497828)
		(width 0.1778)
		(layer "F.Cu")
		(net "VR_PVCCP_NODE1_TONSET")
	)
	(segment
		(start 111.699548 -133.034278)
		(end 111.699548 -132.399024)
		(width 0.1778)
		(layer "F.Cu")
		(net "VR_PVCCP_NODE1_TONSET")
	)
	(via
		(at 111.699548 -133.034278)
		(size 0.508)
		(drill 0.254)
		(layers "F.Cu" "B.Cu")
		(net "VR_PVCCP_NODE1_TONSET")
	)
	(segment
		(start 181.869334 -131.30403)
		(end 181.869334 -130.42519)
		(width 0.1016)
		(layer "F.Cu")
		(net "FM_NODE1_CORE0_1_RST_L")
	)
	(segment
		(start 180.010562 -125.365764)
		(end 180.010562 -127.522478)
		(width 0.1016)
		(layer "F.Cu")
		(net "FM_NODE1_CORE0_1_RST_L")
	)
	(segment
		(start 181.869334 -131.30403)
		(end 181.869334 -132.399024)
		(width 0.1016)
		(layer "F.Cu")
		(net "FM_NODE1_CORE0_1_RST_L")
	)
	(segment
		(start 181.869334 -130.42519)
		(end 181.85638 -130.412236)
		(width 0.1016)
		(layer "F.Cu")
		(net "FM_NODE1_CORE0_1_RST_L")
	)
	(segment
		(start 181.85638 -129.368296)
		(end 181.85638 -130.412236)
		(width 0.1016)
		(layer "F.Cu")
		(net "FM_NODE1_CORE0_1_RST_L")
	)
	(segment
		(start 180.010562 -127.522478)
		(end 181.85638 -129.368296)
		(width 0.1016)
		(layer "F.Cu")
		(net "FM_NODE1_CORE0_1_RST_L")
	)
	(via
		(at 181.869334 -131.30403)
		(size 0.508)
		(drill 0.254)
		(layers "F.Cu" "B.Cu")
		(net "FM_NODE1_CORE0_1_RST_L")
	)
	(segment
		(start 60.15101 -134.058152)
		(end 60.141104 -134.058152)
		(width 0.1016)
		(layer "F.Cu")
		(net "BMC_NODE1_DDR_D1")
	)
	(segment
		(start 60.541916 -134.459472)
		(end 60.541916 -134.449058)
		(width 0.1016)
		(layer "F.Cu")
		(net "BMC_NODE1_DDR_D1")
	)
	(segment
		(start 42.10939 -135.363712)
		(end 42.239438 -135.233664)
		(width 0.1016)
		(layer "F.Cu")
		(net "BMC_NODE1_DDR_D1")
	)
	(segment
		(start 60.541916 -134.449058)
		(end 60.15101 -134.058152)
		(width 0.1016)
		(layer "F.Cu")
		(net "BMC_NODE1_DDR_D1")
	)
	(segment
		(start 41.63314 -135.363712)
		(end 42.10939 -135.363712)
		(width 0.1016)
		(layer "F.Cu")
		(net "BMC_NODE1_DDR_D1")
	)
	(via
		(at 42.239438 -135.233664)
		(size 0.508)
		(drill 0.254)
		(layers "F.Cu" "B.Cu")
		(net "BMC_NODE1_DDR_D1")
	)
	(via
		(at 60.141104 -134.058152)
		(size 0.49022)
		(drill 0.254)
		(layers "F.Cu" "B.Cu")
		(net "BMC_NODE1_DDR_D1")
	)
	(segment
		(start 59.40171 -134.797546)
		(end 60.141104 -134.058152)
		(width 0.1143)
		(layer "In7.Cu")
		(net "BMC_NODE1_DDR_D1")
	)
	(segment
		(start 42.578528 -135.572754)
		(end 45.520864 -135.572754)
		(width 0.1143)
		(layer "In7.Cu")
		(net "BMC_NODE1_DDR_D1")
	)
	(segment
		(start 56.729376 -134.797546)
		(end 59.40171 -134.797546)
		(width 0.1143)
		(layer "In7.Cu")
		(net "BMC_NODE1_DDR_D1")
	)
	(segment
		(start 48.505618 -131.85013)
		(end 49.04486 -131.310888)
		(width 0.1143)
		(layer "In7.Cu")
		(net "BMC_NODE1_DDR_D1")
	)
	(segment
		(start 51.240944 -132.089652)
		(end 51.240944 -134.734046)
		(width 0.1143)
		(layer "In7.Cu")
		(net "BMC_NODE1_DDR_D1")
	)
	(segment
		(start 51.83124 -135.324342)
		(end 56.20258 -135.324342)
		(width 0.1143)
		(layer "In7.Cu")
		(net "BMC_NODE1_DDR_D1")
	)
	(segment
		(start 47.070518 -134.320788)
		(end 47.44466 -133.13156)
		(width 0.1143)
		(layer "In7.Cu")
		(net "BMC_NODE1_DDR_D1")
	)
	(segment
		(start 51.240944 -134.734046)
		(end 51.83124 -135.324342)
		(width 0.1143)
		(layer "In7.Cu")
		(net "BMC_NODE1_DDR_D1")
	)
	(segment
		(start 50.46218 -131.310888)
		(end 51.240944 -132.089652)
		(width 0.1143)
		(layer "In7.Cu")
		(net "BMC_NODE1_DDR_D1")
	)
	(segment
		(start 46.185074 -135.206232)
		(end 47.070518 -134.320788)
		(width 0.1143)
		(layer "In7.Cu")
		(net "BMC_NODE1_DDR_D1")
	)
	(segment
		(start 48.505618 -132.070602)
		(end 48.505618 -131.85013)
		(width 0.1143)
		(layer "In7.Cu")
		(net "BMC_NODE1_DDR_D1")
	)
	(segment
		(start 42.239438 -135.233664)
		(end 42.578528 -135.572754)
		(width 0.1143)
		(layer "In7.Cu")
		(net "BMC_NODE1_DDR_D1")
	)
	(segment
		(start 45.520864 -135.572754)
		(end 45.887386 -135.206232)
		(width 0.1143)
		(layer "In7.Cu")
		(net "BMC_NODE1_DDR_D1")
	)
	(segment
		(start 47.44466 -133.13156)
		(end 48.505618 -132.070602)
		(width 0.1143)
		(layer "In7.Cu")
		(net "BMC_NODE1_DDR_D1")
	)
	(segment
		(start 56.20258 -135.324342)
		(end 56.729376 -134.797546)
		(width 0.1143)
		(layer "In7.Cu")
		(net "BMC_NODE1_DDR_D1")
	)
	(segment
		(start 49.04486 -131.310888)
		(end 50.46218 -131.310888)
		(width 0.1143)
		(layer "In7.Cu")
		(net "BMC_NODE1_DDR_D1")
	)
	(segment
		(start 45.887386 -135.206232)
		(end 46.185074 -135.206232)
		(width 0.1143)
		(layer "In7.Cu")
		(net "BMC_NODE1_DDR_D1")
	)
	(segment
		(start 89.55024 -18.87474)
		(end 89.554812 -18.870168)
		(width 0.1016)
		(layer "F.Cu")
		(net "PD_NODE1_DM5")
	)
	(segment
		(start 89.55024 -20.94992)
		(end 89.55024 -18.87474)
		(width 0.1016)
		(layer "F.Cu")
		(net "PD_NODE1_DM5")
	)
	(segment
		(start 89.554812 -17.60347)
		(end 89.554812 -18.870168)
		(width 0.1016)
		(layer "F.Cu")
		(net "PD_NODE1_DM5")
	)
	(via
		(at 89.554812 -18.870168)
		(size 0.508)
		(drill 0.254)
		(layers "F.Cu" "B.Cu")
		(net "PD_NODE1_DM5")
	)
	(segment
		(start 167.115744 -122.66422)
		(end 167.435784 -122.66422)
		(width 0.1016)
		(layer "F.Cu")
		(net "FM_NODE1_DDR3_DRAM_POK_L")
	)
	(segment
		(start 167.435784 -122.66422)
		(end 167.880792 -123.109228)
		(width 0.1016)
		(layer "F.Cu")
		(net "FM_NODE1_DDR3_DRAM_POK_L")
	)
	(segment
		(start 167.880792 -123.109228)
		(end 167.880792 -123.429268)
		(width 0.1016)
		(layer "F.Cu")
		(net "FM_NODE1_DDR3_DRAM_POK_L")
	)
	(segment
		(start 171.205144 -122.817128)
		(end 170.25493 -123.767342)
		(width 0.1016)
		(layer "F.Cu")
		(net "FM_NODE1_DDR3_DRAM_POK_L")
	)
	(segment
		(start 172.157136 -122.817128)
		(end 171.205144 -122.817128)
		(width 0.1016)
		(layer "F.Cu")
		(net "FM_NODE1_DDR3_DRAM_POK_L")
	)
	(segment
		(start 168.218866 -123.767342)
		(end 167.934132 -123.482608)
		(width 0.1016)
		(layer "F.Cu")
		(net "FM_NODE1_DDR3_DRAM_POK_L")
	)
	(segment
		(start 172.608494 -122.36577)
		(end 172.157136 -122.817128)
		(width 0.1016)
		(layer "F.Cu")
		(net "FM_NODE1_DDR3_DRAM_POK_L")
	)
	(segment
		(start 173.010322 -122.36577)
		(end 172.608494 -122.36577)
		(width 0.1016)
		(layer "F.Cu")
		(net "FM_NODE1_DDR3_DRAM_POK_L")
	)
	(segment
		(start 167.880792 -123.429268)
		(end 167.934132 -123.482608)
		(width 0.1016)
		(layer "F.Cu")
		(net "FM_NODE1_DDR3_DRAM_POK_L")
	)
	(segment
		(start 170.25493 -123.767342)
		(end 168.218866 -123.767342)
		(width 0.1016)
		(layer "F.Cu")
		(net "FM_NODE1_DDR3_DRAM_POK_L")
	)
	(via
		(at 167.934132 -123.482608)
		(size 0.508)
		(drill 0.254)
		(layers "F.Cu" "B.Cu")
		(net "FM_NODE1_DDR3_DRAM_POK_L")
	)
	(segment
		(start 44.849796 -126.768606)
		(end 48.5394 -126.768606)
		(width 0.1016)
		(layer "F.Cu")
		(net "BMC_NODE1_DDR_MA9")
	)
	(segment
		(start 50.41011 -128.639316)
		(end 50.68951 -128.639316)
		(width 0.1016)
		(layer "F.Cu")
		(net "BMC_NODE1_DDR_MA9")
	)
	(segment
		(start 41.63314 -129.763774)
		(end 41.633902 -129.764536)
		(width 0.1016)
		(layer "F.Cu")
		(net "BMC_NODE1_DDR_MA9")
	)
	(segment
		(start 41.853866 -129.764536)
		(end 42.140124 -129.478278)
		(width 0.1016)
		(layer "F.Cu")
		(net "BMC_NODE1_DDR_MA9")
	)
	(segment
		(start 42.940478 -129.478278)
		(end 43.04538 -129.373376)
		(width 0.1016)
		(layer "F.Cu")
		(net "BMC_NODE1_DDR_MA9")
	)
	(segment
		(start 41.633902 -129.764536)
		(end 41.853866 -129.764536)
		(width 0.1016)
		(layer "F.Cu")
		(net "BMC_NODE1_DDR_MA9")
	)
	(segment
		(start 57.143142 -130.052318)
		(end 55.73014 -128.639316)
		(width 0.1016)
		(layer "F.Cu")
		(net "BMC_NODE1_DDR_MA9")
	)
	(segment
		(start 48.5394 -126.768606)
		(end 50.41011 -128.639316)
		(width 0.1016)
		(layer "F.Cu")
		(net "BMC_NODE1_DDR_MA9")
	)
	(segment
		(start 43.04538 -129.373376)
		(end 43.04538 -128.573022)
		(width 0.1016)
		(layer "F.Cu")
		(net "BMC_NODE1_DDR_MA9")
	)
	(segment
		(start 42.140124 -129.478278)
		(end 42.940478 -129.478278)
		(width 0.1016)
		(layer "F.Cu")
		(net "BMC_NODE1_DDR_MA9")
	)
	(segment
		(start 43.04538 -128.573022)
		(end 44.849796 -126.768606)
		(width 0.1016)
		(layer "F.Cu")
		(net "BMC_NODE1_DDR_MA9")
	)
	(segment
		(start 55.73014 -128.639316)
		(end 50.68951 -128.639316)
		(width 0.1016)
		(layer "F.Cu")
		(net "BMC_NODE1_DDR_MA9")
	)
	(segment
		(start 58.14187 -130.45948)
		(end 57.734708 -130.052318)
		(width 0.1016)
		(layer "F.Cu")
		(net "BMC_NODE1_DDR_MA9")
	)
	(segment
		(start 57.734708 -130.052318)
		(end 57.143142 -130.052318)
		(width 0.1016)
		(layer "F.Cu")
		(net "BMC_NODE1_DDR_MA9")
	)
	(via
		(at 50.68951 -128.639316)
		(size 0.762)
		(drill 0.381)
		(layers "F.Cu" "B.Cu")
		(net "BMC_NODE1_DDR_MA9")
	)
	(segment
		(start 115.646962 -140.987526)
		(end 116.012976 -140.621512)
		(width 0.254)
		(layer "F.Cu")
		(net "VSENSE_VCC_CPU_NODE1")
	)
	(segment
		(start 116.012976 -140.621512)
		(end 116.075714 -140.621512)
		(width 0.254)
		(layer "F.Cu")
		(net "VSENSE_VCC_CPU_NODE1")
	)
	(segment
		(start 114.885216 -140.593826)
		(end 115.278916 -140.987526)
		(width 0.254)
		(layer "F.Cu")
		(net "VSENSE_VCC_CPU_NODE1")
	)
	(segment
		(start 61.601096 -77.399642)
		(end 61.615828 -77.399642)
		(width 0.254)
		(layer "F.Cu")
		(net "VSENSE_VCC_CPU_NODE1")
	)
	(segment
		(start 116.075714 -140.621512)
		(end 116.079524 -140.617702)
		(width 0.254)
		(layer "F.Cu")
		(net "VSENSE_VCC_CPU_NODE1")
	)
	(segment
		(start 61.615828 -77.399642)
		(end 62.005972 -77.009498)
		(width 0.254)
		(layer "F.Cu")
		(net "VSENSE_VCC_CPU_NODE1")
	)
	(segment
		(start 115.278916 -140.987526)
		(end 115.646962 -140.987526)
		(width 0.254)
		(layer "F.Cu")
		(net "VSENSE_VCC_CPU_NODE1")
	)
	(segment
		(start 114.50066 -140.593826)
		(end 114.885216 -140.593826)
		(width 0.254)
		(layer "F.Cu")
		(net "VSENSE_VCC_CPU_NODE1")
	)
	(segment
		(start 116.079524 -140.617702)
		(end 117.243352 -140.617702)
		(width 0.254)
		(layer "F.Cu")
		(net "VSENSE_VCC_CPU_NODE1")
	)
	(via
		(at 62.005972 -77.009498)
		(size 0.508)
		(drill 0.254)
		(layers "F.Cu" "B.Cu")
		(net "VSENSE_VCC_CPU_NODE1")
	)
	(via
		(at 115.278916 -140.987526)
		(size 0.508)
		(drill 0.254)
		(layers "F.Cu" "B.Cu")
		(net "VSENSE_VCC_CPU_NODE1")
	)
	(segment
		(start 63.404242 -76.87056)
		(end 63.037974 -76.504292)
		(width 0.254)
		(layer "In2.Cu")
		(net "VSENSE_VCC_CPU_NODE1")
	)
	(segment
		(start 65.322704 -79.569564)
		(end 65.322704 -79.56423)
		(width 0.254)
		(layer "In2.Cu")
		(net "VSENSE_VCC_CPU_NODE1")
	)
	(segment
		(start 90.96248 -105.375202)
		(end 90.96248 -103.246682)
		(width 0.254)
		(layer "In2.Cu")
		(net "VSENSE_VCC_CPU_NODE1")
	)
	(segment
		(start 94.10192 -86.621112)
		(end 93.4593 -85.978492)
		(width 0.254)
		(layer "In2.Cu")
		(net "VSENSE_VCC_CPU_NODE1")
	)
	(segment
		(start 67.187572 -79.782416)
		(end 65.535556 -79.782416)
		(width 0.254)
		(layer "In2.Cu")
		(net "VSENSE_VCC_CPU_NODE1")
	)
	(segment
		(start 115.421156 -140.561314)
		(end 115.717066 -140.561314)
		(width 0.254)
		(layer "In2.Cu")
		(net "VSENSE_VCC_CPU_NODE1")
	)
	(segment
		(start 102.107238 -143.454628)
		(end 99.25558 -140.60297)
		(width 0.254)
		(layer "In2.Cu")
		(net "VSENSE_VCC_CPU_NODE1")
	)
	(segment
		(start 62.511178 -76.504292)
		(end 62.005972 -77.009498)
		(width 0.254)
		(layer "In2.Cu")
		(net "VSENSE_VCC_CPU_NODE1")
	)
	(segment
		(start 94.10192 -100.107242)
		(end 94.10192 -86.621112)
		(width 0.254)
		(layer "In2.Cu")
		(net "VSENSE_VCC_CPU_NODE1")
	)
	(segment
		(start 63.037974 -76.504292)
		(end 62.511178 -76.504292)
		(width 0.254)
		(layer "In2.Cu")
		(net "VSENSE_VCC_CPU_NODE1")
	)
	(segment
		(start 65.535556 -79.782416)
		(end 65.322704 -79.569564)
		(width 0.254)
		(layer "In2.Cu")
		(net "VSENSE_VCC_CPU_NODE1")
	)
	(segment
		(start 90.19159 -85.978492)
		(end 89.408 -85.194902)
		(width 0.254)
		(layer "In2.Cu")
		(net "VSENSE_VCC_CPU_NODE1")
	)
	(segment
		(start 115.717066 -140.561314)
		(end 115.73002 -140.561568)
		(width 0.254)
		(layer "In2.Cu")
		(net "VSENSE_VCC_CPU_NODE1")
	)
	(segment
		(start 115.278916 -140.699998)
		(end 115.421156 -140.561314)
		(width 0.254)
		(layer "In2.Cu")
		(net "VSENSE_VCC_CPU_NODE1")
	)
	(segment
		(start 92.57792 -106.990642)
		(end 90.96248 -105.375202)
		(width 0.254)
		(layer "In2.Cu")
		(net "VSENSE_VCC_CPU_NODE1")
	)
	(segment
		(start 94.240604 -127.389636)
		(end 93.40342 -126.552452)
		(width 0.254)
		(layer "In2.Cu")
		(net "VSENSE_VCC_CPU_NODE1")
	)
	(segment
		(start 97.234248 -127.955802)
		(end 95.349568 -127.955802)
		(width 0.254)
		(layer "In2.Cu")
		(net "VSENSE_VCC_CPU_NODE1")
	)
	(segment
		(start 90.96248 -103.246682)
		(end 94.10192 -100.107242)
		(width 0.254)
		(layer "In2.Cu")
		(net "VSENSE_VCC_CPU_NODE1")
	)
	(segment
		(start 63.404242 -77.645768)
		(end 63.404242 -76.87056)
		(width 0.254)
		(layer "In2.Cu")
		(net "VSENSE_VCC_CPU_NODE1")
	)
	(segment
		(start 115.73002 -140.561568)
		(end 115.739418 -140.561568)
		(width 0.254)
		(layer "In2.Cu")
		(net "VSENSE_VCC_CPU_NODE1")
	)
	(segment
		(start 67.600322 -80.195166)
		(end 67.187572 -79.782416)
		(width 0.254)
		(layer "In2.Cu")
		(net "VSENSE_VCC_CPU_NODE1")
	)
	(segment
		(start 94.783402 -127.389636)
		(end 94.240604 -127.389636)
		(width 0.254)
		(layer "In2.Cu")
		(net "VSENSE_VCC_CPU_NODE1")
	)
	(segment
		(start 92.57792 -122.322336)
		(end 92.57792 -106.990642)
		(width 0.254)
		(layer "In2.Cu")
		(net "VSENSE_VCC_CPU_NODE1")
	)
	(segment
		(start 88.313514 -81.165446)
		(end 84.25434 -81.165446)
		(width 0.254)
		(layer "In2.Cu")
		(net "VSENSE_VCC_CPU_NODE1")
	)
	(segment
		(start 116.171472 -140.828776)
		(end 116.171472 -142.573756)
		(width 0.254)
		(layer "In2.Cu")
		(net "VSENSE_VCC_CPU_NODE1")
	)
	(segment
		(start 99.25558 -129.977134)
		(end 97.234248 -127.955802)
		(width 0.254)
		(layer "In2.Cu")
		(net "VSENSE_VCC_CPU_NODE1")
	)
	(segment
		(start 115.278916 -140.987526)
		(end 115.278916 -140.699998)
		(width 0.254)
		(layer "In2.Cu")
		(net "VSENSE_VCC_CPU_NODE1")
	)
	(segment
		(start 84.25434 -81.165446)
		(end 83.590638 -80.501744)
		(width 0.254)
		(layer "In2.Cu")
		(net "VSENSE_VCC_CPU_NODE1")
	)
	(segment
		(start 83.590638 -80.501744)
		(end 78.312518 -80.501744)
		(width 0.254)
		(layer "In2.Cu")
		(net "VSENSE_VCC_CPU_NODE1")
	)
	(segment
		(start 95.349568 -127.955802)
		(end 94.783402 -127.389636)
		(width 0.254)
		(layer "In2.Cu")
		(net "VSENSE_VCC_CPU_NODE1")
	)
	(segment
		(start 116.171472 -142.573756)
		(end 115.2906 -143.454628)
		(width 0.254)
		(layer "In2.Cu")
		(net "VSENSE_VCC_CPU_NODE1")
	)
	(segment
		(start 115.2906 -143.454628)
		(end 102.107238 -143.454628)
		(width 0.254)
		(layer "In2.Cu")
		(net "VSENSE_VCC_CPU_NODE1")
	)
	(segment
		(start 93.40342 -126.552452)
		(end 93.40342 -123.147836)
		(width 0.254)
		(layer "In2.Cu")
		(net "VSENSE_VCC_CPU_NODE1")
	)
	(segment
		(start 78.00594 -80.195166)
		(end 67.600322 -80.195166)
		(width 0.254)
		(layer "In2.Cu")
		(net "VSENSE_VCC_CPU_NODE1")
	)
	(segment
		(start 89.408 -85.194902)
		(end 89.408 -82.259932)
		(width 0.254)
		(layer "In2.Cu")
		(net "VSENSE_VCC_CPU_NODE1")
	)
	(segment
		(start 78.312518 -80.501744)
		(end 78.00594 -80.195166)
		(width 0.254)
		(layer "In2.Cu")
		(net "VSENSE_VCC_CPU_NODE1")
	)
	(segment
		(start 115.90655 -140.563854)
		(end 116.171472 -140.828776)
		(width 0.254)
		(layer "In2.Cu")
		(net "VSENSE_VCC_CPU_NODE1")
	)
	(segment
		(start 115.739418 -140.561568)
		(end 115.90655 -140.563854)
		(width 0.254)
		(layer "In2.Cu")
		(net "VSENSE_VCC_CPU_NODE1")
	)
	(segment
		(start 65.322704 -79.56423)
		(end 63.404242 -77.645768)
		(width 0.254)
		(layer "In2.Cu")
		(net "VSENSE_VCC_CPU_NODE1")
	)
	(segment
		(start 93.4593 -85.978492)
		(end 90.19159 -85.978492)
		(width 0.254)
		(layer "In2.Cu")
		(net "VSENSE_VCC_CPU_NODE1")
	)
	(segment
		(start 99.25558 -140.60297)
		(end 99.25558 -129.977134)
		(width 0.254)
		(layer "In2.Cu")
		(net "VSENSE_VCC_CPU_NODE1")
	)
	(segment
		(start 89.408 -82.259932)
		(end 88.313514 -81.165446)
		(width 0.254)
		(layer "In2.Cu")
		(net "VSENSE_VCC_CPU_NODE1")
	)
	(segment
		(start 93.40342 -123.147836)
		(end 92.57792 -122.322336)
		(width 0.254)
		(layer "In2.Cu")
		(net "VSENSE_VCC_CPU_NODE1")
	)
	(segment
		(start 69.688202 -66.979038)
		(end 69.688202 -67.311778)
		(width 0.1016)
		(layer "F.Cu")
		(net "M1_DQ_NODE1_DQ47")
	)
	(segment
		(start 92.781882 -32.54375)
		(end 92.510356 -32.54375)
		(width 0.1651)
		(layer "F.Cu")
		(net "M1_DQ_NODE1_DQ47")
	)
	(segment
		(start 69.688202 -67.311778)
		(end 69.474334 -67.525646)
		(width 0.1016)
		(layer "F.Cu")
		(net "M1_DQ_NODE1_DQ47")
	)
	(segment
		(start 91.05011 -31.083504)
		(end 91.05011 -29.149802)
		(width 0.1651)
		(layer "F.Cu")
		(net "M1_DQ_NODE1_DQ47")
	)
	(segment
		(start 92.510356 -32.54375)
		(end 91.05011 -31.083504)
		(width 0.1651)
		(layer "F.Cu")
		(net "M1_DQ_NODE1_DQ47")
	)
	(via
		(at 92.781882 -32.54375)
		(size 0.508)
		(drill 0.254)
		(layers "F.Cu" "B.Cu")
		(net "M1_DQ_NODE1_DQ47")
	)
	(via
		(at 69.474334 -67.525646)
		(size 0.508)
		(drill 0.254)
		(layers "F.Cu" "B.Cu")
		(net "M1_DQ_NODE1_DQ47")
	)
	(segment
		(start 78.730856 -61.631068)
		(end 77.70622 -62.655704)
		(width 0.2032)
		(layer "In2.Cu")
		(net "M1_DQ_NODE1_DQ47")
	)
	(segment
		(start 76.445618 -65.822576)
		(end 74.835766 -65.822576)
		(width 0.1016)
		(layer "In2.Cu")
		(net "M1_DQ_NODE1_DQ47")
	)
	(segment
		(start 92.781882 -32.54375)
		(end 92.783914 -32.54375)
		(width 0.2032)
		(layer "In2.Cu")
		(net "M1_DQ_NODE1_DQ47")
	)
	(segment
		(start 94.37878 -35.215068)
		(end 94.01302 -35.580828)
		(width 0.2032)
		(layer "In2.Cu")
		(net "M1_DQ_NODE1_DQ47")
	)
	(segment
		(start 94.01302 -45.745654)
		(end 94.01302 -46.040294)
		(width 0.2032)
		(layer "In2.Cu")
		(net "M1_DQ_NODE1_DQ47")
	)
	(segment
		(start 94.7293 -48.173894)
		(end 94.52102 -48.382174)
		(width 0.2032)
		(layer "In2.Cu")
		(net "M1_DQ_NODE1_DQ47")
	)
	(segment
		(start 94.52102 -43.403774)
		(end 94.7293 -43.612054)
		(width 0.2032)
		(layer "In2.Cu")
		(net "M1_DQ_NODE1_DQ47")
	)
	(segment
		(start 94.01302 -42.900854)
		(end 94.01302 -43.195494)
		(width 0.2032)
		(layer "In2.Cu")
		(net "M1_DQ_NODE1_DQ47")
	)
	(segment
		(start 94.52102 -44.826174)
		(end 94.7293 -45.034454)
		(width 0.2032)
		(layer "In2.Cu")
		(net "M1_DQ_NODE1_DQ47")
	)
	(segment
		(start 94.52102 -36.291774)
		(end 94.7293 -36.500054)
		(width 0.2032)
		(layer "In2.Cu")
		(net "M1_DQ_NODE1_DQ47")
	)
	(segment
		(start 94.7293 -42.484294)
		(end 94.52102 -42.692574)
		(width 0.2032)
		(layer "In2.Cu")
		(net "M1_DQ_NODE1_DQ47")
	)
	(segment
		(start 92.783914 -32.54375)
		(end 94.01302 -33.772856)
		(width 0.2032)
		(layer "In2.Cu")
		(net "M1_DQ_NODE1_DQ47")
	)
	(segment
		(start 72.401684 -67.468496)
		(end 71.973948 -67.896232)
		(width 0.1016)
		(layer "In2.Cu")
		(net "M1_DQ_NODE1_DQ47")
	)
	(segment
		(start 94.52102 -37.002974)
		(end 94.2213 -37.002974)
		(width 0.2032)
		(layer "In2.Cu")
		(net "M1_DQ_NODE1_DQ47")
	)
	(segment
		(start 77.009752 -65.258442)
		(end 76.445618 -65.822576)
		(width 0.1016)
		(layer "In2.Cu")
		(net "M1_DQ_NODE1_DQ47")
	)
	(segment
		(start 94.01302 -47.462694)
		(end 94.2213 -47.670974)
		(width 0.2032)
		(layer "In2.Cu")
		(net "M1_DQ_NODE1_DQ47")
	)
	(segment
		(start 94.52102 -47.670974)
		(end 94.7293 -47.879254)
		(width 0.2032)
		(layer "In2.Cu")
		(net "M1_DQ_NODE1_DQ47")
	)
	(segment
		(start 94.7293 -38.217094)
		(end 94.52102 -38.425374)
		(width 0.2032)
		(layer "In2.Cu")
		(net "M1_DQ_NODE1_DQ47")
	)
	(segment
		(start 94.01302 -33.772856)
		(end 94.01302 -34.503868)
		(width 0.2032)
		(layer "In2.Cu")
		(net "M1_DQ_NODE1_DQ47")
	)
	(segment
		(start 94.2213 -41.270174)
		(end 94.01302 -41.478454)
		(width 0.2032)
		(layer "In2.Cu")
		(net "M1_DQ_NODE1_DQ47")
	)
	(segment
		(start 94.2213 -44.114974)
		(end 94.01302 -44.323254)
		(width 0.2032)
		(layer "In2.Cu")
		(net "M1_DQ_NODE1_DQ47")
	)
	(segment
		(start 94.01302 -43.195494)
		(end 94.2213 -43.403774)
		(width 0.2032)
		(layer "In2.Cu")
		(net "M1_DQ_NODE1_DQ47")
	)
	(segment
		(start 94.52102 -46.248574)
		(end 94.7293 -46.456854)
		(width 0.2032)
		(layer "In2.Cu")
		(net "M1_DQ_NODE1_DQ47")
	)
	(segment
		(start 74.835766 -65.822576)
		(end 73.189846 -67.468496)
		(width 0.1016)
		(layer "In2.Cu")
		(net "M1_DQ_NODE1_DQ47")
	)
	(segment
		(start 94.01302 -38.928294)
		(end 94.2213 -39.136574)
		(width 0.2032)
		(layer "In2.Cu")
		(net "M1_DQ_NODE1_DQ47")
	)
	(segment
		(start 94.52102 -48.382174)
		(end 94.2213 -48.382174)
		(width 0.2032)
		(layer "In2.Cu")
		(net "M1_DQ_NODE1_DQ47")
	)
	(segment
		(start 94.7293 -39.639494)
		(end 94.52102 -39.847774)
		(width 0.2032)
		(layer "In2.Cu")
		(net "M1_DQ_NODE1_DQ47")
	)
	(segment
		(start 94.52102 -46.959774)
		(end 94.2213 -46.959774)
		(width 0.2032)
		(layer "In2.Cu")
		(net "M1_DQ_NODE1_DQ47")
	)
	(segment
		(start 94.7293 -43.906694)
		(end 94.52102 -44.114974)
		(width 0.2032)
		(layer "In2.Cu")
		(net "M1_DQ_NODE1_DQ47")
	)
	(segment
		(start 94.7293 -41.061894)
		(end 94.52102 -41.270174)
		(width 0.2032)
		(layer "In2.Cu")
		(net "M1_DQ_NODE1_DQ47")
	)
	(segment
		(start 94.01302 -35.580828)
		(end 94.01302 -36.083494)
		(width 0.2032)
		(layer "In2.Cu")
		(net "M1_DQ_NODE1_DQ47")
	)
	(segment
		(start 94.2213 -48.382174)
		(end 94.01302 -48.590454)
		(width 0.2032)
		(layer "In2.Cu")
		(net "M1_DQ_NODE1_DQ47")
	)
	(segment
		(start 94.2213 -45.537374)
		(end 94.01302 -45.745654)
		(width 0.2032)
		(layer "In2.Cu")
		(net "M1_DQ_NODE1_DQ47")
	)
	(segment
		(start 69.642228 -67.69354)
		(end 69.474334 -67.525646)
		(width 0.1016)
		(layer "In2.Cu")
		(net "M1_DQ_NODE1_DQ47")
	)
	(segment
		(start 94.7293 -40.767254)
		(end 94.7293 -41.061894)
		(width 0.2032)
		(layer "In2.Cu")
		(net "M1_DQ_NODE1_DQ47")
	)
	(segment
		(start 94.52102 -39.136574)
		(end 94.7293 -39.344854)
		(width 0.2032)
		(layer "In2.Cu")
		(net "M1_DQ_NODE1_DQ47")
	)
	(segment
		(start 94.01302 -40.056054)
		(end 94.01302 -40.350694)
		(width 0.2032)
		(layer "In2.Cu")
		(net "M1_DQ_NODE1_DQ47")
	)
	(segment
		(start 94.01302 -49.86782)
		(end 82.249772 -61.631068)
		(width 0.2032)
		(layer "In2.Cu")
		(net "M1_DQ_NODE1_DQ47")
	)
	(segment
		(start 94.01302 -40.350694)
		(end 94.2213 -40.558974)
		(width 0.2032)
		(layer "In2.Cu")
		(net "M1_DQ_NODE1_DQ47")
	)
	(segment
		(start 73.189846 -67.468496)
		(end 72.401684 -67.468496)
		(width 0.1016)
		(layer "In2.Cu")
		(net "M1_DQ_NODE1_DQ47")
	)
	(segment
		(start 94.7293 -39.344854)
		(end 94.7293 -39.639494)
		(width 0.2032)
		(layer "In2.Cu")
		(net "M1_DQ_NODE1_DQ47")
	)
	(segment
		(start 94.2213 -36.291774)
		(end 94.52102 -36.291774)
		(width 0.2032)
		(layer "In2.Cu")
		(net "M1_DQ_NODE1_DQ47")
	)
	(segment
		(start 94.01302 -36.083494)
		(end 94.2213 -36.291774)
		(width 0.2032)
		(layer "In2.Cu")
		(net "M1_DQ_NODE1_DQ47")
	)
	(segment
		(start 94.7293 -42.189654)
		(end 94.7293 -42.484294)
		(width 0.2032)
		(layer "In2.Cu")
		(net "M1_DQ_NODE1_DQ47")
	)
	(segment
		(start 94.01302 -44.323254)
		(end 94.01302 -44.617894)
		(width 0.2032)
		(layer "In2.Cu")
		(net "M1_DQ_NODE1_DQ47")
	)
	(segment
		(start 70.896226 -67.896232)
		(end 70.693534 -67.69354)
		(width 0.1016)
		(layer "In2.Cu")
		(net "M1_DQ_NODE1_DQ47")
	)
	(segment
		(start 94.7293 -45.329094)
		(end 94.52102 -45.537374)
		(width 0.2032)
		(layer "In2.Cu")
		(net "M1_DQ_NODE1_DQ47")
	)
	(segment
		(start 94.37878 -34.869628)
		(end 94.37878 -35.215068)
		(width 0.2032)
		(layer "In2.Cu")
		(net "M1_DQ_NODE1_DQ47")
	)
	(segment
		(start 94.52102 -40.558974)
		(end 94.7293 -40.767254)
		(width 0.2032)
		(layer "In2.Cu")
		(net "M1_DQ_NODE1_DQ47")
	)
	(segment
		(start 94.52102 -39.847774)
		(end 94.2213 -39.847774)
		(width 0.2032)
		(layer "In2.Cu")
		(net "M1_DQ_NODE1_DQ47")
	)
	(segment
		(start 94.01302 -38.633654)
		(end 94.01302 -38.928294)
		(width 0.2032)
		(layer "In2.Cu")
		(net "M1_DQ_NODE1_DQ47")
	)
	(segment
		(start 77.70622 -62.655704)
		(end 77.70622 -64.561974)
		(width 0.2032)
		(layer "In2.Cu")
		(net "M1_DQ_NODE1_DQ47")
	)
	(segment
		(start 71.973948 -67.896232)
		(end 70.896226 -67.896232)
		(width 0.1016)
		(layer "In2.Cu")
		(net "M1_DQ_NODE1_DQ47")
	)
	(segment
		(start 94.2213 -47.670974)
		(end 94.52102 -47.670974)
		(width 0.2032)
		(layer "In2.Cu")
		(net "M1_DQ_NODE1_DQ47")
	)
	(segment
		(start 94.52102 -37.714174)
		(end 94.7293 -37.922454)
		(width 0.2032)
		(layer "In2.Cu")
		(net "M1_DQ_NODE1_DQ47")
	)
	(segment
		(start 77.70622 -64.561974)
		(end 77.009752 -65.258442)
		(width 0.2032)
		(layer "In2.Cu")
		(net "M1_DQ_NODE1_DQ47")
	)
	(segment
		(start 94.7293 -45.034454)
		(end 94.7293 -45.329094)
		(width 0.2032)
		(layer "In2.Cu")
		(net "M1_DQ_NODE1_DQ47")
	)
	(segment
		(start 82.249772 -61.631068)
		(end 78.730856 -61.631068)
		(width 0.2032)
		(layer "In2.Cu")
		(net "M1_DQ_NODE1_DQ47")
	)
	(segment
		(start 94.7293 -36.500054)
		(end 94.7293 -36.794694)
		(width 0.2032)
		(layer "In2.Cu")
		(net "M1_DQ_NODE1_DQ47")
	)
	(segment
		(start 94.52102 -41.270174)
		(end 94.2213 -41.270174)
		(width 0.2032)
		(layer "In2.Cu")
		(net "M1_DQ_NODE1_DQ47")
	)
	(segment
		(start 94.2213 -46.248574)
		(end 94.52102 -46.248574)
		(width 0.2032)
		(layer "In2.Cu")
		(net "M1_DQ_NODE1_DQ47")
	)
	(segment
		(start 94.2213 -43.403774)
		(end 94.52102 -43.403774)
		(width 0.2032)
		(layer "In2.Cu")
		(net "M1_DQ_NODE1_DQ47")
	)
	(segment
		(start 94.01302 -44.617894)
		(end 94.2213 -44.826174)
		(width 0.2032)
		(layer "In2.Cu")
		(net "M1_DQ_NODE1_DQ47")
	)
	(segment
		(start 94.01302 -41.773094)
		(end 94.2213 -41.981374)
		(width 0.2032)
		(layer "In2.Cu")
		(net "M1_DQ_NODE1_DQ47")
	)
	(segment
		(start 94.2213 -37.714174)
		(end 94.52102 -37.714174)
		(width 0.2032)
		(layer "In2.Cu")
		(net "M1_DQ_NODE1_DQ47")
	)
	(segment
		(start 94.52102 -44.114974)
		(end 94.2213 -44.114974)
		(width 0.2032)
		(layer "In2.Cu")
		(net "M1_DQ_NODE1_DQ47")
	)
	(segment
		(start 94.7293 -36.794694)
		(end 94.52102 -37.002974)
		(width 0.2032)
		(layer "In2.Cu")
		(net "M1_DQ_NODE1_DQ47")
	)
	(segment
		(start 94.2213 -39.136574)
		(end 94.52102 -39.136574)
		(width 0.2032)
		(layer "In2.Cu")
		(net "M1_DQ_NODE1_DQ47")
	)
	(segment
		(start 70.693534 -67.69354)
		(end 69.642228 -67.69354)
		(width 0.1016)
		(layer "In2.Cu")
		(net "M1_DQ_NODE1_DQ47")
	)
	(segment
		(start 94.7293 -37.922454)
		(end 94.7293 -38.217094)
		(width 0.2032)
		(layer "In2.Cu")
		(net "M1_DQ_NODE1_DQ47")
	)
	(segment
		(start 94.7293 -46.751494)
		(end 94.52102 -46.959774)
		(width 0.2032)
		(layer "In2.Cu")
		(net "M1_DQ_NODE1_DQ47")
	)
	(segment
		(start 94.7293 -46.456854)
		(end 94.7293 -46.751494)
		(width 0.2032)
		(layer "In2.Cu")
		(net "M1_DQ_NODE1_DQ47")
	)
	(segment
		(start 94.2213 -37.002974)
		(end 94.01302 -37.211254)
		(width 0.2032)
		(layer "In2.Cu")
		(net "M1_DQ_NODE1_DQ47")
	)
	(segment
		(start 94.52102 -42.692574)
		(end 94.2213 -42.692574)
		(width 0.2032)
		(layer "In2.Cu")
		(net "M1_DQ_NODE1_DQ47")
	)
	(segment
		(start 94.01302 -48.590454)
		(end 94.01302 -49.86782)
		(width 0.2032)
		(layer "In2.Cu")
		(net "M1_DQ_NODE1_DQ47")
	)
	(segment
		(start 94.2213 -39.847774)
		(end 94.01302 -40.056054)
		(width 0.2032)
		(layer "In2.Cu")
		(net "M1_DQ_NODE1_DQ47")
	)
	(segment
		(start 94.01302 -47.168054)
		(end 94.01302 -47.462694)
		(width 0.2032)
		(layer "In2.Cu")
		(net "M1_DQ_NODE1_DQ47")
	)
	(segment
		(start 94.52102 -45.537374)
		(end 94.2213 -45.537374)
		(width 0.2032)
		(layer "In2.Cu")
		(net "M1_DQ_NODE1_DQ47")
	)
	(segment
		(start 94.2213 -41.981374)
		(end 94.52102 -41.981374)
		(width 0.2032)
		(layer "In2.Cu")
		(net "M1_DQ_NODE1_DQ47")
	)
	(segment
		(start 94.2213 -40.558974)
		(end 94.52102 -40.558974)
		(width 0.2032)
		(layer "In2.Cu")
		(net "M1_DQ_NODE1_DQ47")
	)
	(segment
		(start 94.7293 -43.612054)
		(end 94.7293 -43.906694)
		(width 0.2032)
		(layer "In2.Cu")
		(net "M1_DQ_NODE1_DQ47")
	)
	(segment
		(start 94.01302 -37.505894)
		(end 94.2213 -37.714174)
		(width 0.2032)
		(layer "In2.Cu")
		(net "M1_DQ_NODE1_DQ47")
	)
	(segment
		(start 94.2213 -42.692574)
		(end 94.01302 -42.900854)
		(width 0.2032)
		(layer "In2.Cu")
		(net "M1_DQ_NODE1_DQ47")
	)
	(segment
		(start 94.01302 -34.503868)
		(end 94.37878 -34.869628)
		(width 0.2032)
		(layer "In2.Cu")
		(net "M1_DQ_NODE1_DQ47")
	)
	(segment
		(start 94.7293 -47.879254)
		(end 94.7293 -48.173894)
		(width 0.2032)
		(layer "In2.Cu")
		(net "M1_DQ_NODE1_DQ47")
	)
	(segment
		(start 94.01302 -41.478454)
		(end 94.01302 -41.773094)
		(width 0.2032)
		(layer "In2.Cu")
		(net "M1_DQ_NODE1_DQ47")
	)
	(segment
		(start 94.52102 -38.425374)
		(end 94.2213 -38.425374)
		(width 0.2032)
		(layer "In2.Cu")
		(net "M1_DQ_NODE1_DQ47")
	)
	(segment
		(start 94.2213 -38.425374)
		(end 94.01302 -38.633654)
		(width 0.2032)
		(layer "In2.Cu")
		(net "M1_DQ_NODE1_DQ47")
	)
	(segment
		(start 94.01302 -37.211254)
		(end 94.01302 -37.505894)
		(width 0.2032)
		(layer "In2.Cu")
		(net "M1_DQ_NODE1_DQ47")
	)
	(segment
		(start 94.01302 -46.040294)
		(end 94.2213 -46.248574)
		(width 0.2032)
		(layer "In2.Cu")
		(net "M1_DQ_NODE1_DQ47")
	)
	(segment
		(start 94.52102 -41.981374)
		(end 94.7293 -42.189654)
		(width 0.2032)
		(layer "In2.Cu")
		(net "M1_DQ_NODE1_DQ47")
	)
	(segment
		(start 94.2213 -44.826174)
		(end 94.52102 -44.826174)
		(width 0.2032)
		(layer "In2.Cu")
		(net "M1_DQ_NODE1_DQ47")
	)
	(segment
		(start 94.2213 -46.959774)
		(end 94.01302 -47.168054)
		(width 0.2032)
		(layer "In2.Cu")
		(net "M1_DQ_NODE1_DQ47")
	)
	(segment
		(start 108.715556 -138.46683)
		(end 108.715556 -138.970512)
		(width 0.1778)
		(layer "F.Cu")
		(net "VR_PVCCP_NODE1_ICCMAX")
	)
	(segment
		(start 108.565188 -139.941046)
		(end 108.721906 -139.941046)
		(width 0.254)
		(layer "F.Cu")
		(net "VR_PVCCP_NODE1_ICCMAX")
	)
	(segment
		(start 108.471462 -137.42289)
		(end 108.471462 -138.222736)
		(width 0.1778)
		(layer "F.Cu")
		(net "VR_PVCCP_NODE1_ICCMAX")
	)
	(segment
		(start 108.72724 -142.014448)
		(end 108.48086 -142.014448)
		(width 0.254)
		(layer "F.Cu")
		(net "VR_PVCCP_NODE1_ICCMAX")
	)
	(segment
		(start 108.471462 -138.222736)
		(end 108.715556 -138.46683)
		(width 0.1778)
		(layer "F.Cu")
		(net "VR_PVCCP_NODE1_ICCMAX")
	)
	(segment
		(start 108.721906 -138.976862)
		(end 108.721906 -139.222226)
		(width 0.254)
		(layer "F.Cu")
		(net "VR_PVCCP_NODE1_ICCMAX")
	)
	(segment
		(start 108.185712 -140.320522)
		(end 108.565188 -139.941046)
		(width 0.254)
		(layer "F.Cu")
		(net "VR_PVCCP_NODE1_ICCMAX")
	)
	(segment
		(start 108.715556 -138.970512)
		(end 108.721906 -138.976862)
		(width 0.1778)
		(layer "F.Cu")
		(net "VR_PVCCP_NODE1_ICCMAX")
	)
	(segment
		(start 108.48086 -142.014448)
		(end 108.185712 -141.7193)
		(width 0.254)
		(layer "F.Cu")
		(net "VR_PVCCP_NODE1_ICCMAX")
	)
	(segment
		(start 108.721906 -139.222226)
		(end 108.721906 -139.941046)
		(width 0.254)
		(layer "F.Cu")
		(net "VR_PVCCP_NODE1_ICCMAX")
	)
	(segment
		(start 108.185712 -141.7193)
		(end 108.185712 -140.320522)
		(width 0.254)
		(layer "F.Cu")
		(net "VR_PVCCP_NODE1_ICCMAX")
	)
	(via
		(at 108.721906 -139.222226)
		(size 0.508)
		(drill 0.254)
		(layers "F.Cu" "B.Cu")
		(net "VR_PVCCP_NODE1_ICCMAX")
	)
	(segment
		(start 179.415694 -135.976106)
		(end 179.415694 -135.288528)
		(width 0.1016)
		(layer "F.Cu")
		(net "FM_CPLD_NODE1_WDT_R")
	)
	(segment
		(start 179.415694 -134.42442)
		(end 179.415694 -135.288528)
		(width 0.1016)
		(layer "F.Cu")
		(net "FM_CPLD_NODE1_WDT_R")
	)
	(segment
		(start 179.400454 -135.991346)
		(end 179.415694 -135.976106)
		(width 0.1016)
		(layer "F.Cu")
		(net "FM_CPLD_NODE1_WDT_R")
	)
	(via
		(at 179.415694 -135.288528)
		(size 0.508)
		(drill 0.254)
		(layers "F.Cu" "B.Cu")
		(net "FM_CPLD_NODE1_WDT_R")
	)
	(segment
		(start 60.541916 -132.859018)
		(end 60.141104 -132.458206)
		(width 0.1016)
		(layer "F.Cu")
		(net "BMC_NODE1_DDR_ODT")
	)
	(segment
		(start 40.033194 -133.763766)
		(end 40.43172 -134.162292)
		(width 0.1016)
		(layer "F.Cu")
		(net "BMC_NODE1_DDR_ODT")
	)
	(segment
		(start 60.541916 -132.859526)
		(end 60.541916 -132.859018)
		(width 0.1016)
		(layer "F.Cu")
		(net "BMC_NODE1_DDR_ODT")
	)
	(segment
		(start 40.43172 -134.162292)
		(end 40.43172 -134.169658)
		(width 0.1016)
		(layer "F.Cu")
		(net "BMC_NODE1_DDR_ODT")
	)
	(via
		(at 60.141104 -132.458206)
		(size 0.49022)
		(drill 0.254)
		(layers "F.Cu" "B.Cu")
		(net "BMC_NODE1_DDR_ODT")
	)
	(via
		(at 40.43172 -134.169658)
		(size 0.49022)
		(drill 0.254)
		(layers "F.Cu" "B.Cu")
		(net "BMC_NODE1_DDR_ODT")
	)
	(segment
		(start 60.234322 -134.545324)
		(end 60.515754 -134.263892)
		(width 0.1143)
		(layer "In2.Cu")
		(net "BMC_NODE1_DDR_ODT")
	)
	(segment
		(start 58.932064 -134.98576)
		(end 59.445906 -134.86892)
		(width 0.1143)
		(layer "In2.Cu")
		(net "BMC_NODE1_DDR_ODT")
	)
	(segment
		(start 60.54217 -133.08203)
		(end 60.276486 -132.668772)
		(width 0.1143)
		(layer "In2.Cu")
		(net "BMC_NODE1_DDR_ODT")
	)
	(segment
		(start 59.445906 -134.86892)
		(end 60.234322 -134.545324)
		(width 0.1143)
		(layer "In2.Cu")
		(net "BMC_NODE1_DDR_ODT")
	)
	(segment
		(start 44.014898 -135.821674)
		(end 45.835316 -136.163304)
		(width 0.1143)
		(layer "In2.Cu")
		(net "BMC_NODE1_DDR_ODT")
	)
	(segment
		(start 57.740804 -135.61568)
		(end 58.066686 -135.443468)
		(width 0.1143)
		(layer "In2.Cu")
		(net "BMC_NODE1_DDR_ODT")
	)
	(segment
		(start 47.477934 -136.186164)
		(end 47.570898 -136.150604)
		(width 0.1143)
		(layer "In2.Cu")
		(net "BMC_NODE1_DDR_ODT")
	)
	(segment
		(start 54.699916 -136.405366)
		(end 56.532272 -136.405366)
		(width 0.1143)
		(layer "In2.Cu")
		(net "BMC_NODE1_DDR_ODT")
	)
	(segment
		(start 47.121064 -136.186164)
		(end 47.477934 -136.186164)
		(width 0.1143)
		(layer "In2.Cu")
		(net "BMC_NODE1_DDR_ODT")
	)
	(segment
		(start 42.06113 -135.63219)
		(end 42.06113 -135.642096)
		(width 0.1143)
		(layer "In2.Cu")
		(net "BMC_NODE1_DDR_ODT")
	)
	(segment
		(start 60.54217 -134.237476)
		(end 60.54217 -133.903212)
		(width 0.1016)
		(layer "In2.Cu")
		(net "BMC_NODE1_DDR_ODT")
	)
	(segment
		(start 56.532272 -136.405366)
		(end 56.948578 -136.18337)
		(width 0.1143)
		(layer "In2.Cu")
		(net "BMC_NODE1_DDR_ODT")
	)
	(segment
		(start 60.515754 -134.263892)
		(end 60.54217 -134.237476)
		(width 0.1016)
		(layer "In2.Cu")
		(net "BMC_NODE1_DDR_ODT")
	)
	(segment
		(start 42.248582 -135.691626)
		(end 44.014898 -135.821674)
		(width 0.1143)
		(layer "In2.Cu")
		(net "BMC_NODE1_DDR_ODT")
	)
	(segment
		(start 47.570898 -136.150604)
		(end 48.220376 -136.150604)
		(width 0.1143)
		(layer "In2.Cu")
		(net "BMC_NODE1_DDR_ODT")
	)
	(segment
		(start 42.06113 -135.642096)
		(end 42.248582 -135.691626)
		(width 0.1143)
		(layer "In2.Cu")
		(net "BMC_NODE1_DDR_ODT")
	)
	(segment
		(start 46.237398 -136.163304)
		(end 46.290484 -136.110218)
		(width 0.1143)
		(layer "In2.Cu")
		(net "BMC_NODE1_DDR_ODT")
	)
	(segment
		(start 50.877978 -137.586212)
		(end 53.51907 -137.586212)
		(width 0.1143)
		(layer "In2.Cu")
		(net "BMC_NODE1_DDR_ODT")
	)
	(segment
		(start 53.51907 -137.586212)
		(end 54.699916 -136.405366)
		(width 0.1143)
		(layer "In2.Cu")
		(net "BMC_NODE1_DDR_ODT")
	)
	(segment
		(start 46.290484 -136.110218)
		(end 47.045118 -136.110218)
		(width 0.1143)
		(layer "In2.Cu")
		(net "BMC_NODE1_DDR_ODT")
	)
	(segment
		(start 45.835316 -136.163304)
		(end 46.237398 -136.163304)
		(width 0.1016)
		(layer "In2.Cu")
		(net "BMC_NODE1_DDR_ODT")
	)
	(segment
		(start 58.066686 -135.443468)
		(end 58.932064 -134.98576)
		(width 0.1143)
		(layer "In2.Cu")
		(net "BMC_NODE1_DDR_ODT")
	)
	(segment
		(start 60.54217 -133.903212)
		(end 60.54217 -133.408674)
		(width 0.1143)
		(layer "In2.Cu")
		(net "BMC_NODE1_DDR_ODT")
	)
	(segment
		(start 60.54217 -133.408674)
		(end 60.54217 -133.08203)
		(width 0.1016)
		(layer "In2.Cu")
		(net "BMC_NODE1_DDR_ODT")
	)
	(segment
		(start 40.43172 -134.169658)
		(end 42.06113 -135.63219)
		(width 0.1143)
		(layer "In2.Cu")
		(net "BMC_NODE1_DDR_ODT")
	)
	(segment
		(start 47.045118 -136.110218)
		(end 47.121064 -136.186164)
		(width 0.1143)
		(layer "In2.Cu")
		(net "BMC_NODE1_DDR_ODT")
	)
	(segment
		(start 60.276486 -132.668772)
		(end 60.141104 -132.458206)
		(width 0.1143)
		(layer "In2.Cu")
		(net "BMC_NODE1_DDR_ODT")
	)
	(segment
		(start 56.948578 -136.18337)
		(end 57.740804 -135.61568)
		(width 0.1143)
		(layer "In2.Cu")
		(net "BMC_NODE1_DDR_ODT")
	)
	(segment
		(start 48.220376 -136.150604)
		(end 50.877978 -137.586212)
		(width 0.1143)
		(layer "In2.Cu")
		(net "BMC_NODE1_DDR_ODT")
	)
	(segment
		(start 47.703994 -22.30501)
		(end 47.55007 -22.151086)
		(width 0.1651)
		(layer "F.Cu")
		(net "M_DDR3_NODE1_DQS1N")
	)
	(segment
		(start 47.55007 -22.151086)
		(end 47.55007 -20.94992)
		(width 0.1651)
		(layer "F.Cu")
		(net "M_DDR3_NODE1_DQS1N")
	)
	(segment
		(start 47.980346 -61.003688)
		(end 47.980346 -61.012832)
		(width 0.09906)
		(layer "F.Cu")
		(net "M_DDR3_NODE1_DQS1N")
	)
	(segment
		(start 47.703994 -22.510242)
		(end 47.703994 -22.30501)
		(width 0.1651)
		(layer "F.Cu")
		(net "M_DDR3_NODE1_DQS1N")
	)
	(segment
		(start 47.329344 -23.329138)
		(end 47.460662 -23.19782)
		(width 0.1651)
		(layer "F.Cu")
		(net "M_DDR3_NODE1_DQS1N")
	)
	(segment
		(start 47.460662 -23.19782)
		(end 47.460662 -22.753574)
		(width 0.1651)
		(layer "F.Cu")
		(net "M_DDR3_NODE1_DQS1N")
	)
	(segment
		(start 49.0474 -63.49492)
		(end 49.0474 -63.24854)
		(width 0.09906)
		(layer "F.Cu")
		(net "M_DDR3_NODE1_DQS1N")
	)
	(segment
		(start 47.460662 -22.753574)
		(end 47.703994 -22.510242)
		(width 0.1651)
		(layer "F.Cu")
		(net "M_DDR3_NODE1_DQS1N")
	)
	(segment
		(start 48.543464 -62.744604)
		(end 48.543464 -60.70219)
		(width 0.09906)
		(layer "F.Cu")
		(net "M_DDR3_NODE1_DQS1N")
	)
	(segment
		(start 46.971712 -23.329138)
		(end 47.329344 -23.329138)
		(width 0.1651)
		(layer "F.Cu")
		(net "M_DDR3_NODE1_DQS1N")
	)
	(segment
		(start 48.488092 -60.646818)
		(end 48.337216 -60.646818)
		(width 0.09906)
		(layer "F.Cu")
		(net "M_DDR3_NODE1_DQS1N")
	)
	(segment
		(start 49.0474 -63.24854)
		(end 48.543464 -62.744604)
		(width 0.09906)
		(layer "F.Cu")
		(net "M_DDR3_NODE1_DQS1N")
	)
	(segment
		(start 48.337216 -60.646818)
		(end 47.980346 -61.003688)
		(width 0.09906)
		(layer "F.Cu")
		(net "M_DDR3_NODE1_DQS1N")
	)
	(segment
		(start 48.543464 -60.70219)
		(end 48.488092 -60.646818)
		(width 0.09906)
		(layer "F.Cu")
		(net "M_DDR3_NODE1_DQS1N")
	)
	(via
		(at 47.980346 -61.012832)
		(size 0.508)
		(drill 0.254)
		(layers "F.Cu" "B.Cu")
		(net "M_DDR3_NODE1_DQS1N")
	)
	(via
		(at 46.971712 -23.329138)
		(size 0.508)
		(drill 0.254)
		(layers "F.Cu" "B.Cu")
		(net "M_DDR3_NODE1_DQS1N")
	)
	(segment
		(start 35.9791 -48.033432)
		(end 35.9791 -47.46498)
		(width 0.2032)
		(layer "In2.Cu")
		(net "M_DDR3_NODE1_DQS1N")
	)
	(segment
		(start 47.650146 -60.682632)
		(end 47.466758 -60.682632)
		(width 0.09906)
		(layer "In2.Cu")
		(net "M_DDR3_NODE1_DQS1N")
	)
	(segment
		(start 48.64608 -32.594042)
		(end 48.64608 -32.11957)
		(width 0.2032)
		(layer "In2.Cu")
		(net "M_DDR3_NODE1_DQS1N")
	)
	(segment
		(start 36.85794 -40.606726)
		(end 36.85794 -39.073836)
		(width 0.2032)
		(layer "In2.Cu")
		(net "M_DDR3_NODE1_DQS1N")
	)
	(segment
		(start 36.85794 -42.689526)
		(end 36.85794 -42.394886)
		(width 0.2032)
		(layer "In2.Cu")
		(net "M_DDR3_NODE1_DQS1N")
	)
	(segment
		(start 36.64966 -44.269406)
		(end 36.380674 -44.269406)
		(width 0.2032)
		(layer "In2.Cu")
		(net "M_DDR3_NODE1_DQS1N")
	)
	(segment
		(start 46.903132 -57.918604)
		(end 45.785024 -57.918604)
		(width 0.09906)
		(layer "In2.Cu")
		(net "M_DDR3_NODE1_DQS1N")
	)
	(segment
		(start 36.64966 -49.146206)
		(end 36.85794 -48.937926)
		(width 0.2032)
		(layer "In2.Cu")
		(net "M_DDR3_NODE1_DQS1N")
	)
	(segment
		(start 44.60875 -57.501536)
		(end 44.595542 -57.501536)
		(width 0.09906)
		(layer "In2.Cu")
		(net "M_DDR3_NODE1_DQS1N")
	)
	(segment
		(start 40.456104 -35.475672)
		(end 45.76445 -35.475672)
		(width 0.2032)
		(layer "In2.Cu")
		(net "M_DDR3_NODE1_DQS1N")
	)
	(segment
		(start 45.304456 -57.438036)
		(end 44.67225 -57.438036)
		(width 0.09906)
		(layer "In2.Cu")
		(net "M_DDR3_NODE1_DQS1N")
	)
	(segment
		(start 36.380674 -42.897806)
		(end 36.64966 -42.897806)
		(width 0.2032)
		(layer "In2.Cu")
		(net "M_DDR3_NODE1_DQS1N")
	)
	(segment
		(start 45.76445 -35.475672)
		(end 48.64608 -32.594042)
		(width 0.2032)
		(layer "In2.Cu")
		(net "M_DDR3_NODE1_DQS1N")
	)
	(segment
		(start 47.23638 -58.251852)
		(end 46.903132 -57.918604)
		(width 0.09906)
		(layer "In2.Cu")
		(net "M_DDR3_NODE1_DQS1N")
	)
	(segment
		(start 47.804578 -24.570436)
		(end 47.427642 -24.1935)
		(width 0.2032)
		(layer "In2.Cu")
		(net "M_DDR3_NODE1_DQS1N")
	)
	(segment
		(start 36.85794 -53.682138)
		(end 36.85794 -52.808886)
		(width 0.2032)
		(layer "In2.Cu")
		(net "M_DDR3_NODE1_DQS1N")
	)
	(segment
		(start 39.576502 -56.4007)
		(end 36.85794 -53.682138)
		(width 0.2032)
		(layer "In2.Cu")
		(net "M_DDR3_NODE1_DQS1N")
	)
	(segment
		(start 48.550322 -26.385774)
		(end 49.09566 -25.840436)
		(width 0.2032)
		(layer "In2.Cu")
		(net "M_DDR3_NODE1_DQS1N")
	)
	(segment
		(start 36.85794 -48.937926)
		(end 36.85794 -48.643286)
		(width 0.2032)
		(layer "In2.Cu")
		(net "M_DDR3_NODE1_DQS1N")
	)
	(segment
		(start 48.550322 -28.867862)
		(end 48.550322 -26.385774)
		(width 0.2032)
		(layer "In2.Cu")
		(net "M_DDR3_NODE1_DQS1N")
	)
	(segment
		(start 35.9791 -41.785032)
		(end 35.9791 -41.21658)
		(width 0.2032)
		(layer "In2.Cu")
		(net "M_DDR3_NODE1_DQS1N")
	)
	(segment
		(start 36.380674 -49.146206)
		(end 36.64966 -49.146206)
		(width 0.2032)
		(layer "In2.Cu")
		(net "M_DDR3_NODE1_DQS1N")
	)
	(segment
		(start 49.09566 -24.983186)
		(end 48.68291 -24.570436)
		(width 0.2032)
		(layer "In2.Cu")
		(net "M_DDR3_NODE1_DQS1N")
	)
	(segment
		(start 47.466758 -60.682632)
		(end 47.23638 -60.452254)
		(width 0.09906)
		(layer "In2.Cu")
		(net "M_DDR3_NODE1_DQS1N")
	)
	(segment
		(start 48.68291 -24.570436)
		(end 47.804578 -24.570436)
		(width 0.2032)
		(layer "In2.Cu")
		(net "M_DDR3_NODE1_DQS1N")
	)
	(segment
		(start 36.64966 -48.435006)
		(end 36.380674 -48.435006)
		(width 0.2032)
		(layer "In2.Cu")
		(net "M_DDR3_NODE1_DQS1N")
	)
	(segment
		(start 36.380674 -40.815006)
		(end 36.64966 -40.815006)
		(width 0.2032)
		(layer "In2.Cu")
		(net "M_DDR3_NODE1_DQS1N")
	)
	(segment
		(start 36.85794 -46.560486)
		(end 36.64966 -46.352206)
		(width 0.2032)
		(layer "In2.Cu")
		(net "M_DDR3_NODE1_DQS1N")
	)
	(segment
		(start 36.380674 -50.517806)
		(end 35.9791 -50.116232)
		(width 0.2032)
		(layer "In2.Cu")
		(net "M_DDR3_NODE1_DQS1N")
	)
	(segment
		(start 36.85794 -42.394886)
		(end 36.64966 -42.186606)
		(width 0.2032)
		(layer "In2.Cu")
		(net "M_DDR3_NODE1_DQS1N")
	)
	(segment
		(start 36.380674 -47.063406)
		(end 36.64966 -47.063406)
		(width 0.2032)
		(layer "In2.Cu")
		(net "M_DDR3_NODE1_DQS1N")
	)
	(segment
		(start 36.85794 -51.020726)
		(end 36.85794 -50.726086)
		(width 0.2032)
		(layer "In2.Cu")
		(net "M_DDR3_NODE1_DQS1N")
	)
	(segment
		(start 43.084242 -57.501536)
		(end 41.983406 -56.4007)
		(width 0.2032)
		(layer "In2.Cu")
		(net "M_DDR3_NODE1_DQS1N")
	)
	(segment
		(start 36.85794 -48.643286)
		(end 36.64966 -48.435006)
		(width 0.2032)
		(layer "In2.Cu")
		(net "M_DDR3_NODE1_DQS1N")
	)
	(segment
		(start 35.9791 -45.38218)
		(end 36.380674 -44.980606)
		(width 0.2032)
		(layer "In2.Cu")
		(net "M_DDR3_NODE1_DQS1N")
	)
	(segment
		(start 36.380674 -46.352206)
		(end 35.9791 -45.950632)
		(width 0.2032)
		(layer "In2.Cu")
		(net "M_DDR3_NODE1_DQS1N")
	)
	(segment
		(start 36.85794 -46.855126)
		(end 36.85794 -46.560486)
		(width 0.2032)
		(layer "In2.Cu")
		(net "M_DDR3_NODE1_DQS1N")
	)
	(segment
		(start 48.64608 -32.11957)
		(end 48.14316 -31.61665)
		(width 0.2032)
		(layer "In2.Cu")
		(net "M_DDR3_NODE1_DQS1N")
	)
	(segment
		(start 36.64966 -42.186606)
		(end 36.380674 -42.186606)
		(width 0.2032)
		(layer "In2.Cu")
		(net "M_DDR3_NODE1_DQS1N")
	)
	(segment
		(start 35.9791 -49.54778)
		(end 36.380674 -49.146206)
		(width 0.2032)
		(layer "In2.Cu")
		(net "M_DDR3_NODE1_DQS1N")
	)
	(segment
		(start 48.14316 -31.61665)
		(end 48.14316 -29.275024)
		(width 0.2032)
		(layer "In2.Cu")
		(net "M_DDR3_NODE1_DQS1N")
	)
	(segment
		(start 36.380674 -51.229006)
		(end 36.64966 -51.229006)
		(width 0.2032)
		(layer "In2.Cu")
		(net "M_DDR3_NODE1_DQS1N")
	)
	(segment
		(start 36.380674 -44.269406)
		(end 35.9791 -43.867832)
		(width 0.2032)
		(layer "In2.Cu")
		(net "M_DDR3_NODE1_DQS1N")
	)
	(segment
		(start 36.64966 -52.600606)
		(end 36.380674 -52.600606)
		(width 0.2032)
		(layer "In2.Cu")
		(net "M_DDR3_NODE1_DQS1N")
	)
	(segment
		(start 36.64966 -46.352206)
		(end 36.380674 -46.352206)
		(width 0.2032)
		(layer "In2.Cu")
		(net "M_DDR3_NODE1_DQS1N")
	)
	(segment
		(start 47.23638 -60.452254)
		(end 47.23638 -58.251852)
		(width 0.09906)
		(layer "In2.Cu")
		(net "M_DDR3_NODE1_DQS1N")
	)
	(segment
		(start 35.9791 -43.867832)
		(end 35.9791 -43.29938)
		(width 0.2032)
		(layer "In2.Cu")
		(net "M_DDR3_NODE1_DQS1N")
	)
	(segment
		(start 36.85794 -52.808886)
		(end 36.64966 -52.600606)
		(width 0.2032)
		(layer "In2.Cu")
		(net "M_DDR3_NODE1_DQS1N")
	)
	(segment
		(start 44.67225 -57.438036)
		(end 44.60875 -57.501536)
		(width 0.09906)
		(layer "In2.Cu")
		(net "M_DDR3_NODE1_DQS1N")
	)
	(segment
		(start 36.64966 -44.980606)
		(end 36.85794 -44.772326)
		(width 0.2032)
		(layer "In2.Cu")
		(net "M_DDR3_NODE1_DQS1N")
	)
	(segment
		(start 45.785024 -57.918604)
		(end 45.304456 -57.438036)
		(width 0.09906)
		(layer "In2.Cu")
		(net "M_DDR3_NODE1_DQS1N")
	)
	(segment
		(start 36.380674 -52.600606)
		(end 35.9791 -52.199032)
		(width 0.2032)
		(layer "In2.Cu")
		(net "M_DDR3_NODE1_DQS1N")
	)
	(segment
		(start 36.64966 -51.229006)
		(end 36.85794 -51.020726)
		(width 0.2032)
		(layer "In2.Cu")
		(net "M_DDR3_NODE1_DQS1N")
	)
	(segment
		(start 47.427642 -23.785068)
		(end 46.971712 -23.329138)
		(width 0.2032)
		(layer "In2.Cu")
		(net "M_DDR3_NODE1_DQS1N")
	)
	(segment
		(start 47.980346 -61.012832)
		(end 47.650146 -60.682632)
		(width 0.09906)
		(layer "In2.Cu")
		(net "M_DDR3_NODE1_DQS1N")
	)
	(segment
		(start 36.64966 -47.063406)
		(end 36.85794 -46.855126)
		(width 0.2032)
		(layer "In2.Cu")
		(net "M_DDR3_NODE1_DQS1N")
	)
	(segment
		(start 36.64966 -40.815006)
		(end 36.85794 -40.606726)
		(width 0.2032)
		(layer "In2.Cu")
		(net "M_DDR3_NODE1_DQS1N")
	)
	(segment
		(start 47.427642 -24.1935)
		(end 47.427642 -23.785068)
		(width 0.2032)
		(layer "In2.Cu")
		(net "M_DDR3_NODE1_DQS1N")
	)
	(segment
		(start 36.380674 -42.186606)
		(end 35.9791 -41.785032)
		(width 0.2032)
		(layer "In2.Cu")
		(net "M_DDR3_NODE1_DQS1N")
	)
	(segment
		(start 36.380674 -48.435006)
		(end 35.9791 -48.033432)
		(width 0.2032)
		(layer "In2.Cu")
		(net "M_DDR3_NODE1_DQS1N")
	)
	(segment
		(start 35.9791 -43.29938)
		(end 36.380674 -42.897806)
		(width 0.2032)
		(layer "In2.Cu")
		(net "M_DDR3_NODE1_DQS1N")
	)
	(segment
		(start 36.64966 -42.897806)
		(end 36.85794 -42.689526)
		(width 0.2032)
		(layer "In2.Cu")
		(net "M_DDR3_NODE1_DQS1N")
	)
	(segment
		(start 35.9791 -51.63058)
		(end 36.380674 -51.229006)
		(width 0.2032)
		(layer "In2.Cu")
		(net "M_DDR3_NODE1_DQS1N")
	)
	(segment
		(start 35.9791 -45.950632)
		(end 35.9791 -45.38218)
		(width 0.2032)
		(layer "In2.Cu")
		(net "M_DDR3_NODE1_DQS1N")
	)
	(segment
		(start 35.9791 -47.46498)
		(end 36.380674 -47.063406)
		(width 0.2032)
		(layer "In2.Cu")
		(net "M_DDR3_NODE1_DQS1N")
	)
	(segment
		(start 36.64966 -50.517806)
		(end 36.380674 -50.517806)
		(width 0.2032)
		(layer "In2.Cu")
		(net "M_DDR3_NODE1_DQS1N")
	)
	(segment
		(start 36.380674 -44.980606)
		(end 36.64966 -44.980606)
		(width 0.2032)
		(layer "In2.Cu")
		(net "M_DDR3_NODE1_DQS1N")
	)
	(segment
		(start 35.9791 -50.116232)
		(end 35.9791 -49.54778)
		(width 0.2032)
		(layer "In2.Cu")
		(net "M_DDR3_NODE1_DQS1N")
	)
	(segment
		(start 44.595542 -57.501536)
		(end 43.084242 -57.501536)
		(width 0.2032)
		(layer "In2.Cu")
		(net "M_DDR3_NODE1_DQS1N")
	)
	(segment
		(start 36.85794 -39.073836)
		(end 40.456104 -35.475672)
		(width 0.2032)
		(layer "In2.Cu")
		(net "M_DDR3_NODE1_DQS1N")
	)
	(segment
		(start 35.9791 -41.21658)
		(end 36.380674 -40.815006)
		(width 0.2032)
		(layer "In2.Cu")
		(net "M_DDR3_NODE1_DQS1N")
	)
	(segment
		(start 36.85794 -44.772326)
		(end 36.85794 -44.477686)
		(width 0.2032)
		(layer "In2.Cu")
		(net "M_DDR3_NODE1_DQS1N")
	)
	(segment
		(start 41.983406 -56.4007)
		(end 39.576502 -56.4007)
		(width 0.2032)
		(layer "In2.Cu")
		(net "M_DDR3_NODE1_DQS1N")
	)
	(segment
		(start 35.9791 -52.199032)
		(end 35.9791 -51.63058)
		(width 0.2032)
		(layer "In2.Cu")
		(net "M_DDR3_NODE1_DQS1N")
	)
	(segment
		(start 36.85794 -44.477686)
		(end 36.64966 -44.269406)
		(width 0.2032)
		(layer "In2.Cu")
		(net "M_DDR3_NODE1_DQS1N")
	)
	(segment
		(start 48.14316 -29.275024)
		(end 48.550322 -28.867862)
		(width 0.2032)
		(layer "In2.Cu")
		(net "M_DDR3_NODE1_DQS1N")
	)
	(segment
		(start 36.85794 -50.726086)
		(end 36.64966 -50.517806)
		(width 0.2032)
		(layer "In2.Cu")
		(net "M_DDR3_NODE1_DQS1N")
	)
	(segment
		(start 49.09566 -25.840436)
		(end 49.09566 -24.983186)
		(width 0.2032)
		(layer "In2.Cu")
		(net "M_DDR3_NODE1_DQS1N")
	)
	(segment
		(start 114.30254 -131.612894)
		(end 113.730532 -131.612894)
		(width 0.254)
		(layer "F.Cu")
		(net "VR_PVCCP_NODE1_ISEN1P_RR")
	)
	(segment
		(start 103.725726 -119.224552)
		(end 103.213408 -119.73687)
		(width 0.254)
		(layer "F.Cu")
		(net "VR_PVCCP_NODE1_ISEN1P_RR")
	)
	(segment
		(start 115.03533 -130.40614)
		(end 115.03533 -130.880104)
		(width 0.254)
		(layer "F.Cu")
		(net "VR_PVCCP_NODE1_ISEN1P_RR")
	)
	(segment
		(start 103.725726 -118.600982)
		(end 103.725726 -119.224552)
		(width 0.254)
		(layer "F.Cu")
		(net "VR_PVCCP_NODE1_ISEN1P_RR")
	)
	(segment
		(start 115.03533 -130.880104)
		(end 114.30254 -131.612894)
		(width 0.254)
		(layer "F.Cu")
		(net "VR_PVCCP_NODE1_ISEN1P_RR")
	)
	(segment
		(start 115.03533 -129.555494)
		(end 115.03533 -130.40614)
		(width 0.254)
		(layer "F.Cu")
		(net "VR_PVCCP_NODE1_ISEN1P_RR")
	)
	(via
		(at 103.213408 -119.73687)
		(size 0.508)
		(drill 0.254)
		(layers "F.Cu" "B.Cu")
		(net "VR_PVCCP_NODE1_ISEN1P_RR")
	)
	(via
		(at 115.03533 -129.555494)
		(size 0.508)
		(drill 0.254)
		(layers "F.Cu" "B.Cu")
		(net "VR_PVCCP_NODE1_ISEN1P_RR")
	)
	(segment
		(start 119.607076 -118.577868)
		(end 120.772174 -119.742966)
		(width 0.254)
		(layer "In2.Cu")
		(net "VR_PVCCP_NODE1_ISEN1P_RR")
	)
	(segment
		(start 116.867432 -132.962142)
		(end 115.03533 -131.13004)
		(width 0.254)
		(layer "In2.Cu")
		(net "VR_PVCCP_NODE1_ISEN1P_RR")
	)
	(segment
		(start 120.772174 -119.742966)
		(end 120.772174 -131.480814)
		(width 0.254)
		(layer "In2.Cu")
		(net "VR_PVCCP_NODE1_ISEN1P_RR")
	)
	(segment
		(start 119.290846 -132.962142)
		(end 116.867432 -132.962142)
		(width 0.254)
		(layer "In2.Cu")
		(net "VR_PVCCP_NODE1_ISEN1P_RR")
	)
	(segment
		(start 107.704636 -116.566442)
		(end 110.244128 -116.566442)
		(width 0.254)
		(layer "In2.Cu")
		(net "VR_PVCCP_NODE1_ISEN1P_RR")
	)
	(segment
		(start 103.213408 -119.73687)
		(end 104.534208 -119.73687)
		(width 0.254)
		(layer "In2.Cu")
		(net "VR_PVCCP_NODE1_ISEN1P_RR")
	)
	(segment
		(start 115.03533 -131.13004)
		(end 115.03533 -129.555494)
		(width 0.254)
		(layer "In2.Cu")
		(net "VR_PVCCP_NODE1_ISEN1P_RR")
	)
	(segment
		(start 120.772174 -131.480814)
		(end 119.290846 -132.962142)
		(width 0.254)
		(layer "In2.Cu")
		(net "VR_PVCCP_NODE1_ISEN1P_RR")
	)
	(segment
		(start 110.244128 -116.566442)
		(end 112.255554 -118.577868)
		(width 0.254)
		(layer "In2.Cu")
		(net "VR_PVCCP_NODE1_ISEN1P_RR")
	)
	(segment
		(start 104.534208 -119.73687)
		(end 107.704636 -116.566442)
		(width 0.254)
		(layer "In2.Cu")
		(net "VR_PVCCP_NODE1_ISEN1P_RR")
	)
	(segment
		(start 112.255554 -118.577868)
		(end 119.607076 -118.577868)
		(width 0.254)
		(layer "In2.Cu")
		(net "VR_PVCCP_NODE1_ISEN1P_RR")
	)
	(segment
		(start 55.10149 -131.749292)
		(end 54.194456 -131.749292)
		(width 0.1016)
		(layer "F.Cu")
		(net "BMC_NODE1_DDR_BA1")
	)
	(segment
		(start 55.26405 -132.781548)
		(end 55.26405 -131.911852)
		(width 0.1016)
		(layer "F.Cu")
		(net "BMC_NODE1_DDR_BA1")
	)
	(segment
		(start 54.637432 -132.937504)
		(end 54.39664 -133.178296)
		(width 0.1016)
		(layer "F.Cu")
		(net "BMC_NODE1_DDR_BA1")
	)
	(segment
		(start 45.633132 -131.36372)
		(end 45.633132 -131.363212)
		(width 0.1016)
		(layer "F.Cu")
		(net "BMC_NODE1_DDR_BA1")
	)
	(segment
		(start 58.14187 -132.859526)
		(end 57.955942 -132.859526)
		(width 0.1016)
		(layer "F.Cu")
		(net "BMC_NODE1_DDR_BA1")
	)
	(segment
		(start 56.060594 -132.968492)
		(end 55.450994 -132.968492)
		(width 0.1016)
		(layer "F.Cu")
		(net "BMC_NODE1_DDR_BA1")
	)
	(segment
		(start 53.748686 -131.310126)
		(end 53.748686 -131.204462)
		(width 0.1016)
		(layer "F.Cu")
		(net "BMC_NODE1_DDR_BA1")
	)
	(segment
		(start 53.178456 -131.880356)
		(end 53.748686 -131.310126)
		(width 0.1016)
		(layer "F.Cu")
		(net "BMC_NODE1_DDR_BA1")
	)
	(segment
		(start 56.554624 -132.474462)
		(end 56.060594 -132.968492)
		(width 0.1016)
		(layer "F.Cu")
		(net "BMC_NODE1_DDR_BA1")
	)
	(segment
		(start 53.916326 -132.027422)
		(end 53.916326 -132.206238)
		(width 0.1016)
		(layer "F.Cu")
		(net "BMC_NODE1_DDR_BA1")
	)
	(segment
		(start 53.178456 -132.93471)
		(end 53.178456 -131.880356)
		(width 0.1016)
		(layer "F.Cu")
		(net "BMC_NODE1_DDR_BA1")
	)
	(segment
		(start 53.422042 -133.178296)
		(end 53.178456 -132.93471)
		(width 0.1016)
		(layer "F.Cu")
		(net "BMC_NODE1_DDR_BA1")
	)
	(segment
		(start 55.450994 -132.968492)
		(end 55.26405 -132.781548)
		(width 0.1016)
		(layer "F.Cu")
		(net "BMC_NODE1_DDR_BA1")
	)
	(segment
		(start 53.916326 -132.206238)
		(end 54.06898 -132.358892)
		(width 0.1016)
		(layer "F.Cu")
		(net "BMC_NODE1_DDR_BA1")
	)
	(segment
		(start 54.06898 -132.358892)
		(end 54.45887 -132.358892)
		(width 0.1016)
		(layer "F.Cu")
		(net "BMC_NODE1_DDR_BA1")
	)
	(segment
		(start 57.570878 -132.474462)
		(end 56.554624 -132.474462)
		(width 0.1016)
		(layer "F.Cu")
		(net "BMC_NODE1_DDR_BA1")
	)
	(segment
		(start 46.032166 -130.964178)
		(end 46.032928 -130.964178)
		(width 0.1016)
		(layer "F.Cu")
		(net "BMC_NODE1_DDR_BA1")
	)
	(segment
		(start 45.633132 -131.363212)
		(end 46.032166 -130.964178)
		(width 0.1016)
		(layer "F.Cu")
		(net "BMC_NODE1_DDR_BA1")
	)
	(segment
		(start 57.955942 -132.859526)
		(end 57.570878 -132.474462)
		(width 0.1016)
		(layer "F.Cu")
		(net "BMC_NODE1_DDR_BA1")
	)
	(segment
		(start 54.39664 -133.178296)
		(end 53.422042 -133.178296)
		(width 0.1016)
		(layer "F.Cu")
		(net "BMC_NODE1_DDR_BA1")
	)
	(segment
		(start 54.637432 -132.537454)
		(end 54.637432 -132.937504)
		(width 0.1016)
		(layer "F.Cu")
		(net "BMC_NODE1_DDR_BA1")
	)
	(segment
		(start 54.194456 -131.749292)
		(end 53.916326 -132.027422)
		(width 0.1016)
		(layer "F.Cu")
		(net "BMC_NODE1_DDR_BA1")
	)
	(segment
		(start 54.45887 -132.358892)
		(end 54.637432 -132.537454)
		(width 0.1016)
		(layer "F.Cu")
		(net "BMC_NODE1_DDR_BA1")
	)
	(segment
		(start 55.26405 -131.911852)
		(end 55.10149 -131.749292)
		(width 0.1016)
		(layer "F.Cu")
		(net "BMC_NODE1_DDR_BA1")
	)
	(via
		(at 53.748686 -131.204462)
		(size 0.508)
		(drill 0.254)
		(layers "F.Cu" "B.Cu")
		(net "BMC_NODE1_DDR_BA1")
	)
	(via
		(at 46.032928 -130.964178)
		(size 0.49022)
		(drill 0.254)
		(layers "F.Cu" "B.Cu")
		(net "BMC_NODE1_DDR_BA1")
	)
	(segment
		(start 52.977542 -130.160522)
		(end 53.748686 -130.931666)
		(width 0.1143)
		(layer "In2.Cu")
		(net "BMC_NODE1_DDR_BA1")
	)
	(segment
		(start 46.891702 -129.668778)
		(end 48.338232 -129.668778)
		(width 0.1143)
		(layer "In2.Cu")
		(net "BMC_NODE1_DDR_BA1")
	)
	(segment
		(start 53.748686 -130.931666)
		(end 53.748686 -131.204462)
		(width 0.1143)
		(layer "In2.Cu")
		(net "BMC_NODE1_DDR_BA1")
	)
	(segment
		(start 48.829976 -130.160522)
		(end 52.977542 -130.160522)
		(width 0.1143)
		(layer "In2.Cu")
		(net "BMC_NODE1_DDR_BA1")
	)
	(segment
		(start 46.032928 -130.964178)
		(end 46.19117 -130.964178)
		(width 0.1143)
		(layer "In2.Cu")
		(net "BMC_NODE1_DDR_BA1")
	)
	(segment
		(start 46.509178 -130.051302)
		(end 46.891702 -129.668778)
		(width 0.1143)
		(layer "In2.Cu")
		(net "BMC_NODE1_DDR_BA1")
	)
	(segment
		(start 48.338232 -129.668778)
		(end 48.829976 -130.160522)
		(width 0.1143)
		(layer "In2.Cu")
		(net "BMC_NODE1_DDR_BA1")
	)
	(segment
		(start 46.19117 -130.964178)
		(end 46.509178 -130.64617)
		(width 0.1143)
		(layer "In2.Cu")
		(net "BMC_NODE1_DDR_BA1")
	)
	(segment
		(start 46.509178 -130.64617)
		(end 46.509178 -130.051302)
		(width 0.1143)
		(layer "In2.Cu")
		(net "BMC_NODE1_DDR_BA1")
	)
	(segment
		(start 51.150266 -24.440134)
		(end 51.150266 -20.94992)
		(width 0.1651)
		(layer "F.Cu")
		(net "M1_DQ_NODE1_DQ16")
	)
	(segment
		(start 53.797962 -65.489328)
		(end 53.41747 -65.86982)
		(width 0.1016)
		(layer "F.Cu")
		(net "M1_DQ_NODE1_DQ16")
	)
	(segment
		(start 50.92192 -24.812498)
		(end 50.92192 -24.66848)
		(width 0.1651)
		(layer "F.Cu")
		(net "M1_DQ_NODE1_DQ16")
	)
	(segment
		(start 53.797962 -65.455038)
		(end 53.797962 -65.489328)
		(width 0.1016)
		(layer "F.Cu")
		(net "M1_DQ_NODE1_DQ16")
	)
	(segment
		(start 50.92192 -24.66848)
		(end 51.150266 -24.440134)
		(width 0.1651)
		(layer "F.Cu")
		(net "M1_DQ_NODE1_DQ16")
	)
	(via
		(at 53.41747 -65.86982)
		(size 0.508)
		(drill 0.254)
		(layers "F.Cu" "B.Cu")
		(net "M1_DQ_NODE1_DQ16")
	)
	(via
		(at 50.92192 -24.812498)
		(size 0.508)
		(drill 0.254)
		(layers "F.Cu" "B.Cu")
		(net "M1_DQ_NODE1_DQ16")
	)
	(segment
		(start 50.142902 -30.216094)
		(end 49.10074 -30.216094)
		(width 0.2032)
		(layer "In7.Cu")
		(net "M1_DQ_NODE1_DQ16")
	)
	(segment
		(start 50.351182 -29.296614)
		(end 50.351182 -28.820618)
		(width 0.2032)
		(layer "In7.Cu")
		(net "M1_DQ_NODE1_DQ16")
	)
	(segment
		(start 50.351182 -28.820618)
		(end 50.181002 -28.650438)
		(width 0.2032)
		(layer "In7.Cu")
		(net "M1_DQ_NODE1_DQ16")
	)
	(segment
		(start 40.34282 -47.026322)
		(end 40.34282 -43.539918)
		(width 0.2032)
		(layer "In7.Cu")
		(net "M1_DQ_NODE1_DQ16")
	)
	(segment
		(start 49.10074 -29.504894)
		(end 50.142902 -29.504894)
		(width 0.2032)
		(layer "In7.Cu")
		(net "M1_DQ_NODE1_DQ16")
	)
	(segment
		(start 41.56202 -46.182026)
		(end 41.25722 -46.182026)
		(width 0.2032)
		(layer "In7.Cu")
		(net "M1_DQ_NODE1_DQ16")
	)
	(segment
		(start 49.01692 -27.377898)
		(end 49.01692 -26.915364)
		(width 0.2032)
		(layer "In7.Cu")
		(net "M1_DQ_NODE1_DQ16")
	)
	(segment
		(start 48.89246 -30.007814)
		(end 48.89246 -29.713174)
		(width 0.2032)
		(layer "In7.Cu")
		(net "M1_DQ_NODE1_DQ16")
	)
	(segment
		(start 53.41747 -65.357502)
		(end 52.836064 -64.776096)
		(width 0.1016)
		(layer "In7.Cu")
		(net "M1_DQ_NODE1_DQ16")
	)
	(segment
		(start 53.41747 -65.86982)
		(end 53.41747 -65.357502)
		(width 0.1016)
		(layer "In7.Cu")
		(net "M1_DQ_NODE1_DQ16")
	)
	(segment
		(start 51.276758 -58.844434)
		(end 41.76522 -49.332896)
		(width 0.2032)
		(layer "In7.Cu")
		(net "M1_DQ_NODE1_DQ16")
	)
	(segment
		(start 50.181002 -28.650438)
		(end 49.327562 -28.650438)
		(width 0.2032)
		(layer "In7.Cu")
		(net "M1_DQ_NODE1_DQ16")
	)
	(segment
		(start 50.351182 -31.352998)
		(end 50.351182 -30.424374)
		(width 0.2032)
		(layer "In7.Cu")
		(net "M1_DQ_NODE1_DQ16")
	)
	(segment
		(start 49.10074 -30.216094)
		(end 48.89246 -30.007814)
		(width 0.2032)
		(layer "In7.Cu")
		(net "M1_DQ_NODE1_DQ16")
	)
	(segment
		(start 51.56708 -62.507114)
		(end 51.56708 -60.051442)
		(width 0.2032)
		(layer "In7.Cu")
		(net "M1_DQ_NODE1_DQ16")
	)
	(segment
		(start 52.836064 -64.776096)
		(end 52.836064 -63.776098)
		(width 0.1016)
		(layer "In7.Cu")
		(net "M1_DQ_NODE1_DQ16")
	)
	(segment
		(start 49.017682 -28.340558)
		(end 49.017682 -27.377898)
		(width 0.2032)
		(layer "In7.Cu")
		(net "M1_DQ_NODE1_DQ16")
	)
	(segment
		(start 41.05402 -47.026322)
		(end 40.85082 -47.229522)
		(width 0.2032)
		(layer "In7.Cu")
		(net "M1_DQ_NODE1_DQ16")
	)
	(segment
		(start 41.05402 -46.385226)
		(end 41.05402 -47.026322)
		(width 0.2032)
		(layer "In7.Cu")
		(net "M1_DQ_NODE1_DQ16")
	)
	(segment
		(start 41.76522 -49.332896)
		(end 41.76522 -46.385226)
		(width 0.2032)
		(layer "In7.Cu")
		(net "M1_DQ_NODE1_DQ16")
	)
	(segment
		(start 49.01692 -26.915364)
		(end 50.92192 -25.010364)
		(width 0.2032)
		(layer "In7.Cu")
		(net "M1_DQ_NODE1_DQ16")
	)
	(segment
		(start 52.329334 -63.269368)
		(end 51.56708 -62.507114)
		(width 0.2032)
		(layer "In7.Cu")
		(net "M1_DQ_NODE1_DQ16")
	)
	(segment
		(start 49.017682 -27.377898)
		(end 49.01692 -27.377898)
		(width 0.2032)
		(layer "In7.Cu")
		(net "M1_DQ_NODE1_DQ16")
	)
	(segment
		(start 49.327562 -28.650438)
		(end 49.017682 -28.340558)
		(width 0.2032)
		(layer "In7.Cu")
		(net "M1_DQ_NODE1_DQ16")
	)
	(segment
		(start 41.76522 -46.385226)
		(end 41.56202 -46.182026)
		(width 0.2032)
		(layer "In7.Cu")
		(net "M1_DQ_NODE1_DQ16")
	)
	(segment
		(start 40.34282 -43.539918)
		(end 50.35042 -33.532318)
		(width 0.2032)
		(layer "In7.Cu")
		(net "M1_DQ_NODE1_DQ16")
	)
	(segment
		(start 40.85082 -47.229522)
		(end 40.54602 -47.229522)
		(width 0.2032)
		(layer "In7.Cu")
		(net "M1_DQ_NODE1_DQ16")
	)
	(segment
		(start 50.35042 -31.35376)
		(end 50.351182 -31.352998)
		(width 0.2032)
		(layer "In7.Cu")
		(net "M1_DQ_NODE1_DQ16")
	)
	(segment
		(start 50.92192 -25.010364)
		(end 50.92192 -24.812498)
		(width 0.2032)
		(layer "In7.Cu")
		(net "M1_DQ_NODE1_DQ16")
	)
	(segment
		(start 50.351182 -30.424374)
		(end 50.142902 -30.216094)
		(width 0.2032)
		(layer "In7.Cu")
		(net "M1_DQ_NODE1_DQ16")
	)
	(segment
		(start 40.54602 -47.229522)
		(end 40.34282 -47.026322)
		(width 0.2032)
		(layer "In7.Cu")
		(net "M1_DQ_NODE1_DQ16")
	)
	(segment
		(start 50.142902 -29.504894)
		(end 50.351182 -29.296614)
		(width 0.2032)
		(layer "In7.Cu")
		(net "M1_DQ_NODE1_DQ16")
	)
	(segment
		(start 52.836064 -63.776098)
		(end 52.329334 -63.269368)
		(width 0.1016)
		(layer "In7.Cu")
		(net "M1_DQ_NODE1_DQ16")
	)
	(segment
		(start 51.276758 -59.76112)
		(end 51.276758 -58.844434)
		(width 0.2032)
		(layer "In7.Cu")
		(net "M1_DQ_NODE1_DQ16")
	)
	(segment
		(start 50.35042 -33.532318)
		(end 50.35042 -31.35376)
		(width 0.2032)
		(layer "In7.Cu")
		(net "M1_DQ_NODE1_DQ16")
	)
	(segment
		(start 48.89246 -29.713174)
		(end 49.10074 -29.504894)
		(width 0.2032)
		(layer "In7.Cu")
		(net "M1_DQ_NODE1_DQ16")
	)
	(segment
		(start 51.56708 -60.051442)
		(end 51.276758 -59.76112)
		(width 0.2032)
		(layer "In7.Cu")
		(net "M1_DQ_NODE1_DQ16")
	)
	(segment
		(start 41.25722 -46.182026)
		(end 41.05402 -46.385226)
		(width 0.2032)
		(layer "In7.Cu")
		(net "M1_DQ_NODE1_DQ16")
	)
	(segment
		(start 112.12322 -134.185152)
		(end 112.6363 -133.672072)
		(width 0.254)
		(layer "F.Cu")
		(net "ISENSE_PVCCP_NODE1_ISEN1N")
	)
	(segment
		(start 111.46663 -134.185152)
		(end 112.12322 -134.185152)
		(width 0.254)
		(layer "F.Cu")
		(net "ISENSE_PVCCP_NODE1_ISEN1N")
	)
	(segment
		(start 107.0356 -117.580156)
		(end 108.800138 -117.580156)
		(width 0.254)
		(layer "F.Cu")
		(net "ISENSE_PVCCP_NODE1_ISEN1N")
	)
	(segment
		(start 114.509042 -133.726682)
		(end 114.63655 -133.599174)
		(width 0.254)
		(layer "F.Cu")
		(net "ISENSE_PVCCP_NODE1_ISEN1N")
	)
	(segment
		(start 115.83543 -130.756152)
		(end 116.375942 -131.296664)
		(width 0.254)
		(layer "F.Cu")
		(net "ISENSE_PVCCP_NODE1_ISEN1N")
	)
	(segment
		(start 114.930174 -133.599174)
		(end 114.63655 -133.599174)
		(width 0.254)
		(layer "F.Cu")
		(net "ISENSE_PVCCP_NODE1_ISEN1N")
	)
	(segment
		(start 116.375942 -131.296664)
		(end 116.375942 -132.153406)
		(width 0.254)
		(layer "F.Cu")
		(net "ISENSE_PVCCP_NODE1_ISEN1N")
	)
	(segment
		(start 115.478814 -133.050534)
		(end 114.930174 -133.599174)
		(width 0.254)
		(layer "F.Cu")
		(net "ISENSE_PVCCP_NODE1_ISEN1N")
	)
	(segment
		(start 108.901738 -117.681756)
		(end 108.901738 -116.508276)
		(width 0.254)
		(layer "F.Cu")
		(net "ISENSE_PVCCP_NODE1_ISEN1N")
	)
	(segment
		(start 115.83543 -130.40614)
		(end 115.83543 -130.756152)
		(width 0.254)
		(layer "F.Cu")
		(net "ISENSE_PVCCP_NODE1_ISEN1N")
	)
	(segment
		(start 114.509042 -133.95071)
		(end 114.509042 -133.726682)
		(width 0.254)
		(layer "F.Cu")
		(net "ISENSE_PVCCP_NODE1_ISEN1N")
	)
	(segment
		(start 116.375942 -132.153406)
		(end 115.478814 -133.050534)
		(width 0.254)
		(layer "F.Cu")
		(net "ISENSE_PVCCP_NODE1_ISEN1N")
	)
	(segment
		(start 104.825546 -118.600982)
		(end 106.014774 -118.600982)
		(width 0.254)
		(layer "F.Cu")
		(net "ISENSE_PVCCP_NODE1_ISEN1N")
	)
	(segment
		(start 108.800138 -117.580156)
		(end 108.901738 -117.681756)
		(width 0.254)
		(layer "F.Cu")
		(net "ISENSE_PVCCP_NODE1_ISEN1N")
	)
	(segment
		(start 111.353854 -134.297928)
		(end 111.46663 -134.185152)
		(width 0.1778)
		(layer "F.Cu")
		(net "ISENSE_PVCCP_NODE1_ISEN1N")
	)
	(segment
		(start 113.07826 -133.854698)
		(end 113.51641 -134.292848)
		(width 0.254)
		(layer "F.Cu")
		(net "ISENSE_PVCCP_NODE1_ISEN1N")
	)
	(segment
		(start 109.996478 -134.297928)
		(end 111.353854 -134.297928)
		(width 0.1778)
		(layer "F.Cu")
		(net "ISENSE_PVCCP_NODE1_ISEN1N")
	)
	(segment
		(start 114.166904 -134.292848)
		(end 114.509042 -133.95071)
		(width 0.254)
		(layer "F.Cu")
		(net "ISENSE_PVCCP_NODE1_ISEN1N")
	)
	(segment
		(start 113.07826 -133.735572)
		(end 113.07826 -133.854698)
		(width 0.254)
		(layer "F.Cu")
		(net "ISENSE_PVCCP_NODE1_ISEN1N")
	)
	(segment
		(start 106.014774 -118.600982)
		(end 107.0356 -117.580156)
		(width 0.254)
		(layer "F.Cu")
		(net "ISENSE_PVCCP_NODE1_ISEN1N")
	)
	(segment
		(start 112.6363 -133.672072)
		(end 113.07826 -133.735572)
		(width 0.254)
		(layer "F.Cu")
		(net "ISENSE_PVCCP_NODE1_ISEN1N")
	)
	(segment
		(start 113.51641 -134.292848)
		(end 114.166904 -134.292848)
		(width 0.254)
		(layer "F.Cu")
		(net "ISENSE_PVCCP_NODE1_ISEN1N")
	)
	(via
		(at 114.63655 -133.599174)
		(size 0.508)
		(drill 0.254)
		(layers "F.Cu" "B.Cu")
		(net "ISENSE_PVCCP_NODE1_ISEN1N")
	)
	(via
		(at 108.901738 -117.681756)
		(size 0.508)
		(drill 0.254)
		(layers "F.Cu" "B.Cu")
		(net "ISENSE_PVCCP_NODE1_ISEN1N")
	)
	(segment
		(start 120.512586 -131.488688)
		(end 120.512586 -118.958106)
		(width 0.254)
		(layer "In6.Cu")
		(net "ISENSE_PVCCP_NODE1_ISEN1N")
	)
	(segment
		(start 114.63655 -133.31825)
		(end 115.356132 -132.598668)
		(width 0.254)
		(layer "In6.Cu")
		(net "ISENSE_PVCCP_NODE1_ISEN1N")
	)
	(segment
		(start 114.63655 -133.599174)
		(end 114.63655 -133.31825)
		(width 0.254)
		(layer "In6.Cu")
		(net "ISENSE_PVCCP_NODE1_ISEN1N")
	)
	(segment
		(start 118.700296 -133.300978)
		(end 120.512586 -131.488688)
		(width 0.254)
		(layer "In6.Cu")
		(net "ISENSE_PVCCP_NODE1_ISEN1N")
	)
	(segment
		(start 120.512586 -118.958106)
		(end 119.725948 -118.171468)
		(width 0.254)
		(layer "In6.Cu")
		(net "ISENSE_PVCCP_NODE1_ISEN1N")
	)
	(segment
		(start 115.796314 -132.598668)
		(end 116.498624 -133.300978)
		(width 0.254)
		(layer "In6.Cu")
		(net "ISENSE_PVCCP_NODE1_ISEN1N")
	)
	(segment
		(start 116.498624 -133.300978)
		(end 118.700296 -133.300978)
		(width 0.254)
		(layer "In6.Cu")
		(net "ISENSE_PVCCP_NODE1_ISEN1N")
	)
	(segment
		(start 115.356132 -132.598668)
		(end 115.796314 -132.598668)
		(width 0.254)
		(layer "In6.Cu")
		(net "ISENSE_PVCCP_NODE1_ISEN1N")
	)
	(segment
		(start 109.39145 -118.171468)
		(end 108.901738 -117.681756)
		(width 0.254)
		(layer "In6.Cu")
		(net "ISENSE_PVCCP_NODE1_ISEN1N")
	)
	(segment
		(start 119.725948 -118.171468)
		(end 109.39145 -118.171468)
		(width 0.254)
		(layer "In6.Cu")
		(net "ISENSE_PVCCP_NODE1_ISEN1N")
	)
	(segment
		(start 182.819294 -135.89127)
		(end 182.819294 -135.237728)
		(width 0.1016)
		(layer "F.Cu")
		(net "FM_NODE1_DFX_GPIO_GRP05_R")
	)
	(segment
		(start 182.819294 -134.39902)
		(end 182.819294 -135.237728)
		(width 0.1016)
		(layer "F.Cu")
		(net "FM_NODE1_DFX_GPIO_GRP05_R")
	)
	(segment
		(start 182.812944 -135.89762)
		(end 182.819294 -135.89127)
		(width 0.1016)
		(layer "F.Cu")
		(net "FM_NODE1_DFX_GPIO_GRP05_R")
	)
	(via
		(at 182.819294 -135.237728)
		(size 0.508)
		(drill 0.254)
		(layers "F.Cu" "B.Cu")
		(net "FM_NODE1_DFX_GPIO_GRP05_R")
	)
	(segment
		(start 95.11411 -171.512484)
		(end 96.383094 -171.512484)
		(width 0.1016)
		(layer "F.Cu")
		(net "FAN3_TACH_IN")
	)
	(segment
		(start 94.851982 -171.250356)
		(end 95.11411 -171.512484)
		(width 0.1016)
		(layer "F.Cu")
		(net "FAN3_TACH_IN")
	)
	(segment
		(start 97.067878 -172.197268)
		(end 96.383094 -171.512484)
		(width 0.1016)
		(layer "F.Cu")
		(net "FAN3_TACH_IN")
	)
	(segment
		(start 97.728532 -172.197268)
		(end 97.067878 -172.197268)
		(width 0.1016)
		(layer "F.Cu")
		(net "FAN3_TACH_IN")
	)
	(via
		(at 96.383094 -171.512484)
		(size 0.508)
		(drill 0.254)
		(layers "F.Cu" "B.Cu")
		(net "FAN3_TACH_IN")
	)
	(segment
		(start 46.845982 -134.665212)
		(end 47.790354 -134.665212)
		(width 0.1016)
		(layer "F.Cu")
		(net "TP_BMC_NODE1_DDR3_CE1_NC1")
	)
	(segment
		(start 47.790354 -134.665212)
		(end 47.91456 -134.789418)
		(width 0.1016)
		(layer "F.Cu")
		(net "TP_BMC_NODE1_DDR3_CE1_NC1")
	)
	(segment
		(start 46.744382 -134.563612)
		(end 46.845982 -134.665212)
		(width 0.1016)
		(layer "F.Cu")
		(net "TP_BMC_NODE1_DDR3_CE1_NC1")
	)
	(segment
		(start 46.432978 -134.563612)
		(end 46.744382 -134.563612)
		(width 0.1016)
		(layer "F.Cu")
		(net "TP_BMC_NODE1_DDR3_CE1_NC1")
	)
	(via
		(at 47.91456 -134.789418)
		(size 0.508)
		(drill 0.254)
		(layers "F.Cu" "B.Cu")
		(net "TP_BMC_NODE1_DDR3_CE1_NC1")
	)
	(via
		(at 48.070008 -133.663944)
		(size 0.6604)
		(drill 0.3302)
		(layers "F.Cu" "B.Cu")
		(net "TP_BMC_NODE1_DDR3_CE1_NC1")
	)
	(segment
		(start 47.91456 -134.789418)
		(end 47.91456 -133.819392)
		(width 0.1016)
		(layer "B.Cu")
		(net "TP_BMC_NODE1_DDR3_CE1_NC1")
	)
	(segment
		(start 47.91456 -133.819392)
		(end 48.070008 -133.663944)
		(width 0.1016)
		(layer "B.Cu")
		(net "TP_BMC_NODE1_DDR3_CE1_NC1")
	)
	(segment
		(start 40.596058 -79.439262)
		(end 40.141398 -79.893922)
		(width 0.1016)
		(layer "F.Cu")
		(net "PD_CPU_NODE1_Y2")
	)
	(segment
		(start 36.394898 -79.893922)
		(end 36.97732 -80.476344)
		(width 0.1016)
		(layer "F.Cu")
		(net "PD_CPU_NODE1_Y2")
	)
	(segment
		(start 42.194988 -79.439262)
		(end 40.596058 -79.439262)
		(width 0.1016)
		(layer "F.Cu")
		(net "PD_CPU_NODE1_Y2")
	)
	(segment
		(start 37.559742 -79.893922)
		(end 36.97732 -80.476344)
		(width 0.1016)
		(layer "F.Cu")
		(net "PD_CPU_NODE1_Y2")
	)
	(segment
		(start 36.069778 -79.893922)
		(end 36.394898 -79.893922)
		(width 0.1016)
		(layer "F.Cu")
		(net "PD_CPU_NODE1_Y2")
	)
	(segment
		(start 40.141398 -79.893922)
		(end 37.559742 -79.893922)
		(width 0.1016)
		(layer "F.Cu")
		(net "PD_CPU_NODE1_Y2")
	)
	(via
		(at 36.97732 -80.476344)
		(size 0.508)
		(drill 0.254)
		(layers "F.Cu" "B.Cu")
		(net "PD_CPU_NODE1_Y2")
	)
	(segment
		(start 112.275366 -135.706104)
		(end 112.179354 -135.706104)
		(width 0.254)
		(layer "F.Cu")
		(net "VR_PVCCP_NODE1_FB")
	)
	(segment
		(start 111.562896 -135.706104)
		(end 111.082836 -135.226044)
		(width 0.254)
		(layer "F.Cu")
		(net "VR_PVCCP_NODE1_FB")
	)
	(segment
		(start 111.082836 -135.226044)
		(end 110.954566 -135.097774)
		(width 0.1778)
		(layer "F.Cu")
		(net "VR_PVCCP_NODE1_FB")
	)
	(segment
		(start 116.007388 -136.017254)
		(end 114.577368 -136.017254)
		(width 0.254)
		(layer "F.Cu")
		(net "VR_PVCCP_NODE1_FB")
	)
	(segment
		(start 110.954566 -135.097774)
		(end 109.996478 -135.097774)
		(width 0.1778)
		(layer "F.Cu")
		(net "VR_PVCCP_NODE1_FB")
	)
	(segment
		(start 113.242852 -136.67359)
		(end 114.221768 -136.67359)
		(width 0.254)
		(layer "F.Cu")
		(net "VR_PVCCP_NODE1_FB")
	)
	(segment
		(start 115.987322 -137.018522)
		(end 116.007388 -136.998456)
		(width 0.254)
		(layer "F.Cu")
		(net "VR_PVCCP_NODE1_FB")
	)
	(segment
		(start 113.242852 -136.67359)
		(end 112.275366 -135.706104)
		(width 0.254)
		(layer "F.Cu")
		(net "VR_PVCCP_NODE1_FB")
	)
	(segment
		(start 117.023388 -136.017254)
		(end 116.007388 -136.017254)
		(width 0.254)
		(layer "F.Cu")
		(net "VR_PVCCP_NODE1_FB")
	)
	(segment
		(start 114.577368 -136.017254)
		(end 114.221768 -136.372854)
		(width 0.254)
		(layer "F.Cu")
		(net "VR_PVCCP_NODE1_FB")
	)
	(segment
		(start 116.007388 -136.998456)
		(end 116.007388 -136.017254)
		(width 0.254)
		(layer "F.Cu")
		(net "VR_PVCCP_NODE1_FB")
	)
	(segment
		(start 114.221768 -136.372854)
		(end 114.221768 -136.67359)
		(width 0.254)
		(layer "F.Cu")
		(net "VR_PVCCP_NODE1_FB")
	)
	(segment
		(start 112.179354 -135.706104)
		(end 111.562896 -135.706104)
		(width 0.254)
		(layer "F.Cu")
		(net "VR_PVCCP_NODE1_FB")
	)
	(via
		(at 113.242852 -136.67359)
		(size 0.508)
		(drill 0.254)
		(layers "F.Cu" "B.Cu")
		(net "VR_PVCCP_NODE1_FB")
	)
	(segment
		(start 166.315644 -122.66422)
		(end 165.232334 -122.66422)
		(width 0.1016)
		(layer "F.Cu")
		(net "FM_NODE1_DDR3_DRAM_POK_R_L")
	)
	(segment
		(start 163.261294 -123.07062)
		(end 164.825934 -123.07062)
		(width 0.1016)
		(layer "F.Cu")
		(net "FM_NODE1_DDR3_DRAM_POK_R_L")
	)
	(segment
		(start 164.825934 -123.07062)
		(end 165.232334 -122.66422)
		(width 0.1016)
		(layer "F.Cu")
		(net "FM_NODE1_DDR3_DRAM_POK_R_L")
	)
	(via
		(at 165.232334 -122.66422)
		(size 0.508)
		(drill 0.254)
		(layers "F.Cu" "B.Cu")
		(net "FM_NODE1_DDR3_DRAM_POK_R_L")
	)
	(segment
		(start 94.851982 -164.123624)
		(end 95.526606 -164.123624)
		(width 0.1016)
		(layer "F.Cu")
		(net "FAN6_TACH_IN")
	)
	(segment
		(start 97.728532 -164.525706)
		(end 95.928688 -164.525706)
		(width 0.1016)
		(layer "F.Cu")
		(net "FAN6_TACH_IN")
	)
	(segment
		(start 95.928688 -164.525706)
		(end 95.526606 -164.123624)
		(width 0.1016)
		(layer "F.Cu")
		(net "FAN6_TACH_IN")
	)
	(via
		(at 95.526606 -164.123624)
		(size 0.508)
		(drill 0.254)
		(layers "F.Cu" "B.Cu")
		(net "FAN6_TACH_IN")
	)
	(segment
		(start 58.941716 -131.25958)
		(end 58.941716 -131.259072)
		(width 0.1016)
		(layer "F.Cu")
		(net "BMC_NODE1_DDR_MA3")
	)
	(segment
		(start 40.83304 -131.362704)
		(end 40.435784 -130.965448)
		(width 0.1016)
		(layer "F.Cu")
		(net "BMC_NODE1_DDR_MA3")
	)
	(segment
		(start 40.83304 -131.36372)
		(end 40.83304 -131.362704)
		(width 0.1016)
		(layer "F.Cu")
		(net "BMC_NODE1_DDR_MA3")
	)
	(segment
		(start 58.941716 -131.259072)
		(end 58.540904 -130.85826)
		(width 0.1016)
		(layer "F.Cu")
		(net "BMC_NODE1_DDR_MA3")
	)
	(via
		(at 40.435784 -130.965448)
		(size 0.49022)
		(drill 0.254)
		(layers "F.Cu" "B.Cu")
		(net "BMC_NODE1_DDR_MA3")
	)
	(via
		(at 58.540904 -130.85826)
		(size 0.49022)
		(drill 0.254)
		(layers "F.Cu" "B.Cu")
		(net "BMC_NODE1_DDR_MA3")
	)
	(segment
		(start 55.951374 -128.78435)
		(end 58.025284 -130.85826)
		(width 0.1143)
		(layer "In2.Cu")
		(net "BMC_NODE1_DDR_MA3")
	)
	(segment
		(start 42.46372 -129.768092)
		(end 45.585634 -126.646178)
		(width 0.1143)
		(layer "In2.Cu")
		(net "BMC_NODE1_DDR_MA3")
	)
	(segment
		(start 53.00472 -126.716028)
		(end 54.071012 -127.165608)
		(width 0.1143)
		(layer "In2.Cu")
		(net "BMC_NODE1_DDR_MA3")
	)
	(segment
		(start 58.025284 -130.85826)
		(end 58.540904 -130.85826)
		(width 0.1143)
		(layer "In2.Cu")
		(net "BMC_NODE1_DDR_MA3")
	)
	(segment
		(start 41.918128 -130.190494)
		(end 42.46372 -129.768092)
		(width 0.1143)
		(layer "In2.Cu")
		(net "BMC_NODE1_DDR_MA3")
	)
	(segment
		(start 45.585634 -126.646178)
		(end 52.63388 -126.646178)
		(width 0.1143)
		(layer "In2.Cu")
		(net "BMC_NODE1_DDR_MA3")
	)
	(segment
		(start 40.435784 -130.965448)
		(end 41.143174 -130.965448)
		(width 0.1143)
		(layer "In2.Cu")
		(net "BMC_NODE1_DDR_MA3")
	)
	(segment
		(start 52.63388 -126.646178)
		(end 53.00472 -126.716028)
		(width 0.1143)
		(layer "In2.Cu")
		(net "BMC_NODE1_DDR_MA3")
	)
	(segment
		(start 41.143174 -130.965448)
		(end 41.918128 -130.190494)
		(width 0.1143)
		(layer "In2.Cu")
		(net "BMC_NODE1_DDR_MA3")
	)
	(segment
		(start 54.071012 -127.165608)
		(end 55.951374 -128.78435)
		(width 0.1143)
		(layer "In2.Cu")
		(net "BMC_NODE1_DDR_MA3")
	)
	(segment
		(start 117.249194 -134.991348)
		(end 117.853714 -134.991348)
		(width 0.254)
		(layer "F.Cu")
		(net "VR_PVCCP_NODE1_FB_RR")
	)
	(segment
		(start 118.183914 -135.332216)
		(end 117.853714 -135.002016)
		(width 0.254)
		(layer "F.Cu")
		(net "VR_PVCCP_NODE1_FB_RR")
	)
	(segment
		(start 117.023388 -135.217154)
		(end 117.249194 -134.991348)
		(width 0.254)
		(layer "F.Cu")
		(net "VR_PVCCP_NODE1_FB_RR")
	)
	(segment
		(start 118.183914 -135.84809)
		(end 118.183914 -135.332216)
		(width 0.254)
		(layer "F.Cu")
		(net "VR_PVCCP_NODE1_FB_RR")
	)
	(segment
		(start 117.853714 -134.991348)
		(end 117.853714 -135.002016)
		(width 0.254)
		(layer "F.Cu")
		(net "VR_PVCCP_NODE1_FB_RR")
	)
	(via
		(at 117.853714 -135.002016)
		(size 0.508)
		(drill 0.254)
		(layers "F.Cu" "B.Cu")
		(net "VR_PVCCP_NODE1_FB_RR")
	)
	(segment
		(start 178.96586 -130.36042)
		(end 178.964844 -130.36042)
		(width 0.1016)
		(layer "F.Cu")
		(net "FM_CPLD_NODE1_WDT")
	)
	(segment
		(start 179.00904 -126.717044)
		(end 179.00904 -130.31724)
		(width 0.1016)
		(layer "F.Cu")
		(net "FM_CPLD_NODE1_WDT")
	)
	(segment
		(start 179.00904 -130.31724)
		(end 178.96586 -130.36042)
		(width 0.1016)
		(layer "F.Cu")
		(net "FM_CPLD_NODE1_WDT")
	)
	(segment
		(start 178.964844 -131.549394)
		(end 178.964844 -130.36042)
		(width 0.1016)
		(layer "F.Cu")
		(net "FM_CPLD_NODE1_WDT")
	)
	(segment
		(start 179.010564 -126.71552)
		(end 179.00904 -126.717044)
		(width 0.1016)
		(layer "F.Cu")
		(net "FM_CPLD_NODE1_WDT")
	)
	(segment
		(start 178.465734 -132.424424)
		(end 178.465734 -132.048504)
		(width 0.1016)
		(layer "F.Cu")
		(net "FM_CPLD_NODE1_WDT")
	)
	(segment
		(start 178.465734 -132.048504)
		(end 178.964844 -131.549394)
		(width 0.1016)
		(layer "F.Cu")
		(net "FM_CPLD_NODE1_WDT")
	)
	(segment
		(start 179.010564 -126.71552)
		(end 179.010564 -125.365764)
		(width 0.1016)
		(layer "F.Cu")
		(net "FM_CPLD_NODE1_WDT")
	)
	(via
		(at 179.010564 -126.71552)
		(size 0.508)
		(drill 0.254)
		(layers "F.Cu" "B.Cu")
		(net "FM_CPLD_NODE1_WDT")
	)
	(segment
		(start 40.83304 -136.965436)
		(end 41.245028 -137.377424)
		(width 0.1016)
		(layer "F.Cu")
		(net "BMC_NODE1_DDR_D4")
	)
	(segment
		(start 42.348658 -137.847324)
		(end 42.733722 -137.847324)
		(width 0.1016)
		(layer "F.Cu")
		(net "BMC_NODE1_DDR_D4")
	)
	(segment
		(start 58.93943 -135.259572)
		(end 58.540904 -135.658098)
		(width 0.1016)
		(layer "F.Cu")
		(net "BMC_NODE1_DDR_D4")
	)
	(segment
		(start 58.941716 -135.259572)
		(end 58.93943 -135.259572)
		(width 0.1016)
		(layer "F.Cu")
		(net "BMC_NODE1_DDR_D4")
	)
	(segment
		(start 41.245028 -137.377424)
		(end 41.878758 -137.377424)
		(width 0.1016)
		(layer "F.Cu")
		(net "BMC_NODE1_DDR_D4")
	)
	(segment
		(start 40.83304 -136.963658)
		(end 40.83304 -136.965436)
		(width 0.1016)
		(layer "F.Cu")
		(net "BMC_NODE1_DDR_D4")
	)
	(segment
		(start 41.878758 -137.377424)
		(end 42.348658 -137.847324)
		(width 0.1016)
		(layer "F.Cu")
		(net "BMC_NODE1_DDR_D4")
	)
	(via
		(at 42.733722 -137.847324)
		(size 0.508)
		(drill 0.254)
		(layers "F.Cu" "B.Cu")
		(net "BMC_NODE1_DDR_D4")
	)
	(via
		(at 58.540904 -135.658098)
		(size 0.49022)
		(drill 0.254)
		(layers "F.Cu" "B.Cu")
		(net "BMC_NODE1_DDR_D4")
	)
	(segment
		(start 56.627522 -136.245346)
		(end 55.47106 -137.401808)
		(width 0.1143)
		(layer "In7.Cu")
		(net "BMC_NODE1_DDR_D4")
	)
	(segment
		(start 58.540904 -135.658098)
		(end 57.785508 -135.658098)
		(width 0.1143)
		(layer "In7.Cu")
		(net "BMC_NODE1_DDR_D4")
	)
	(segment
		(start 57.19826 -136.245346)
		(end 56.627522 -136.245346)
		(width 0.1143)
		(layer "In7.Cu")
		(net "BMC_NODE1_DDR_D4")
	)
	(segment
		(start 55.47106 -137.401808)
		(end 54.259988 -137.401808)
		(width 0.1143)
		(layer "In7.Cu")
		(net "BMC_NODE1_DDR_D4")
	)
	(segment
		(start 43.632374 -138.338814)
		(end 43.140884 -137.847324)
		(width 0.1143)
		(layer "In7.Cu")
		(net "BMC_NODE1_DDR_D4")
	)
	(segment
		(start 52.227734 -139.434062)
		(end 47.26178 -139.434062)
		(width 0.1143)
		(layer "In7.Cu")
		(net "BMC_NODE1_DDR_D4")
	)
	(segment
		(start 45.882306 -139.006072)
		(end 45.215048 -138.338814)
		(width 0.1143)
		(layer "In7.Cu")
		(net "BMC_NODE1_DDR_D4")
	)
	(segment
		(start 54.259988 -137.401808)
		(end 52.227734 -139.434062)
		(width 0.1143)
		(layer "In7.Cu")
		(net "BMC_NODE1_DDR_D4")
	)
	(segment
		(start 47.26178 -139.434062)
		(end 45.882306 -139.006072)
		(width 0.1143)
		(layer "In7.Cu")
		(net "BMC_NODE1_DDR_D4")
	)
	(segment
		(start 45.215048 -138.338814)
		(end 43.632374 -138.338814)
		(width 0.1143)
		(layer "In7.Cu")
		(net "BMC_NODE1_DDR_D4")
	)
	(segment
		(start 43.140884 -137.847324)
		(end 42.733722 -137.847324)
		(width 0.1143)
		(layer "In7.Cu")
		(net "BMC_NODE1_DDR_D4")
	)
	(segment
		(start 57.785508 -135.658098)
		(end 57.19826 -136.245346)
		(width 0.1143)
		(layer "In7.Cu")
		(net "BMC_NODE1_DDR_D4")
	)
	(segment
		(start 107.713272 -131.524756)
		(end 107.400344 -131.524756)
		(width 0.1778)
		(layer "F.Cu")
		(net "VR_PVCCP_NODE1_PVCC")
	)
	(segment
		(start 108.071412 -132.372862)
		(end 108.071412 -131.882896)
		(width 0.1778)
		(layer "F.Cu")
		(net "VR_PVCCP_NODE1_PVCC")
	)
	(segment
		(start 107.2007 -131.325112)
		(end 107.400344 -131.524756)
		(width 0.1778)
		(layer "F.Cu")
		(net "VR_PVCCP_NODE1_PVCC")
	)
	(segment
		(start 108.071412 -131.882896)
		(end 107.713272 -131.524756)
		(width 0.1778)
		(layer "F.Cu")
		(net "VR_PVCCP_NODE1_PVCC")
	)
	(via
		(at 107.2007 -131.325112)
		(size 0.508)
		(drill 0.254)
		(layers "F.Cu" "B.Cu")
		(net "VR_PVCCP_NODE1_PVCC")
	)
	(segment
		(start 39.400226 -134.563612)
		(end 39.23665 -134.727188)
		(width 0.1016)
		(layer "F.Cu")
		(net "TP_BMC_NODE1_DDR3_ODT_1NC")
	)
	(segment
		(start 40.033194 -134.563612)
		(end 39.400226 -134.563612)
		(width 0.1016)
		(layer "F.Cu")
		(net "TP_BMC_NODE1_DDR3_ODT_1NC")
	)
	(via
		(at 39.23665 -134.727188)
		(size 0.508)
		(drill 0.254)
		(layers "F.Cu" "B.Cu")
		(net "TP_BMC_NODE1_DDR3_ODT_1NC")
	)
	(segment
		(start 78.571598 -91.3003)
		(end 77.583284 -91.3003)
		(width 0.1016)
		(layer "F.Cu")
		(net "FM_CPLD_NODE1_SYS_PG")
	)
	(segment
		(start 75.79233 -85.85454)
		(end 76.28128 -86.34349)
		(width 0.1016)
		(layer "F.Cu")
		(net "FM_CPLD_NODE1_SYS_PG")
	)
	(segment
		(start 78.99781 -92.076524)
		(end 78.99781 -91.726512)
		(width 0.1016)
		(layer "F.Cu")
		(net "FM_CPLD_NODE1_SYS_PG")
	)
	(segment
		(start 74.929746 -85.85454)
		(end 75.79233 -85.85454)
		(width 0.1016)
		(layer "F.Cu")
		(net "FM_CPLD_NODE1_SYS_PG")
	)
	(segment
		(start 72.826372 -84.908898)
		(end 73.131172 -85.213698)
		(width 0.1016)
		(layer "F.Cu")
		(net "FM_CPLD_NODE1_SYS_PG")
	)
	(segment
		(start 74.288904 -85.213698)
		(end 74.929746 -85.85454)
		(width 0.1016)
		(layer "F.Cu")
		(net "FM_CPLD_NODE1_SYS_PG")
	)
	(segment
		(start 78.99781 -91.726512)
		(end 78.571598 -91.3003)
		(width 0.1016)
		(layer "F.Cu")
		(net "FM_CPLD_NODE1_SYS_PG")
	)
	(segment
		(start 73.131172 -85.213698)
		(end 74.288904 -85.213698)
		(width 0.1016)
		(layer "F.Cu")
		(net "FM_CPLD_NODE1_SYS_PG")
	)
	(segment
		(start 172.010324 -121.365518)
		(end 169.659046 -121.365518)
		(width 0.1016)
		(layer "F.Cu")
		(net "FM_CPLD_NODE1_SYS_PG")
	)
	(segment
		(start 169.659046 -121.365518)
		(end 169.614596 -121.409968)
		(width 0.1016)
		(layer "F.Cu")
		(net "FM_CPLD_NODE1_SYS_PG")
	)
	(segment
		(start 76.28128 -89.998296)
		(end 77.583284 -91.3003)
		(width 0.1016)
		(layer "F.Cu")
		(net "FM_CPLD_NODE1_SYS_PG")
	)
	(segment
		(start 76.28128 -86.34349)
		(end 76.28128 -89.998296)
		(width 0.1016)
		(layer "F.Cu")
		(net "FM_CPLD_NODE1_SYS_PG")
	)
	(segment
		(start 72.543162 -84.908898)
		(end 72.826372 -84.908898)
		(width 0.1016)
		(layer "F.Cu")
		(net "FM_CPLD_NODE1_SYS_PG")
	)
	(via
		(at 162.98926 -112.688624)
		(size 0.508)
		(drill 0.254)
		(layers "F.Cu" "B.Cu")
		(net "FM_CPLD_NODE1_SYS_PG")
	)
	(via
		(at 77.583284 -91.3003)
		(size 0.508)
		(drill 0.254)
		(layers "F.Cu" "B.Cu")
		(net "FM_CPLD_NODE1_SYS_PG")
	)
	(via
		(at 169.614596 -121.409968)
		(size 0.508)
		(drill 0.254)
		(layers "F.Cu" "B.Cu")
		(net "FM_CPLD_NODE1_SYS_PG")
	)
	(segment
		(start 166.64432 -119.124476)
		(end 167.707056 -120.187212)
		(width 0.1143)
		(layer "In2.Cu")
		(net "FM_CPLD_NODE1_SYS_PG")
	)
	(segment
		(start 168.39184 -120.187212)
		(end 169.614596 -121.409968)
		(width 0.1143)
		(layer "In2.Cu")
		(net "FM_CPLD_NODE1_SYS_PG")
	)
	(segment
		(start 164.21735 -112.688624)
		(end 166.64432 -115.115594)
		(width 0.1143)
		(layer "In2.Cu")
		(net "FM_CPLD_NODE1_SYS_PG")
	)
	(segment
		(start 162.98926 -112.688624)
		(end 164.21735 -112.688624)
		(width 0.1143)
		(layer "In2.Cu")
		(net "FM_CPLD_NODE1_SYS_PG")
	)
	(segment
		(start 166.64432 -115.115594)
		(end 166.64432 -119.124476)
		(width 0.1143)
		(layer "In2.Cu")
		(net "FM_CPLD_NODE1_SYS_PG")
	)
	(segment
		(start 167.707056 -120.187212)
		(end 168.39184 -120.187212)
		(width 0.1143)
		(layer "In2.Cu")
		(net "FM_CPLD_NODE1_SYS_PG")
	)
	(segment
		(start 85.771736 -92.884244)
		(end 79.167228 -92.884244)
		(width 0.1143)
		(layer "In6.Cu")
		(net "FM_CPLD_NODE1_SYS_PG")
	)
	(segment
		(start 88.639142 -94.933008)
		(end 87.945722 -94.239588)
		(width 0.1143)
		(layer "In6.Cu")
		(net "FM_CPLD_NODE1_SYS_PG")
	)
	(segment
		(start 87.945722 -94.239588)
		(end 87.12708 -94.239588)
		(width 0.1143)
		(layer "In6.Cu")
		(net "FM_CPLD_NODE1_SYS_PG")
	)
	(segment
		(start 149.12848 -107.780582)
		(end 149.12848 -104.713024)
		(width 0.1143)
		(layer "In6.Cu")
		(net "FM_CPLD_NODE1_SYS_PG")
	)
	(segment
		(start 97.889314 -90.423746)
		(end 93.380052 -94.933008)
		(width 0.1143)
		(layer "In6.Cu")
		(net "FM_CPLD_NODE1_SYS_PG")
	)
	(segment
		(start 134.839202 -90.423746)
		(end 97.889314 -90.423746)
		(width 0.1143)
		(layer "In6.Cu")
		(net "FM_CPLD_NODE1_SYS_PG")
	)
	(segment
		(start 162.98926 -112.688624)
		(end 154.036522 -112.688624)
		(width 0.1143)
		(layer "In6.Cu")
		(net "FM_CPLD_NODE1_SYS_PG")
	)
	(segment
		(start 93.380052 -94.933008)
		(end 88.639142 -94.933008)
		(width 0.1143)
		(layer "In6.Cu")
		(net "FM_CPLD_NODE1_SYS_PG")
	)
	(segment
		(start 79.167228 -92.884244)
		(end 77.583284 -91.3003)
		(width 0.1143)
		(layer "In6.Cu")
		(net "FM_CPLD_NODE1_SYS_PG")
	)
	(segment
		(start 87.12708 -94.239588)
		(end 85.771736 -92.884244)
		(width 0.1143)
		(layer "In6.Cu")
		(net "FM_CPLD_NODE1_SYS_PG")
	)
	(segment
		(start 154.036522 -112.688624)
		(end 149.12848 -107.780582)
		(width 0.1143)
		(layer "In6.Cu")
		(net "FM_CPLD_NODE1_SYS_PG")
	)
	(segment
		(start 149.12848 -104.713024)
		(end 134.839202 -90.423746)
		(width 0.1143)
		(layer "In6.Cu")
		(net "FM_CPLD_NODE1_SYS_PG")
	)
	(segment
		(start 55.722774 -131.442206)
		(end 55.43423 -131.153662)
		(width 0.1016)
		(layer "F.Cu")
		(net "BMC_NODE1_DDR_MA4")
	)
	(segment
		(start 55.43423 -131.153662)
		(end 55.272686 -131.153662)
		(width 0.1016)
		(layer "F.Cu")
		(net "BMC_NODE1_DDR_MA4")
	)
	(segment
		(start 56.48325 -132.059426)
		(end 56.013858 -132.528818)
		(width 0.1016)
		(layer "F.Cu")
		(net "BMC_NODE1_DDR_MA4")
	)
	(segment
		(start 56.013858 -132.528818)
		(end 55.831994 -132.528818)
		(width 0.1016)
		(layer "F.Cu")
		(net "BMC_NODE1_DDR_MA4")
	)
	(segment
		(start 57.34177 -132.059426)
		(end 56.48325 -132.059426)
		(width 0.1016)
		(layer "F.Cu")
		(net "BMC_NODE1_DDR_MA4")
	)
	(segment
		(start 55.831994 -132.528818)
		(end 55.722774 -132.419598)
		(width 0.1016)
		(layer "F.Cu")
		(net "BMC_NODE1_DDR_MA4")
	)
	(segment
		(start 55.722774 -132.419598)
		(end 55.722774 -131.442206)
		(width 0.1016)
		(layer "F.Cu")
		(net "BMC_NODE1_DDR_MA4")
	)
	(segment
		(start 45.633132 -130.563112)
		(end 46.032674 -130.16357)
		(width 0.1016)
		(layer "F.Cu")
		(net "BMC_NODE1_DDR_MA4")
	)
	(segment
		(start 45.633132 -130.56362)
		(end 45.633132 -130.563112)
		(width 0.1016)
		(layer "F.Cu")
		(net "BMC_NODE1_DDR_MA4")
	)
	(via
		(at 55.272686 -131.153662)
		(size 0.508)
		(drill 0.254)
		(layers "F.Cu" "B.Cu")
		(net "BMC_NODE1_DDR_MA4")
	)
	(via
		(at 46.032674 -130.16357)
		(size 0.508)
		(drill 0.254)
		(layers "F.Cu" "B.Cu")
		(net "BMC_NODE1_DDR_MA4")
	)
	(segment
		(start 51.525932 -129.639822)
		(end 51.681888 -129.639822)
		(width 0.1143)
		(layer "In2.Cu")
		(net "BMC_NODE1_DDR_MA4")
	)
	(segment
		(start 55.272686 -131.07035)
		(end 55.272686 -131.153662)
		(width 0.1143)
		(layer "In2.Cu")
		(net "BMC_NODE1_DDR_MA4")
	)
	(segment
		(start 51.225958 -128.744726)
		(end 51.414934 -128.933702)
		(width 0.1143)
		(layer "In2.Cu")
		(net "BMC_NODE1_DDR_MA4")
	)
	(segment
		(start 52.58562 -129.636012)
		(end 53.198522 -129.636012)
		(width 0.1143)
		(layer "In2.Cu")
		(net "BMC_NODE1_DDR_MA4")
	)
	(segment
		(start 49.548034 -128.920494)
		(end 49.723802 -128.744726)
		(width 0.1143)
		(layer "In2.Cu")
		(net "BMC_NODE1_DDR_MA4")
	)
	(segment
		(start 49.548034 -129.45745)
		(end 49.548034 -128.920494)
		(width 0.1143)
		(layer "In2.Cu")
		(net "BMC_NODE1_DDR_MA4")
	)
	(segment
		(start 52.070762 -129.250948)
		(end 52.200556 -129.250948)
		(width 0.1143)
		(layer "In2.Cu")
		(net "BMC_NODE1_DDR_MA4")
	)
	(segment
		(start 48.156876 -128.730248)
		(end 49.06645 -129.639822)
		(width 0.1143)
		(layer "In2.Cu")
		(net "BMC_NODE1_DDR_MA4")
	)
	(segment
		(start 53.198522 -129.636012)
		(end 54.069996 -130.507486)
		(width 0.1143)
		(layer "In2.Cu")
		(net "BMC_NODE1_DDR_MA4")
	)
	(segment
		(start 46.032674 -130.16357)
		(end 45.50664 -129.637536)
		(width 0.1143)
		(layer "In2.Cu")
		(net "BMC_NODE1_DDR_MA4")
	)
	(segment
		(start 54.069996 -130.507486)
		(end 54.709822 -130.507486)
		(width 0.1143)
		(layer "In2.Cu")
		(net "BMC_NODE1_DDR_MA4")
	)
	(segment
		(start 49.365662 -129.639822)
		(end 49.548034 -129.45745)
		(width 0.1143)
		(layer "In2.Cu")
		(net "BMC_NODE1_DDR_MA4")
	)
	(segment
		(start 51.414934 -129.528824)
		(end 51.525932 -129.639822)
		(width 0.1143)
		(layer "In2.Cu")
		(net "BMC_NODE1_DDR_MA4")
	)
	(segment
		(start 50.968402 -128.744726)
		(end 51.225958 -128.744726)
		(width 0.1143)
		(layer "In2.Cu")
		(net "BMC_NODE1_DDR_MA4")
	)
	(segment
		(start 50.792634 -128.920494)
		(end 50.968402 -128.744726)
		(width 0.1143)
		(layer "In2.Cu")
		(net "BMC_NODE1_DDR_MA4")
	)
	(segment
		(start 50.352706 -129.639822)
		(end 50.610262 -129.639822)
		(width 0.1143)
		(layer "In2.Cu")
		(net "BMC_NODE1_DDR_MA4")
	)
	(segment
		(start 45.50664 -129.637536)
		(end 45.50664 -129.453132)
		(width 0.1143)
		(layer "In2.Cu")
		(net "BMC_NODE1_DDR_MA4")
	)
	(segment
		(start 45.50664 -129.453132)
		(end 46.229524 -128.730248)
		(width 0.1143)
		(layer "In2.Cu")
		(net "BMC_NODE1_DDR_MA4")
	)
	(segment
		(start 49.06645 -129.639822)
		(end 49.365662 -129.639822)
		(width 0.1143)
		(layer "In2.Cu")
		(net "BMC_NODE1_DDR_MA4")
	)
	(segment
		(start 46.229524 -128.730248)
		(end 48.156876 -128.730248)
		(width 0.1143)
		(layer "In2.Cu")
		(net "BMC_NODE1_DDR_MA4")
	)
	(segment
		(start 54.709822 -130.507486)
		(end 55.272686 -131.07035)
		(width 0.1143)
		(layer "In2.Cu")
		(net "BMC_NODE1_DDR_MA4")
	)
	(segment
		(start 49.981358 -128.744726)
		(end 50.170334 -128.933702)
		(width 0.1143)
		(layer "In2.Cu")
		(net "BMC_NODE1_DDR_MA4")
	)
	(segment
		(start 51.681888 -129.639822)
		(end 52.070762 -129.250948)
		(width 0.1143)
		(layer "In2.Cu")
		(net "BMC_NODE1_DDR_MA4")
	)
	(segment
		(start 50.170334 -128.933702)
		(end 50.170334 -129.45745)
		(width 0.1143)
		(layer "In2.Cu")
		(net "BMC_NODE1_DDR_MA4")
	)
	(segment
		(start 50.170334 -129.45745)
		(end 50.352706 -129.639822)
		(width 0.1143)
		(layer "In2.Cu")
		(net "BMC_NODE1_DDR_MA4")
	)
	(segment
		(start 51.414934 -128.933702)
		(end 51.414934 -129.528824)
		(width 0.1143)
		(layer "In2.Cu")
		(net "BMC_NODE1_DDR_MA4")
	)
	(segment
		(start 52.200556 -129.250948)
		(end 52.58562 -129.636012)
		(width 0.1143)
		(layer "In2.Cu")
		(net "BMC_NODE1_DDR_MA4")
	)
	(segment
		(start 49.723802 -128.744726)
		(end 49.981358 -128.744726)
		(width 0.1143)
		(layer "In2.Cu")
		(net "BMC_NODE1_DDR_MA4")
	)
	(segment
		(start 50.792634 -129.45745)
		(end 50.792634 -128.920494)
		(width 0.1143)
		(layer "In2.Cu")
		(net "BMC_NODE1_DDR_MA4")
	)
	(segment
		(start 50.610262 -129.639822)
		(end 50.792634 -129.45745)
		(width 0.1143)
		(layer "In2.Cu")
		(net "BMC_NODE1_DDR_MA4")
	)
	(segment
		(start 104.94645 -135.897874)
		(end 104.340152 -135.897874)
		(width 0.1016)
		(layer "F.Cu")
		(net "SVID_CPU_NODE1_PVCCP_ALERT_L")
	)
	(segment
		(start 104.340152 -135.897874)
		(end 103.755444 -136.482582)
		(width 0.1016)
		(layer "F.Cu")
		(net "SVID_CPU_NODE1_PVCCP_ALERT_L")
	)
	(via
		(at 103.755444 -136.482582)
		(size 0.508)
		(drill 0.254)
		(layers "F.Cu" "B.Cu")
		(net "SVID_CPU_NODE1_PVCCP_ALERT_L")
	)
	(segment
		(start 100.09505 -104.119172)
		(end 100.34778 -104.371902)
		(width 0.1016)
		(layer "B.Cu")
		(net "SVID_CPU_NODE1_PVCCP_ALERT_L")
	)
	(segment
		(start 95.71736 -83.99399)
		(end 95.71736 -90.343482)
		(width 0.1016)
		(layer "B.Cu")
		(net "SVID_CPU_NODE1_PVCCP_ALERT_L")
	)
	(segment
		(start 99.66706 -103.710994)
		(end 100.075238 -104.119172)
		(width 0.1016)
		(layer "B.Cu")
		(net "SVID_CPU_NODE1_PVCCP_ALERT_L")
	)
	(segment
		(start 83.719162 -77.748384)
		(end 84.65058 -78.679802)
		(width 0.1016)
		(layer "B.Cu")
		(net "SVID_CPU_NODE1_PVCCP_ALERT_L")
	)
	(segment
		(start 94.92234 -83.19897)
		(end 95.71736 -83.99399)
		(width 0.1016)
		(layer "B.Cu")
		(net "SVID_CPU_NODE1_PVCCP_ALERT_L")
	)
	(segment
		(start 101.186488 -118.942358)
		(end 101.186488 -129.59842)
		(width 0.1016)
		(layer "B.Cu")
		(net "SVID_CPU_NODE1_PVCCP_ALERT_L")
	)
	(segment
		(start 94.38386 -83.19897)
		(end 94.92234 -83.19897)
		(width 0.1016)
		(layer "B.Cu")
		(net "SVID_CPU_NODE1_PVCCP_ALERT_L")
	)
	(segment
		(start 98.64852 -93.274642)
		(end 98.64852 -100.53447)
		(width 0.1016)
		(layer "B.Cu")
		(net "SVID_CPU_NODE1_PVCCP_ALERT_L")
	)
	(segment
		(start 101.846888 -135.761222)
		(end 102.568248 -136.482582)
		(width 0.1016)
		(layer "B.Cu")
		(net "SVID_CPU_NODE1_PVCCP_ALERT_L")
	)
	(segment
		(start 92.601034 -81.416144)
		(end 94.38386 -83.19897)
		(width 0.1016)
		(layer "B.Cu")
		(net "SVID_CPU_NODE1_PVCCP_ALERT_L")
	)
	(segment
		(start 88.440768 -80.83042)
		(end 88.440768 -81.053178)
		(width 0.1016)
		(layer "B.Cu")
		(net "SVID_CPU_NODE1_PVCCP_ALERT_L")
	)
	(segment
		(start 100.075238 -104.119172)
		(end 100.09505 -104.119172)
		(width 0.1016)
		(layer "B.Cu")
		(net "SVID_CPU_NODE1_PVCCP_ALERT_L")
	)
	(segment
		(start 98.64852 -100.53447)
		(end 99.66706 -101.55301)
		(width 0.1016)
		(layer "B.Cu")
		(net "SVID_CPU_NODE1_PVCCP_ALERT_L")
	)
	(segment
		(start 100.34778 -104.730042)
		(end 100.09632 -104.981502)
		(width 0.1016)
		(layer "B.Cu")
		(net "SVID_CPU_NODE1_PVCCP_ALERT_L")
	)
	(segment
		(start 80.672178 -77.946504)
		(end 82.08137 -77.946504)
		(width 0.1016)
		(layer "B.Cu")
		(net "SVID_CPU_NODE1_PVCCP_ALERT_L")
	)
	(segment
		(start 85.710014 -79.856584)
		(end 86.22792 -79.856584)
		(width 0.1016)
		(layer "B.Cu")
		(net "SVID_CPU_NODE1_PVCCP_ALERT_L")
	)
	(segment
		(start 87.87892 -80.666844)
		(end 88.042496 -80.83042)
		(width 0.1016)
		(layer "B.Cu")
		(net "SVID_CPU_NODE1_PVCCP_ALERT_L")
	)
	(segment
		(start 100.09632 -104.981502)
		(end 100.09632 -117.85219)
		(width 0.1016)
		(layer "B.Cu")
		(net "SVID_CPU_NODE1_PVCCP_ALERT_L")
	)
	(segment
		(start 100.09632 -117.85219)
		(end 101.186488 -118.942358)
		(width 0.1016)
		(layer "B.Cu")
		(net "SVID_CPU_NODE1_PVCCP_ALERT_L")
	)
	(segment
		(start 88.042496 -80.83042)
		(end 88.440768 -80.83042)
		(width 0.1016)
		(layer "B.Cu")
		(net "SVID_CPU_NODE1_PVCCP_ALERT_L")
	)
	(segment
		(start 84.65058 -78.79715)
		(end 85.710014 -79.856584)
		(width 0.1016)
		(layer "B.Cu")
		(net "SVID_CPU_NODE1_PVCCP_ALERT_L")
	)
	(segment
		(start 101.186488 -129.59842)
		(end 101.846888 -130.25882)
		(width 0.1016)
		(layer "B.Cu")
		(net "SVID_CPU_NODE1_PVCCP_ALERT_L")
	)
	(segment
		(start 82.27949 -77.748384)
		(end 83.719162 -77.748384)
		(width 0.1016)
		(layer "B.Cu")
		(net "SVID_CPU_NODE1_PVCCP_ALERT_L")
	)
	(segment
		(start 87.03818 -80.666844)
		(end 87.87892 -80.666844)
		(width 0.1016)
		(layer "B.Cu")
		(net "SVID_CPU_NODE1_PVCCP_ALERT_L")
	)
	(segment
		(start 99.66706 -101.55301)
		(end 99.66706 -103.710994)
		(width 0.1016)
		(layer "B.Cu")
		(net "SVID_CPU_NODE1_PVCCP_ALERT_L")
	)
	(segment
		(start 95.71736 -90.343482)
		(end 98.64852 -93.274642)
		(width 0.1016)
		(layer "B.Cu")
		(net "SVID_CPU_NODE1_PVCCP_ALERT_L")
	)
	(segment
		(start 88.803734 -81.416144)
		(end 92.601034 -81.416144)
		(width 0.1016)
		(layer "B.Cu")
		(net "SVID_CPU_NODE1_PVCCP_ALERT_L")
	)
	(segment
		(start 101.846888 -130.25882)
		(end 101.846888 -135.761222)
		(width 0.1016)
		(layer "B.Cu")
		(net "SVID_CPU_NODE1_PVCCP_ALERT_L")
	)
	(segment
		(start 100.34778 -104.371902)
		(end 100.34778 -104.730042)
		(width 0.1016)
		(layer "B.Cu")
		(net "SVID_CPU_NODE1_PVCCP_ALERT_L")
	)
	(segment
		(start 82.08137 -77.946504)
		(end 82.27949 -77.748384)
		(width 0.1016)
		(layer "B.Cu")
		(net "SVID_CPU_NODE1_PVCCP_ALERT_L")
	)
	(segment
		(start 84.65058 -78.679802)
		(end 84.65058 -78.79715)
		(width 0.1016)
		(layer "B.Cu")
		(net "SVID_CPU_NODE1_PVCCP_ALERT_L")
	)
	(segment
		(start 86.22792 -79.856584)
		(end 87.03818 -80.666844)
		(width 0.1016)
		(layer "B.Cu")
		(net "SVID_CPU_NODE1_PVCCP_ALERT_L")
	)
	(segment
		(start 88.440768 -81.053178)
		(end 88.803734 -81.416144)
		(width 0.1016)
		(layer "B.Cu")
		(net "SVID_CPU_NODE1_PVCCP_ALERT_L")
	)
	(segment
		(start 102.568248 -136.482582)
		(end 103.755444 -136.482582)
		(width 0.1016)
		(layer "B.Cu")
		(net "SVID_CPU_NODE1_PVCCP_ALERT_L")
	)
	(segment
		(start 173.597062 -113.69421)
		(end 169.693844 -113.69421)
		(width 0.1016)
		(layer "F.Cu")
		(net "FM_CPLD_NODE1_PVCCP_EN")
	)
	(segment
		(start 174.530512 -116.88572)
		(end 174.530512 -114.62766)
		(width 0.1016)
		(layer "F.Cu")
		(net "FM_CPLD_NODE1_PVCCP_EN")
	)
	(segment
		(start 162.221418 -114.185954)
		(end 161.589466 -114.185954)
		(width 0.1016)
		(layer "F.Cu")
		(net "FM_CPLD_NODE1_PVCCP_EN")
	)
	(segment
		(start 164.215572 -112.1918)
		(end 162.221418 -114.185954)
		(width 0.1016)
		(layer "F.Cu")
		(net "FM_CPLD_NODE1_PVCCP_EN")
	)
	(segment
		(start 168.191434 -112.1918)
		(end 164.215572 -112.1918)
		(width 0.1016)
		(layer "F.Cu")
		(net "FM_CPLD_NODE1_PVCCP_EN")
	)
	(segment
		(start 169.693844 -113.69421)
		(end 168.191434 -112.1918)
		(width 0.1016)
		(layer "F.Cu")
		(net "FM_CPLD_NODE1_PVCCP_EN")
	)
	(segment
		(start 174.530512 -114.62766)
		(end 173.597062 -113.69421)
		(width 0.1016)
		(layer "F.Cu")
		(net "FM_CPLD_NODE1_PVCCP_EN")
	)
	(segment
		(start 103.1621 -129.74574)
		(end 103.1621 -128.807972)
		(width 0.1016)
		(layer "F.Cu")
		(net "FM_CPLD_NODE1_PVCCP_EN")
	)
	(segment
		(start 103.1621 -128.807972)
		(end 102.958392 -128.604264)
		(width 0.1016)
		(layer "F.Cu")
		(net "FM_CPLD_NODE1_PVCCP_EN")
	)
	(segment
		(start 175.010318 -117.365526)
		(end 174.530512 -116.88572)
		(width 0.1016)
		(layer "F.Cu")
		(net "FM_CPLD_NODE1_PVCCP_EN")
	)
	(segment
		(start 161.589466 -114.185954)
		(end 161.50336 -114.27206)
		(width 0.1016)
		(layer "F.Cu")
		(net "FM_CPLD_NODE1_PVCCP_EN")
	)
	(via
		(at 102.958392 -128.604264)
		(size 0.508)
		(drill 0.254)
		(layers "F.Cu" "B.Cu")
		(net "FM_CPLD_NODE1_PVCCP_EN")
	)
	(via
		(at 161.50336 -114.27206)
		(size 0.508)
		(drill 0.254)
		(layers "F.Cu" "B.Cu")
		(net "FM_CPLD_NODE1_PVCCP_EN")
	)
	(via
		(at 162.1409 -129.004822)
		(size 0.508)
		(drill 0.254)
		(layers "F.Cu" "B.Cu")
		(net "FM_CPLD_NODE1_PVCCP_EN")
	)
	(segment
		(start 162.1409 -114.9096)
		(end 162.1409 -129.004822)
		(width 0.1143)
		(layer "In2.Cu")
		(net "FM_CPLD_NODE1_PVCCP_EN")
	)
	(segment
		(start 161.50336 -114.27206)
		(end 162.1409 -114.9096)
		(width 0.1143)
		(layer "In2.Cu")
		(net "FM_CPLD_NODE1_PVCCP_EN")
	)
	(segment
		(start 99.436682 -129.562606)
		(end 101.17074 -127.828548)
		(width 0.1143)
		(layer "In6.Cu")
		(net "FM_CPLD_NODE1_PVCCP_EN")
	)
	(segment
		(start 102.587298 -127.828548)
		(end 102.958392 -128.199642)
		(width 0.1143)
		(layer "In6.Cu")
		(net "FM_CPLD_NODE1_PVCCP_EN")
	)
	(segment
		(start 162.1409 -129.004822)
		(end 159.8041 -131.341622)
		(width 0.1143)
		(layer "In6.Cu")
		(net "FM_CPLD_NODE1_PVCCP_EN")
	)
	(segment
		(start 148.783802 -131.341622)
		(end 148.50237 -131.623054)
		(width 0.1143)
		(layer "In6.Cu")
		(net "FM_CPLD_NODE1_PVCCP_EN")
	)
	(segment
		(start 124.860304 -131.6228)
		(end 124.4473 -131.6228)
		(width 0.1143)
		(layer "In6.Cu")
		(net "FM_CPLD_NODE1_PVCCP_EN")
	)
	(segment
		(start 115.732306 -140.337794)
		(end 114.97818 -140.337794)
		(width 0.1143)
		(layer "In6.Cu")
		(net "FM_CPLD_NODE1_PVCCP_EN")
	)
	(segment
		(start 102.958392 -128.199642)
		(end 102.958392 -128.604264)
		(width 0.1143)
		(layer "In6.Cu")
		(net "FM_CPLD_NODE1_PVCCP_EN")
	)
	(segment
		(start 99.436682 -140.965428)
		(end 99.436682 -129.562606)
		(width 0.1143)
		(layer "In6.Cu")
		(net "FM_CPLD_NODE1_PVCCP_EN")
	)
	(segment
		(start 124.860558 -131.623054)
		(end 124.860304 -131.6228)
		(width 0.1143)
		(layer "In6.Cu")
		(net "FM_CPLD_NODE1_PVCCP_EN")
	)
	(segment
		(start 116.75618 -139.31392)
		(end 115.732306 -140.337794)
		(width 0.1143)
		(layer "In6.Cu")
		(net "FM_CPLD_NODE1_PVCCP_EN")
	)
	(segment
		(start 101.61143 -143.140176)
		(end 99.436682 -140.965428)
		(width 0.1143)
		(layer "In6.Cu")
		(net "FM_CPLD_NODE1_PVCCP_EN")
	)
	(segment
		(start 123.027694 -131.623054)
		(end 116.75618 -137.894568)
		(width 0.1143)
		(layer "In6.Cu")
		(net "FM_CPLD_NODE1_PVCCP_EN")
	)
	(segment
		(start 124.447046 -131.623054)
		(end 123.027694 -131.623054)
		(width 0.1143)
		(layer "In6.Cu")
		(net "FM_CPLD_NODE1_PVCCP_EN")
	)
	(segment
		(start 112.175798 -143.140176)
		(end 101.61143 -143.140176)
		(width 0.1143)
		(layer "In6.Cu")
		(net "FM_CPLD_NODE1_PVCCP_EN")
	)
	(segment
		(start 124.4473 -131.6228)
		(end 124.447046 -131.623054)
		(width 0.1143)
		(layer "In6.Cu")
		(net "FM_CPLD_NODE1_PVCCP_EN")
	)
	(segment
		(start 101.17074 -127.828548)
		(end 102.587298 -127.828548)
		(width 0.1143)
		(layer "In6.Cu")
		(net "FM_CPLD_NODE1_PVCCP_EN")
	)
	(segment
		(start 148.50237 -131.623054)
		(end 124.860558 -131.623054)
		(width 0.1143)
		(layer "In6.Cu")
		(net "FM_CPLD_NODE1_PVCCP_EN")
	)
	(segment
		(start 116.75618 -137.894568)
		(end 116.75618 -139.31392)
		(width 0.1143)
		(layer "In6.Cu")
		(net "FM_CPLD_NODE1_PVCCP_EN")
	)
	(segment
		(start 114.97818 -140.337794)
		(end 112.175798 -143.140176)
		(width 0.1143)
		(layer "In6.Cu")
		(net "FM_CPLD_NODE1_PVCCP_EN")
	)
	(segment
		(start 159.8041 -131.341622)
		(end 148.783802 -131.341622)
		(width 0.1143)
		(layer "In6.Cu")
		(net "FM_CPLD_NODE1_PVCCP_EN")
	)
	(segment
		(start 46.432978 -132.963666)
		(end 46.477174 -133.007862)
		(width 0.1016)
		(layer "F.Cu")
		(net "TP_BMC_NODE1_DDR3_ZQ1")
	)
	(segment
		(start 46.477174 -133.007862)
		(end 47.352204 -133.007862)
		(width 0.1016)
		(layer "F.Cu")
		(net "TP_BMC_NODE1_DDR3_ZQ1")
	)
	(segment
		(start 49.63541 -132.804662)
		(end 49.964086 -133.133338)
		(width 0.1016)
		(layer "F.Cu")
		(net "TP_BMC_NODE1_DDR3_ZQ1")
	)
	(segment
		(start 47.555404 -132.804662)
		(end 49.63541 -132.804662)
		(width 0.1016)
		(layer "F.Cu")
		(net "TP_BMC_NODE1_DDR3_ZQ1")
	)
	(segment
		(start 47.352204 -133.007862)
		(end 47.555404 -132.804662)
		(width 0.1016)
		(layer "F.Cu")
		(net "TP_BMC_NODE1_DDR3_ZQ1")
	)
	(segment
		(start 49.964086 -138.085322)
		(end 49.140364 -138.909044)
		(width 0.1016)
		(layer "F.Cu")
		(net "TP_BMC_NODE1_DDR3_ZQ1")
	)
	(segment
		(start 49.964086 -133.133338)
		(end 49.964086 -138.085322)
		(width 0.1016)
		(layer "F.Cu")
		(net "TP_BMC_NODE1_DDR3_ZQ1")
	)
	(via
		(at 49.140364 -138.909044)
		(size 0.508)
		(drill 0.254)
		(layers "F.Cu" "B.Cu")
		(net "TP_BMC_NODE1_DDR3_ZQ1")
	)
	(segment
		(start 116.129054 -63.422784)
		(end 116.129054 -63.823596)
		(width 0.1016)
		(layer "F.Cu")
		(net "RST_NODE1_CPU_XDP_RSTIN_L")
	)
	(segment
		(start 113.73104 -63.348616)
		(end 113.739168 -63.348616)
		(width 0.1016)
		(layer "F.Cu")
		(net "RST_NODE1_CPU_XDP_RSTIN_L")
	)
	(segment
		(start 113.26622 -63.348616)
		(end 111.708438 -64.906398)
		(width 0.1016)
		(layer "F.Cu")
		(net "RST_NODE1_CPU_XDP_RSTIN_L")
	)
	(segment
		(start 113.739168 -63.348616)
		(end 114.399568 -64.009016)
		(width 0.1016)
		(layer "F.Cu")
		(net "RST_NODE1_CPU_XDP_RSTIN_L")
	)
	(segment
		(start 115.542822 -64.009016)
		(end 116.129054 -63.422784)
		(width 0.1016)
		(layer "F.Cu")
		(net "RST_NODE1_CPU_XDP_RSTIN_L")
	)
	(segment
		(start 173.010322 -124.365766)
		(end 172.541946 -124.834142)
		(width 0.1016)
		(layer "F.Cu")
		(net "RST_NODE1_CPU_XDP_RSTIN_L")
	)
	(segment
		(start 114.399568 -64.009016)
		(end 115.542822 -64.009016)
		(width 0.1016)
		(layer "F.Cu")
		(net "RST_NODE1_CPU_XDP_RSTIN_L")
	)
	(segment
		(start 116.129054 -63.823596)
		(end 116.613432 -64.307974)
		(width 0.1016)
		(layer "F.Cu")
		(net "RST_NODE1_CPU_XDP_RSTIN_L")
	)
	(segment
		(start 111.708438 -64.906398)
		(end 110.460028 -64.906398)
		(width 0.1016)
		(layer "F.Cu")
		(net "RST_NODE1_CPU_XDP_RSTIN_L")
	)
	(segment
		(start 113.73104 -63.348616)
		(end 113.26622 -63.348616)
		(width 0.1016)
		(layer "F.Cu")
		(net "RST_NODE1_CPU_XDP_RSTIN_L")
	)
	(via
		(at 116.613432 -64.307974)
		(size 0.508)
		(drill 0.254)
		(layers "F.Cu" "B.Cu")
		(net "RST_NODE1_CPU_XDP_RSTIN_L")
	)
	(via
		(at 172.541946 -124.834142)
		(size 0.508)
		(drill 0.254)
		(layers "F.Cu" "B.Cu")
		(net "RST_NODE1_CPU_XDP_RSTIN_L")
	)
	(segment
		(start 130.29184 -99.358196)
		(end 141.580362 -99.358196)
		(width 0.1143)
		(layer "In7.Cu")
		(net "RST_NODE1_CPU_XDP_RSTIN_L")
	)
	(segment
		(start 159.77362 -123.258326)
		(end 161.835084 -123.258326)
		(width 0.1143)
		(layer "In7.Cu")
		(net "RST_NODE1_CPU_XDP_RSTIN_L")
	)
	(segment
		(start 154.34183 -113.139728)
		(end 154.34183 -117.826536)
		(width 0.1143)
		(layer "In7.Cu")
		(net "RST_NODE1_CPU_XDP_RSTIN_L")
	)
	(segment
		(start 168.744138 -124.834142)
		(end 172.541946 -124.834142)
		(width 0.1143)
		(layer "In7.Cu")
		(net "RST_NODE1_CPU_XDP_RSTIN_L")
	)
	(segment
		(start 165.443154 -124.373894)
		(end 166.694358 -125.625098)
		(width 0.1143)
		(layer "In7.Cu")
		(net "RST_NODE1_CPU_XDP_RSTIN_L")
	)
	(segment
		(start 161.835084 -123.258326)
		(end 162.950652 -124.373894)
		(width 0.1143)
		(layer "In7.Cu")
		(net "RST_NODE1_CPU_XDP_RSTIN_L")
	)
	(segment
		(start 112.67186 -71.926958)
		(end 112.67186 -81.738216)
		(width 0.1143)
		(layer "In7.Cu")
		(net "RST_NODE1_CPU_XDP_RSTIN_L")
	)
	(segment
		(start 167.953182 -125.625098)
		(end 168.744138 -124.834142)
		(width 0.1143)
		(layer "In7.Cu")
		(net "RST_NODE1_CPU_XDP_RSTIN_L")
	)
	(segment
		(start 113.3094 -71.289418)
		(end 112.67186 -71.926958)
		(width 0.1143)
		(layer "In7.Cu")
		(net "RST_NODE1_CPU_XDP_RSTIN_L")
	)
	(segment
		(start 113.3094 -66.981324)
		(end 113.3094 -71.289418)
		(width 0.1143)
		(layer "In7.Cu")
		(net "RST_NODE1_CPU_XDP_RSTIN_L")
	)
	(segment
		(start 148.749766 -107.547664)
		(end 154.34183 -113.139728)
		(width 0.1143)
		(layer "In7.Cu")
		(net "RST_NODE1_CPU_XDP_RSTIN_L")
	)
	(segment
		(start 154.34183 -117.826536)
		(end 159.77362 -123.258326)
		(width 0.1143)
		(layer "In7.Cu")
		(net "RST_NODE1_CPU_XDP_RSTIN_L")
	)
	(segment
		(start 162.950652 -124.373894)
		(end 165.443154 -124.373894)
		(width 0.1143)
		(layer "In7.Cu")
		(net "RST_NODE1_CPU_XDP_RSTIN_L")
	)
	(segment
		(start 112.67186 -81.738216)
		(end 130.29184 -99.358196)
		(width 0.1143)
		(layer "In7.Cu")
		(net "RST_NODE1_CPU_XDP_RSTIN_L")
	)
	(segment
		(start 166.694358 -125.625098)
		(end 167.953182 -125.625098)
		(width 0.1143)
		(layer "In7.Cu")
		(net "RST_NODE1_CPU_XDP_RSTIN_L")
	)
	(segment
		(start 141.580362 -99.358196)
		(end 148.749766 -106.5276)
		(width 0.1143)
		(layer "In7.Cu")
		(net "RST_NODE1_CPU_XDP_RSTIN_L")
	)
	(segment
		(start 115.98275 -64.307974)
		(end 113.3094 -66.981324)
		(width 0.1143)
		(layer "In7.Cu")
		(net "RST_NODE1_CPU_XDP_RSTIN_L")
	)
	(segment
		(start 116.613432 -64.307974)
		(end 115.98275 -64.307974)
		(width 0.1143)
		(layer "In7.Cu")
		(net "RST_NODE1_CPU_XDP_RSTIN_L")
	)
	(segment
		(start 148.749766 -106.5276)
		(end 148.749766 -107.547664)
		(width 0.1143)
		(layer "In7.Cu")
		(net "RST_NODE1_CPU_XDP_RSTIN_L")
	)
	(segment
		(start 113.735612 -132.418074)
		(end 113.730532 -132.412994)
		(width 0.254)
		(layer "F.Cu")
		(net "VR_PVCCP_NODE1_ISEN1P_CC")
	)
	(segment
		(start 114.43716 -132.366512)
		(end 114.43716 -132.418074)
		(width 0.254)
		(layer "F.Cu")
		(net "VR_PVCCP_NODE1_ISEN1P_CC")
	)
	(segment
		(start 110.983776 -133.897878)
		(end 109.996478 -133.897878)
		(width 0.1778)
		(layer "F.Cu")
		(net "VR_PVCCP_NODE1_ISEN1P_CC")
	)
	(segment
		(start 112.717072 -132.822696)
		(end 111.908336 -133.631432)
		(width 0.254)
		(layer "F.Cu")
		(net "VR_PVCCP_NODE1_ISEN1P_CC")
	)
	(segment
		(start 112.717072 -132.412994)
		(end 112.717072 -132.822696)
		(width 0.254)
		(layer "F.Cu")
		(net "VR_PVCCP_NODE1_ISEN1P_CC")
	)
	(segment
		(start 111.908336 -133.631432)
		(end 111.34852 -133.631432)
		(width 0.254)
		(layer "F.Cu")
		(net "VR_PVCCP_NODE1_ISEN1P_CC")
	)
	(segment
		(start 111.250222 -133.631432)
		(end 110.983776 -133.897878)
		(width 0.1778)
		(layer "F.Cu")
		(net "VR_PVCCP_NODE1_ISEN1P_CC")
	)
	(segment
		(start 113.730532 -132.412994)
		(end 112.717072 -132.412994)
		(width 0.254)
		(layer "F.Cu")
		(net "VR_PVCCP_NODE1_ISEN1P_CC")
	)
	(segment
		(start 115.478814 -131.577334)
		(end 114.689636 -132.366512)
		(width 0.254)
		(layer "F.Cu")
		(net "VR_PVCCP_NODE1_ISEN1P_CC")
	)
	(segment
		(start 111.34852 -133.631432)
		(end 111.250222 -133.631432)
		(width 0.1778)
		(layer "F.Cu")
		(net "VR_PVCCP_NODE1_ISEN1P_CC")
	)
	(segment
		(start 114.689636 -132.366512)
		(end 114.43716 -132.366512)
		(width 0.254)
		(layer "F.Cu")
		(net "VR_PVCCP_NODE1_ISEN1P_CC")
	)
	(segment
		(start 114.43716 -132.418074)
		(end 113.735612 -132.418074)
		(width 0.254)
		(layer "F.Cu")
		(net "VR_PVCCP_NODE1_ISEN1P_CC")
	)
	(via
		(at 114.43716 -132.418074)
		(size 0.508)
		(drill 0.254)
		(layers "F.Cu" "B.Cu")
		(net "VR_PVCCP_NODE1_ISEN1P_CC")
	)
	(segment
		(start 59.741816 -131.259072)
		(end 59.341004 -130.85826)
		(width 0.1016)
		(layer "F.Cu")
		(net "BMC_NODE1_DDR_MA5")
	)
	(segment
		(start 40.833294 -130.56362)
		(end 41.23309 -130.163824)
		(width 0.1016)
		(layer "F.Cu")
		(net "BMC_NODE1_DDR_MA5")
	)
	(segment
		(start 40.83304 -130.56362)
		(end 40.833294 -130.56362)
		(width 0.1016)
		(layer "F.Cu")
		(net "BMC_NODE1_DDR_MA5")
	)
	(segment
		(start 59.741816 -131.25958)
		(end 59.741816 -131.259072)
		(width 0.1016)
		(layer "F.Cu")
		(net "BMC_NODE1_DDR_MA5")
	)
	(via
		(at 59.341004 -130.85826)
		(size 0.49022)
		(drill 0.254)
		(layers "F.Cu" "B.Cu")
		(net "BMC_NODE1_DDR_MA5")
	)
	(via
		(at 41.23309 -130.163824)
		(size 0.508)
		(drill 0.254)
		(layers "F.Cu" "B.Cu")
		(net "BMC_NODE1_DDR_MA5")
	)
	(segment
		(start 41.23309 -130.163824)
		(end 42.29862 -129.196592)
		(width 0.1143)
		(layer "In2.Cu")
		(net "BMC_NODE1_DDR_MA5")
	)
	(segment
		(start 56.579262 -128.777238)
		(end 58.258202 -130.456178)
		(width 0.1143)
		(layer "In2.Cu")
		(net "BMC_NODE1_DDR_MA5")
	)
	(segment
		(start 58.938922 -130.456178)
		(end 59.341004 -130.85826)
		(width 0.1143)
		(layer "In2.Cu")
		(net "BMC_NODE1_DDR_MA5")
	)
	(segment
		(start 58.74385 -130.456178)
		(end 58.938922 -130.456178)
		(width 0.1143)
		(layer "In2.Cu")
		(net "BMC_NODE1_DDR_MA5")
	)
	(segment
		(start 45.369734 -126.125478)
		(end 52.815998 -126.125478)
		(width 0.1143)
		(layer "In2.Cu")
		(net "BMC_NODE1_DDR_MA5")
	)
	(segment
		(start 58.470546 -130.456178)
		(end 58.74385 -130.456178)
		(width 0.1016)
		(layer "In2.Cu")
		(net "BMC_NODE1_DDR_MA5")
	)
	(segment
		(start 58.258202 -130.456178)
		(end 58.470546 -130.456178)
		(width 0.1143)
		(layer "In2.Cu")
		(net "BMC_NODE1_DDR_MA5")
	)
	(segment
		(start 54.242462 -126.734316)
		(end 56.15178 -128.40335)
		(width 0.1143)
		(layer "In2.Cu")
		(net "BMC_NODE1_DDR_MA5")
	)
	(segment
		(start 56.15178 -128.40335)
		(end 56.230266 -128.471168)
		(width 0.1143)
		(layer "In2.Cu")
		(net "BMC_NODE1_DDR_MA5")
	)
	(segment
		(start 42.29862 -129.196592)
		(end 45.369734 -126.125478)
		(width 0.1143)
		(layer "In2.Cu")
		(net "BMC_NODE1_DDR_MA5")
	)
	(segment
		(start 56.230266 -128.471168)
		(end 56.579262 -128.777238)
		(width 0.1143)
		(layer "In2.Cu")
		(net "BMC_NODE1_DDR_MA5")
	)
	(segment
		(start 52.815998 -126.125478)
		(end 54.242462 -126.734316)
		(width 0.1143)
		(layer "In2.Cu")
		(net "BMC_NODE1_DDR_MA5")
	)
	(segment
		(start 176.49444 -114.738658)
		(end 176.49444 -114.734594)
		(width 0.1016)
		(layer "F.Cu")
		(net "FM_CPLD_NODE1_LPCRST_L")
	)
	(segment
		(start 97.9678 -105.6132)
		(end 97.9678 -103.3272)
		(width 0.1016)
		(layer "F.Cu")
		(net "FM_CPLD_NODE1_LPCRST_L")
	)
	(segment
		(start 99.6315 -15.004796)
		(end 99.004374 -14.37767)
		(width 0.1016)
		(layer "F.Cu")
		(net "FM_CPLD_NODE1_LPCRST_L")
	)
	(segment
		(start 87.1728 -115.2398)
		(end 87.1728 -114.2238)
		(width 0.1016)
		(layer "F.Cu")
		(net "FM_CPLD_NODE1_LPCRST_L")
	)
	(segment
		(start 99.6315 -15.214346)
		(end 99.6315 -15.004796)
		(width 0.1016)
		(layer "F.Cu")
		(net "FM_CPLD_NODE1_LPCRST_L")
	)
	(segment
		(start 177.010314 -118.365524)
		(end 176.510442 -117.865652)
		(width 0.1016)
		(layer "F.Cu")
		(net "FM_CPLD_NODE1_LPCRST_L")
	)
	(segment
		(start 176.49444 -114.734594)
		(end 173.77664 -112.016794)
		(width 0.1016)
		(layer "F.Cu")
		(net "FM_CPLD_NODE1_LPCRST_L")
	)
	(segment
		(start 176.510442 -117.865652)
		(end 176.510442 -114.75466)
		(width 0.1016)
		(layer "F.Cu")
		(net "FM_CPLD_NODE1_LPCRST_L")
	)
	(segment
		(start 93.2942 -108.1024)
		(end 95.4786 -108.1024)
		(width 0.1016)
		(layer "F.Cu")
		(net "FM_CPLD_NODE1_LPCRST_L")
	)
	(segment
		(start 95.4786 -108.1024)
		(end 97.9678 -105.6132)
		(width 0.1016)
		(layer "F.Cu")
		(net "FM_CPLD_NODE1_LPCRST_L")
	)
	(segment
		(start 87.866474 -115.933474)
		(end 87.1728 -115.2398)
		(width 0.1016)
		(layer "F.Cu")
		(net "FM_CPLD_NODE1_LPCRST_L")
	)
	(segment
		(start 96.5708 -101.9302)
		(end 96.5708 -98.425)
		(width 0.1016)
		(layer "F.Cu")
		(net "FM_CPLD_NODE1_LPCRST_L")
	)
	(segment
		(start 117.6274 -77.1398)
		(end 118.06174 -77.57414)
		(width 0.1016)
		(layer "F.Cu")
		(net "FM_CPLD_NODE1_LPCRST_L")
	)
	(segment
		(start 99.004374 -14.37767)
		(end 99.004374 -11.91768)
		(width 0.1016)
		(layer "F.Cu")
		(net "FM_CPLD_NODE1_LPCRST_L")
	)
	(segment
		(start 173.77664 -112.015778)
		(end 170.85564 -112.015778)
		(width 0.1016)
		(layer "F.Cu")
		(net "FM_CPLD_NODE1_LPCRST_L")
	)
	(segment
		(start 96.5708 -98.425)
		(end 96.901 -98.0948)
		(width 0.1016)
		(layer "F.Cu")
		(net "FM_CPLD_NODE1_LPCRST_L")
	)
	(segment
		(start 96.901 -98.0948)
		(end 96.901 -91.5162)
		(width 0.1016)
		(layer "F.Cu")
		(net "FM_CPLD_NODE1_LPCRST_L")
	)
	(segment
		(start 118.06174 -77.57414)
		(end 118.06174 -79.058262)
		(width 0.1016)
		(layer "F.Cu")
		(net "FM_CPLD_NODE1_LPCRST_L")
	)
	(segment
		(start 116.7638 -77.1398)
		(end 117.6274 -77.1398)
		(width 0.1016)
		(layer "F.Cu")
		(net "FM_CPLD_NODE1_LPCRST_L")
	)
	(segment
		(start 111.0996 -82.804)
		(end 116.7638 -77.1398)
		(width 0.1016)
		(layer "F.Cu")
		(net "FM_CPLD_NODE1_LPCRST_L")
	)
	(segment
		(start 176.510442 -114.75466)
		(end 176.49444 -114.738658)
		(width 0.1016)
		(layer "F.Cu")
		(net "FM_CPLD_NODE1_LPCRST_L")
	)
	(segment
		(start 87.866474 -116.591588)
		(end 87.866474 -115.933474)
		(width 0.1016)
		(layer "F.Cu")
		(net "FM_CPLD_NODE1_LPCRST_L")
	)
	(segment
		(start 97.9678 -103.3272)
		(end 96.5708 -101.9302)
		(width 0.1016)
		(layer "F.Cu")
		(net "FM_CPLD_NODE1_LPCRST_L")
	)
	(segment
		(start 87.1728 -114.2238)
		(end 93.2942 -108.1024)
		(width 0.1016)
		(layer "F.Cu")
		(net "FM_CPLD_NODE1_LPCRST_L")
	)
	(segment
		(start 96.901 -91.5162)
		(end 105.6132 -82.804)
		(width 0.1016)
		(layer "F.Cu")
		(net "FM_CPLD_NODE1_LPCRST_L")
	)
	(segment
		(start 105.6132 -82.804)
		(end 111.0996 -82.804)
		(width 0.1016)
		(layer "F.Cu")
		(net "FM_CPLD_NODE1_LPCRST_L")
	)
	(segment
		(start 173.77664 -112.016794)
		(end 173.77664 -112.015778)
		(width 0.1016)
		(layer "F.Cu")
		(net "FM_CPLD_NODE1_LPCRST_L")
	)
	(via
		(at 170.85564 -112.015778)
		(size 0.508)
		(drill 0.254)
		(layers "F.Cu" "B.Cu")
		(net "FM_CPLD_NODE1_LPCRST_L")
	)
	(via
		(at 99.6315 -15.214346)
		(size 0.508)
		(drill 0.254)
		(layers "F.Cu" "B.Cu")
		(net "FM_CPLD_NODE1_LPCRST_L")
	)
	(via
		(at 118.06174 -79.058262)
		(size 0.508)
		(drill 0.254)
		(layers "F.Cu" "B.Cu")
		(net "FM_CPLD_NODE1_LPCRST_L")
	)
	(segment
		(start 99.73564 -15.110206)
		(end 99.6315 -15.214346)
		(width 0.1143)
		(layer "In2.Cu")
		(net "FM_CPLD_NODE1_LPCRST_L")
	)
	(segment
		(start 118.06174 -79.058262)
		(end 119.39778 -77.722222)
		(width 0.1143)
		(layer "In2.Cu")
		(net "FM_CPLD_NODE1_LPCRST_L")
	)
	(segment
		(start 115.82908 -52.083716)
		(end 115.82908 -51.805078)
		(width 0.1143)
		(layer "In2.Cu")
		(net "FM_CPLD_NODE1_LPCRST_L")
	)
	(segment
		(start 111.707422 -21.806154)
		(end 105.011474 -15.110206)
		(width 0.1143)
		(layer "In2.Cu")
		(net "FM_CPLD_NODE1_LPCRST_L")
	)
	(segment
		(start 119.642382 -55.897018)
		(end 115.82908 -52.083716)
		(width 0.1143)
		(layer "In2.Cu")
		(net "FM_CPLD_NODE1_LPCRST_L")
	)
	(segment
		(start 114.450368 -50.477928)
		(end 111.707422 -47.734982)
		(width 0.1143)
		(layer "In2.Cu")
		(net "FM_CPLD_NODE1_LPCRST_L")
	)
	(segment
		(start 119.39778 -67.875404)
		(end 119.642382 -67.630802)
		(width 0.1143)
		(layer "In2.Cu")
		(net "FM_CPLD_NODE1_LPCRST_L")
	)
	(segment
		(start 119.642382 -67.630802)
		(end 119.642382 -55.897018)
		(width 0.1143)
		(layer "In2.Cu")
		(net "FM_CPLD_NODE1_LPCRST_L")
	)
	(segment
		(start 115.82908 -51.805078)
		(end 114.50193 -50.477928)
		(width 0.1143)
		(layer "In2.Cu")
		(net "FM_CPLD_NODE1_LPCRST_L")
	)
	(segment
		(start 114.50193 -50.477928)
		(end 114.450368 -50.477928)
		(width 0.1143)
		(layer "In2.Cu")
		(net "FM_CPLD_NODE1_LPCRST_L")
	)
	(segment
		(start 111.707422 -47.734982)
		(end 111.707422 -21.806154)
		(width 0.1143)
		(layer "In2.Cu")
		(net "FM_CPLD_NODE1_LPCRST_L")
	)
	(segment
		(start 119.39778 -77.722222)
		(end 119.39778 -67.875404)
		(width 0.1143)
		(layer "In2.Cu")
		(net "FM_CPLD_NODE1_LPCRST_L")
	)
	(segment
		(start 105.011474 -15.110206)
		(end 99.73564 -15.110206)
		(width 0.1143)
		(layer "In2.Cu")
		(net "FM_CPLD_NODE1_LPCRST_L")
	)
	(segment
		(start 150.65502 -100.496878)
		(end 143.998696 -93.840554)
		(width 0.1143)
		(layer "In7.Cu")
		(net "FM_CPLD_NODE1_LPCRST_L")
	)
	(segment
		(start 133.231128 -93.840554)
		(end 129.81432 -90.423746)
		(width 0.1143)
		(layer "In7.Cu")
		(net "FM_CPLD_NODE1_LPCRST_L")
	)
	(segment
		(start 157.33268 -107.174538)
		(end 150.948644 -100.790502)
		(width 0.1143)
		(layer "In7.Cu")
		(net "FM_CPLD_NODE1_LPCRST_L")
	)
	(segment
		(start 157.33268 -108.34751)
		(end 157.33268 -107.174538)
		(width 0.1143)
		(layer "In7.Cu")
		(net "FM_CPLD_NODE1_LPCRST_L")
	)
	(segment
		(start 167.852852 -112.015778)
		(end 165.866826 -110.029752)
		(width 0.1143)
		(layer "In7.Cu")
		(net "FM_CPLD_NODE1_LPCRST_L")
	)
	(segment
		(start 150.65502 -100.533962)
		(end 150.65502 -100.496878)
		(width 0.1143)
		(layer "In7.Cu")
		(net "FM_CPLD_NODE1_LPCRST_L")
	)
	(segment
		(start 170.85564 -112.015778)
		(end 167.852852 -112.015778)
		(width 0.1143)
		(layer "In7.Cu")
		(net "FM_CPLD_NODE1_LPCRST_L")
	)
	(segment
		(start 159.014922 -110.029752)
		(end 157.33268 -108.34751)
		(width 0.1143)
		(layer "In7.Cu")
		(net "FM_CPLD_NODE1_LPCRST_L")
	)
	(segment
		(start 150.91156 -100.790502)
		(end 150.65502 -100.533962)
		(width 0.1143)
		(layer "In7.Cu")
		(net "FM_CPLD_NODE1_LPCRST_L")
	)
	(segment
		(start 150.948644 -100.790502)
		(end 150.91156 -100.790502)
		(width 0.1143)
		(layer "In7.Cu")
		(net "FM_CPLD_NODE1_LPCRST_L")
	)
	(segment
		(start 127.0381 -90.423746)
		(end 118.06174 -81.447386)
		(width 0.1143)
		(layer "In7.Cu")
		(net "FM_CPLD_NODE1_LPCRST_L")
	)
	(segment
		(start 129.81432 -90.423746)
		(end 127.0381 -90.423746)
		(width 0.1143)
		(layer "In7.Cu")
		(net "FM_CPLD_NODE1_LPCRST_L")
	)
	(segment
		(start 118.06174 -81.447386)
		(end 118.06174 -79.058262)
		(width 0.1143)
		(layer "In7.Cu")
		(net "FM_CPLD_NODE1_LPCRST_L")
	)
	(segment
		(start 143.998696 -93.840554)
		(end 133.231128 -93.840554)
		(width 0.1143)
		(layer "In7.Cu")
		(net "FM_CPLD_NODE1_LPCRST_L")
	)
	(segment
		(start 165.866826 -110.029752)
		(end 159.014922 -110.029752)
		(width 0.1143)
		(layer "In7.Cu")
		(net "FM_CPLD_NODE1_LPCRST_L")
	)
	(segment
		(start 102.728014 -133.119114)
		(end 103.575104 -133.966204)
		(width 0.1016)
		(layer "F.Cu")
		(net "SVID_CPU_NODE1_CLK_R")
	)
	(segment
		(start 102.406704 -133.119114)
		(end 102.728014 -133.119114)
		(width 0.1016)
		(layer "F.Cu")
		(net "SVID_CPU_NODE1_CLK_R")
	)
	(segment
		(start 104.480106 -135.097774)
		(end 103.575104 -134.192772)
		(width 0.1016)
		(layer "F.Cu")
		(net "SVID_CPU_NODE1_CLK_R")
	)
	(segment
		(start 104.94645 -135.097774)
		(end 104.480106 -135.097774)
		(width 0.1016)
		(layer "F.Cu")
		(net "SVID_CPU_NODE1_CLK_R")
	)
	(segment
		(start 103.575104 -134.192772)
		(end 103.575104 -133.966204)
		(width 0.1016)
		(layer "F.Cu")
		(net "SVID_CPU_NODE1_CLK_R")
	)
	(via
		(at 103.575104 -133.966204)
		(size 0.508)
		(drill 0.254)
		(layers "F.Cu" "B.Cu")
		(net "SVID_CPU_NODE1_CLK_R")
	)
	(segment
		(start 51.655472 -134.19455)
		(end 51.78171 -134.320788)
		(width 0.1016)
		(layer "F.Cu")
		(net "BMC_NODE1_DDR_CS_L")
	)
	(segment
		(start 51.78171 -134.320788)
		(end 52.135278 -134.320788)
		(width 0.1016)
		(layer "F.Cu")
		(net "BMC_NODE1_DDR_CS_L")
	)
	(segment
		(start 58.14187 -133.659626)
		(end 57.761632 -133.279388)
		(width 0.1016)
		(layer "F.Cu")
		(net "BMC_NODE1_DDR_CS_L")
	)
	(segment
		(start 52.10937 -133.584696)
		(end 51.655472 -134.038594)
		(width 0.1016)
		(layer "F.Cu")
		(net "BMC_NODE1_DDR_CS_L")
	)
	(segment
		(start 40.83304 -132.963666)
		(end 40.833548 -132.963666)
		(width 0.1016)
		(layer "F.Cu")
		(net "BMC_NODE1_DDR_CS_L")
	)
	(segment
		(start 54.772052 -133.584696)
		(end 52.10937 -133.584696)
		(width 0.1016)
		(layer "F.Cu")
		(net "BMC_NODE1_DDR_CS_L")
	)
	(segment
		(start 55.019956 -133.336792)
		(end 54.772052 -133.584696)
		(width 0.1016)
		(layer "F.Cu")
		(net "BMC_NODE1_DDR_CS_L")
	)
	(segment
		(start 57.067704 -133.279388)
		(end 57.0103 -133.336792)
		(width 0.1016)
		(layer "F.Cu")
		(net "BMC_NODE1_DDR_CS_L")
	)
	(segment
		(start 57.761632 -133.279388)
		(end 57.067704 -133.279388)
		(width 0.1016)
		(layer "F.Cu")
		(net "BMC_NODE1_DDR_CS_L")
	)
	(segment
		(start 51.655472 -134.038594)
		(end 51.655472 -134.19455)
		(width 0.1016)
		(layer "F.Cu")
		(net "BMC_NODE1_DDR_CS_L")
	)
	(segment
		(start 57.0103 -133.336792)
		(end 55.019956 -133.336792)
		(width 0.1016)
		(layer "F.Cu")
		(net "BMC_NODE1_DDR_CS_L")
	)
	(segment
		(start 40.833548 -132.963666)
		(end 41.23309 -132.564124)
		(width 0.1016)
		(layer "F.Cu")
		(net "BMC_NODE1_DDR_CS_L")
	)
	(via
		(at 41.23309 -132.564124)
		(size 0.49022)
		(drill 0.254)
		(layers "F.Cu" "B.Cu")
		(net "BMC_NODE1_DDR_CS_L")
	)
	(via
		(at 52.135278 -134.320788)
		(size 0.508)
		(drill 0.254)
		(layers "F.Cu" "B.Cu")
		(net "BMC_NODE1_DDR_CS_L")
	)
	(segment
		(start 42.971974 -133.986524)
		(end 43.396154 -133.562344)
		(width 0.1143)
		(layer "In2.Cu")
		(net "BMC_NODE1_DDR_CS_L")
	)
	(segment
		(start 44.575222 -133.699504)
		(end 46.464728 -133.699504)
		(width 0.1143)
		(layer "In2.Cu")
		(net "BMC_NODE1_DDR_CS_L")
	)
	(segment
		(start 51.896264 -133.884162)
		(end 52.135278 -134.123176)
		(width 0.1143)
		(layer "In2.Cu")
		(net "BMC_NODE1_DDR_CS_L")
	)
	(segment
		(start 43.396154 -133.562344)
		(end 44.438062 -133.562344)
		(width 0.1143)
		(layer "In2.Cu")
		(net "BMC_NODE1_DDR_CS_L")
	)
	(segment
		(start 41.23309 -132.564124)
		(end 41.23309 -132.38734)
		(width 0.1143)
		(layer "In2.Cu")
		(net "BMC_NODE1_DDR_CS_L")
	)
	(segment
		(start 41.23309 -132.38734)
		(end 41.424098 -132.196332)
		(width 0.1143)
		(layer "In2.Cu")
		(net "BMC_NODE1_DDR_CS_L")
	)
	(segment
		(start 42.490898 -133.986524)
		(end 42.971974 -133.986524)
		(width 0.1143)
		(layer "In2.Cu")
		(net "BMC_NODE1_DDR_CS_L")
	)
	(segment
		(start 41.761156 -132.196332)
		(end 41.963848 -132.399024)
		(width 0.1143)
		(layer "In2.Cu")
		(net "BMC_NODE1_DDR_CS_L")
	)
	(segment
		(start 46.464728 -133.699504)
		(end 46.649386 -133.884162)
		(width 0.1143)
		(layer "In2.Cu")
		(net "BMC_NODE1_DDR_CS_L")
	)
	(segment
		(start 46.649386 -133.884162)
		(end 51.896264 -133.884162)
		(width 0.1143)
		(layer "In2.Cu")
		(net "BMC_NODE1_DDR_CS_L")
	)
	(segment
		(start 44.438062 -133.562344)
		(end 44.575222 -133.699504)
		(width 0.1143)
		(layer "In2.Cu")
		(net "BMC_NODE1_DDR_CS_L")
	)
	(segment
		(start 41.963848 -132.399024)
		(end 41.963848 -133.459474)
		(width 0.1143)
		(layer "In2.Cu")
		(net "BMC_NODE1_DDR_CS_L")
	)
	(segment
		(start 41.424098 -132.196332)
		(end 41.761156 -132.196332)
		(width 0.1143)
		(layer "In2.Cu")
		(net "BMC_NODE1_DDR_CS_L")
	)
	(segment
		(start 52.135278 -134.123176)
		(end 52.135278 -134.320788)
		(width 0.1143)
		(layer "In2.Cu")
		(net "BMC_NODE1_DDR_CS_L")
	)
	(segment
		(start 41.963848 -133.459474)
		(end 42.490898 -133.986524)
		(width 0.1143)
		(layer "In2.Cu")
		(net "BMC_NODE1_DDR_CS_L")
	)
	(segment
		(start 161.3662 -118.94693)
		(end 162.771328 -118.94693)
		(width 0.1016)
		(layer "F.Cu")
		(net "FM_CPU_NODE1_RSTWARN")
	)
	(segment
		(start 165.667182 -120.65127)
		(end 163.693602 -118.67769)
		(width 0.1016)
		(layer "F.Cu")
		(net "FM_CPU_NODE1_RSTWARN")
	)
	(segment
		(start 174.01032 -120.365774)
		(end 173.526196 -120.849898)
		(width 0.1016)
		(layer "F.Cu")
		(net "FM_CPU_NODE1_RSTWARN")
	)
	(segment
		(start 150.04288 -115.843304)
		(end 153.261314 -119.061738)
		(width 0.1016)
		(layer "F.Cu")
		(net "FM_CPU_NODE1_RSTWARN")
	)
	(segment
		(start 161.251392 -119.061738)
		(end 161.3662 -118.94693)
		(width 0.1016)
		(layer "F.Cu")
		(net "FM_CPU_NODE1_RSTWARN")
	)
	(segment
		(start 163.096956 -118.621302)
		(end 163.096956 -118.335552)
		(width 0.1016)
		(layer "F.Cu")
		(net "FM_CPU_NODE1_RSTWARN")
	)
	(segment
		(start 67.511168 -82.807302)
		(end 67.390772 -82.927698)
		(width 0.1016)
		(layer "F.Cu")
		(net "FM_CPU_NODE1_RSTWARN")
	)
	(segment
		(start 163.430712 -118.335552)
		(end 163.096956 -118.335552)
		(width 0.1016)
		(layer "F.Cu")
		(net "FM_CPU_NODE1_RSTWARN")
	)
	(segment
		(start 67.916044 -81.528158)
		(end 67.511168 -81.933034)
		(width 0.1016)
		(layer "F.Cu")
		(net "FM_CPU_NODE1_RSTWARN")
	)
	(segment
		(start 67.511168 -81.933034)
		(end 67.511168 -82.807302)
		(width 0.1016)
		(layer "F.Cu")
		(net "FM_CPU_NODE1_RSTWARN")
	)
	(segment
		(start 171.376594 -120.849898)
		(end 171.177966 -120.65127)
		(width 0.1016)
		(layer "F.Cu")
		(net "FM_CPU_NODE1_RSTWARN")
	)
	(segment
		(start 173.526196 -120.849898)
		(end 171.376594 -120.849898)
		(width 0.1016)
		(layer "F.Cu")
		(net "FM_CPU_NODE1_RSTWARN")
	)
	(segment
		(start 171.177966 -120.65127)
		(end 165.667182 -120.65127)
		(width 0.1016)
		(layer "F.Cu")
		(net "FM_CPU_NODE1_RSTWARN")
	)
	(segment
		(start 163.693602 -118.598442)
		(end 163.430712 -118.335552)
		(width 0.1016)
		(layer "F.Cu")
		(net "FM_CPU_NODE1_RSTWARN")
	)
	(segment
		(start 162.771328 -118.94693)
		(end 163.096956 -118.621302)
		(width 0.1016)
		(layer "F.Cu")
		(net "FM_CPU_NODE1_RSTWARN")
	)
	(segment
		(start 163.693602 -118.67769)
		(end 163.693602 -118.598442)
		(width 0.1016)
		(layer "F.Cu")
		(net "FM_CPU_NODE1_RSTWARN")
	)
	(segment
		(start 153.261314 -119.061738)
		(end 161.251392 -119.061738)
		(width 0.1016)
		(layer "F.Cu")
		(net "FM_CPU_NODE1_RSTWARN")
	)
	(via
		(at 150.04288 -115.843304)
		(size 0.508)
		(drill 0.254)
		(layers "F.Cu" "B.Cu")
		(net "FM_CPU_NODE1_RSTWARN")
	)
	(via
		(at 67.390772 -82.927698)
		(size 0.508)
		(drill 0.254)
		(layers "F.Cu" "B.Cu")
		(net "FM_CPU_NODE1_RSTWARN")
	)
	(segment
		(start 67.390772 -82.927698)
		(end 67.502278 -82.816192)
		(width 0.1143)
		(layer "In7.Cu")
		(net "FM_CPU_NODE1_RSTWARN")
	)
	(segment
		(start 143.10233 -106.398314)
		(end 150.57755 -113.873534)
		(width 0.1143)
		(layer "In7.Cu")
		(net "FM_CPU_NODE1_RSTWARN")
	)
	(segment
		(start 150.57755 -113.873534)
		(end 150.57755 -115.308634)
		(width 0.1143)
		(layer "In7.Cu")
		(net "FM_CPU_NODE1_RSTWARN")
	)
	(segment
		(start 141.627098 -106.398314)
		(end 143.10233 -106.398314)
		(width 0.1143)
		(layer "In7.Cu")
		(net "FM_CPU_NODE1_RSTWARN")
	)
	(segment
		(start 67.502278 -82.718656)
		(end 69.184266 -81.036668)
		(width 0.1143)
		(layer "In7.Cu")
		(net "FM_CPU_NODE1_RSTWARN")
	)
	(segment
		(start 138.100054 -102.87127)
		(end 141.627098 -106.398314)
		(width 0.1143)
		(layer "In7.Cu")
		(net "FM_CPU_NODE1_RSTWARN")
	)
	(segment
		(start 109.231176 -86.29777)
		(end 125.804676 -102.87127)
		(width 0.1143)
		(layer "In7.Cu")
		(net "FM_CPU_NODE1_RSTWARN")
	)
	(segment
		(start 150.57755 -115.308634)
		(end 150.04288 -115.843304)
		(width 0.1143)
		(layer "In7.Cu")
		(net "FM_CPU_NODE1_RSTWARN")
	)
	(segment
		(start 67.502278 -82.816192)
		(end 67.502278 -82.718656)
		(width 0.1143)
		(layer "In7.Cu")
		(net "FM_CPU_NODE1_RSTWARN")
	)
	(segment
		(start 102.363524 -86.29777)
		(end 109.231176 -86.29777)
		(width 0.1143)
		(layer "In7.Cu")
		(net "FM_CPU_NODE1_RSTWARN")
	)
	(segment
		(start 99.504754 -83.439)
		(end 102.363524 -86.29777)
		(width 0.1143)
		(layer "In7.Cu")
		(net "FM_CPU_NODE1_RSTWARN")
	)
	(segment
		(start 125.804676 -102.87127)
		(end 138.100054 -102.87127)
		(width 0.1143)
		(layer "In7.Cu")
		(net "FM_CPU_NODE1_RSTWARN")
	)
	(segment
		(start 96.906842 -83.439)
		(end 99.504754 -83.439)
		(width 0.1143)
		(layer "In7.Cu")
		(net "FM_CPU_NODE1_RSTWARN")
	)
	(segment
		(start 94.50451 -81.036668)
		(end 96.906842 -83.439)
		(width 0.1143)
		(layer "In7.Cu")
		(net "FM_CPU_NODE1_RSTWARN")
	)
	(segment
		(start 69.184266 -81.036668)
		(end 94.50451 -81.036668)
		(width 0.1143)
		(layer "In7.Cu")
		(net "FM_CPU_NODE1_RSTWARN")
	)
	(segment
		(start 112.529112 -139.52982)
		(end 112.461802 -139.59713)
		(width 0.254)
		(layer "F.Cu")
		(net "VR_PVCCP_NODE1_EN")
	)
	(segment
		(start 106.071416 -132.372862)
		(end 106.071416 -131.699762)
		(width 0.1778)
		(layer "F.Cu")
		(net "VR_PVCCP_NODE1_EN")
	)
	(segment
		(start 112.529112 -138.754358)
		(end 112.529112 -139.52982)
		(width 0.254)
		(layer "F.Cu")
		(net "VR_PVCCP_NODE1_EN")
	)
	(segment
		(start 106.071416 -131.699762)
		(end 105.864406 -131.492752)
		(width 0.1778)
		(layer "F.Cu")
		(net "VR_PVCCP_NODE1_EN")
	)
	(via
		(at 103.59771 -131.223258)
		(size 0.508)
		(drill 0.254)
		(layers "F.Cu" "B.Cu")
		(net "VR_PVCCP_NODE1_EN")
	)
	(via
		(at 112.461802 -139.59713)
		(size 0.508)
		(drill 0.254)
		(layers "F.Cu" "B.Cu")
		(net "VR_PVCCP_NODE1_EN")
	)
	(via
		(at 104.505506 -131.306824)
		(size 0.508)
		(drill 0.254)
		(layers "F.Cu" "B.Cu")
		(net "VR_PVCCP_NODE1_EN")
	)
	(segment
		(start 105.64622 -132.554726)
		(end 105.64622 -131.675886)
		(width 0.254)
		(layer "In2.Cu")
		(net "VR_PVCCP_NODE1_EN")
	)
	(segment
		(start 113.249964 -140.385292)
		(end 113.249964 -141.917674)
		(width 0.254)
		(layer "In2.Cu")
		(net "VR_PVCCP_NODE1_EN")
	)
	(segment
		(start 112.74425 -142.423388)
		(end 104.338882 -142.423388)
		(width 0.254)
		(layer "In2.Cu")
		(net "VR_PVCCP_NODE1_EN")
	)
	(segment
		(start 105.64622 -131.675886)
		(end 105.277158 -131.306824)
		(width 0.254)
		(layer "In2.Cu")
		(net "VR_PVCCP_NODE1_EN")
	)
	(segment
		(start 104.393746 -137.949686)
		(end 105.032048 -137.311384)
		(width 0.254)
		(layer "In2.Cu")
		(net "VR_PVCCP_NODE1_EN")
	)
	(segment
		(start 112.461802 -139.59713)
		(end 113.249964 -140.385292)
		(width 0.254)
		(layer "In2.Cu")
		(net "VR_PVCCP_NODE1_EN")
	)
	(segment
		(start 105.032048 -133.168898)
		(end 105.64622 -132.554726)
		(width 0.254)
		(layer "In2.Cu")
		(net "VR_PVCCP_NODE1_EN")
	)
	(segment
		(start 105.277158 -131.306824)
		(end 104.505506 -131.306824)
		(width 0.254)
		(layer "In2.Cu")
		(net "VR_PVCCP_NODE1_EN")
	)
	(segment
		(start 104.74833 -140.279882)
		(end 104.74833 -139.388596)
		(width 0.254)
		(layer "In2.Cu")
		(net "VR_PVCCP_NODE1_EN")
	)
	(segment
		(start 103.965756 -142.050262)
		(end 103.965756 -141.062456)
		(width 0.254)
		(layer "In2.Cu")
		(net "VR_PVCCP_NODE1_EN")
	)
	(segment
		(start 104.338882 -142.423388)
		(end 103.965756 -142.050262)
		(width 0.254)
		(layer "In2.Cu")
		(net "VR_PVCCP_NODE1_EN")
	)
	(segment
		(start 113.249964 -141.917674)
		(end 112.74425 -142.423388)
		(width 0.254)
		(layer "In2.Cu")
		(net "VR_PVCCP_NODE1_EN")
	)
	(segment
		(start 105.032048 -137.311384)
		(end 105.032048 -133.168898)
		(width 0.254)
		(layer "In2.Cu")
		(net "VR_PVCCP_NODE1_EN")
	)
	(segment
		(start 104.393746 -139.034012)
		(end 104.393746 -137.949686)
		(width 0.254)
		(layer "In2.Cu")
		(net "VR_PVCCP_NODE1_EN")
	)
	(segment
		(start 104.74833 -139.388596)
		(end 104.393746 -139.034012)
		(width 0.254)
		(layer "In2.Cu")
		(net "VR_PVCCP_NODE1_EN")
	)
	(segment
		(start 103.965756 -141.062456)
		(end 104.74833 -140.279882)
		(width 0.254)
		(layer "In2.Cu")
		(net "VR_PVCCP_NODE1_EN")
	)
	(segment
		(start 96.369886 -165.139624)
		(end 96.390968 -165.160706)
		(width 0.1016)
		(layer "F.Cu")
		(net "FAN5_TACH_IN")
	)
	(segment
		(start 94.851982 -165.139624)
		(end 96.369886 -165.139624)
		(width 0.1016)
		(layer "F.Cu")
		(net "FAN5_TACH_IN")
	)
	(segment
		(start 97.728532 -165.160706)
		(end 96.390968 -165.160706)
		(width 0.1016)
		(layer "F.Cu")
		(net "FAN5_TACH_IN")
	)
	(via
		(at 96.390968 -165.160706)
		(size 0.508)
		(drill 0.254)
		(layers "F.Cu" "B.Cu")
		(net "FAN5_TACH_IN")
	)
	(segment
		(start 40.033194 -132.963666)
		(end 39.384732 -132.963666)
		(width 0.1016)
		(layer "F.Cu")
		(net "TP_BMC_NODE1_DDR3_CS1_L")
	)
	(segment
		(start 39.384732 -132.963666)
		(end 39.148004 -133.200394)
		(width 0.1016)
		(layer "F.Cu")
		(net "TP_BMC_NODE1_DDR3_CS1_L")
	)
	(via
		(at 39.148004 -133.200394)
		(size 0.508)
		(drill 0.254)
		(layers "F.Cu" "B.Cu")
		(net "TP_BMC_NODE1_DDR3_CS1_L")
	)
	(segment
		(start 43.796204 -73.104502)
		(end 43.796204 -73.045574)
		(width 0.1143)
		(layer "F.Cu")
		(net "PD_CPU_NODE1_AN5")
	)
	(segment
		(start 44.89196 -72.439022)
		(end 45.41774 -72.964802)
		(width 0.1143)
		(layer "F.Cu")
		(net "PD_CPU_NODE1_AN5")
	)
	(segment
		(start 43.796204 -73.045574)
		(end 44.402756 -72.439022)
		(width 0.1143)
		(layer "F.Cu")
		(net "PD_CPU_NODE1_AN5")
	)
	(segment
		(start 44.402756 -72.439022)
		(end 44.89196 -72.439022)
		(width 0.1143)
		(layer "F.Cu")
		(net "PD_CPU_NODE1_AN5")
	)
	(via
		(at 45.41774 -72.964802)
		(size 0.508)
		(drill 0.254)
		(layers "F.Cu" "B.Cu")
		(net "PD_CPU_NODE1_AN5")
	)
	(segment
		(start 42.951908 -72.478138)
		(end 44.931076 -72.478138)
		(width 0.1016)
		(layer "B.Cu")
		(net "PD_CPU_NODE1_AN5")
	)
	(segment
		(start 44.931076 -72.478138)
		(end 45.41774 -72.964802)
		(width 0.1016)
		(layer "B.Cu")
		(net "PD_CPU_NODE1_AN5")
	)
	(segment
		(start 179.010564 -119.365522)
		(end 179.010564 -119.36603)
		(width 0.1016)
		(layer "F.Cu")
		(net "PWRGD_NODE1_P1V538_BMC_PG")
	)
	(segment
		(start 27.932888 -130.189732)
		(end 29.050488 -130.189732)
		(width 0.1016)
		(layer "F.Cu")
		(net "PWRGD_NODE1_P1V538_BMC_PG")
	)
	(segment
		(start 29.641292 -128.354582)
		(end 29.641292 -128.74879)
		(width 0.1016)
		(layer "F.Cu")
		(net "PWRGD_NODE1_P1V538_BMC_PG")
	)
	(segment
		(start 29.641292 -128.74879)
		(end 29.050488 -129.339594)
		(width 0.1016)
		(layer "F.Cu")
		(net "PWRGD_NODE1_P1V538_BMC_PG")
	)
	(segment
		(start 179.010564 -119.36603)
		(end 179.510436 -119.865902)
		(width 0.1016)
		(layer "F.Cu")
		(net "PWRGD_NODE1_P1V538_BMC_PG")
	)
	(segment
		(start 29.050488 -129.339594)
		(end 29.050488 -130.189732)
		(width 0.1016)
		(layer "F.Cu")
		(net "PWRGD_NODE1_P1V538_BMC_PG")
	)
	(segment
		(start 27.932888 -129.367534)
		(end 27.932888 -130.189732)
		(width 0.1016)
		(layer "F.Cu")
		(net "PWRGD_NODE1_P1V538_BMC_PG")
	)
	(via
		(at 179.510436 -119.865902)
		(size 0.49022)
		(drill 0.254)
		(layers "F.Cu" "B.Cu")
		(net "PWRGD_NODE1_P1V538_BMC_PG")
	)
	(via
		(at 27.932888 -129.367534)
		(size 0.508)
		(drill 0.254)
		(layers "F.Cu" "B.Cu")
		(net "PWRGD_NODE1_P1V538_BMC_PG")
	)
	(via
		(at 165.56736 -116.843048)
		(size 0.508)
		(drill 0.254)
		(layers "F.Cu" "B.Cu")
		(net "PWRGD_NODE1_P1V538_BMC_PG")
	)
	(segment
		(start 153.483056 -117.206268)
		(end 148.453348 -122.235976)
		(width 0.1143)
		(layer "In6.Cu")
		(net "PWRGD_NODE1_P1V538_BMC_PG")
	)
	(segment
		(start 138.423396 -122.235976)
		(end 138.09218 -122.567192)
		(width 0.1143)
		(layer "In6.Cu")
		(net "PWRGD_NODE1_P1V538_BMC_PG")
	)
	(segment
		(start 120.480836 -112.810036)
		(end 119.162068 -111.491268)
		(width 0.1143)
		(layer "In6.Cu")
		(net "PWRGD_NODE1_P1V538_BMC_PG")
	)
	(segment
		(start 50.672492 -116.067332)
		(end 47.143416 -119.596408)
		(width 0.1143)
		(layer "In6.Cu")
		(net "PWRGD_NODE1_P1V538_BMC_PG")
	)
	(segment
		(start 148.453348 -122.235976)
		(end 138.423396 -122.235976)
		(width 0.1143)
		(layer "In6.Cu")
		(net "PWRGD_NODE1_P1V538_BMC_PG")
	)
	(segment
		(start 119.162068 -111.491268)
		(end 102.027482 -111.491268)
		(width 0.1143)
		(layer "In6.Cu")
		(net "PWRGD_NODE1_P1V538_BMC_PG")
	)
	(segment
		(start 27.54884 -122.20575)
		(end 27.54884 -122.970544)
		(width 0.1143)
		(layer "In6.Cu")
		(net "PWRGD_NODE1_P1V538_BMC_PG")
	)
	(segment
		(start 127.8255 -120.982486)
		(end 127.8255 -119.687594)
		(width 0.1143)
		(layer "In6.Cu")
		(net "PWRGD_NODE1_P1V538_BMC_PG")
	)
	(segment
		(start 165.56736 -116.843048)
		(end 165.559232 -116.851176)
		(width 0.1143)
		(layer "In6.Cu")
		(net "PWRGD_NODE1_P1V538_BMC_PG")
	)
	(segment
		(start 36.31692 -121.345452)
		(end 35.971226 -120.999758)
		(width 0.1143)
		(layer "In6.Cu")
		(net "PWRGD_NODE1_P1V538_BMC_PG")
	)
	(segment
		(start 93.06052 -118.674642)
		(end 92.797884 -118.937278)
		(width 0.1143)
		(layer "In6.Cu")
		(net "PWRGD_NODE1_P1V538_BMC_PG")
	)
	(segment
		(start 96.31426 -117.20449)
		(end 96.31426 -117.458744)
		(width 0.1143)
		(layer "In6.Cu")
		(net "PWRGD_NODE1_P1V538_BMC_PG")
	)
	(segment
		(start 133.805676 -123.379992)
		(end 130.223006 -123.379992)
		(width 0.1143)
		(layer "In6.Cu")
		(net "PWRGD_NODE1_P1V538_BMC_PG")
	)
	(segment
		(start 27.000454 -123.51893)
		(end 27.000454 -127.97917)
		(width 0.1143)
		(layer "In6.Cu")
		(net "PWRGD_NODE1_P1V538_BMC_PG")
	)
	(segment
		(start 95.098362 -118.674642)
		(end 93.06052 -118.674642)
		(width 0.1143)
		(layer "In6.Cu")
		(net "PWRGD_NODE1_P1V538_BMC_PG")
	)
	(segment
		(start 92.797884 -118.937278)
		(end 85.766656 -118.937278)
		(width 0.1143)
		(layer "In6.Cu")
		(net "PWRGD_NODE1_P1V538_BMC_PG")
	)
	(segment
		(start 27.54884 -122.970544)
		(end 27.000454 -123.51893)
		(width 0.1143)
		(layer "In6.Cu")
		(net "PWRGD_NODE1_P1V538_BMC_PG")
	)
	(segment
		(start 40.232076 -121.345452)
		(end 36.31692 -121.345452)
		(width 0.1143)
		(layer "In6.Cu")
		(net "PWRGD_NODE1_P1V538_BMC_PG")
	)
	(segment
		(start 154.879548 -117.438932)
		(end 154.646884 -117.206268)
		(width 0.1143)
		(layer "In6.Cu")
		(net "PWRGD_NODE1_P1V538_BMC_PG")
	)
	(segment
		(start 35.971226 -120.999758)
		(end 28.754832 -120.999758)
		(width 0.1143)
		(layer "In6.Cu")
		(net "PWRGD_NODE1_P1V538_BMC_PG")
	)
	(segment
		(start 27.932888 -128.911604)
		(end 27.932888 -129.367534)
		(width 0.1143)
		(layer "In6.Cu")
		(net "PWRGD_NODE1_P1V538_BMC_PG")
	)
	(segment
		(start 80.899508 -116.067332)
		(end 50.672492 -116.067332)
		(width 0.1143)
		(layer "In6.Cu")
		(net "PWRGD_NODE1_P1V538_BMC_PG")
	)
	(segment
		(start 154.646884 -117.206268)
		(end 153.483056 -117.206268)
		(width 0.1143)
		(layer "In6.Cu")
		(net "PWRGD_NODE1_P1V538_BMC_PG")
	)
	(segment
		(start 134.618476 -122.567192)
		(end 133.805676 -123.379992)
		(width 0.1143)
		(layer "In6.Cu")
		(net "PWRGD_NODE1_P1V538_BMC_PG")
	)
	(segment
		(start 83.429348 -116.59997)
		(end 81.432146 -116.59997)
		(width 0.1143)
		(layer "In6.Cu")
		(net "PWRGD_NODE1_P1V538_BMC_PG")
	)
	(segment
		(start 120.947942 -112.810036)
		(end 120.480836 -112.810036)
		(width 0.1143)
		(layer "In6.Cu")
		(net "PWRGD_NODE1_P1V538_BMC_PG")
	)
	(segment
		(start 28.754832 -120.999758)
		(end 27.54884 -122.20575)
		(width 0.1143)
		(layer "In6.Cu")
		(net "PWRGD_NODE1_P1V538_BMC_PG")
	)
	(segment
		(start 127.8255 -119.687594)
		(end 120.947942 -112.810036)
		(width 0.1143)
		(layer "In6.Cu")
		(net "PWRGD_NODE1_P1V538_BMC_PG")
	)
	(segment
		(start 102.027482 -111.491268)
		(end 96.31426 -117.20449)
		(width 0.1143)
		(layer "In6.Cu")
		(net "PWRGD_NODE1_P1V538_BMC_PG")
	)
	(segment
		(start 130.223006 -123.379992)
		(end 127.8255 -120.982486)
		(width 0.1143)
		(layer "In6.Cu")
		(net "PWRGD_NODE1_P1V538_BMC_PG")
	)
	(segment
		(start 165.559232 -116.851176)
		(end 158.017718 -116.851176)
		(width 0.1143)
		(layer "In6.Cu")
		(net "PWRGD_NODE1_P1V538_BMC_PG")
	)
	(segment
		(start 27.000454 -127.97917)
		(end 27.932888 -128.911604)
		(width 0.1143)
		(layer "In6.Cu")
		(net "PWRGD_NODE1_P1V538_BMC_PG")
	)
	(segment
		(start 157.429962 -117.438932)
		(end 154.879548 -117.438932)
		(width 0.1143)
		(layer "In6.Cu")
		(net "PWRGD_NODE1_P1V538_BMC_PG")
	)
	(segment
		(start 44.346368 -120.65508)
		(end 40.922448 -120.65508)
		(width 0.1143)
		(layer "In6.Cu")
		(net "PWRGD_NODE1_P1V538_BMC_PG")
	)
	(segment
		(start 96.31426 -117.458744)
		(end 95.098362 -118.674642)
		(width 0.1143)
		(layer "In6.Cu")
		(net "PWRGD_NODE1_P1V538_BMC_PG")
	)
	(segment
		(start 45.40504 -119.596408)
		(end 44.346368 -120.65508)
		(width 0.1143)
		(layer "In6.Cu")
		(net "PWRGD_NODE1_P1V538_BMC_PG")
	)
	(segment
		(start 40.922448 -120.65508)
		(end 40.232076 -121.345452)
		(width 0.1143)
		(layer "In6.Cu")
		(net "PWRGD_NODE1_P1V538_BMC_PG")
	)
	(segment
		(start 47.143416 -119.596408)
		(end 45.40504 -119.596408)
		(width 0.1143)
		(layer "In6.Cu")
		(net "PWRGD_NODE1_P1V538_BMC_PG")
	)
	(segment
		(start 85.766656 -118.937278)
		(end 83.429348 -116.59997)
		(width 0.1143)
		(layer "In6.Cu")
		(net "PWRGD_NODE1_P1V538_BMC_PG")
	)
	(segment
		(start 81.432146 -116.59997)
		(end 80.899508 -116.067332)
		(width 0.1143)
		(layer "In6.Cu")
		(net "PWRGD_NODE1_P1V538_BMC_PG")
	)
	(segment
		(start 158.017718 -116.851176)
		(end 157.429962 -117.438932)
		(width 0.1143)
		(layer "In6.Cu")
		(net "PWRGD_NODE1_P1V538_BMC_PG")
	)
	(segment
		(start 138.09218 -122.567192)
		(end 134.618476 -122.567192)
		(width 0.1143)
		(layer "In6.Cu")
		(net "PWRGD_NODE1_P1V538_BMC_PG")
	)
	(segment
		(start 176.036224 -117.045232)
		(end 177.35804 -118.367048)
		(width 0.1143)
		(layer "In7.Cu")
		(net "PWRGD_NODE1_P1V538_BMC_PG")
	)
	(segment
		(start 177.35804 -118.367048)
		(end 178.61915 -118.367048)
		(width 0.1143)
		(layer "In7.Cu")
		(net "PWRGD_NODE1_P1V538_BMC_PG")
	)
	(segment
		(start 165.56736 -116.843048)
		(end 165.73119 -117.006878)
		(width 0.1143)
		(layer "In7.Cu")
		(net "PWRGD_NODE1_P1V538_BMC_PG")
	)
	(segment
		(start 172.45838 -117.006878)
		(end 172.496734 -117.045232)
		(width 0.1143)
		(layer "In7.Cu")
		(net "PWRGD_NODE1_P1V538_BMC_PG")
	)
	(segment
		(start 178.61915 -118.367048)
		(end 179.510436 -119.258334)
		(width 0.1143)
		(layer "In7.Cu")
		(net "PWRGD_NODE1_P1V538_BMC_PG")
	)
	(segment
		(start 165.73119 -117.006878)
		(end 172.45838 -117.006878)
		(width 0.1143)
		(layer "In7.Cu")
		(net "PWRGD_NODE1_P1V538_BMC_PG")
	)
	(segment
		(start 172.496734 -117.045232)
		(end 176.036224 -117.045232)
		(width 0.1143)
		(layer "In7.Cu")
		(net "PWRGD_NODE1_P1V538_BMC_PG")
	)
	(segment
		(start 179.510436 -119.258334)
		(end 179.510436 -119.865902)
		(width 0.1143)
		(layer "In7.Cu")
		(net "PWRGD_NODE1_P1V538_BMC_PG")
	)
	(segment
		(start 44.833032 -135.363712)
		(end 44.838874 -135.363712)
		(width 0.1016)
		(layer "F.Cu")
		(net "BMC_NODE1_DDR_D0")
	)
	(segment
		(start 44.838874 -135.363712)
		(end 45.235876 -134.96671)
		(width 0.1016)
		(layer "F.Cu")
		(net "BMC_NODE1_DDR_D0")
	)
	(segment
		(start 59.741816 -134.459472)
		(end 59.741816 -134.458964)
		(width 0.1016)
		(layer "F.Cu")
		(net "BMC_NODE1_DDR_D0")
	)
	(segment
		(start 59.741816 -134.458964)
		(end 59.341004 -134.058152)
		(width 0.1016)
		(layer "F.Cu")
		(net "BMC_NODE1_DDR_D0")
	)
	(via
		(at 45.235876 -134.96671)
		(size 0.49022)
		(drill 0.254)
		(layers "F.Cu" "B.Cu")
		(net "BMC_NODE1_DDR_D0")
	)
	(via
		(at 59.341004 -134.058152)
		(size 0.49022)
		(drill 0.254)
		(layers "F.Cu" "B.Cu")
		(net "BMC_NODE1_DDR_D0")
	)
	(segment
		(start 50.678588 -130.782568)
		(end 51.869086 -131.973066)
		(width 0.1143)
		(layer "In7.Cu")
		(net "BMC_NODE1_DDR_D0")
	)
	(segment
		(start 58.923428 -134.475728)
		(end 59.341004 -134.058152)
		(width 0.1143)
		(layer "In7.Cu")
		(net "BMC_NODE1_DDR_D0")
	)
	(segment
		(start 48.64608 -130.782568)
		(end 50.678588 -130.782568)
		(width 0.1143)
		(layer "In7.Cu")
		(net "BMC_NODE1_DDR_D0")
	)
	(segment
		(start 45.235876 -134.96671)
		(end 45.847254 -134.96671)
		(width 0.1143)
		(layer "In7.Cu")
		(net "BMC_NODE1_DDR_D0")
	)
	(segment
		(start 51.869086 -131.973066)
		(end 51.869086 -132.601462)
		(width 0.1143)
		(layer "In7.Cu")
		(net "BMC_NODE1_DDR_D0")
	)
	(segment
		(start 52.005992 -134.878572)
		(end 55.916576 -134.878572)
		(width 0.1143)
		(layer "In7.Cu")
		(net "BMC_NODE1_DDR_D0")
	)
	(segment
		(start 55.916576 -134.878572)
		(end 56.31942 -134.475728)
		(width 0.1143)
		(layer "In7.Cu")
		(net "BMC_NODE1_DDR_D0")
	)
	(segment
		(start 56.31942 -134.475728)
		(end 58.923428 -134.475728)
		(width 0.1143)
		(layer "In7.Cu")
		(net "BMC_NODE1_DDR_D0")
	)
	(segment
		(start 51.869086 -132.601462)
		(end 51.689254 -132.781294)
		(width 0.1143)
		(layer "In7.Cu")
		(net "BMC_NODE1_DDR_D0")
	)
	(segment
		(start 46.536864 -134.2771)
		(end 46.536864 -133.224778)
		(width 0.1143)
		(layer "In7.Cu")
		(net "BMC_NODE1_DDR_D0")
	)
	(segment
		(start 51.689254 -134.561834)
		(end 52.005992 -134.878572)
		(width 0.1143)
		(layer "In7.Cu")
		(net "BMC_NODE1_DDR_D0")
	)
	(segment
		(start 45.847254 -134.96671)
		(end 46.536864 -134.2771)
		(width 0.1143)
		(layer "In7.Cu")
		(net "BMC_NODE1_DDR_D0")
	)
	(segment
		(start 46.536864 -133.224778)
		(end 47.944786 -131.816856)
		(width 0.1143)
		(layer "In7.Cu")
		(net "BMC_NODE1_DDR_D0")
	)
	(segment
		(start 47.944786 -131.483862)
		(end 48.64608 -130.782568)
		(width 0.1143)
		(layer "In7.Cu")
		(net "BMC_NODE1_DDR_D0")
	)
	(segment
		(start 47.944786 -131.816856)
		(end 47.944786 -131.483862)
		(width 0.1143)
		(layer "In7.Cu")
		(net "BMC_NODE1_DDR_D0")
	)
	(segment
		(start 51.689254 -132.781294)
		(end 51.689254 -134.561834)
		(width 0.1143)
		(layer "In7.Cu")
		(net "BMC_NODE1_DDR_D0")
	)
	(segment
		(start 82.278474 -150.876508)
		(end 82.029046 -151.125936)
		(width 0.254)
		(layer "F.Cu")
		(net "P5V_STB_NODE1")
	)
	(segment
		(start 165.601904 -78.753462)
		(end 165.935152 -79.08671)
		(width 0.508)
		(layer "F.Cu")
		(net "P5V_STB_NODE1")
	)
	(segment
		(start 108.071412 -137.42289)
		(end 108.071412 -138.546332)
		(width 0.1778)
		(layer "F.Cu")
		(net "P5V_STB_NODE1")
	)
	(segment
		(start 96.338644 -132.285232)
		(end 96.719644 -131.904232)
		(width 0.254)
		(layer "F.Cu")
		(net "P5V_STB_NODE1")
	)
	(segment
		(start 38.39083 -118.512336)
		(end 38.39083 -119.241824)
		(width 0.508)
		(layer "F.Cu")
		(net "P5V_STB_NODE1")
	)
	(segment
		(start 106.471466 -138.214608)
		(end 106.166666 -138.519408)
		(width 0.1778)
		(layer "F.Cu")
		(net "P5V_STB_NODE1")
	)
	(segment
		(start 164.73297 -78.363318)
		(end 165.21176 -78.363318)
		(width 0.254)
		(layer "F.Cu")
		(net "P5V_STB_NODE1")
	)
	(segment
		(start 82.278474 -149.792182)
		(end 82.278474 -150.876508)
		(width 0.254)
		(layer "F.Cu")
		(net "P5V_STB_NODE1")
	)
	(segment
		(start 81.767934 -152.684734)
		(end 81.609438 -152.526238)
		(width 0.254)
		(layer "F.Cu")
		(net "P5V_STB_NODE1")
	)
	(segment
		(start 165.21176 -78.363318)
		(end 165.601904 -78.753462)
		(width 0.254)
		(layer "F.Cu")
		(net "P5V_STB_NODE1")
	)
	(segment
		(start 165.935152 -79.08671)
		(end 166.400988 -79.08671)
		(width 0.508)
		(layer "F.Cu")
		(net "P5V_STB_NODE1")
	)
	(segment
		(start 82.029046 -151.125936)
		(end 82.029046 -151.688292)
		(width 0.254)
		(layer "F.Cu")
		(net "P5V_STB_NODE1")
	)
	(segment
		(start 96.719644 -131.558538)
		(end 96.719644 -131.904232)
		(width 0.254)
		(layer "F.Cu")
		(net "P5V_STB_NODE1")
	)
	(segment
		(start 7.689596 -9.579356)
		(end 8.553958 -9.579356)
		(width 0.508)
		(layer "F.Cu")
		(net "P5V_STB_NODE1")
	)
	(segment
		(start 81.609438 -152.526238)
		(end 79.96682 -152.526238)
		(width 0.254)
		(layer "F.Cu")
		(net "P5V_STB_NODE1")
	)
	(segment
		(start 166.400988 -80.02778)
		(end 166.400988 -79.08671)
		(width 0.508)
		(layer "F.Cu")
		(net "P5V_STB_NODE1")
	)
	(segment
		(start 79.57312 -152.919938)
		(end 79.57312 -153.265378)
		(width 0.254)
		(layer "F.Cu")
		(net "P5V_STB_NODE1")
	)
	(segment
		(start 96.338644 -133.138164)
		(end 96.338644 -132.285232)
		(width 0.254)
		(layer "F.Cu")
		(net "P5V_STB_NODE1")
	)
	(segment
		(start 82.029046 -152.684734)
		(end 82.029046 -151.688292)
		(width 0.254)
		(layer "F.Cu")
		(net "P5V_STB_NODE1")
	)
	(segment
		(start 10.09396 -9.577832)
		(end 8.555482 -9.577832)
		(width 0.508)
		(layer "F.Cu")
		(net "P5V_STB_NODE1")
	)
	(segment
		(start 67.285616 -99.281234)
		(end 68.025518 -99.281234)
		(width 0.508)
		(layer "F.Cu")
		(net "P5V_STB_NODE1")
	)
	(segment
		(start 79.96682 -152.526238)
		(end 79.57312 -152.919938)
		(width 0.254)
		(layer "F.Cu")
		(net "P5V_STB_NODE1")
	)
	(segment
		(start 68.025518 -99.281234)
		(end 68.070222 -99.23653)
		(width 0.508)
		(layer "F.Cu")
		(net "P5V_STB_NODE1")
	)
	(segment
		(start 108.071412 -138.546332)
		(end 108.221272 -138.696192)
		(width 0.1778)
		(layer "F.Cu")
		(net "P5V_STB_NODE1")
	)
	(segment
		(start 8.555482 -9.577832)
		(end 8.553958 -9.579356)
		(width 0.508)
		(layer "F.Cu")
		(net "P5V_STB_NODE1")
	)
	(segment
		(start 64.853058 -112.672368)
		(end 64.17818 -112.672368)
		(width 0.508)
		(layer "F.Cu")
		(net "P5V_STB_NODE1")
	)
	(segment
		(start 106.471466 -137.42289)
		(end 106.471466 -138.214608)
		(width 0.1778)
		(layer "F.Cu")
		(net "P5V_STB_NODE1")
	)
	(segment
		(start 82.029046 -152.684734)
		(end 81.767934 -152.684734)
		(width 0.254)
		(layer "F.Cu")
		(net "P5V_STB_NODE1")
	)
	(via
		(at 14.94282 -126.47676)
		(size 0.508)
		(drill 0.254)
		(layers "F.Cu" "B.Cu")
		(net "P5V_STB_NODE1")
	)
	(via
		(at 7.689596 -9.579356)
		(size 0.508)
		(drill 0.254)
		(layers "F.Cu" "B.Cu")
		(net "P5V_STB_NODE1")
	)
	(via
		(at 66.539618 -156.880052)
		(size 0.508)
		(drill 0.254)
		(layers "F.Cu" "B.Cu")
		(net "P5V_STB_NODE1")
	)
	(via
		(at 106.33964 -137.520934)
		(size 0.6604)
		(drill 0.3302)
		(layers "F.Cu" "B.Cu")
		(net "P5V_STB_NODE1")
	)
	(via
		(at 103.347774 -150.195788)
		(size 0.508)
		(drill 0.254)
		(layers "F.Cu" "B.Cu")
		(net "P5V_STB_NODE1")
	)
	(via
		(at 66.539618 -154.594052)
		(size 0.508)
		(drill 0.254)
		(layers "F.Cu" "B.Cu")
		(net "P5V_STB_NODE1")
	)
	(via
		(at 97.438718 -131.536948)
		(size 0.508)
		(drill 0.254)
		(layers "F.Cu" "B.Cu")
		(net "P5V_STB_NODE1")
	)
	(via
		(at 104.937052 -128.222502)
		(size 0.508)
		(drill 0.254)
		(layers "F.Cu" "B.Cu")
		(net "P5V_STB_NODE1")
	)
	(via
		(at 88.0364 -9.794494)
		(size 0.508)
		(drill 0.254)
		(layers "F.Cu" "B.Cu")
		(net "P5V_STB_NODE1")
	)
	(via
		(at 27.49169 -101.858318)
		(size 0.508)
		(drill 0.254)
		(layers "F.Cu" "B.Cu")
		(net "P5V_STB_NODE1")
	)
	(via
		(at 64.17818 -112.672368)
		(size 0.508)
		(drill 0.254)
		(layers "F.Cu" "B.Cu")
		(net "P5V_STB_NODE1")
	)
	(via
		(at 104.670352 -132.517134)
		(size 0.508)
		(drill 0.254)
		(layers "F.Cu" "B.Cu")
		(net "P5V_STB_NODE1")
	)
	(via
		(at 69.09054 -10.300462)
		(size 0.508)
		(drill 0.254)
		(layers "F.Cu" "B.Cu")
		(net "P5V_STB_NODE1")
	)
	(via
		(at 190.60922 -79.83982)
		(size 0.508)
		(drill 0.254)
		(layers "F.Cu" "B.Cu")
		(net "P5V_STB_NODE1")
	)
	(via
		(at 38.39083 -119.241824)
		(size 0.508)
		(drill 0.254)
		(layers "F.Cu" "B.Cu")
		(net "P5V_STB_NODE1")
	)
	(via
		(at 40.045386 -12.164314)
		(size 0.508)
		(drill 0.254)
		(layers "F.Cu" "B.Cu")
		(net "P5V_STB_NODE1")
	)
	(via
		(at 68.434712 -158.233364)
		(size 0.508)
		(drill 0.254)
		(layers "F.Cu" "B.Cu")
		(net "P5V_STB_NODE1")
	)
	(via
		(at 69.72554 -10.300462)
		(size 0.508)
		(drill 0.254)
		(layers "F.Cu" "B.Cu")
		(net "P5V_STB_NODE1")
	)
	(via
		(at 69.580252 -160.803336)
		(size 0.508)
		(drill 0.254)
		(layers "F.Cu" "B.Cu")
		(net "P5V_STB_NODE1")
	)
	(via
		(at 190.5889 -79.081122)
		(size 0.508)
		(drill 0.254)
		(layers "F.Cu" "B.Cu")
		(net "P5V_STB_NODE1")
	)
	(via
		(at 103.348536 -150.920704)
		(size 0.508)
		(drill 0.254)
		(layers "F.Cu" "B.Cu")
		(net "P5V_STB_NODE1")
	)
	(via
		(at 66.539618 -156.118052)
		(size 0.508)
		(drill 0.254)
		(layers "F.Cu" "B.Cu")
		(net "P5V_STB_NODE1")
	)
	(via
		(at 39.68877 -11.618722)
		(size 0.508)
		(drill 0.254)
		(layers "F.Cu" "B.Cu")
		(net "P5V_STB_NODE1")
	)
	(via
		(at 66.539618 -153.832052)
		(size 0.508)
		(drill 0.254)
		(layers "F.Cu" "B.Cu")
		(net "P5V_STB_NODE1")
	)
	(via
		(at 82.064352 -142.621762)
		(size 0.508)
		(drill 0.254)
		(layers "F.Cu" "B.Cu")
		(net "P5V_STB_NODE1")
	)
	(via
		(at 82.278474 -149.792182)
		(size 0.508)
		(drill 0.254)
		(layers "F.Cu" "B.Cu")
		(net "P5V_STB_NODE1")
	)
	(via
		(at 28.22448 -101.875336)
		(size 0.508)
		(drill 0.254)
		(layers "F.Cu" "B.Cu")
		(net "P5V_STB_NODE1")
	)
	(via
		(at 106.166666 -138.519408)
		(size 0.508)
		(drill 0.254)
		(layers "F.Cu" "B.Cu")
		(net "P5V_STB_NODE1")
	)
	(via
		(at 66.920618 -158.404052)
		(size 0.508)
		(drill 0.254)
		(layers "F.Cu" "B.Cu")
		(net "P5V_STB_NODE1")
	)
	(via
		(at 82.089752 -143.383762)
		(size 0.508)
		(drill 0.254)
		(layers "F.Cu" "B.Cu")
		(net "P5V_STB_NODE1")
	)
	(via
		(at 44.75988 -113.854738)
		(size 0.508)
		(drill 0.254)
		(layers "F.Cu" "B.Cu")
		(net "P5V_STB_NODE1")
	)
	(via
		(at 26.3525 -102.29596)
		(size 0.508)
		(drill 0.254)
		(layers "F.Cu" "B.Cu")
		(net "P5V_STB_NODE1")
	)
	(via
		(at 68.254118 -153.92781)
		(size 0.508)
		(drill 0.254)
		(layers "F.Cu" "B.Cu")
		(net "P5V_STB_NODE1")
	)
	(via
		(at 26.36774 -103.092504)
		(size 0.508)
		(drill 0.254)
		(layers "F.Cu" "B.Cu")
		(net "P5V_STB_NODE1")
	)
	(via
		(at 45.456094 -113.827052)
		(size 0.508)
		(drill 0.254)
		(layers "F.Cu" "B.Cu")
		(net "P5V_STB_NODE1")
	)
	(via
		(at 68.070222 -99.23653)
		(size 0.508)
		(drill 0.254)
		(layers "F.Cu" "B.Cu")
		(net "P5V_STB_NODE1")
	)
	(via
		(at 108.221272 -138.696192)
		(size 0.508)
		(drill 0.254)
		(layers "F.Cu" "B.Cu")
		(net "P5V_STB_NODE1")
	)
	(via
		(at 69.481192 -161.663634)
		(size 0.508)
		(drill 0.254)
		(layers "F.Cu" "B.Cu")
		(net "P5V_STB_NODE1")
	)
	(via
		(at 26.38298 -101.499416)
		(size 0.508)
		(drill 0.254)
		(layers "F.Cu" "B.Cu")
		(net "P5V_STB_NODE1")
	)
	(via
		(at 32.43707 -124.315474)
		(size 0.508)
		(drill 0.254)
		(layers "F.Cu" "B.Cu")
		(net "P5V_STB_NODE1")
	)
	(via
		(at 104.408732 -138.519662)
		(size 0.6604)
		(drill 0.3302)
		(layers "F.Cu" "B.Cu")
		(net "P5V_STB_NODE1")
	)
	(via
		(at 31.77667 -124.315474)
		(size 0.508)
		(drill 0.254)
		(layers "F.Cu" "B.Cu")
		(net "P5V_STB_NODE1")
	)
	(via
		(at 104.958388 -129.045716)
		(size 0.508)
		(drill 0.254)
		(layers "F.Cu" "B.Cu")
		(net "P5V_STB_NODE1")
	)
	(via
		(at 14.30782 -126.47676)
		(size 0.508)
		(drill 0.254)
		(layers "F.Cu" "B.Cu")
		(net "P5V_STB_NODE1")
	)
	(via
		(at 66.056256 -153.160222)
		(size 0.508)
		(drill 0.254)
		(layers "F.Cu" "B.Cu")
		(net "P5V_STB_NODE1")
	)
	(via
		(at 103.949754 -132.527802)
		(size 0.508)
		(drill 0.254)
		(layers "F.Cu" "B.Cu")
		(net "P5V_STB_NODE1")
	)
	(via
		(at 87.9221 -9.15162)
		(size 0.508)
		(drill 0.254)
		(layers "F.Cu" "B.Cu")
		(net "P5V_STB_NODE1")
	)
	(via
		(at 126.861824 -32.681164)
		(size 0.508)
		(drill 0.254)
		(layers "F.Cu" "B.Cu")
		(net "P5V_STB_NODE1")
	)
	(via
		(at 69.513196 -162.58413)
		(size 0.508)
		(drill 0.254)
		(layers "F.Cu" "B.Cu")
		(net "P5V_STB_NODE1")
	)
	(via
		(at 66.920618 -159.166052)
		(size 0.508)
		(drill 0.254)
		(layers "F.Cu" "B.Cu")
		(net "P5V_STB_NODE1")
	)
	(via
		(at 166.400988 -80.02778)
		(size 0.508)
		(drill 0.254)
		(layers "F.Cu" "B.Cu")
		(net "P5V_STB_NODE1")
	)
	(segment
		(start 125.945646 -32.681164)
		(end 126.861824 -32.681164)
		(width 0.508)
		(layer "B.Cu")
		(net "P5V_STB_NODE1")
	)
	(segment
		(start 168.811448 -82.43824)
		(end 166.400988 -80.02778)
		(width 1.016)
		(layer "In2.Cu")
		(net "P5V_STB_NODE1")
	)
	(segment
		(start 189.385956 -79.422752)
		(end 186.370468 -82.43824)
		(width 1.016)
		(layer "In2.Cu")
		(net "P5V_STB_NODE1")
	)
	(segment
		(start 186.370468 -82.43824)
		(end 168.811448 -82.43824)
		(width 1.016)
		(layer "In2.Cu")
		(net "P5V_STB_NODE1")
	)
	(segment
		(start 72.93864 -111.079026)
		(end 73.938892 -110.078774)
		(width 0.508)
		(layer "In6.Cu")
		(net "P5V_STB_NODE1")
	)
	(segment
		(start 68.112132 -147.969224)
		(end 66.05524 -150.026116)
		(width 0.254)
		(layer "In6.Cu")
		(net "P5V_STB_NODE1")
	)
	(segment
		(start 149.826726 -146.459956)
		(end 149.826726 -149.161754)
		(width 1.016)
		(layer "In6.Cu")
		(net "P5V_STB_NODE1")
	)
	(segment
		(start 132.485892 -154.34183)
		(end 130.939032 -152.79497)
		(width 1.016)
		(layer "In6.Cu")
		(net "P5V_STB_NODE1")
	)
	(segment
		(start 110.199424 -153.52395)
		(end 109.97438 -153.298906)
		(width 1.016)
		(layer "In6.Cu")
		(net "P5V_STB_NODE1")
	)
	(segment
		(start 73.938892 -110.078774)
		(end 73.938892 -101.815392)
		(width 0.508)
		(layer "In6.Cu")
		(net "P5V_STB_NODE1")
	)
	(segment
		(start 72.53478 -147.969224)
		(end 68.112132 -147.969224)
		(width 0.254)
		(layer "In6.Cu")
		(net "P5V_STB_NODE1")
	)
	(segment
		(start 177.608738 -139.822174)
		(end 157.848046 -139.822174)
		(width 1.016)
		(layer "In6.Cu")
		(net "P5V_STB_NODE1")
	)
	(segment
		(start 65.04178 -111.079026)
		(end 72.93864 -111.079026)
		(width 0.508)
		(layer "In6.Cu")
		(net "P5V_STB_NODE1")
	)
	(segment
		(start 191.809878 -79.494126)
		(end 193.30797 -79.494126)
		(width 1.016)
		(layer "In6.Cu")
		(net "P5V_STB_NODE1")
	)
	(segment
		(start 133.4135 -154.34183)
		(end 132.485892 -154.34183)
		(width 1.016)
		(layer "In6.Cu")
		(net "P5V_STB_NODE1")
	)
	(segment
		(start 196.2658 -123.048522)
		(end 181.49316 -137.821162)
		(width 1.016)
		(layer "In6.Cu")
		(net "P5V_STB_NODE1")
	)
	(segment
		(start 155.158948 -145.136362)
		(end 151.15032 -145.136362)
		(width 1.016)
		(layer "In6.Cu")
		(net "P5V_STB_NODE1")
	)
	(segment
		(start 73.579482 -101.455982)
		(end 71.6915 -101.455982)
		(width 0.508)
		(layer "In6.Cu")
		(net "P5V_STB_NODE1")
	)
	(segment
		(start 133.538976 -154.467306)
		(end 133.4135 -154.34183)
		(width 1.016)
		(layer "In6.Cu")
		(net "P5V_STB_NODE1")
	)
	(segment
		(start 149.826726 -149.161754)
		(end 149.306026 -149.682454)
		(width 1.016)
		(layer "In6.Cu")
		(net "P5V_STB_NODE1")
	)
	(segment
		(start 66.05524 -150.026116)
		(end 66.05524 -153.160222)
		(width 0.254)
		(layer "In6.Cu")
		(net "P5V_STB_NODE1")
	)
	(segment
		(start 151.15032 -145.136362)
		(end 149.826726 -146.459956)
		(width 1.016)
		(layer "In6.Cu")
		(net "P5V_STB_NODE1")
	)
	(segment
		(start 73.938892 -101.815392)
		(end 73.579482 -101.455982)
		(width 0.508)
		(layer "In6.Cu")
		(net "P5V_STB_NODE1")
	)
	(segment
		(start 149.306026 -149.682454)
		(end 147.937728 -149.682454)
		(width 1.016)
		(layer "In6.Cu")
		(net "P5V_STB_NODE1")
	)
	(segment
		(start 147.937728 -149.682454)
		(end 143.152876 -154.467306)
		(width 1.016)
		(layer "In6.Cu")
		(net "P5V_STB_NODE1")
	)
	(segment
		(start 82.278474 -149.792182)
		(end 82.278474 -149.053296)
		(width 0.254)
		(layer "In6.Cu")
		(net "P5V_STB_NODE1")
	)
	(segment
		(start 106.828336 -152.0571)
		(end 103.93553 -152.0571)
		(width 1.016)
		(layer "In6.Cu")
		(net "P5V_STB_NODE1")
	)
	(segment
		(start 71.243698 -101.00818)
		(end 68.9102 -101.00818)
		(width 0.508)
		(layer "In6.Cu")
		(net "P5V_STB_NODE1")
	)
	(segment
		(start 80.51165 -147.286472)
		(end 73.217532 -147.286472)
		(width 0.254)
		(layer "In6.Cu")
		(net "P5V_STB_NODE1")
	)
	(segment
		(start 66.05524 -153.160222)
		(end 66.056256 -153.160222)
		(width 0.254)
		(layer "In6.Cu")
		(net "P5V_STB_NODE1")
	)
	(segment
		(start 64.65824 -111.462566)
		(end 65.04178 -111.079026)
		(width 0.508)
		(layer "In6.Cu")
		(net "P5V_STB_NODE1")
	)
	(segment
		(start 129.473452 -153.52395)
		(end 110.199424 -153.52395)
		(width 1.016)
		(layer "In6.Cu")
		(net "P5V_STB_NODE1")
	)
	(segment
		(start 143.152876 -154.467306)
		(end 133.538976 -154.467306)
		(width 1.016)
		(layer "In6.Cu")
		(net "P5V_STB_NODE1")
	)
	(segment
		(start 71.6915 -101.455982)
		(end 71.243698 -101.00818)
		(width 0.508)
		(layer "In6.Cu")
		(net "P5V_STB_NODE1")
	)
	(segment
		(start 82.278474 -149.053296)
		(end 80.51165 -147.286472)
		(width 0.254)
		(layer "In6.Cu")
		(net "P5V_STB_NODE1")
	)
	(segment
		(start 109.97438 -153.298906)
		(end 108.070142 -153.298906)
		(width 1.016)
		(layer "In6.Cu")
		(net "P5V_STB_NODE1")
	)
	(segment
		(start 193.30797 -79.494126)
		(end 196.2658 -82.451956)
		(width 1.016)
		(layer "In6.Cu")
		(net "P5V_STB_NODE1")
	)
	(segment
		(start 157.05836 -143.23695)
		(end 155.158948 -145.136362)
		(width 1.016)
		(layer "In6.Cu")
		(net "P5V_STB_NODE1")
	)
	(segment
		(start 73.217532 -147.286472)
		(end 72.53478 -147.969224)
		(width 0.254)
		(layer "In6.Cu")
		(net "P5V_STB_NODE1")
	)
	(segment
		(start 179.60975 -137.821162)
		(end 177.608738 -139.822174)
		(width 1.016)
		(layer "In6.Cu")
		(net "P5V_STB_NODE1")
	)
	(segment
		(start 196.2658 -82.451956)
		(end 196.2658 -123.048522)
		(width 1.016)
		(layer "In6.Cu")
		(net "P5V_STB_NODE1")
	)
	(segment
		(start 130.202432 -152.79497)
		(end 129.473452 -153.52395)
		(width 1.016)
		(layer "In6.Cu")
		(net "P5V_STB_NODE1")
	)
	(segment
		(start 108.070142 -153.298906)
		(end 106.828336 -152.0571)
		(width 1.016)
		(layer "In6.Cu")
		(net "P5V_STB_NODE1")
	)
	(segment
		(start 68.9102 -101.00818)
		(end 68.070222 -100.168202)
		(width 0.508)
		(layer "In6.Cu")
		(net "P5V_STB_NODE1")
	)
	(segment
		(start 68.070222 -100.168202)
		(end 68.070222 -99.23653)
		(width 0.508)
		(layer "In6.Cu")
		(net "P5V_STB_NODE1")
	)
	(segment
		(start 157.848046 -139.822174)
		(end 157.05836 -140.61186)
		(width 1.016)
		(layer "In6.Cu")
		(net "P5V_STB_NODE1")
	)
	(segment
		(start 130.939032 -152.79497)
		(end 130.202432 -152.79497)
		(width 1.016)
		(layer "In6.Cu")
		(net "P5V_STB_NODE1")
	)
	(segment
		(start 157.05836 -140.61186)
		(end 157.05836 -143.23695)
		(width 1.016)
		(layer "In6.Cu")
		(net "P5V_STB_NODE1")
	)
	(segment
		(start 181.49316 -137.821162)
		(end 179.60975 -137.821162)
		(width 1.016)
		(layer "In6.Cu")
		(net "P5V_STB_NODE1")
	)
	(segment
		(start 119.507 -14.685264)
		(end 119.507 -16.374364)
		(width 1.016)
		(layer "In7.Cu")
		(net "P5V_STB_NODE1")
	)
	(segment
		(start 123.320302 -29.542994)
		(end 123.33478 -29.528516)
		(width 1.016)
		(layer "In7.Cu")
		(net "P5V_STB_NODE1")
	)
	(segment
		(start 119.507 -16.374364)
		(end 121.44248 -18.309844)
		(width 1.016)
		(layer "In7.Cu")
		(net "P5V_STB_NODE1")
	)
	(segment
		(start 125.63094 -29.528516)
		(end 127.23622 -31.133796)
		(width 1.016)
		(layer "In7.Cu")
		(net "P5V_STB_NODE1")
	)
	(segment
		(start 122.6566 -29.542994)
		(end 123.320302 -29.542994)
		(width 1.016)
		(layer "In7.Cu")
		(net "P5V_STB_NODE1")
	)
	(segment
		(start 118.26748 -13.445744)
		(end 119.507 -14.685264)
		(width 1.016)
		(layer "In7.Cu")
		(net "P5V_STB_NODE1")
	)
	(segment
		(start 116.835936 -13.445744)
		(end 118.26748 -13.445744)
		(width 1.016)
		(layer "In7.Cu")
		(net "P5V_STB_NODE1")
	)
	(segment
		(start 127.23622 -31.133796)
		(end 127.23622 -31.957518)
		(width 1.016)
		(layer "In7.Cu")
		(net "P5V_STB_NODE1")
	)
	(segment
		(start 89.584022 -8.163052)
		(end 111.553244 -8.163052)
		(width 1.016)
		(layer "In7.Cu")
		(net "P5V_STB_NODE1")
	)
	(segment
		(start 121.44248 -28.328874)
		(end 122.6566 -29.542994)
		(width 1.016)
		(layer "In7.Cu")
		(net "P5V_STB_NODE1")
	)
	(segment
		(start 126.861824 -32.331914)
		(end 126.861824 -32.681164)
		(width 1.016)
		(layer "In7.Cu")
		(net "P5V_STB_NODE1")
	)
	(segment
		(start 111.553244 -8.163052)
		(end 116.835936 -13.445744)
		(width 1.016)
		(layer "In7.Cu")
		(net "P5V_STB_NODE1")
	)
	(segment
		(start 123.33478 -29.528516)
		(end 125.63094 -29.528516)
		(width 1.016)
		(layer "In7.Cu")
		(net "P5V_STB_NODE1")
	)
	(segment
		(start 121.44248 -18.309844)
		(end 121.44248 -28.328874)
		(width 1.016)
		(layer "In7.Cu")
		(net "P5V_STB_NODE1")
	)
	(segment
		(start 127.23622 -31.957518)
		(end 126.861824 -32.331914)
		(width 1.016)
		(layer "In7.Cu")
		(net "P5V_STB_NODE1")
	)
	(segment
		(start 52.728114 -73.399142)
		(end 52.399946 -73.72731)
		(width 0.3048)
		(layer "F.Cu")
		(net "PD_CPU_NODE1_AM23")
	)
	(segment
		(start 52.799996 -73.399142)
		(end 52.728114 -73.399142)
		(width 0.3048)
		(layer "F.Cu")
		(net "PD_CPU_NODE1_AM23")
	)
	(segment
		(start 52.399946 -73.72731)
		(end 52.399946 -73.799192)
		(width 0.3048)
		(layer "F.Cu")
		(net "PD_CPU_NODE1_AM23")
	)
	(via
		(at 48.76038 -75.623674)
		(size 0.6604)
		(drill 0.3302)
		(layers "F.Cu" "B.Cu")
		(net "PD_CPU_NODE1_AM23")
	)
	(via
		(at 52.399946 -73.799192)
		(size 0.508)
		(drill 0.254)
		(layers "F.Cu" "B.Cu")
		(net "PD_CPU_NODE1_AM23")
	)
	(segment
		(start 52.399946 -73.799192)
		(end 52.000912 -74.198226)
		(width 0.381)
		(layer "B.Cu")
		(net "PD_CPU_NODE1_AM23")
	)
	(segment
		(start 50.253138 -75.623674)
		(end 48.76038 -75.623674)
		(width 0.1016)
		(layer "B.Cu")
		(net "PD_CPU_NODE1_AM23")
	)
	(segment
		(start 51.999388 -74.198226)
		(end 51.82489 -74.372724)
		(width 0.381)
		(layer "B.Cu")
		(net "PD_CPU_NODE1_AM23")
	)
	(segment
		(start 50.671476 -74.891392)
		(end 50.253138 -75.30973)
		(width 0.381)
		(layer "B.Cu")
		(net "PD_CPU_NODE1_AM23")
	)
	(segment
		(start 50.253138 -75.30973)
		(end 50.253138 -75.623674)
		(width 0.381)
		(layer "B.Cu")
		(net "PD_CPU_NODE1_AM23")
	)
	(segment
		(start 51.058064 -74.372724)
		(end 50.671476 -74.759312)
		(width 0.381)
		(layer "B.Cu")
		(net "PD_CPU_NODE1_AM23")
	)
	(segment
		(start 51.82489 -74.372724)
		(end 51.058064 -74.372724)
		(width 0.381)
		(layer "B.Cu")
		(net "PD_CPU_NODE1_AM23")
	)
	(segment
		(start 50.671476 -74.759312)
		(end 50.671476 -74.891392)
		(width 0.381)
		(layer "B.Cu")
		(net "PD_CPU_NODE1_AM23")
	)
	(segment
		(start 52.000912 -74.198226)
		(end 51.999388 -74.198226)
		(width 0.381)
		(layer "B.Cu")
		(net "PD_CPU_NODE1_AM23")
	)
	(segment
		(start 168.007538 -119.365522)
		(end 167.756332 -119.616728)
		(width 0.1016)
		(layer "F.Cu")
		(net "FM_CPLD_NODE1_BMC_SRST_L")
	)
	(segment
		(start 167.13327 -119.39651)
		(end 167.536114 -119.39651)
		(width 0.1016)
		(layer "F.Cu")
		(net "FM_CPLD_NODE1_BMC_SRST_L")
	)
	(segment
		(start 167.536114 -119.39651)
		(end 167.756332 -119.616728)
		(width 0.1016)
		(layer "F.Cu")
		(net "FM_CPLD_NODE1_BMC_SRST_L")
	)
	(segment
		(start 172.010324 -119.365522)
		(end 168.007538 -119.365522)
		(width 0.1016)
		(layer "F.Cu")
		(net "FM_CPLD_NODE1_BMC_SRST_L")
	)
	(via
		(at 167.756332 -119.616728)
		(size 0.508)
		(drill 0.254)
		(layers "F.Cu" "B.Cu")
		(net "FM_CPLD_NODE1_BMC_SRST_L")
	)
	(segment
		(start 49.281588 -132.014722)
		(end 50.5587 -132.014722)
		(width 0.1016)
		(layer "F.Cu")
		(net "BMC_NODE1_DDR_MA6")
	)
	(segment
		(start 52.11953 -133.059678)
		(end 52.11953 -132.67309)
		(width 0.1016)
		(layer "F.Cu")
		(net "BMC_NODE1_DDR_MA6")
	)
	(segment
		(start 51.499516 -132.198618)
		(end 52.013612 -132.198618)
		(width 0.1016)
		(layer "F.Cu")
		(net "BMC_NODE1_DDR_MA6")
	)
	(segment
		(start 51.371246 -132.715508)
		(end 51.371246 -132.326888)
		(width 0.1016)
		(layer "F.Cu")
		(net "BMC_NODE1_DDR_MA6")
	)
	(segment
		(start 52.761896 -132.99567)
		(end 52.57927 -133.178296)
		(width 0.1016)
		(layer "F.Cu")
		(net "BMC_NODE1_DDR_MA6")
	)
	(segment
		(start 45.633132 -129.763774)
		(end 46.049438 -129.347468)
		(width 0.1016)
		(layer "F.Cu")
		(net "BMC_NODE1_DDR_MA6")
	)
	(segment
		(start 46.402244 -128.467104)
		(end 47.629318 -128.467104)
		(width 0.1016)
		(layer "F.Cu")
		(net "BMC_NODE1_DDR_MA6")
	)
	(segment
		(start 58.14187 -132.059426)
		(end 57.741312 -131.658868)
		(width 0.1016)
		(layer "F.Cu")
		(net "BMC_NODE1_DDR_MA6")
	)
	(segment
		(start 50.5587 -132.014722)
		(end 50.66792 -132.123942)
		(width 0.1016)
		(layer "F.Cu")
		(net "BMC_NODE1_DDR_MA6")
	)
	(segment
		(start 47.629318 -128.467104)
		(end 48.160686 -128.998472)
		(width 0.1016)
		(layer "F.Cu")
		(net "BMC_NODE1_DDR_MA6")
	)
	(segment
		(start 53.609494 -130.708654)
		(end 52.761896 -131.556252)
		(width 0.1016)
		(layer "F.Cu")
		(net "BMC_NODE1_DDR_MA6")
	)
	(segment
		(start 46.049438 -129.347468)
		(end 46.049438 -128.81991)
		(width 0.1016)
		(layer "F.Cu")
		(net "BMC_NODE1_DDR_MA6")
	)
	(segment
		(start 51.371246 -132.326888)
		(end 51.499516 -132.198618)
		(width 0.1016)
		(layer "F.Cu")
		(net "BMC_NODE1_DDR_MA6")
	)
	(segment
		(start 46.049438 -128.81991)
		(end 46.402244 -128.467104)
		(width 0.1016)
		(layer "F.Cu")
		(net "BMC_NODE1_DDR_MA6")
	)
	(segment
		(start 52.761896 -131.556252)
		(end 52.761896 -132.99567)
		(width 0.1016)
		(layer "F.Cu")
		(net "BMC_NODE1_DDR_MA6")
	)
	(segment
		(start 50.903632 -132.874004)
		(end 51.21275 -132.874004)
		(width 0.1016)
		(layer "F.Cu")
		(net "BMC_NODE1_DDR_MA6")
	)
	(segment
		(start 50.66792 -132.638292)
		(end 50.903632 -132.874004)
		(width 0.1016)
		(layer "F.Cu")
		(net "BMC_NODE1_DDR_MA6")
	)
	(segment
		(start 50.66792 -132.123942)
		(end 50.66792 -132.638292)
		(width 0.1016)
		(layer "F.Cu")
		(net "BMC_NODE1_DDR_MA6")
	)
	(segment
		(start 52.11953 -132.304536)
		(end 52.11953 -132.67309)
		(width 0.1016)
		(layer "F.Cu")
		(net "BMC_NODE1_DDR_MA6")
	)
	(segment
		(start 55.564278 -130.708654)
		(end 53.609494 -130.708654)
		(width 0.1016)
		(layer "F.Cu")
		(net "BMC_NODE1_DDR_MA6")
	)
	(segment
		(start 48.160686 -128.998472)
		(end 48.160686 -130.24485)
		(width 0.1016)
		(layer "F.Cu")
		(net "BMC_NODE1_DDR_MA6")
	)
	(segment
		(start 48.696626 -130.78079)
		(end 48.696626 -131.42976)
		(width 0.1016)
		(layer "F.Cu")
		(net "BMC_NODE1_DDR_MA6")
	)
	(segment
		(start 52.57927 -133.178296)
		(end 52.238148 -133.178296)
		(width 0.1016)
		(layer "F.Cu")
		(net "BMC_NODE1_DDR_MA6")
	)
	(segment
		(start 52.238148 -133.178296)
		(end 52.11953 -133.059678)
		(width 0.1016)
		(layer "F.Cu")
		(net "BMC_NODE1_DDR_MA6")
	)
	(segment
		(start 52.013612 -132.198618)
		(end 52.11953 -132.304536)
		(width 0.1016)
		(layer "F.Cu")
		(net "BMC_NODE1_DDR_MA6")
	)
	(segment
		(start 56.514492 -131.658868)
		(end 55.564278 -130.708654)
		(width 0.1016)
		(layer "F.Cu")
		(net "BMC_NODE1_DDR_MA6")
	)
	(segment
		(start 57.741312 -131.658868)
		(end 56.514492 -131.658868)
		(width 0.1016)
		(layer "F.Cu")
		(net "BMC_NODE1_DDR_MA6")
	)
	(segment
		(start 48.696626 -131.42976)
		(end 49.281588 -132.014722)
		(width 0.1016)
		(layer "F.Cu")
		(net "BMC_NODE1_DDR_MA6")
	)
	(segment
		(start 48.160686 -130.24485)
		(end 48.696626 -130.78079)
		(width 0.1016)
		(layer "F.Cu")
		(net "BMC_NODE1_DDR_MA6")
	)
	(segment
		(start 51.21275 -132.874004)
		(end 51.371246 -132.715508)
		(width 0.1016)
		(layer "F.Cu")
		(net "BMC_NODE1_DDR_MA6")
	)
	(via
		(at 52.11953 -132.67309)
		(size 0.762)
		(drill 0.381)
		(layers "F.Cu" "B.Cu")
		(net "BMC_NODE1_DDR_MA6")
	)
	(segment
		(start 152.262078 -150.14067)
		(end 151.804116 -150.14067)
		(width 0.508)
		(layer "F.Cu")
		(net "P3V3_NODE1")
	)
	(segment
		(start 42.332402 -145.404332)
		(end 42.363644 -145.37309)
		(width 0.508)
		(layer "F.Cu")
		(net "P3V3_NODE1")
	)
	(segment
		(start 150.997666 -30.54985)
		(end 151.202644 -30.54985)
		(width 0.508)
		(layer "F.Cu")
		(net "P3V3_NODE1")
	)
	(segment
		(start 130.938016 -150.124414)
		(end 130.914902 -150.1013)
		(width 0.1778)
		(layer "F.Cu")
		(net "P3V3_NODE1")
	)
	(segment
		(start 93.613986 -179.386992)
		(end 93.33992 -179.112926)
		(width 0.508)
		(layer "F.Cu")
		(net "P3V3_NODE1")
	)
	(segment
		(start 137.807192 -179.908962)
		(end 137.807192 -180.376068)
		(width 0.254)
		(layer "F.Cu")
		(net "P3V3_NODE1")
	)
	(segment
		(start 89.962228 -133.963156)
		(end 91.486228 -133.963156)
		(width 0.508)
		(layer "F.Cu")
		(net "P3V3_NODE1")
	)
	(segment
		(start 56.923432 -98.590862)
		(end 56.923432 -98.559366)
		(width 0.508)
		(layer "F.Cu")
		(net "P3V3_NODE1")
	)
	(segment
		(start 123.00712 -50.435764)
		(end 123.815856 -50.435764)
		(width 0.508)
		(layer "F.Cu")
		(net "P3V3_NODE1")
	)
	(segment
		(start 57.210198 -170.630088)
		(end 56.484266 -170.630088)
		(width 0.508)
		(layer "F.Cu")
		(net "P3V3_NODE1")
	)
	(segment
		(start 105.768648 -179.179982)
		(end 105.462832 -179.485798)
		(width 0.508)
		(layer "F.Cu")
		(net "P3V3_NODE1")
	)
	(segment
		(start 89.18194 -135.08609)
		(end 87.93353 -135.08609)
		(width 0.508)
		(layer "F.Cu")
		(net "P3V3_NODE1")
	)
	(segment
		(start 41.316402 -145.404332)
		(end 41.347644 -145.37309)
		(width 0.508)
		(layer "F.Cu")
		(net "P3V3_NODE1")
	)
	(segment
		(start 172.355256 -103.507794)
		(end 172.424852 -103.57739)
		(width 0.1778)
		(layer "F.Cu")
		(net "P3V3_NODE1")
	)
	(segment
		(start 73.337166 -97.110042)
		(end 74.353166 -97.110042)
		(width 0.508)
		(layer "F.Cu")
		(net "P3V3_NODE1")
	)
	(segment
		(start 147.833842 -144.082262)
		(end 147.833842 -145.095468)
		(width 0.508)
		(layer "F.Cu")
		(net "P3V3_NODE1")
	)
	(segment
		(start 130.08864 -55.136542)
		(end 130.08864 -54.5084)
		(width 0.4572)
		(layer "F.Cu")
		(net "P3V3_NODE1")
	)
	(segment
		(start 66.891408 -8.501888)
		(end 66.891408 -9.506966)
		(width 0.254)
		(layer "F.Cu")
		(net "P3V3_NODE1")
	)
	(segment
		(start 82.342228 -133.961124)
		(end 82.342228 -133.963156)
		(width 0.508)
		(layer "F.Cu")
		(net "P3V3_NODE1")
	)
	(segment
		(start 86.914228 -133.963156)
		(end 86.914228 -134.565898)
		(width 0.508)
		(layer "F.Cu")
		(net "P3V3_NODE1")
	)
	(segment
		(start 65.341754 -130.45948)
		(end 65.341754 -130.458972)
		(width 0.381)
		(layer "F.Cu")
		(net "P3V3_NODE1")
	)
	(segment
		(start 69.547486 -149.20849)
		(end 69.46392 -149.292056)
		(width 0.508)
		(layer "F.Cu")
		(net "P3V3_NODE1")
	)
	(segment
		(start 66.414142 -171.628054)
		(end 66.81343 -171.228766)
		(width 0.508)
		(layer "F.Cu")
		(net "P3V3_NODE1")
	)
	(segment
		(start 45.532802 -145.429732)
		(end 45.532802 -144.634712)
		(width 0.508)
		(layer "F.Cu")
		(net "P3V3_NODE1")
	)
	(segment
		(start 76.693776 -183.089042)
		(end 77.414882 -183.089042)
		(width 0.4572)
		(layer "F.Cu")
		(net "P3V3_NODE1")
	)
	(segment
		(start 83.78317 -11.121898)
		(end 80.092296 -14.812772)
		(width 0.254)
		(layer "F.Cu")
		(net "P3V3_NODE1")
	)
	(segment
		(start 52.17414 -164.2999)
		(end 52.17414 -165.10889)
		(width 0.508)
		(layer "F.Cu")
		(net "P3V3_NODE1")
	)
	(segment
		(start 15.320772 -16.660622)
		(end 15.997174 -16.660622)
		(width 0.508)
		(layer "F.Cu")
		(net "P3V3_NODE1")
	)
	(segment
		(start 133.737858 -150.224744)
		(end 134.020052 -149.94255)
		(width 0.1778)
		(layer "F.Cu")
		(net "P3V3_NODE1")
	)
	(segment
		(start 158.098236 -172.902372)
		(end 159.375602 -172.902372)
		(width 0.381)
		(layer "F.Cu")
		(net "P3V3_NODE1")
	)
	(segment
		(start 147.929346 -148.333714)
		(end 147.461478 -147.865846)
		(width 0.508)
		(layer "F.Cu")
		(net "P3V3_NODE1")
	)
	(segment
		(start 70.141846 -135.259572)
		(end 70.142354 -135.259572)
		(width 0.381)
		(layer "F.Cu")
		(net "P3V3_NODE1")
	)
	(segment
		(start 108.6866 -173.519846)
		(end 108.22559 -173.980856)
		(width 0.508)
		(layer "F.Cu")
		(net "P3V3_NODE1")
	)
	(segment
		(start 82.275934 -121.14149)
		(end 82.68208 -121.14149)
		(width 0.4572)
		(layer "F.Cu")
		(net "P3V3_NODE1")
	)
	(segment
		(start 94.051882 -179.386992)
		(end 93.613986 -179.386992)
		(width 0.508)
		(layer "F.Cu")
		(net "P3V3_NODE1")
	)
	(segment
		(start 149.462998 -142.48638)
		(end 149.462998 -141.610334)
		(width 0.508)
		(layer "F.Cu")
		(net "P3V3_NODE1")
	)
	(segment
		(start 146.913346 -149.843998)
		(end 146.913346 -148.766784)
		(width 0.508)
		(layer "F.Cu")
		(net "P3V3_NODE1")
	)
	(segment
		(start 56.484266 -171.331382)
		(end 56.484266 -170.630088)
		(width 0.508)
		(layer "F.Cu")
		(net "P3V3_NODE1")
	)
	(segment
		(start 161.070798 -161.770568)
		(end 161.070798 -162.395408)
		(width 0.508)
		(layer "F.Cu")
		(net "P3V3_NODE1")
	)
	(segment
		(start 156.445712 -103.5939)
		(end 157.101794 -103.5939)
		(width 0.4064)
		(layer "F.Cu")
		(net "P3V3_NODE1")
	)
	(segment
		(start 82.888836 -118.141496)
		(end 83.816444 -118.141496)
		(width 0.2032)
		(layer "F.Cu")
		(net "P3V3_NODE1")
	)
	(segment
		(start 55.450232 -161.528506)
		(end 56.166766 -161.528506)
		(width 0.508)
		(layer "F.Cu")
		(net "P3V3_NODE1")
	)
	(segment
		(start 153.526998 -142.48638)
		(end 153.526998 -141.720824)
		(width 0.508)
		(layer "F.Cu")
		(net "P3V3_NODE1")
	)
	(segment
		(start 168.443148 -104.839008)
		(end 168.443148 -106.041698)
		(width 0.1778)
		(layer "F.Cu")
		(net "P3V3_NODE1")
	)
	(segment
		(start 163.287202 -90.14079)
		(end 163.270184 -90.123772)
		(width 0.508)
		(layer "F.Cu")
		(net "P3V3_NODE1")
	)
	(segment
		(start 106.026458 -178.984656)
		(end 106.026458 -179.010056)
		(width 0.508)
		(layer "F.Cu")
		(net "P3V3_NODE1")
	)
	(segment
		(start 88.80094 -175.01997)
		(end 89.652348 -175.01997)
		(width 0.254)
		(layer "F.Cu")
		(net "P3V3_NODE1")
	)
	(segment
		(start 81.596484 -120.057926)
		(end 81.306924 -120.347486)
		(width 0.4572)
		(layer "F.Cu")
		(net "P3V3_NODE1")
	)
	(segment
		(start 83.78317 -8.212074)
		(end 83.78317 -11.121898)
		(width 0.254)
		(layer "F.Cu")
		(net "P3V3_NODE1")
	)
	(segment
		(start 96.22282 -98.133408)
		(end 95.949008 -98.133408)
		(width 0.508)
		(layer "F.Cu")
		(net "P3V3_NODE1")
	)
	(segment
		(start 97.663 -181.722268)
		(end 97.663 -181.461664)
		(width 0.508)
		(layer "F.Cu")
		(net "P3V3_NODE1")
	)
	(segment
		(start 80.131158 -181.083204)
		(end 80.131158 -180.790088)
		(width 0.254)
		(layer "F.Cu")
		(net "P3V3_NODE1")
	)
	(segment
		(start 108.094018 -163.930584)
		(end 107.600242 -163.930584)
		(width 0.508)
		(layer "F.Cu")
		(net "P3V3_NODE1")
	)
	(segment
		(start 95.254064 -143.3068)
		(end 97.405952 -143.3068)
		(width 0.508)
		(layer "F.Cu")
		(net "P3V3_NODE1")
	)
	(segment
		(start 7.7089 -137.028428)
		(end 7.7089 -137.026904)
		(width 0.508)
		(layer "F.Cu")
		(net "P3V3_NODE1")
	)
	(segment
		(start 57.207912 -99.95916)
		(end 57.207912 -98.875342)
		(width 0.508)
		(layer "F.Cu")
		(net "P3V3_NODE1")
	)
	(segment
		(start 147.04568 -167.217852)
		(end 147.04568 -167.1955)
		(width 0.254)
		(layer "F.Cu")
		(net "P3V3_NODE1")
	)
	(segment
		(start 70.142354 -136.059418)
		(end 70.54215 -136.459214)
		(width 0.381)
		(layer "F.Cu")
		(net "P3V3_NODE1")
	)
	(segment
		(start 140.23594 -140.175488)
		(end 140.039852 -139.9794)
		(width 0.1778)
		(layer "F.Cu")
		(net "P3V3_NODE1")
	)
	(segment
		(start 79.99476 -163.085018)
		(end 79.99476 -164.374576)
		(width 0.254)
		(layer "F.Cu")
		(net "P3V3_NODE1")
	)
	(segment
		(start 70.142608 -133.659626)
		(end 70.54215 -134.059168)
		(width 0.381)
		(layer "F.Cu")
		(net "P3V3_NODE1")
	)
	(segment
		(start 73.442068 -94.648782)
		(end 74.088244 -95.294958)
		(width 0.508)
		(layer "F.Cu")
		(net "P3V3_NODE1")
	)
	(segment
		(start 125.8062 -61.690758)
		(end 125.807978 -61.690758)
		(width 0.508)
		(layer "F.Cu")
		(net "P3V3_NODE1")
	)
	(segment
		(start 79.971392 -163.06165)
		(end 79.99476 -163.085018)
		(width 0.508)
		(layer "F.Cu")
		(net "P3V3_NODE1")
	)
	(segment
		(start 64.541908 -130.458972)
		(end 64.141096 -130.05816)
		(width 0.381)
		(layer "F.Cu")
		(net "P3V3_NODE1")
	)
	(segment
		(start 147.461478 -147.865846)
		(end 146.83994 -147.865846)
		(width 0.508)
		(layer "F.Cu")
		(net "P3V3_NODE1")
	)
	(segment
		(start 43.8531 -122.251724)
		(end 43.8531 -121.35866)
		(width 0.381)
		(layer "F.Cu")
		(net "P3V3_NODE1")
	)
	(segment
		(start 95.5675 -97.7519)
		(end 95.5675 -91.170252)
		(width 0.508)
		(layer "F.Cu")
		(net "P3V3_NODE1")
	)
	(segment
		(start 82.02676 -181.3052)
		(end 81.74228 -181.02072)
		(width 0.254)
		(layer "F.Cu")
		(net "P3V3_NODE1")
	)
	(segment
		(start 47.60214 -164.2999)
		(end 47.60214 -165.02761)
		(width 0.508)
		(layer "F.Cu")
		(net "P3V3_NODE1")
	)
	(segment
		(start 8.67156 -138.220196)
		(end 8.67156 -137.24763)
		(width 0.508)
		(layer "F.Cu")
		(net "P3V3_NODE1")
	)
	(segment
		(start 9.999218 -153.566622)
		(end 10.182098 -153.749502)
		(width 0.508)
		(layer "F.Cu")
		(net "P3V3_NODE1")
	)
	(segment
		(start 106.570526 -171.954952)
		(end 106.924602 -171.600876)
		(width 0.508)
		(layer "F.Cu")
		(net "P3V3_NODE1")
	)
	(segment
		(start 44.168568 -122.566684)
		(end 44.16806 -122.566684)
		(width 0.381)
		(layer "F.Cu")
		(net "P3V3_NODE1")
	)
	(segment
		(start 66.891408 -12.885166)
		(end 66.891408 -9.506966)
		(width 0.254)
		(layer "F.Cu")
		(net "P3V3_NODE1")
	)
	(segment
		(start 168.443148 -106.041698)
		(end 168.573196 -106.171746)
		(width 0.1778)
		(layer "F.Cu")
		(net "P3V3_NODE1")
	)
	(segment
		(start 151.494998 -141.7193)
		(end 151.3967 -141.621002)
		(width 0.508)
		(layer "F.Cu")
		(net "P3V3_NODE1")
	)
	(segment
		(start 94.871286 -166.155878)
		(end 95.6691 -166.155878)
		(width 0.508)
		(layer "F.Cu")
		(net "P3V3_NODE1")
	)
	(segment
		(start 68.5419 -130.45948)
		(end 68.5419 -130.457448)
		(width 0.381)
		(layer "F.Cu")
		(net "P3V3_NODE1")
	)
	(segment
		(start 70.155054 -175.523652)
		(end 70.209156 -175.577754)
		(width 0.254)
		(layer "F.Cu")
		(net "P3V3_NODE1")
	)
	(segment
		(start 136.161272 -160.648904)
		(end 136.161272 -161.41065)
		(width 0.508)
		(layer "F.Cu")
		(net "P3V3_NODE1")
	)
	(segment
		(start 160.054798 -161.770568)
		(end 160.054798 -162.385248)
		(width 0.508)
		(layer "F.Cu")
		(net "P3V3_NODE1")
	)
	(segment
		(start 9.99744 -153.566622)
		(end 9.999218 -153.566622)
		(width 0.508)
		(layer "F.Cu")
		(net "P3V3_NODE1")
	)
	(segment
		(start 101.660198 -137.192258)
		(end 100.596192 -137.192258)
		(width 0.381)
		(layer "F.Cu")
		(net "P3V3_NODE1")
	)
	(segment
		(start 57.973468 -118.560596)
		(end 57.973468 -117.774974)
		(width 0.508)
		(layer "F.Cu")
		(net "P3V3_NODE1")
	)
	(segment
		(start 148.458682 -140.50518)
		(end 148.218652 -140.26515)
		(width 0.4572)
		(layer "F.Cu")
		(net "P3V3_NODE1")
	)
	(segment
		(start 80.092296 -14.812772)
		(end 68.819014 -14.812772)
		(width 0.254)
		(layer "F.Cu")
		(net "P3V3_NODE1")
	)
	(segment
		(start 4.70916 -150.991316)
		(end 4.70916 -151.57196)
		(width 0.508)
		(layer "F.Cu")
		(net "P3V3_NODE1")
	)
	(segment
		(start 44.516802 -145.429732)
		(end 44.548044 -145.39849)
		(width 0.508)
		(layer "F.Cu")
		(net "P3V3_NODE1")
	)
	(segment
		(start 149.8092 -173.712886)
		(end 149.8092 -172.95114)
		(width 0.508)
		(layer "F.Cu")
		(net "P3V3_NODE1")
	)
	(segment
		(start 68.5419 -130.457448)
		(end 68.941188 -130.05816)
		(width 0.381)
		(layer "F.Cu")
		(net "P3V3_NODE1")
	)
	(segment
		(start 90.202258 -175.418496)
		(end 89.72804 -174.944278)
		(width 0.254)
		(layer "F.Cu")
		(net "P3V3_NODE1")
	)
	(segment
		(start 130.938016 -151.32558)
		(end 130.938016 -150.124414)
		(width 0.1778)
		(layer "F.Cu")
		(net "P3V3_NODE1")
	)
	(segment
		(start 94.867476 -167.162734)
		(end 96.192594 -167.162734)
		(width 0.508)
		(layer "F.Cu")
		(net "P3V3_NODE1")
	)
	(segment
		(start 149.8092 -172.95114)
		(end 149.6187 -172.76064)
		(width 0.508)
		(layer "F.Cu")
		(net "P3V3_NODE1")
	)
	(segment
		(start 168.443148 -97.032572)
		(end 168.443148 -95.963994)
		(width 0.1778)
		(layer "F.Cu")
		(net "P3V3_NODE1")
	)
	(segment
		(start 93.00083 -123.641612)
		(end 92.416376 -123.641612)
		(width 0.2032)
		(layer "F.Cu")
		(net "P3V3_NODE1")
	)
	(segment
		(start 125.418342 -161.189162)
		(end 125.701298 -161.641028)
		(width 0.508)
		(layer "F.Cu")
		(net "P3V3_NODE1")
	)
	(segment
		(start 43.854116 -121.35866)
		(end 43.8531 -121.35866)
		(width 0.508)
		(layer "F.Cu")
		(net "P3V3_NODE1")
	)
	(segment
		(start 105.856532 -179.179982)
		(end 105.768648 -179.179982)
		(width 0.508)
		(layer "F.Cu")
		(net "P3V3_NODE1")
	)
	(segment
		(start 51.121818 -96.562672)
		(end 50.276252 -95.717106)
		(width 0.381)
		(layer "F.Cu")
		(net "P3V3_NODE1")
	)
	(segment
		(start 130.98145 -60.530232)
		(end 130.98145 -59.57697)
		(width 0.508)
		(layer "F.Cu")
		(net "P3V3_NODE1")
	)
	(segment
		(start 173.61408 -201.18832)
		(end 173.61408 -200.42632)
		(width 0.508)
		(layer "F.Cu")
		(net "P3V3_NODE1")
	)
	(segment
		(start 95.5675 -91.170252)
		(end 90.936572 -86.539324)
		(width 0.508)
		(layer "F.Cu")
		(net "P3V3_NODE1")
	)
	(segment
		(start 124.723144 -162.464242)
		(end 124.81052 -162.376866)
		(width 0.508)
		(layer "F.Cu")
		(net "P3V3_NODE1")
	)
	(segment
		(start 4.32308 -150.605236)
		(end 4.70916 -150.991316)
		(width 0.508)
		(layer "F.Cu")
		(net "P3V3_NODE1")
	)
	(segment
		(start 11.933174 -15.860522)
		(end 11.933174 -14.90726)
		(width 0.508)
		(layer "F.Cu")
		(net "P3V3_NODE1")
	)
	(segment
		(start 79.99476 -180.65369)
		(end 79.99476 -179.874672)
		(width 0.254)
		(layer "F.Cu")
		(net "P3V3_NODE1")
	)
	(segment
		(start 59.517026 -83.472782)
		(end 59.126628 -83.082384)
		(width 0.3048)
		(layer "F.Cu")
		(net "P3V3_NODE1")
	)
	(segment
		(start 4.90982 -151.77262)
		(end 4.911852 -151.77262)
		(width 0.508)
		(layer "F.Cu")
		(net "P3V3_NODE1")
	)
	(segment
		(start 130.429 -57.052972)
		(end 130.412998 -57.068974)
		(width 0.4572)
		(layer "F.Cu")
		(net "P3V3_NODE1")
	)
	(segment
		(start 21.604986 -63.672466)
		(end 21.965666 -63.311786)
		(width 0.508)
		(layer "F.Cu")
		(net "P3V3_NODE1")
	)
	(segment
		(start 60.748672 -170.604688)
		(end 59.986418 -170.604688)
		(width 0.508)
		(layer "F.Cu")
		(net "P3V3_NODE1")
	)
	(segment
		(start 71.706486 -148.876512)
		(end 71.706486 -149.276816)
		(width 0.508)
		(layer "F.Cu")
		(net "P3V3_NODE1")
	)
	(segment
		(start 157.522164 -140.98016)
		(end 157.94736 -140.98016)
		(width 0.508)
		(layer "F.Cu")
		(net "P3V3_NODE1")
	)
	(segment
		(start 10.390632 -140.166344)
		(end 10.390632 -142.550642)
		(width 0.381)
		(layer "F.Cu")
		(net "P3V3_NODE1")
	)
	(segment
		(start 101.609398 -136.176258)
		(end 100.564188 -136.176258)
		(width 0.381)
		(layer "F.Cu")
		(net "P3V3_NODE1")
	)
	(segment
		(start 126.84887 -61.690758)
		(end 125.807978 -61.690758)
		(width 0.508)
		(layer "F.Cu")
		(net "P3V3_NODE1")
	)
	(segment
		(start 123.152916 -163.475416)
		(end 122.47372 -164.154612)
		(width 0.508)
		(layer "F.Cu")
		(net "P3V3_NODE1")
	)
	(segment
		(start 137.52576 -163.358576)
		(end 137.52576 -164.488876)
		(width 0.254)
		(layer "F.Cu")
		(net "P3V3_NODE1")
	)
	(segment
		(start 25.973278 -43.700446)
		(end 25.973278 -42.66057)
		(width 0.508)
		(layer "F.Cu")
		(net "P3V3_NODE1")
	)
	(segment
		(start 59.048396 -81.952846)
		(end 58.818018 -81.722468)
		(width 0.3048)
		(layer "F.Cu")
		(net "P3V3_NODE1")
	)
	(segment
		(start 110.72876 -171.609512)
		(end 111.47171 -171.609512)
		(width 0.508)
		(layer "F.Cu")
		(net "P3V3_NODE1")
	)
	(segment
		(start 160.269936 -157.647132)
		(end 160.269936 -158.706566)
		(width 0.254)
		(layer "F.Cu")
		(net "P3V3_NODE1")
	)
	(segment
		(start 85.34654 -135.025892)
		(end 86.358222 -135.025892)
		(width 0.508)
		(layer "F.Cu")
		(net "P3V3_NODE1")
	)
	(segment
		(start 95.047308 -121.038366)
		(end 93.977206 -121.038366)
		(width 0.4572)
		(layer "F.Cu")
		(net "P3V3_NODE1")
	)
	(segment
		(start 107.8738 -168.015666)
		(end 107.8738 -168.62044)
		(width 0.508)
		(layer "F.Cu")
		(net "P3V3_NODE1")
	)
	(segment
		(start 136.850374 -157.537658)
		(end 137.66292 -157.537658)
		(width 0.508)
		(layer "F.Cu")
		(net "P3V3_NODE1")
	)
	(segment
		(start 159.98317 -97.315528)
		(end 159.411162 -97.315528)
		(width 0.4572)
		(layer "F.Cu")
		(net "P3V3_NODE1")
	)
	(segment
		(start 137.193528 -60.704222)
		(end 136.264904 -60.704222)
		(width 0.508)
		(layer "F.Cu")
		(net "P3V3_NODE1")
	)
	(segment
		(start 166.211504 -166.388288)
		(end 167.0177 -166.388288)
		(width 0.381)
		(layer "F.Cu")
		(net "P3V3_NODE1")
	)
	(segment
		(start 164.843206 -104.839008)
		(end 164.843206 -105.84815)
		(width 0.1778)
		(layer "F.Cu")
		(net "P3V3_NODE1")
	)
	(segment
		(start 126.993142 -132.7785)
		(end 126.72568 -133.045962)
		(width 0.508)
		(layer "F.Cu")
		(net "P3V3_NODE1")
	)
	(segment
		(start 70.141846 -137.659618)
		(end 70.142354 -137.659618)
		(width 0.381)
		(layer "F.Cu")
		(net "P3V3_NODE1")
	)
	(segment
		(start 150.601172 -30.946344)
		(end 150.997666 -30.54985)
		(width 0.508)
		(layer "F.Cu")
		(net "P3V3_NODE1")
	)
	(segment
		(start 130.08864 -54.5084)
		(end 129.422906 -54.5084)
		(width 0.4572)
		(layer "F.Cu")
		(net "P3V3_NODE1")
	)
	(segment
		(start 137.52576 -181.106572)
		(end 137.52576 -180.98516)
		(width 0.508)
		(layer "F.Cu")
		(net "P3V3_NODE1")
	)
	(segment
		(start 106.924602 -171.600876)
		(end 106.9594 -171.600876)
		(width 0.508)
		(layer "F.Cu")
		(net "P3V3_NODE1")
	)
	(segment
		(start 135.777732 -161.79419)
		(end 135.716264 -161.855658)
		(width 0.254)
		(layer "F.Cu")
		(net "P3V3_NODE1")
	)
	(segment
		(start 64.541908 -130.45948)
		(end 64.541908 -130.458972)
		(width 0.381)
		(layer "F.Cu")
		(net "P3V3_NODE1")
	)
	(segment
		(start 49.142142 -171.703492)
		(end 49.355502 -171.490132)
		(width 0.508)
		(layer "F.Cu")
		(net "P3V3_NODE1")
	)
	(segment
		(start 83.866228 -133.963156)
		(end 85.390228 -133.963156)
		(width 0.508)
		(layer "F.Cu")
		(net "P3V3_NODE1")
	)
	(segment
		(start 174.015654 -202.782424)
		(end 173.61408 -202.38085)
		(width 0.508)
		(layer "F.Cu")
		(net "P3V3_NODE1")
	)
	(segment
		(start 59.195208 -150.350728)
		(end 59.527948 -150.683468)
		(width 0.508)
		(layer "F.Cu")
		(net "P3V3_NODE1")
	)
	(segment
		(start 44.16806 -122.566684)
		(end 43.8531 -122.251724)
		(width 0.381)
		(layer "F.Cu")
		(net "P3V3_NODE1")
	)
	(segment
		(start 128.560322 -174.667926)
		(end 128.619504 -174.608744)
		(width 0.508)
		(layer "F.Cu")
		(net "P3V3_NODE1")
	)
	(segment
		(start 156.239464 -172.230288)
		(end 156.614114 -172.604938)
		(width 0.508)
		(layer "F.Cu")
		(net "P3V3_NODE1")
	)
	(segment
		(start 52.623212 -147.546822)
		(end 53.23586 -147.546822)
		(width 0.508)
		(layer "F.Cu")
		(net "P3V3_NODE1")
	)
	(segment
		(start 71.21652 -175.623474)
		(end 72.244712 -175.623474)
		(width 0.254)
		(layer "F.Cu")
		(net "P3V3_NODE1")
	)
	(segment
		(start 56.964326 -160.226756)
		(end 56.964326 -158.351982)
		(width 0.508)
		(layer "F.Cu")
		(net "P3V3_NODE1")
	)
	(segment
		(start 128.029208 -52.145184)
		(end 126.80315 -52.145184)
		(width 0.508)
		(layer "F.Cu")
		(net "P3V3_NODE1")
	)
	(segment
		(start 128.13792 -135.825484)
		(end 128.13792 -134.601458)
		(width 0.1778)
		(layer "F.Cu")
		(net "P3V3_NODE1")
	)
	(segment
		(start 154.859228 -177.282856)
		(end 155.07716 -177.282856)
		(width 0.508)
		(layer "F.Cu")
		(net "P3V3_NODE1")
	)
	(segment
		(start 59.527948 -150.683468)
		(end 59.52998 -150.683468)
		(width 0.508)
		(layer "F.Cu")
		(net "P3V3_NODE1")
	)
	(segment
		(start 163.270184 -90.123772)
		(end 161.14776 -90.123772)
		(width 0.508)
		(layer "F.Cu")
		(net "P3V3_NODE1")
	)
	(segment
		(start 70.141846 -136.059418)
		(end 70.142354 -136.059418)
		(width 0.381)
		(layer "F.Cu")
		(net "P3V3_NODE1")
	)
	(segment
		(start 174.015654 -205.199488)
		(end 174.015654 -202.782424)
		(width 0.508)
		(layer "F.Cu")
		(net "P3V3_NODE1")
	)
	(segment
		(start 59.517026 -81.952846)
		(end 59.048396 -81.952846)
		(width 0.3048)
		(layer "F.Cu")
		(net "P3V3_NODE1")
	)
	(segment
		(start 118.244366 -161.670746)
		(end 119.110252 -160.80486)
		(width 0.508)
		(layer "F.Cu")
		(net "P3V3_NODE1")
	)
	(segment
		(start 81.90357 -87.979504)
		(end 81.230978 -87.979504)
		(width 0.508)
		(layer "F.Cu")
		(net "P3V3_NODE1")
	)
	(segment
		(start 107.385612 -163.715954)
		(end 107.600242 -163.930584)
		(width 0.4572)
		(layer "F.Cu")
		(net "P3V3_NODE1")
	)
	(segment
		(start 69.347334 -8.266684)
		(end 69.347334 -7.921244)
		(width 0.254)
		(layer "F.Cu")
		(net "P3V3_NODE1")
	)
	(segment
		(start 101.03866 -17.68094)
		(end 101.748082 -17.68094)
		(width 0.381)
		(layer "F.Cu")
		(net "P3V3_NODE1")
	)
	(segment
		(start 153.541222 -91.72956)
		(end 154.212798 -91.72956)
		(width 0.508)
		(layer "F.Cu")
		(net "P3V3_NODE1")
	)
	(segment
		(start 104.548432 -129.553716)
		(end 104.13619 -129.141474)
		(width 0.381)
		(layer "F.Cu")
		(net "P3V3_NODE1")
	)
	(segment
		(start 105.297732 -179.693824)
		(end 105.2957 -179.695856)
		(width 0.508)
		(layer "F.Cu")
		(net "P3V3_NODE1")
	)
	(segment
		(start 106.570526 -171.990512)
		(end 106.570526 -171.954952)
		(width 0.508)
		(layer "F.Cu")
		(net "P3V3_NODE1")
	)
	(segment
		(start 88.495886 -168.1226)
		(end 88.64346 -167.975026)
		(width 0.254)
		(layer "F.Cu")
		(net "P3V3_NODE1")
	)
	(segment
		(start 59.556142 -171.506642)
		(end 59.986418 -171.076366)
		(width 0.508)
		(layer "F.Cu")
		(net "P3V3_NODE1")
	)
	(segment
		(start 105.053638 -178.984656)
		(end 106.026458 -178.984656)
		(width 0.508)
		(layer "F.Cu")
		(net "P3V3_NODE1")
	)
	(segment
		(start 97.27184 -181.070504)
		(end 97.27184 -180.703474)
		(width 0.508)
		(layer "F.Cu")
		(net "P3V3_NODE1")
	)
	(segment
		(start 118.25732 -162.919918)
		(end 118.244366 -162.906964)
		(width 0.508)
		(layer "F.Cu")
		(net "P3V3_NODE1")
	)
	(segment
		(start 62.985142 -172.302424)
		(end 62.985142 -171.683426)
		(width 0.508)
		(layer "F.Cu")
		(net "P3V3_NODE1")
	)
	(segment
		(start 149.97811 -30.946344)
		(end 150.601172 -30.946344)
		(width 0.508)
		(layer "F.Cu")
		(net "P3V3_NODE1")
	)
	(segment
		(start 77.414882 -183.089042)
		(end 77.524102 -182.979822)
		(width 0.4572)
		(layer "F.Cu")
		(net "P3V3_NODE1")
	)
	(segment
		(start 149.277578 -56.849772)
		(end 149.277578 -56.064912)
		(width 0.508)
		(layer "F.Cu")
		(net "P3V3_NODE1")
	)
	(segment
		(start 77.994764 -164.374576)
		(end 77.994764 -162.628834)
		(width 0.254)
		(layer "F.Cu")
		(net "P3V3_NODE1")
	)
	(segment
		(start 95.047562 -124.721366)
		(end 95.047562 -123.958096)
		(width 0.4572)
		(layer "F.Cu")
		(net "P3V3_NODE1")
	)
	(segment
		(start 166.610538 -12.892024)
		(end 166.610538 -13.633958)
		(width 0.508)
		(layer "F.Cu")
		(net "P3V3_NODE1")
	)
	(segment
		(start 144.73047 -59.916822)
		(end 144.73047 -58.893456)
		(width 0.1778)
		(layer "F.Cu")
		(net "P3V3_NODE1")
	)
	(segment
		(start 61.339476 -136.859518)
		(end 60.94095 -137.258044)
		(width 0.381)
		(layer "F.Cu")
		(net "P3V3_NODE1")
	)
	(segment
		(start 133.766052 -153.87955)
		(end 133.49478 -153.608278)
		(width 0.4572)
		(layer "F.Cu")
		(net "P3V3_NODE1")
	)
	(segment
		(start 130.956812 -57.052972)
		(end 130.429 -57.052972)
		(width 0.4572)
		(layer "F.Cu")
		(net "P3V3_NODE1")
	)
	(segment
		(start 63.832486 -120.028462)
		(end 63.832486 -119.183912)
		(width 0.508)
		(layer "F.Cu")
		(net "P3V3_NODE1")
	)
	(segment
		(start 128.917954 -162.25012)
		(end 130.010408 -162.25012)
		(width 0.508)
		(layer "F.Cu")
		(net "P3V3_NODE1")
	)
	(segment
		(start 147.319746 -156.95422)
		(end 147.98548 -157.619954)
		(width 0.508)
		(layer "F.Cu")
		(net "P3V3_NODE1")
	)
	(segment
		(start 62.985142 -171.683426)
		(end 63.40348 -171.265088)
		(width 0.508)
		(layer "F.Cu")
		(net "P3V3_NODE1")
	)
	(segment
		(start 72.321166 -97.185988)
		(end 71.593456 -97.913698)
		(width 0.508)
		(layer "F.Cu")
		(net "P3V3_NODE1")
	)
	(segment
		(start 95.048578 -121.749566)
		(end 95.048578 -121.037096)
		(width 0.4572)
		(layer "F.Cu")
		(net "P3V3_NODE1")
	)
	(segment
		(start 80.131158 -180.790088)
		(end 79.99476 -180.65369)
		(width 0.254)
		(layer "F.Cu")
		(net "P3V3_NODE1")
	)
	(segment
		(start 53.962046 -157.982158)
		(end 54.763416 -157.982158)
		(width 0.508)
		(layer "F.Cu")
		(net "P3V3_NODE1")
	)
	(segment
		(start 171.14647 -99.735894)
		(end 172.462444 -99.735894)
		(width 0.1778)
		(layer "F.Cu")
		(net "P3V3_NODE1")
	)
	(segment
		(start 154.151076 -164.56533)
		(end 154.33548 -164.380926)
		(width 0.508)
		(layer "F.Cu")
		(net "P3V3_NODE1")
	)
	(segment
		(start 171.14647 -103.335836)
		(end 172.05198 -103.335836)
		(width 0.1778)
		(layer "F.Cu")
		(net "P3V3_NODE1")
	)
	(segment
		(start 151.494998 -142.48638)
		(end 151.494998 -141.7193)
		(width 0.508)
		(layer "F.Cu")
		(net "P3V3_NODE1")
	)
	(segment
		(start 72.244712 -175.623474)
		(end 72.244712 -175.624744)
		(width 0.254)
		(layer "F.Cu")
		(net "P3V3_NODE1")
	)
	(segment
		(start 150.293578 -56.849772)
		(end 150.293578 -56.15813)
		(width 0.508)
		(layer "F.Cu")
		(net "P3V3_NODE1")
	)
	(segment
		(start 96.153986 -172.268388)
		(end 96.466914 -172.581316)
		(width 0.508)
		(layer "F.Cu")
		(net "P3V3_NODE1")
	)
	(segment
		(start 56.884062 -118.571518)
		(end 56.884062 -117.7417)
		(width 0.508)
		(layer "F.Cu")
		(net "P3V3_NODE1")
	)
	(segment
		(start 51.439572 -171.011342)
		(end 51.820826 -170.630088)
		(width 0.508)
		(layer "F.Cu")
		(net "P3V3_NODE1")
	)
	(segment
		(start 70.209156 -175.577754)
		(end 71.1708 -175.577754)
		(width 0.254)
		(layer "F.Cu")
		(net "P3V3_NODE1")
	)
	(segment
		(start 20.413472 -128.115822)
		(end 20.618196 -127.911098)
		(width 0.508)
		(layer "F.Cu")
		(net "P3V3_NODE1")
	)
	(segment
		(start 93.85173 -123.959366)
		(end 93.528388 -123.959366)
		(width 0.2032)
		(layer "F.Cu")
		(net "P3V3_NODE1")
	)
	(segment
		(start 146.978878 -174.108618)
		(end 145.275808 -174.108618)
		(width 0.254)
		(layer "F.Cu")
		(net "P3V3_NODE1")
	)
	(segment
		(start 156.828998 -142.53718)
		(end 156.828998 -141.673326)
		(width 0.508)
		(layer "F.Cu")
		(net "P3V3_NODE1")
	)
	(segment
		(start 63.832486 -120.644412)
		(end 63.832486 -120.028462)
		(width 0.508)
		(layer "F.Cu")
		(net "P3V3_NODE1")
	)
	(segment
		(start 137.52576 -178.858672)
		(end 137.52576 -179.62753)
		(width 0.254)
		(layer "F.Cu")
		(net "P3V3_NODE1")
	)
	(segment
		(start 56.09463 -171.721018)
		(end 56.484266 -171.331382)
		(width 0.508)
		(layer "F.Cu")
		(net "P3V3_NODE1")
	)
	(segment
		(start 70.814946 -169.87393)
		(end 70.88886 -169.800016)
		(width 0.508)
		(layer "F.Cu")
		(net "P3V3_NODE1")
	)
	(segment
		(start 81.994756 -179.874672)
		(end 81.994756 -180.768244)
		(width 0.254)
		(layer "F.Cu")
		(net "P3V3_NODE1")
	)
	(segment
		(start 70.142354 -137.659618)
		(end 70.54215 -138.059414)
		(width 0.381)
		(layer "F.Cu")
		(net "P3V3_NODE1")
	)
	(segment
		(start 80.131158 -181.487064)
		(end 80.131158 -181.083204)
		(width 0.508)
		(layer "F.Cu")
		(net "P3V3_NODE1")
	)
	(segment
		(start 89.18194 -137.234676)
		(end 95.254064 -143.3068)
		(width 0.508)
		(layer "F.Cu")
		(net "P3V3_NODE1")
	)
	(segment
		(start 138.1379 -136.762998)
		(end 138.465052 -137.09015)
		(width 0.1778)
		(layer "F.Cu")
		(net "P3V3_NODE1")
	)
	(segment
		(start 42.363644 -145.37309)
		(end 42.363644 -144.540224)
		(width 0.508)
		(layer "F.Cu")
		(net "P3V3_NODE1")
	)
	(segment
		(start 10.657078 -138.946636)
		(end 10.657078 -139.899898)
		(width 0.381)
		(layer "F.Cu")
		(net "P3V3_NODE1")
	)
	(segment
		(start 157.302708 -161.59861)
		(end 156.583634 -161.59861)
		(width 0.508)
		(layer "F.Cu")
		(net "P3V3_NODE1")
	)
	(segment
		(start 101.748082 -19.049238)
		(end 101.748082 -17.68094)
		(width 0.381)
		(layer "F.Cu")
		(net "P3V3_NODE1")
	)
	(segment
		(start 25.391872 -95.061278)
		(end 25.967436 -95.061278)
		(width 0.508)
		(layer "F.Cu")
		(net "P3V3_NODE1")
	)
	(segment
		(start 87.744808 -168.124632)
		(end 87.744808 -168.1226)
		(width 0.254)
		(layer "F.Cu")
		(net "P3V3_NODE1")
	)
	(segment
		(start 88.438228 -134.581392)
		(end 87.93353 -135.08609)
		(width 0.508)
		(layer "F.Cu")
		(net "P3V3_NODE1")
	)
	(segment
		(start 93.245178 -120.641618)
		(end 92.416376 -120.641618)
		(width 0.2032)
		(layer "F.Cu")
		(net "P3V3_NODE1")
	)
	(segment
		(start 59.556142 -172.302424)
		(end 59.556142 -171.506642)
		(width 0.508)
		(layer "F.Cu")
		(net "P3V3_NODE1")
	)
	(segment
		(start 70.141846 -133.659626)
		(end 70.142608 -133.659626)
		(width 0.381)
		(layer "F.Cu")
		(net "P3V3_NODE1")
	)
	(segment
		(start 110.72876 -171.614084)
		(end 110.72876 -171.609512)
		(width 0.508)
		(layer "F.Cu")
		(net "P3V3_NODE1")
	)
	(segment
		(start 73.337166 -97.852992)
		(end 73.337166 -97.110042)
		(width 0.508)
		(layer "F.Cu")
		(net "P3V3_NODE1")
	)
	(segment
		(start 136.161272 -161.41065)
		(end 135.777732 -161.79419)
		(width 0.508)
		(layer "F.Cu")
		(net "P3V3_NODE1")
	)
	(segment
		(start 47.60214 -166.8399)
		(end 47.60214 -167.56507)
		(width 0.508)
		(layer "F.Cu")
		(net "P3V3_NODE1")
	)
	(segment
		(start 104.548432 -129.76098)
		(end 104.548432 -129.553716)
		(width 0.381)
		(layer "F.Cu")
		(net "P3V3_NODE1")
	)
	(segment
		(start 71.1708 -175.577754)
		(end 71.21652 -175.623474)
		(width 0.254)
		(layer "F.Cu")
		(net "P3V3_NODE1")
	)
	(segment
		(start 124.791216 -58.875422)
		(end 124.79528 -58.879486)
		(width 0.4572)
		(layer "F.Cu")
		(net "P3V3_NODE1")
	)
	(segment
		(start 155.116022 -172.550582)
		(end 155.116022 -172.550328)
		(width 0.508)
		(layer "F.Cu")
		(net "P3V3_NODE1")
	)
	(segment
		(start 87.93353 -135.08609)
		(end 87.921338 -135.073898)
		(width 0.508)
		(layer "F.Cu")
		(net "P3V3_NODE1")
	)
	(segment
		(start 147.676108 -173.878748)
		(end 147.676108 -174.250604)
		(width 0.508)
		(layer "F.Cu")
		(net "P3V3_NODE1")
	)
	(segment
		(start 172.05198 -103.335836)
		(end 172.223938 -103.507794)
		(width 0.1778)
		(layer "F.Cu")
		(net "P3V3_NODE1")
	)
	(segment
		(start 82.272378 -117.802406)
		(end 82.549746 -117.802406)
		(width 0.2032)
		(layer "F.Cu")
		(net "P3V3_NODE1")
	)
	(segment
		(start 89.443052 -179.610512)
		(end 89.35974 -179.5272)
		(width 0.381)
		(layer "F.Cu")
		(net "P3V3_NODE1")
	)
	(segment
		(start 4.911852 -151.77262)
		(end 5.487162 -152.34793)
		(width 0.508)
		(layer "F.Cu")
		(net "P3V3_NODE1")
	)
	(segment
		(start 164.843206 -105.84815)
		(end 164.717222 -105.974134)
		(width 0.1778)
		(layer "F.Cu")
		(net "P3V3_NODE1")
	)
	(segment
		(start 59.341004 -129.258822)
		(end 59.341004 -129.258314)
		(width 0.381)
		(layer "F.Cu")
		(net "P3V3_NODE1")
	)
	(segment
		(start 65.209166 -97.110042)
		(end 65.159128 -97.16008)
		(width 0.508)
		(layer "F.Cu")
		(net "P3V3_NODE1")
	)
	(segment
		(start 52.698142 -172.302424)
		(end 52.698142 -171.840652)
		(width 0.4572)
		(layer "F.Cu")
		(net "P3V3_NODE1")
	)
	(segment
		(start 147.676108 -174.250604)
		(end 147.11934 -174.250604)
		(width 0.254)
		(layer "F.Cu")
		(net "P3V3_NODE1")
	)
	(segment
		(start 133.26745 -60.530232)
		(end 133.26745 -59.630564)
		(width 0.508)
		(layer "F.Cu")
		(net "P3V3_NODE1")
	)
	(segment
		(start 66.414142 -172.302424)
		(end 66.414142 -171.628054)
		(width 0.508)
		(layer "F.Cu")
		(net "P3V3_NODE1")
	)
	(segment
		(start 9.758934 -156.657802)
		(end 9.758934 -158.220156)
		(width 0.381)
		(layer "F.Cu")
		(net "P3V3_NODE1")
	)
	(segment
		(start 50.263806 -170.491404)
		(end 49.933606 -170.821604)
		(width 0.508)
		(layer "F.Cu")
		(net "P3V3_NODE1")
	)
	(segment
		(start 137.338054 -151.32558)
		(end 137.338054 -149.901148)
		(width 0.1778)
		(layer "F.Cu")
		(net "P3V3_NODE1")
	)
	(segment
		(start 140.68933 -61.957966)
		(end 139.71016 -61.957966)
		(width 0.1778)
		(layer "F.Cu")
		(net "P3V3_NODE1")
	)
	(segment
		(start 122.901202 -137.03935)
		(end 122.901202 -136.73328)
		(width 0.508)
		(layer "F.Cu")
		(net "P3V3_NODE1")
	)
	(segment
		(start 147.11934 -174.250604)
		(end 146.978878 -174.110142)
		(width 0.254)
		(layer "F.Cu")
		(net "P3V3_NODE1")
	)
	(segment
		(start 111.47171 -172.625512)
		(end 111.47171 -171.609512)
		(width 0.508)
		(layer "F.Cu")
		(net "P3V3_NODE1")
	)
	(segment
		(start 106.570526 -166.848282)
		(end 107.194604 -166.848282)
		(width 0.508)
		(layer "F.Cu")
		(net "P3V3_NODE1")
	)
	(segment
		(start 7.18058 -153.73731)
		(end 7.18058 -152.957276)
		(width 0.508)
		(layer "F.Cu")
		(net "P3V3_NODE1")
	)
	(segment
		(start 69.46392 -149.292056)
		(end 69.46392 -149.657054)
		(width 0.508)
		(layer "F.Cu")
		(net "P3V3_NODE1")
	)
	(segment
		(start 56.191912 -99.95916)
		(end 57.207912 -99.95916)
		(width 0.508)
		(layer "F.Cu")
		(net "P3V3_NODE1")
	)
	(segment
		(start 156.470096 -149.347174)
		(end 155.881832 -149.347174)
		(width 0.254)
		(layer "F.Cu")
		(net "P3V3_NODE1")
	)
	(segment
		(start 29.21762 -98.546412)
		(end 29.72562 -99.054412)
		(width 0.508)
		(layer "F.Cu")
		(net "P3V3_NODE1")
	)
	(segment
		(start 71.706486 -149.276816)
		(end 72.046846 -149.617176)
		(width 0.508)
		(layer "F.Cu")
		(net "P3V3_NODE1")
	)
	(segment
		(start 185.731658 -127.0254)
		(end 184.810908 -127.0254)
		(width 0.508)
		(layer "F.Cu")
		(net "P3V3_NODE1")
	)
	(segment
		(start 90.40749 -175.418496)
		(end 90.202258 -175.418496)
		(width 0.254)
		(layer "F.Cu")
		(net "P3V3_NODE1")
	)
	(segment
		(start 111.47171 -170.593512)
		(end 110.626906 -170.593512)
		(width 0.508)
		(layer "F.Cu")
		(net "P3V3_NODE1")
	)
	(segment
		(start 42.76598 -121.35866)
		(end 43.8531 -121.35866)
		(width 0.508)
		(layer "F.Cu")
		(net "P3V3_NODE1")
	)
	(segment
		(start 149.462998 -141.610334)
		(end 149.48916 -141.584172)
		(width 0.508)
		(layer "F.Cu")
		(net "P3V3_NODE1")
	)
	(segment
		(start 164.355018 -167.658288)
		(end 162.796474 -167.658288)
		(width 0.508)
		(layer "F.Cu")
		(net "P3V3_NODE1")
	)
	(segment
		(start 88.438228 -133.963156)
		(end 88.438228 -134.581392)
		(width 0.508)
		(layer "F.Cu")
		(net "P3V3_NODE1")
	)
	(segment
		(start 15.997174 -16.660622)
		(end 15.997174 -17.706848)
		(width 0.508)
		(layer "F.Cu")
		(net "P3V3_NODE1")
	)
	(segment
		(start 166.100252 -93.44914)
		(end 166.100252 -92.68079)
		(width 0.508)
		(layer "F.Cu")
		(net "P3V3_NODE1")
	)
	(segment
		(start 52.698142 -171.840652)
		(end 52.255928 -171.398438)
		(width 0.4572)
		(layer "F.Cu")
		(net "P3V3_NODE1")
	)
	(segment
		(start 165.411404 -169.237152)
		(end 165.411404 -167.764968)
		(width 0.508)
		(layer "F.Cu")
		(net "P3V3_NODE1")
	)
	(segment
		(start 49.705768 -158.673038)
		(end 50.07102 -159.03829)
		(width 0.254)
		(layer "F.Cu")
		(net "P3V3_NODE1")
	)
	(segment
		(start 124.791216 -57.900062)
		(end 124.791216 -58.875422)
		(width 0.4572)
		(layer "F.Cu")
		(net "P3V3_NODE1")
	)
	(segment
		(start 81.306924 -120.347486)
		(end 81.306924 -120.807226)
		(width 0.4572)
		(layer "F.Cu")
		(net "P3V3_NODE1")
	)
	(segment
		(start 93.33992 -179.112926)
		(end 93.33992 -179.802536)
		(width 0.508)
		(layer "F.Cu")
		(net "P3V3_NODE1")
	)
	(segment
		(start 148.261578 -56.849772)
		(end 148.261578 -56.073548)
		(width 0.508)
		(layer "F.Cu")
		(net "P3V3_NODE1")
	)
	(segment
		(start 95.047562 -123.958096)
		(end 93.853 -123.958096)
		(width 0.4572)
		(layer "F.Cu")
		(net "P3V3_NODE1")
	)
	(segment
		(start 97.728532 -167.065706)
		(end 96.289622 -167.065706)
		(width 0.3556)
		(layer "F.Cu")
		(net "P3V3_NODE1")
	)
	(segment
		(start 82.02676 -182.011574)
		(end 82.02676 -181.3052)
		(width 0.508)
		(layer "F.Cu")
		(net "P3V3_NODE1")
	)
	(segment
		(start 107.052872 -171.507404)
		(end 107.244388 -171.507404)
		(width 0.508)
		(layer "F.Cu")
		(net "P3V3_NODE1")
	)
	(segment
		(start 148.23948 -158.194502)
		(end 148.717 -157.716982)
		(width 0.508)
		(layer "F.Cu")
		(net "P3V3_NODE1")
	)
	(segment
		(start 67.7418 -130.457448)
		(end 68.141088 -130.05816)
		(width 0.381)
		(layer "F.Cu")
		(net "P3V3_NODE1")
	)
	(segment
		(start 130.010408 -162.25012)
		(end 130.02514 -162.235388)
		(width 0.508)
		(layer "F.Cu")
		(net "P3V3_NODE1")
	)
	(segment
		(start 137.52576 -180.98516)
		(end 137.971022 -180.539898)
		(width 0.508)
		(layer "F.Cu")
		(net "P3V3_NODE1")
	)
	(segment
		(start 122.901202 -136.73328)
		(end 123.31954 -136.314942)
		(width 0.508)
		(layer "F.Cu")
		(net "P3V3_NODE1")
	)
	(segment
		(start 59.517026 -82.714846)
		(end 59.517026 -81.952846)
		(width 0.3048)
		(layer "F.Cu")
		(net "P3V3_NODE1")
	)
	(segment
		(start 97.663 -181.461664)
		(end 97.27184 -181.070504)
		(width 0.508)
		(layer "F.Cu")
		(net "P3V3_NODE1")
	)
	(segment
		(start 49.142142 -172.302424)
		(end 49.142142 -171.703492)
		(width 0.508)
		(layer "F.Cu")
		(net "P3V3_NODE1")
	)
	(segment
		(start 106.592116 -163.766754)
		(end 106.642916 -163.715954)
		(width 0.4572)
		(layer "F.Cu")
		(net "P3V3_NODE1")
	)
	(segment
		(start 147.07108 -167.1955)
		(end 147.068032 -167.1955)
		(width 0.4572)
		(layer "F.Cu")
		(net "P3V3_NODE1")
	)
	(segment
		(start 135.716264 -161.855658)
		(end 135.716264 -162.179762)
		(width 0.254)
		(layer "F.Cu")
		(net "P3V3_NODE1")
	)
	(segment
		(start 70.142354 -136.859518)
		(end 70.54215 -137.259314)
		(width 0.381)
		(layer "F.Cu")
		(net "P3V3_NODE1")
	)
	(segment
		(start 59.986418 -171.076366)
		(end 59.986418 -170.604688)
		(width 0.508)
		(layer "F.Cu")
		(net "P3V3_NODE1")
	)
	(segment
		(start 106.026458 -179.010056)
		(end 105.856532 -179.179982)
		(width 0.508)
		(layer "F.Cu")
		(net "P3V3_NODE1")
	)
	(segment
		(start 70.142354 -135.259572)
		(end 70.54215 -135.659368)
		(width 0.381)
		(layer "F.Cu")
		(net "P3V3_NODE1")
	)
	(segment
		(start 164.271198 -161.795968)
		(end 164.271198 -162.410902)
		(width 0.508)
		(layer "F.Cu")
		(net "P3V3_NODE1")
	)
	(segment
		(start 141.288008 -138.975592)
		(end 139.994894 -138.975592)
		(width 0.1778)
		(layer "F.Cu")
		(net "P3V3_NODE1")
	)
	(segment
		(start 81.94167 -120.807226)
		(end 82.275934 -121.14149)
		(width 0.4572)
		(layer "F.Cu")
		(net "P3V3_NODE1")
	)
	(segment
		(start 57.207912 -98.875342)
		(end 56.923432 -98.590862)
		(width 0.508)
		(layer "F.Cu")
		(net "P3V3_NODE1")
	)
	(segment
		(start 89.18194 -135.08609)
		(end 89.18194 -137.234676)
		(width 0.508)
		(layer "F.Cu")
		(net "P3V3_NODE1")
	)
	(segment
		(start 61.339476 -137.659618)
		(end 60.94095 -138.058144)
		(width 0.381)
		(layer "F.Cu")
		(net "P3V3_NODE1")
	)
	(segment
		(start 89.337388 -167.467026)
		(end 89.385394 -167.41902)
		(width 0.508)
		(layer "F.Cu")
		(net "P3V3_NODE1")
	)
	(segment
		(start 10.182098 -154.46375)
		(end 10.182098 -156.234638)
		(width 0.381)
		(layer "F.Cu")
		(net "P3V3_NODE1")
	)
	(segment
		(start 93.853 -123.958096)
		(end 93.85173 -123.959366)
		(width 0.2032)
		(layer "F.Cu")
		(net "P3V3_NODE1")
	)
	(segment
		(start 70.54215 -134.059168)
		(end 70.141846 -134.459472)
		(width 0.381)
		(layer "F.Cu")
		(net "P3V3_NODE1")
	)
	(segment
		(start 163.287202 -90.93454)
		(end 163.287202 -90.14079)
		(width 0.508)
		(layer "F.Cu")
		(net "P3V3_NODE1")
	)
	(segment
		(start 81.994756 -180.768244)
		(end 81.74228 -181.02072)
		(width 0.254)
		(layer "F.Cu")
		(net "P3V3_NODE1")
	)
	(segment
		(start 77.18298 -161.312352)
		(end 77.18298 -161.734246)
		(width 0.381)
		(layer "F.Cu")
		(net "P3V3_NODE1")
	)
	(segment
		(start 93.677486 -176.338992)
		(end 93.373956 -176.035462)
		(width 0.508)
		(layer "F.Cu")
		(net "P3V3_NODE1")
	)
	(segment
		(start 87.042498 -106.86161)
		(end 87.042498 -107.9119)
		(width 0.508)
		(layer "F.Cu")
		(net "P3V3_NODE1")
	)
	(segment
		(start 65.339468 -139.259564)
		(end 64.940942 -139.65809)
		(width 0.381)
		(layer "F.Cu")
		(net "P3V3_NODE1")
	)
	(segment
		(start 20.413472 -128.52908)
		(end 20.413472 -128.115822)
		(width 0.508)
		(layer "F.Cu")
		(net "P3V3_NODE1")
	)
	(segment
		(start 70.155054 -168.695624)
		(end 70.99427 -168.695624)
		(width 0.508)
		(layer "F.Cu")
		(net "P3V3_NODE1")
	)
	(segment
		(start 159.145732 -106.368596)
		(end 158.732728 -106.7816)
		(width 0.508)
		(layer "F.Cu")
		(net "P3V3_NODE1")
	)
	(segment
		(start 118.244366 -162.906964)
		(end 118.244366 -161.670746)
		(width 0.508)
		(layer "F.Cu")
		(net "P3V3_NODE1")
	)
	(segment
		(start 70.7009 -174.576486)
		(end 70.155054 -175.122332)
		(width 0.508)
		(layer "F.Cu")
		(net "P3V3_NODE1")
	)
	(segment
		(start 67.742308 -139.259564)
		(end 68.141088 -139.658344)
		(width 0.381)
		(layer "F.Cu")
		(net "P3V3_NODE1")
	)
	(segment
		(start 81.308702 -117.802406)
		(end 82.272378 -117.802406)
		(width 0.4572)
		(layer "F.Cu")
		(net "P3V3_NODE1")
	)
	(segment
		(start 126.552452 -154.0764)
		(end 126.552452 -154.18435)
		(width 0.4572)
		(layer "F.Cu")
		(net "P3V3_NODE1")
	)
	(segment
		(start 80.363568 -87.979504)
		(end 81.230978 -87.979504)
		(width 0.508)
		(layer "F.Cu")
		(net "P3V3_NODE1")
	)
	(segment
		(start 59.200796 -80.600042)
		(end 59.200796 -81.300066)
		(width 0.3048)
		(layer "F.Cu")
		(net "P3V3_NODE1")
	)
	(segment
		(start 56.09463 -172.302424)
		(end 56.09463 -171.721018)
		(width 0.508)
		(layer "F.Cu")
		(net "P3V3_NODE1")
	)
	(segment
		(start 165.411404 -167.764968)
		(end 164.461698 -167.764968)
		(width 0.508)
		(layer "F.Cu")
		(net "P3V3_NODE1")
	)
	(segment
		(start 20.413726 -63.672466)
		(end 21.604986 -63.672466)
		(width 0.508)
		(layer "F.Cu")
		(net "P3V3_NODE1")
	)
	(segment
		(start 156.614114 -172.604938)
		(end 156.779468 -172.604938)
		(width 0.508)
		(layer "F.Cu")
		(net "P3V3_NODE1")
	)
	(segment
		(start 124.93244 -165.231064)
		(end 125.04674 -165.231064)
		(width 0.508)
		(layer "F.Cu")
		(net "P3V3_NODE1")
	)
	(segment
		(start 76.92898 -161.058352)
		(end 77.18298 -161.312352)
		(width 0.381)
		(layer "F.Cu")
		(net "P3V3_NODE1")
	)
	(segment
		(start 146.93646 -167.108632)
		(end 147.04568 -167.217852)
		(width 0.254)
		(layer "F.Cu")
		(net "P3V3_NODE1")
	)
	(segment
		(start 28.898596 -98.546412)
		(end 29.21762 -98.546412)
		(width 0.508)
		(layer "F.Cu")
		(net "P3V3_NODE1")
	)
	(segment
		(start 7.65556 -137.081768)
		(end 7.7089 -137.028428)
		(width 0.508)
		(layer "F.Cu")
		(net "P3V3_NODE1")
	)
	(segment
		(start 93.001084 -123.641866)
		(end 93.00083 -123.641612)
		(width 0.2032)
		(layer "F.Cu")
		(net "P3V3_NODE1")
	)
	(segment
		(start 65.341754 -130.458972)
		(end 64.940942 -130.05816)
		(width 0.381)
		(layer "F.Cu")
		(net "P3V3_NODE1")
	)
	(segment
		(start 90.41257 -179.610512)
		(end 89.443052 -179.610512)
		(width 0.381)
		(layer "F.Cu")
		(net "P3V3_NODE1")
	)
	(segment
		(start 137.025634 -160.648904)
		(end 136.161272 -160.648904)
		(width 0.508)
		(layer "F.Cu")
		(net "P3V3_NODE1")
	)
	(segment
		(start 89.856564 -167.975026)
		(end 90.41257 -167.41902)
		(width 0.254)
		(layer "F.Cu")
		(net "P3V3_NODE1")
	)
	(segment
		(start 64.539622 -139.259564)
		(end 64.141096 -139.65809)
		(width 0.381)
		(layer "F.Cu")
		(net "P3V3_NODE1")
	)
	(segment
		(start 157.101794 -103.5939)
		(end 157.229556 -103.721662)
		(width 0.4064)
		(layer "F.Cu")
		(net "P3V3_NODE1")
	)
	(segment
		(start 94.051882 -175.322992)
		(end 93.343984 -175.322992)
		(width 0.508)
		(layer "F.Cu")
		(net "P3V3_NODE1")
	)
	(segment
		(start 102.487984 -180.74767)
		(end 102.487984 -181.31409)
		(width 0.508)
		(layer "F.Cu")
		(net "P3V3_NODE1")
	)
	(segment
		(start 59.517026 -83.476846)
		(end 59.517026 -83.472782)
		(width 0.3048)
		(layer "F.Cu")
		(net "P3V3_NODE1")
	)
	(segment
		(start 137.193528 -61.720222)
		(end 136.390888 -61.720222)
		(width 0.508)
		(layer "F.Cu")
		(net "P3V3_NODE1")
	)
	(segment
		(start 72.046846 -149.617176)
		(end 72.0471 -149.617176)
		(width 0.508)
		(layer "F.Cu")
		(net "P3V3_NODE1")
	)
	(segment
		(start 61.341762 -137.659618)
		(end 61.339476 -137.659618)
		(width 0.381)
		(layer "F.Cu")
		(net "P3V3_NODE1")
	)
	(segment
		(start 108.6866 -172.646086)
		(end 108.6866 -173.519846)
		(width 0.508)
		(layer "F.Cu")
		(net "P3V3_NODE1")
	)
	(segment
		(start 94.051882 -176.338992)
		(end 93.677486 -176.338992)
		(width 0.508)
		(layer "F.Cu")
		(net "P3V3_NODE1")
	)
	(segment
		(start 155.685998 -140.835634)
		(end 155.685998 -142.53718)
		(width 0.508)
		(layer "F.Cu")
		(net "P3V3_NODE1")
	)
	(segment
		(start 125.8062 -62.438534)
		(end 125.8062 -61.690758)
		(width 0.508)
		(layer "F.Cu")
		(net "P3V3_NODE1")
	)
	(segment
		(start 93.641926 -121.038366)
		(end 93.245178 -120.641618)
		(width 0.2032)
		(layer "F.Cu")
		(net "P3V3_NODE1")
	)
	(segment
		(start 85.626956 -87.236554)
		(end 82.64652 -87.236554)
		(width 0.508)
		(layer "F.Cu")
		(net "P3V3_NODE1")
	)
	(segment
		(start 135.525764 -162.370262)
		(end 135.525764 -163.358576)
		(width 0.254)
		(layer "F.Cu")
		(net "P3V3_NODE1")
	)
	(segment
		(start 172.223938 -103.507794)
		(end 172.355256 -103.507794)
		(width 0.1778)
		(layer "F.Cu")
		(net "P3V3_NODE1")
	)
	(segment
		(start 111.471202 -166.52113)
		(end 110.736888 -166.52113)
		(width 0.508)
		(layer "F.Cu")
		(net "P3V3_NODE1")
	)
	(segment
		(start 147.319746 -156.515816)
		(end 147.319746 -156.95422)
		(width 0.508)
		(layer "F.Cu")
		(net "P3V3_NODE1")
	)
	(segment
		(start 86.324186 -86.539324)
		(end 85.626956 -87.236554)
		(width 0.508)
		(layer "F.Cu")
		(net "P3V3_NODE1")
	)
	(segment
		(start 158.732728 -106.7816)
		(end 157.835346 -106.7816)
		(width 0.508)
		(layer "F.Cu")
		(net "P3V3_NODE1")
	)
	(segment
		(start 141.288008 -140.175488)
		(end 140.23594 -140.175488)
		(width 0.1778)
		(layer "F.Cu")
		(net "P3V3_NODE1")
	)
	(segment
		(start 89.962228 -134.305802)
		(end 89.18194 -135.08609)
		(width 0.508)
		(layer "F.Cu")
		(net "P3V3_NODE1")
	)
	(segment
		(start 139.280138 -69.662548)
		(end 140.040614 -69.662548)
		(width 0.508)
		(layer "F.Cu")
		(net "P3V3_NODE1")
	)
	(segment
		(start 64.541908 -139.259564)
		(end 64.539622 -139.259564)
		(width 0.381)
		(layer "F.Cu")
		(net "P3V3_NODE1")
	)
	(segment
		(start 51.03114 -164.2999)
		(end 51.03114 -165.13937)
		(width 0.508)
		(layer "F.Cu")
		(net "P3V3_NODE1")
	)
	(segment
		(start 137.807192 -180.376068)
		(end 137.971022 -180.539898)
		(width 0.254)
		(layer "F.Cu")
		(net "P3V3_NODE1")
	)
	(segment
		(start 69.547486 -148.876512)
		(end 69.547486 -149.20849)
		(width 0.508)
		(layer "F.Cu")
		(net "P3V3_NODE1")
	)
	(segment
		(start 19.543776 -101.069902)
		(end 18.762472 -101.069902)
		(width 0.508)
		(layer "F.Cu")
		(net "P3V3_NODE1")
	)
	(segment
		(start 163.255198 -161.795968)
		(end 163.255198 -162.410902)
		(width 0.508)
		(layer "F.Cu")
		(net "P3V3_NODE1")
	)
	(segment
		(start 151.202644 -30.54985)
		(end 151.21763 -30.534864)
		(width 0.508)
		(layer "F.Cu")
		(net "P3V3_NODE1")
	)
	(segment
		(start 129.422906 -54.5084)
		(end 129.352802 -54.578504)
		(width 0.4572)
		(layer "F.Cu")
		(net "P3V3_NODE1")
	)
	(segment
		(start 141.288008 -144.97558)
		(end 140.257022 -144.97558)
		(width 0.1778)
		(layer "F.Cu")
		(net "P3V3_NODE1")
	)
	(segment
		(start 88.158066 -104.128062)
		(end 88.158066 -103.859584)
		(width 0.508)
		(layer "F.Cu")
		(net "P3V3_NODE1")
	)
	(segment
		(start 79.971392 -162.450272)
		(end 79.971392 -163.06165)
		(width 0.508)
		(layer "F.Cu")
		(net "P3V3_NODE1")
	)
	(segment
		(start 70.99427 -168.695624)
		(end 71.06539 -168.624504)
		(width 0.508)
		(layer "F.Cu")
		(net "P3V3_NODE1")
	)
	(segment
		(start 97.728532 -172.832268)
		(end 96.717866 -172.832268)
		(width 0.3556)
		(layer "F.Cu")
		(net "P3V3_NODE1")
	)
	(segment
		(start 106.570526 -173.004988)
		(end 106.570526 -171.990512)
		(width 0.508)
		(layer "F.Cu")
		(net "P3V3_NODE1")
	)
	(segment
		(start 44.548044 -145.39849)
		(end 44.548044 -144.675606)
		(width 0.508)
		(layer "F.Cu")
		(net "P3V3_NODE1")
	)
	(segment
		(start 106.642916 -163.715954)
		(end 107.385612 -163.715954)
		(width 0.4572)
		(layer "F.Cu")
		(net "P3V3_NODE1")
	)
	(segment
		(start 149.108922 -33.586928)
		(end 148.292566 -33.586928)
		(width 0.508)
		(layer "F.Cu")
		(net "P3V3_NODE1")
	)
	(segment
		(start 87.921338 -135.073898)
		(end 86.406228 -135.073898)
		(width 0.508)
		(layer "F.Cu")
		(net "P3V3_NODE1")
	)
	(segment
		(start 126.552452 -154.18435)
		(end 127.024892 -154.65679)
		(width 0.4572)
		(layer "F.Cu")
		(net "P3V3_NODE1")
	)
	(segment
		(start 50.50663 -95.486728)
		(end 50.276252 -95.717106)
		(width 0.508)
		(layer "F.Cu")
		(net "P3V3_NODE1")
	)
	(segment
		(start 151.804116 -150.14067)
		(end 151.485854 -149.822408)
		(width 0.508)
		(layer "F.Cu")
		(net "P3V3_NODE1")
	)
	(segment
		(start 81.308702 -116.320062)
		(end 81.308702 -117.802406)
		(width 0.4572)
		(layer "F.Cu")
		(net "P3V3_NODE1")
	)
	(segment
		(start 103.103172 -179.363624)
		(end 104.67467 -179.363624)
		(width 0.508)
		(layer "F.Cu")
		(net "P3V3_NODE1")
	)
	(segment
		(start 95.048578 -121.037096)
		(end 95.047308 -121.038366)
		(width 0.4572)
		(layer "F.Cu")
		(net "P3V3_NODE1")
	)
	(segment
		(start 127.517652 -132.7785)
		(end 126.993142 -132.7785)
		(width 0.508)
		(layer "F.Cu")
		(net "P3V3_NODE1")
	)
	(segment
		(start 139.68476 -181.106572)
		(end 139.455398 -181.106572)
		(width 0.4572)
		(layer "F.Cu")
		(net "P3V3_NODE1")
	)
	(segment
		(start 52.799996 -76.599542)
		(end 52.399946 -76.999592)
		(width 0.3048)
		(layer "F.Cu")
		(net "P3V3_NODE1")
	)
	(segment
		(start 72.244712 -168.624504)
		(end 71.06539 -168.624504)
		(width 0.254)
		(layer "F.Cu")
		(net "P3V3_NODE1")
	)
	(segment
		(start 4.225036 -155.388056)
		(end 4.0259 -155.18892)
		(width 0.381)
		(layer "F.Cu")
		(net "P3V3_NODE1")
	)
	(segment
		(start 154.151076 -165.245288)
		(end 154.151076 -164.56533)
		(width 0.508)
		(layer "F.Cu")
		(net "P3V3_NODE1")
	)
	(segment
		(start 106.826558 -176.965102)
		(end 107.45597 -176.965102)
		(width 0.508)
		(layer "F.Cu")
		(net "P3V3_NODE1")
	)
	(segment
		(start 133.766052 -154.4447)
		(end 133.766052 -153.87955)
		(width 0.4572)
		(layer "F.Cu")
		(net "P3V3_NODE1")
	)
	(segment
		(start 10.182098 -156.234638)
		(end 9.758934 -156.657802)
		(width 0.381)
		(layer "F.Cu")
		(net "P3V3_NODE1")
	)
	(segment
		(start 163.565078 -12.87145)
		(end 163.565078 -13.636752)
		(width 0.508)
		(layer "F.Cu")
		(net "P3V3_NODE1")
	)
	(segment
		(start 57.195466 -162.328606)
		(end 57.195466 -163.223956)
		(width 0.508)
		(layer "F.Cu")
		(net "P3V3_NODE1")
	)
	(segment
		(start 107.8738 -168.62044)
		(end 108.2294 -168.97604)
		(width 0.508)
		(layer "F.Cu")
		(net "P3V3_NODE1")
	)
	(segment
		(start 82.549746 -117.802406)
		(end 82.888836 -118.141496)
		(width 0.2032)
		(layer "F.Cu")
		(net "P3V3_NODE1")
	)
	(segment
		(start 91.486228 -134.424674)
		(end 90.978228 -134.932674)
		(width 0.508)
		(layer "F.Cu")
		(net "P3V3_NODE1")
	)
	(segment
		(start 15.138146 -18.565876)
		(end 15.138146 -20.20316)
		(width 0.381)
		(layer "F.Cu")
		(net "P3V3_NODE1")
	)
	(segment
		(start 94.851982 -172.268388)
		(end 96.153986 -172.268388)
		(width 0.508)
		(layer "F.Cu")
		(net "P3V3_NODE1")
	)
	(segment
		(start 111.471202 -165.50513)
		(end 111.471202 -166.52113)
		(width 0.508)
		(layer "F.Cu")
		(net "P3V3_NODE1")
	)
	(segment
		(start 159.608012 -98.178366)
		(end 159.287972 -97.858326)
		(width 0.4572)
		(layer "F.Cu")
		(net "P3V3_NODE1")
	)
	(segment
		(start 88.696292 -175.124618)
		(end 88.80094 -175.01997)
		(width 0.254)
		(layer "F.Cu")
		(net "P3V3_NODE1")
	)
	(segment
		(start 51.820826 -170.630088)
		(end 52.255928 -170.630088)
		(width 0.508)
		(layer "F.Cu")
		(net "P3V3_NODE1")
	)
	(segment
		(start 101.748082 -17.68094)
		(end 101.749606 -17.68094)
		(width 0.381)
		(layer "F.Cu")
		(net "P3V3_NODE1")
	)
	(segment
		(start 93.33992 -179.802536)
		(end 94.27718 -180.739796)
		(width 0.508)
		(layer "F.Cu")
		(net "P3V3_NODE1")
	)
	(segment
		(start 8.19658 -153.187908)
		(end 8.41756 -152.966928)
		(width 0.508)
		(layer "F.Cu")
		(net "P3V3_NODE1")
	)
	(segment
		(start 106.592116 -163.767516)
		(end 106.592116 -163.766754)
		(width 0.4572)
		(layer "F.Cu")
		(net "P3V3_NODE1")
	)
	(segment
		(start 63.40348 -170.630088)
		(end 63.40475 -170.630088)
		(width 0.508)
		(layer "F.Cu")
		(net "P3V3_NODE1")
	)
	(segment
		(start 125.464316 -63.648336)
		(end 125.464316 -62.780418)
		(width 0.508)
		(layer "F.Cu")
		(net "P3V3_NODE1")
	)
	(segment
		(start 66.891408 -8.501888)
		(end 69.11213 -8.501888)
		(width 0.254)
		(layer "F.Cu")
		(net "P3V3_NODE1")
	)
	(segment
		(start 77.994764 -162.628834)
		(end 78.123796 -162.499802)
		(width 0.254)
		(layer "F.Cu")
		(net "P3V3_NODE1")
	)
	(segment
		(start 139.455398 -181.106572)
		(end 139.075668 -180.726842)
		(width 0.4572)
		(layer "F.Cu")
		(net "P3V3_NODE1")
	)
	(segment
		(start 20.12569 -132.360416)
		(end 20.73529 -132.360416)
		(width 0.4572)
		(layer "F.Cu")
		(net "P3V3_NODE1")
	)
	(segment
		(start 91.486228 -133.963156)
		(end 91.486228 -134.424674)
		(width 0.508)
		(layer "F.Cu")
		(net "P3V3_NODE1")
	)
	(segment
		(start 124.10821 -169.571416)
		(end 124.725176 -169.571416)
		(width 0.508)
		(layer "F.Cu")
		(net "P3V3_NODE1")
	)
	(segment
		(start 157.971998 -142.53718)
		(end 157.971998 -141.802104)
		(width 0.508)
		(layer "F.Cu")
		(net "P3V3_NODE1")
	)
	(segment
		(start 10.182098 -153.749502)
		(end 10.182098 -154.46375)
		(width 0.508)
		(layer "F.Cu")
		(net "P3V3_NODE1")
	)
	(segment
		(start 65.159128 -97.16008)
		(end 65.159128 -97.76333)
		(width 0.508)
		(layer "F.Cu")
		(net "P3V3_NODE1")
	)
	(segment
		(start 108.27258 -164.1094)
		(end 108.27258 -164.109146)
		(width 0.508)
		(layer "F.Cu")
		(net "P3V3_NODE1")
	)
	(segment
		(start 124.10821 -164.491416)
		(end 124.192792 -164.491416)
		(width 0.508)
		(layer "F.Cu")
		(net "P3V3_NODE1")
	)
	(segment
		(start 140.257022 -144.97558)
		(end 140.014452 -145.21815)
		(width 0.1778)
		(layer "F.Cu")
		(net "P3V3_NODE1")
	)
	(segment
		(start 25.967436 -95.061278)
		(end 26.200354 -94.82836)
		(width 0.508)
		(layer "F.Cu")
		(net "P3V3_NODE1")
	)
	(segment
		(start 10.657078 -138.003534)
		(end 10.657078 -138.946636)
		(width 0.508)
		(layer "F.Cu")
		(net "P3V3_NODE1")
	)
	(segment
		(start 41.347644 -145.37309)
		(end 41.347644 -144.424146)
		(width 0.508)
		(layer "F.Cu")
		(net "P3V3_NODE1")
	)
	(segment
		(start 143.310102 -135.18515)
		(end 144.143222 -135.18515)
		(width 0.508)
		(layer "F.Cu")
		(net "P3V3_NODE1")
	)
	(segment
		(start 94.051882 -176.338992)
		(end 94.051882 -175.322992)
		(width 0.508)
		(layer "F.Cu")
		(net "P3V3_NODE1")
	)
	(segment
		(start 157.800802 -172.604938)
		(end 158.098236 -172.902372)
		(width 0.381)
		(layer "F.Cu")
		(net "P3V3_NODE1")
	)
	(segment
		(start 81.306924 -120.807226)
		(end 81.94167 -120.807226)
		(width 0.4572)
		(layer "F.Cu")
		(net "P3V3_NODE1")
	)
	(segment
		(start 93.210888 -123.641866)
		(end 93.001084 -123.641866)
		(width 0.2032)
		(layer "F.Cu")
		(net "P3V3_NODE1")
	)
	(segment
		(start 148.440902 -142.09903)
		(end 148.440902 -143.052292)
		(width 0.4572)
		(layer "F.Cu")
		(net "P3V3_NODE1")
	)
	(segment
		(start 164.112702 -88.84539)
		(end 164.804852 -88.84539)
		(width 0.508)
		(layer "F.Cu")
		(net "P3V3_NODE1")
	)
	(segment
		(start 122.321828 -164.306504)
		(end 122.47372 -164.154612)
		(width 0.3556)
		(layer "F.Cu")
		(net "P3V3_NODE1")
	)
	(segment
		(start 155.926028 -176.483772)
		(end 156.412184 -176.483772)
		(width 0.508)
		(layer "F.Cu")
		(net "P3V3_NODE1")
	)
	(segment
		(start 149.792944 -45.70857)
		(end 150.692358 -45.70857)
		(width 0.508)
		(layer "F.Cu")
		(net "P3V3_NODE1")
	)
	(segment
		(start 81.624678 -116.004086)
		(end 81.308702 -116.320062)
		(width 0.4572)
		(layer "F.Cu")
		(net "P3V3_NODE1")
	)
	(segment
		(start 49.117504 -158.673038)
		(end 49.705768 -158.673038)
		(width 0.254)
		(layer "F.Cu")
		(net "P3V3_NODE1")
	)
	(segment
		(start 108.22559 -173.980856)
		(end 108.22559 -174.098458)
		(width 0.508)
		(layer "F.Cu")
		(net "P3V3_NODE1")
	)
	(segment
		(start 61.341762 -136.859518)
		(end 61.339476 -136.859518)
		(width 0.381)
		(layer "F.Cu")
		(net "P3V3_NODE1")
	)
	(segment
		(start 129.775712 -174.608744)
		(end 128.619504 -174.608744)
		(width 0.254)
		(layer "F.Cu")
		(net "P3V3_NODE1")
	)
	(segment
		(start 102.24516 -180.504846)
		(end 102.487984 -180.74767)
		(width 0.508)
		(layer "F.Cu")
		(net "P3V3_NODE1")
	)
	(segment
		(start 125.97384 -161.91357)
		(end 125.97384 -163.002976)
		(width 0.508)
		(layer "F.Cu")
		(net "P3V3_NODE1")
	)
	(segment
		(start 125.21057 -26.169366)
		(end 125.21057 -25.25776)
		(width 0.508)
		(layer "F.Cu")
		(net "P3V3_NODE1")
	)
	(segment
		(start 40.817546 -150.37308)
		(end 40.817546 -149.327616)
		(width 0.254)
		(layer "F.Cu")
		(net "P3V3_NODE1")
	)
	(segment
		(start 4.70916 -151.57196)
		(end 4.90982 -151.77262)
		(width 0.508)
		(layer "F.Cu")
		(net "P3V3_NODE1")
	)
	(segment
		(start 48.74514 -164.2999)
		(end 48.74514 -165.11397)
		(width 0.508)
		(layer "F.Cu")
		(net "P3V3_NODE1")
	)
	(segment
		(start 89.962228 -107.123738)
		(end 90.2335 -106.852466)
		(width 0.508)
		(layer "F.Cu")
		(net "P3V3_NODE1")
	)
	(segment
		(start 87.744808 -168.1226)
		(end 88.495886 -168.1226)
		(width 0.254)
		(layer "F.Cu")
		(net "P3V3_NODE1")
	)
	(segment
		(start 86.914228 -134.565898)
		(end 86.406228 -135.073898)
		(width 0.508)
		(layer "F.Cu")
		(net "P3V3_NODE1")
	)
	(segment
		(start 102.150164 -20.94992)
		(end 102.150164 -19.45132)
		(width 0.381)
		(layer "F.Cu")
		(net "P3V3_NODE1")
	)
	(segment
		(start 76.166218 -183.15432)
		(end 76.628498 -183.15432)
		(width 0.4572)
		(layer "F.Cu")
		(net "P3V3_NODE1")
	)
	(segment
		(start 159.287972 -97.858326)
		(end 159.287972 -97.487486)
		(width 0.4572)
		(layer "F.Cu")
		(net "P3V3_NODE1")
	)
	(segment
		(start 139.525756 -179.625244)
		(end 139.075668 -180.075332)
		(width 0.254)
		(layer "F.Cu")
		(net "P3V3_NODE1")
	)
	(segment
		(start 87.744808 -175.124618)
		(end 88.696292 -175.124618)
		(width 0.254)
		(layer "F.Cu")
		(net "P3V3_NODE1")
	)
	(segment
		(start 59.200796 -81.33969)
		(end 58.818018 -81.722468)
		(width 0.3048)
		(layer "F.Cu")
		(net "P3V3_NODE1")
	)
	(segment
		(start 147.722844 -167.093392)
		(end 147.17014 -167.093392)
		(width 0.4572)
		(layer "F.Cu")
		(net "P3V3_NODE1")
	)
	(segment
		(start 73.326498 -97.86366)
		(end 73.337166 -97.852992)
		(width 0.508)
		(layer "F.Cu")
		(net "P3V3_NODE1")
	)
	(segment
		(start 73.442068 -94.531942)
		(end 73.442068 -94.648782)
		(width 0.508)
		(layer "F.Cu")
		(net "P3V3_NODE1")
	)
	(segment
		(start 111.47171 -169.577512)
		(end 110.85703 -169.577512)
		(width 0.508)
		(layer "F.Cu")
		(net "P3V3_NODE1")
	)
	(segment
		(start 76.628498 -183.15432)
		(end 76.693776 -183.089042)
		(width 0.4572)
		(layer "F.Cu")
		(net "P3V3_NODE1")
	)
	(segment
		(start 147.98548 -158.194502)
		(end 148.23948 -158.194502)
		(width 0.508)
		(layer "F.Cu")
		(net "P3V3_NODE1")
	)
	(segment
		(start 148.458682 -141.02969)
		(end 148.458682 -140.50518)
		(width 0.4572)
		(layer "F.Cu")
		(net "P3V3_NODE1")
	)
	(segment
		(start 85.390228 -134.982204)
		(end 85.34654 -135.025892)
		(width 0.508)
		(layer "F.Cu")
		(net "P3V3_NODE1")
	)
	(segment
		(start 159.287972 -97.487486)
		(end 159.263588 -97.463102)
		(width 0.4572)
		(layer "F.Cu")
		(net "P3V3_NODE1")
	)
	(segment
		(start 6.64083 -138.232134)
		(end 7.643622 -138.232134)
		(width 0.508)
		(layer "F.Cu")
		(net "P3V3_NODE1")
	)
	(segment
		(start 8.34644 -136.389364)
		(end 8.69696 -136.389364)
		(width 0.508)
		(layer "F.Cu")
		(net "P3V3_NODE1")
	)
	(segment
		(start 173.61408 -202.38085)
		(end 173.61408 -201.18832)
		(width 0.508)
		(layer "F.Cu")
		(net "P3V3_NODE1")
	)
	(segment
		(start 79.99476 -181.623462)
		(end 80.131158 -181.487064)
		(width 0.508)
		(layer "F.Cu")
		(net "P3V3_NODE1")
	)
	(segment
		(start 59.200796 -81.300066)
		(end 59.200796 -81.33969)
		(width 0.3048)
		(layer "F.Cu")
		(net "P3V3_NODE1")
	)
	(segment
		(start 159.411162 -97.315528)
		(end 159.263588 -97.463102)
		(width 0.4572)
		(layer "F.Cu")
		(net "P3V3_NODE1")
	)
	(segment
		(start 130.08102 -154.696668)
		(end 129.48031 -154.696668)
		(width 0.508)
		(layer "F.Cu")
		(net "P3V3_NODE1")
	)
	(segment
		(start 67.7418 -139.259564)
		(end 67.742308 -139.259564)
		(width 0.381)
		(layer "F.Cu")
		(net "P3V3_NODE1")
	)
	(segment
		(start 141.530578 -68.799202)
		(end 141.530578 -69.806312)
		(width 0.1778)
		(layer "F.Cu")
		(net "P3V3_NODE1")
	)
	(segment
		(start 93.977206 -121.038366)
		(end 93.641926 -121.038366)
		(width 0.2032)
		(layer "F.Cu")
		(net "P3V3_NODE1")
	)
	(segment
		(start 105.462832 -179.485798)
		(end 105.462832 -179.516278)
		(width 0.508)
		(layer "F.Cu")
		(net "P3V3_NODE1")
	)
	(segment
		(start 147.31492 -173.51756)
		(end 147.676108 -173.878748)
		(width 0.508)
		(layer "F.Cu")
		(net "P3V3_NODE1")
	)
	(segment
		(start 96.717866 -172.832268)
		(end 96.466914 -172.581316)
		(width 0.3556)
		(layer "F.Cu")
		(net "P3V3_NODE1")
	)
	(segment
		(start 86.358222 -135.025892)
		(end 86.406228 -135.073898)
		(width 0.508)
		(layer "F.Cu")
		(net "P3V3_NODE1")
	)
	(segment
		(start 154.212798 -91.72956)
		(end 154.509724 -91.432634)
		(width 0.508)
		(layer "F.Cu")
		(net "P3V3_NODE1")
	)
	(segment
		(start 87.042498 -107.9119)
		(end 88.102948 -107.9119)
		(width 0.508)
		(layer "F.Cu")
		(net "P3V3_NODE1")
	)
	(segment
		(start 51.121818 -98.144584)
		(end 51.121818 -96.562672)
		(width 0.381)
		(layer "F.Cu")
		(net "P3V3_NODE1")
	)
	(segment
		(start 144.73047 -58.893456)
		(end 144.747996 -58.87593)
		(width 0.1778)
		(layer "F.Cu")
		(net "P3V3_NODE1")
	)
	(segment
		(start 131.366006 -57.462166)
		(end 130.956812 -57.052972)
		(width 0.4572)
		(layer "F.Cu")
		(net "P3V3_NODE1")
	)
	(segment
		(start 70.639686 -149.666452)
		(end 70.639686 -148.876512)
		(width 0.508)
		(layer "F.Cu")
		(net "P3V3_NODE1")
	)
	(segment
		(start 7.643622 -138.232134)
		(end 7.65556 -138.220196)
		(width 0.508)
		(layer "F.Cu")
		(net "P3V3_NODE1")
	)
	(segment
		(start 45.532802 -144.634712)
		(end 45.65396 -144.513554)
		(width 0.508)
		(layer "F.Cu")
		(net "P3V3_NODE1")
	)
	(segment
		(start 77.948536 -162.499802)
		(end 78.123796 -162.499802)
		(width 0.381)
		(layer "F.Cu")
		(net "P3V3_NODE1")
	)
	(segment
		(start 7.7089 -137.026904)
		(end 8.34644 -136.389364)
		(width 0.508)
		(layer "F.Cu")
		(net "P3V3_NODE1")
	)
	(segment
		(start 77.18298 -161.734246)
		(end 77.948536 -162.499802)
		(width 0.381)
		(layer "F.Cu")
		(net "P3V3_NODE1")
	)
	(segment
		(start 146.978878 -174.110142)
		(end 146.978878 -174.108618)
		(width 0.254)
		(layer "F.Cu")
		(net "P3V3_NODE1")
	)
	(segment
		(start 145.275808 -167.108632)
		(end 146.93646 -167.108632)
		(width 0.254)
		(layer "F.Cu")
		(net "P3V3_NODE1")
	)
	(segment
		(start 79.50454 -182.011574)
		(end 79.99476 -182.011574)
		(width 0.508)
		(layer "F.Cu")
		(net "P3V3_NODE1")
	)
	(segment
		(start 77.203046 -182.171848)
		(end 77.203046 -182.658766)
		(width 0.4572)
		(layer "F.Cu")
		(net "P3V3_NODE1")
	)
	(segment
		(start 63.40348 -171.265088)
		(end 63.40348 -170.630088)
		(width 0.508)
		(layer "F.Cu")
		(net "P3V3_NODE1")
	)
	(segment
		(start 25.641554 -97.426272)
		(end 25.641554 -96.256602)
		(width 0.508)
		(layer "F.Cu")
		(net "P3V3_NODE1")
	)
	(segment
		(start 163.340034 -98.535744)
		(end 162.169348 -98.535744)
		(width 0.1778)
		(layer "F.Cu")
		(net "P3V3_NODE1")
	)
	(segment
		(start 97.405952 -143.3068)
		(end 97.89414 -143.794988)
		(width 0.508)
		(layer "F.Cu")
		(net "P3V3_NODE1")
	)
	(segment
		(start 124.192792 -164.491416)
		(end 124.93244 -165.231064)
		(width 0.508)
		(layer "F.Cu")
		(net "P3V3_NODE1")
	)
	(segment
		(start 50.50663 -94.920054)
		(end 50.50663 -95.486728)
		(width 0.508)
		(layer "F.Cu")
		(net "P3V3_NODE1")
	)
	(segment
		(start 90.936572 -86.539324)
		(end 86.324186 -86.539324)
		(width 0.508)
		(layer "F.Cu")
		(net "P3V3_NODE1")
	)
	(segment
		(start 129.352802 -54.578504)
		(end 128.594866 -54.578504)
		(width 0.4572)
		(layer "F.Cu")
		(net "P3V3_NODE1")
	)
	(segment
		(start 67.7418 -130.45948)
		(end 67.7418 -130.457448)
		(width 0.381)
		(layer "F.Cu")
		(net "P3V3_NODE1")
	)
	(segment
		(start 125.701298 -161.641028)
		(end 125.97384 -161.91357)
		(width 0.508)
		(layer "F.Cu")
		(net "P3V3_NODE1")
	)
	(segment
		(start 106.9594 -171.600876)
		(end 107.052872 -171.507404)
		(width 0.508)
		(layer "F.Cu")
		(net "P3V3_NODE1")
	)
	(segment
		(start 108.27258 -164.109146)
		(end 108.094018 -163.930584)
		(width 0.508)
		(layer "F.Cu")
		(net "P3V3_NODE1")
	)
	(segment
		(start 82.342228 -133.963156)
		(end 83.866228 -133.963156)
		(width 0.508)
		(layer "F.Cu")
		(net "P3V3_NODE1")
	)
	(segment
		(start 7.65556 -138.220196)
		(end 7.65556 -137.081768)
		(width 0.508)
		(layer "F.Cu")
		(net "P3V3_NODE1")
	)
	(segment
		(start 20.419314 -62.600586)
		(end 21.839174 -62.600586)
		(width 0.508)
		(layer "F.Cu")
		(net "P3V3_NODE1")
	)
	(segment
		(start 65.341754 -139.259564)
		(end 65.339468 -139.259564)
		(width 0.381)
		(layer "F.Cu")
		(net "P3V3_NODE1")
	)
	(segment
		(start 168.443148 -95.963994)
		(end 168.24706 -95.767906)
		(width 0.1778)
		(layer "F.Cu")
		(net "P3V3_NODE1")
	)
	(segment
		(start 89.385394 -167.41902)
		(end 90.41257 -167.41902)
		(width 0.508)
		(layer "F.Cu")
		(net "P3V3_NODE1")
	)
	(segment
		(start 21.839174 -62.600586)
		(end 22.453346 -61.986414)
		(width 0.508)
		(layer "F.Cu")
		(net "P3V3_NODE1")
	)
	(segment
		(start 88.158066 -104.128062)
		(end 88.158066 -105.746042)
		(width 0.508)
		(layer "F.Cu")
		(net "P3V3_NODE1")
	)
	(segment
		(start 68.5419 -139.259564)
		(end 68.542154 -139.259564)
		(width 0.381)
		(layer "F.Cu")
		(net "P3V3_NODE1")
	)
	(segment
		(start 130.412998 -57.068974)
		(end 128.614424 -57.068974)
		(width 0.4572)
		(layer "F.Cu")
		(net "P3V3_NODE1")
	)
	(segment
		(start 137.52576 -179.62753)
		(end 137.807192 -179.908962)
		(width 0.254)
		(layer "F.Cu")
		(net "P3V3_NODE1")
	)
	(segment
		(start 63.334646 -151.481028)
		(end 64.309498 -151.481028)
		(width 0.508)
		(layer "F.Cu")
		(net "P3V3_NODE1")
	)
	(segment
		(start 45.317664 -150.37308)
		(end 45.317664 -149.313646)
		(width 0.254)
		(layer "F.Cu")
		(net "P3V3_NODE1")
	)
	(segment
		(start 82.68208 -121.14149)
		(end 83.816444 -121.14149)
		(width 0.2032)
		(layer "F.Cu")
		(net "P3V3_NODE1")
	)
	(segment
		(start 164.461698 -167.764968)
		(end 164.355018 -167.658288)
		(width 0.508)
		(layer "F.Cu")
		(net "P3V3_NODE1")
	)
	(segment
		(start 139.525756 -178.858672)
		(end 139.525756 -179.625244)
		(width 0.254)
		(layer "F.Cu")
		(net "P3V3_NODE1")
	)
	(segment
		(start 49.355502 -171.490132)
		(end 49.355502 -170.821604)
		(width 0.508)
		(layer "F.Cu")
		(net "P3V3_NODE1")
	)
	(segment
		(start 129.48031 -154.696668)
		(end 129.346452 -154.56281)
		(width 0.508)
		(layer "F.Cu")
		(net "P3V3_NODE1")
	)
	(segment
		(start 88.158066 -105.746042)
		(end 87.042498 -106.86161)
		(width 0.508)
		(layer "F.Cu")
		(net "P3V3_NODE1")
	)
	(segment
		(start 70.141846 -136.859518)
		(end 70.142354 -136.859518)
		(width 0.381)
		(layer "F.Cu")
		(net "P3V3_NODE1")
	)
	(segment
		(start 69.11213 -8.501888)
		(end 69.347334 -8.266684)
		(width 0.254)
		(layer "F.Cu")
		(net "P3V3_NODE1")
	)
	(segment
		(start 63.40475 -170.630088)
		(end 64.131444 -170.630088)
		(width 0.508)
		(layer "F.Cu")
		(net "P3V3_NODE1")
	)
	(segment
		(start 138.938 -151.32558)
		(end 138.938 -149.901402)
		(width 0.1778)
		(layer "F.Cu")
		(net "P3V3_NODE1")
	)
	(segment
		(start 62.511686 -120.644412)
		(end 62.511686 -120.00611)
		(width 0.508)
		(layer "F.Cu")
		(net "P3V3_NODE1")
	)
	(segment
		(start 123.30811 -163.475416)
		(end 123.152916 -163.475416)
		(width 0.508)
		(layer "F.Cu")
		(net "P3V3_NODE1")
	)
	(segment
		(start 19.538696 -98.963734)
		(end 18.810732 -98.963734)
		(width 0.508)
		(layer "F.Cu")
		(net "P3V3_NODE1")
	)
	(segment
		(start 69.979286 -169.87393)
		(end 70.814946 -169.87393)
		(width 0.508)
		(layer "F.Cu")
		(net "P3V3_NODE1")
	)
	(segment
		(start 156.412184 -176.483772)
		(end 156.97708 -177.048668)
		(width 0.508)
		(layer "F.Cu")
		(net "P3V3_NODE1")
	)
	(segment
		(start 68.480686 -148.876512)
		(end 68.480686 -149.517862)
		(width 0.508)
		(layer "F.Cu")
		(net "P3V3_NODE1")
	)
	(segment
		(start 59.126628 -83.082384)
		(end 59.494166 -82.714846)
		(width 0.3048)
		(layer "F.Cu")
		(net "P3V3_NODE1")
	)
	(segment
		(start 12.949174 -15.860522)
		(end 12.949174 -14.904974)
		(width 0.508)
		(layer "F.Cu")
		(net "P3V3_NODE1")
	)
	(segment
		(start 102.487984 -181.31409)
		(end 101.432614 -181.31409)
		(width 0.4064)
		(layer "F.Cu")
		(net "P3V3_NODE1")
	)
	(segment
		(start 125.97384 -163.002976)
		(end 125.9586 -163.018216)
		(width 0.508)
		(layer "F.Cu")
		(net "P3V3_NODE1")
	)
	(segment
		(start 59.195208 -149.689058)
		(end 59.195208 -150.350728)
		(width 0.508)
		(layer "F.Cu")
		(net "P3V3_NODE1")
	)
	(segment
		(start 59.741816 -129.659634)
		(end 59.341004 -129.258822)
		(width 0.381)
		(layer "F.Cu")
		(net "P3V3_NODE1")
	)
	(segment
		(start 52.255928 -171.398438)
		(end 52.255928 -170.630088)
		(width 0.4572)
		(layer "F.Cu")
		(net "P3V3_NODE1")
	)
	(segment
		(start 10.657078 -139.899898)
		(end 10.390632 -140.166344)
		(width 0.381)
		(layer "F.Cu")
		(net "P3V3_NODE1")
	)
	(segment
		(start 49.933606 -170.821604)
		(end 49.355502 -170.821604)
		(width 0.508)
		(layer "F.Cu")
		(net "P3V3_NODE1")
	)
	(segment
		(start 68.819014 -14.812772)
		(end 66.891408 -12.885166)
		(width 0.254)
		(layer "F.Cu")
		(net "P3V3_NODE1")
	)
	(segment
		(start 67.541902 -170.630088)
		(end 66.81343 -170.630088)
		(width 0.508)
		(layer "F.Cu")
		(net "P3V3_NODE1")
	)
	(segment
		(start 156.97708 -177.048668)
		(end 156.97708 -177.8)
		(width 0.508)
		(layer "F.Cu")
		(net "P3V3_NODE1")
	)
	(segment
		(start 148.717 -157.716982)
		(end 148.717 -157.715204)
		(width 0.508)
		(layer "F.Cu")
		(net "P3V3_NODE1")
	)
	(segment
		(start 138.1379 -135.825484)
		(end 138.1379 -136.762998)
		(width 0.1778)
		(layer "F.Cu")
		(net "P3V3_NODE1")
	)
	(segment
		(start 119.110252 -160.80486)
		(end 119.238776 -160.80486)
		(width 0.508)
		(layer "F.Cu")
		(net "P3V3_NODE1")
	)
	(segment
		(start 79.24546 -182.270654)
		(end 79.50454 -182.011574)
		(width 0.508)
		(layer "F.Cu")
		(net "P3V3_NODE1")
	)
	(segment
		(start 25.641554 -96.256602)
		(end 25.391872 -96.00692)
		(width 0.508)
		(layer "F.Cu")
		(net "P3V3_NODE1")
	)
	(segment
		(start 149.108922 -32.570928)
		(end 148.220938 -32.570928)
		(width 0.508)
		(layer "F.Cu")
		(net "P3V3_NODE1")
	)
	(segment
		(start 71.593456 -97.913698)
		(end 71.593456 -98.089212)
		(width 0.508)
		(layer "F.Cu")
		(net "P3V3_NODE1")
	)
	(segment
		(start 89.962228 -107.83824)
		(end 89.962228 -107.123738)
		(width 0.508)
		(layer "F.Cu")
		(net "P3V3_NODE1")
	)
	(segment
		(start 108.2294 -168.97604)
		(end 108.2294 -169.642536)
		(width 0.508)
		(layer "F.Cu")
		(net "P3V3_NODE1")
	)
	(segment
		(start 45.557694 -102.799134)
		(end 44.798234 -102.799134)
		(width 0.508)
		(layer "F.Cu")
		(net "P3V3_NODE1")
	)
	(segment
		(start 4.725162 -155.388056)
		(end 4.225036 -155.388056)
		(width 0.381)
		(layer "F.Cu")
		(net "P3V3_NODE1")
	)
	(segment
		(start 56.166766 -161.024316)
		(end 56.964326 -160.226756)
		(width 0.508)
		(layer "F.Cu")
		(net "P3V3_NODE1")
	)
	(segment
		(start 66.81343 -171.228766)
		(end 66.81343 -170.630088)
		(width 0.508)
		(layer "F.Cu")
		(net "P3V3_NODE1")
	)
	(segment
		(start 59.494166 -82.714846)
		(end 59.517026 -82.714846)
		(width 0.3048)
		(layer "F.Cu")
		(net "P3V3_NODE1")
	)
	(segment
		(start 120.60936 -164.306504)
		(end 122.321828 -164.306504)
		(width 0.3556)
		(layer "F.Cu")
		(net "P3V3_NODE1")
	)
	(segment
		(start 70.155054 -175.122332)
		(end 70.155054 -175.523652)
		(width 0.508)
		(layer "F.Cu")
		(net "P3V3_NODE1")
	)
	(segment
		(start 164.770054 -157.647132)
		(end 164.770054 -158.692596)
		(width 0.254)
		(layer "F.Cu")
		(net "P3V3_NODE1")
	)
	(segment
		(start 139.075668 -180.075332)
		(end 139.075668 -180.726842)
		(width 0.254)
		(layer "F.Cu")
		(net "P3V3_NODE1")
	)
	(segment
		(start 155.084018 -140.233654)
		(end 155.685998 -140.835634)
		(width 0.508)
		(layer "F.Cu")
		(net "P3V3_NODE1")
	)
	(segment
		(start 133.737858 -151.32558)
		(end 133.737858 -150.224744)
		(width 0.1778)
		(layer "F.Cu")
		(net "P3V3_NODE1")
	)
	(segment
		(start 147.929346 -149.843998)
		(end 147.929346 -148.333714)
		(width 0.508)
		(layer "F.Cu")
		(net "P3V3_NODE1")
	)
	(segment
		(start 89.652348 -175.01997)
		(end 89.72804 -174.944278)
		(width 0.254)
		(layer "F.Cu")
		(net "P3V3_NODE1")
	)
	(segment
		(start 124.10821 -170.587416)
		(end 124.72924 -170.587416)
		(width 0.508)
		(layer "F.Cu")
		(net "P3V3_NODE1")
	)
	(segment
		(start 151.21763 -30.534864)
		(end 152.429972 -30.534864)
		(width 0.3556)
		(layer "F.Cu")
		(net "P3V3_NODE1")
	)
	(segment
		(start 135.716264 -162.179762)
		(end 135.525764 -162.370262)
		(width 0.254)
		(layer "F.Cu")
		(net "P3V3_NODE1")
	)
	(segment
		(start 15.997174 -17.706848)
		(end 15.138146 -18.565876)
		(width 0.381)
		(layer "F.Cu")
		(net "P3V3_NODE1")
	)
	(segment
		(start 95.949008 -98.133408)
		(end 95.5675 -97.7519)
		(width 0.508)
		(layer "F.Cu")
		(net "P3V3_NODE1")
	)
	(segment
		(start 102.150164 -19.45132)
		(end 101.748082 -19.049238)
		(width 0.381)
		(layer "F.Cu")
		(net "P3V3_NODE1")
	)
	(segment
		(start 105.462832 -179.516278)
		(end 105.297732 -179.681378)
		(width 0.508)
		(layer "F.Cu")
		(net "P3V3_NODE1")
	)
	(segment
		(start 162.169348 -98.535744)
		(end 161.79546 -98.161856)
		(width 0.1778)
		(layer "F.Cu")
		(net "P3V3_NODE1")
	)
	(segment
		(start 156.779468 -172.604938)
		(end 157.800802 -172.604938)
		(width 0.381)
		(layer "F.Cu")
		(net "P3V3_NODE1")
	)
	(segment
		(start 127.00127 -174.667926)
		(end 128.560322 -174.667926)
		(width 0.508)
		(layer "F.Cu")
		(net "P3V3_NODE1")
	)
	(segment
		(start 49.88814 -164.2999)
		(end 49.88814 -165.13937)
		(width 0.508)
		(layer "F.Cu")
		(net "P3V3_NODE1")
	)
	(segment
		(start 106.570526 -165.793928)
		(end 107.189778 -165.793928)
		(width 0.508)
		(layer "F.Cu")
		(net "P3V3_NODE1")
	)
	(segment
		(start 147.04568 -167.1955)
		(end 147.068032 -167.1955)
		(width 0.254)
		(layer "F.Cu")
		(net "P3V3_NODE1")
	)
	(segment
		(start 147.17014 -167.093392)
		(end 147.068032 -167.1955)
		(width 0.4572)
		(layer "F.Cu")
		(net "P3V3_NODE1")
	)
	(segment
		(start 76.92898 -161.031174)
		(end 76.92898 -161.058352)
		(width 0.381)
		(layer "F.Cu")
		(net "P3V3_NODE1")
	)
	(segment
		(start 154.70124 -140.233654)
		(end 155.084018 -140.233654)
		(width 0.508)
		(layer "F.Cu")
		(net "P3V3_NODE1")
	)
	(segment
		(start 82.64652 -87.236554)
		(end 81.90357 -87.979504)
		(width 0.508)
		(layer "F.Cu")
		(net "P3V3_NODE1")
	)
	(segment
		(start 93.528388 -123.959366)
		(end 93.210888 -123.641866)
		(width 0.2032)
		(layer "F.Cu")
		(net "P3V3_NODE1")
	)
	(segment
		(start 8.19658 -153.73731)
		(end 8.19658 -153.187908)
		(width 0.508)
		(layer "F.Cu")
		(net "P3V3_NODE1")
	)
	(segment
		(start 88.64346 -167.975026)
		(end 89.856564 -167.975026)
		(width 0.254)
		(layer "F.Cu")
		(net "P3V3_NODE1")
	)
	(segment
		(start 156.828998 -141.673326)
		(end 157.522164 -140.98016)
		(width 0.508)
		(layer "F.Cu")
		(net "P3V3_NODE1")
	)
	(segment
		(start 155.116022 -172.550328)
		(end 155.436062 -172.230288)
		(width 0.508)
		(layer "F.Cu")
		(net "P3V3_NODE1")
	)
	(segment
		(start 5.487162 -152.34793)
		(end 5.82549 -152.34793)
		(width 0.508)
		(layer "F.Cu")
		(net "P3V3_NODE1")
	)
	(segment
		(start 105.297732 -179.681378)
		(end 105.297732 -179.693824)
		(width 0.508)
		(layer "F.Cu")
		(net "P3V3_NODE1")
	)
	(segment
		(start 68.542154 -139.259564)
		(end 68.940934 -139.658344)
		(width 0.381)
		(layer "F.Cu")
		(net "P3V3_NODE1")
	)
	(segment
		(start 96.192594 -167.162734)
		(end 96.289622 -167.065706)
		(width 0.508)
		(layer "F.Cu")
		(net "P3V3_NODE1")
	)
	(segment
		(start 140.069316 -25.412192)
		(end 140.069316 -24.677116)
		(width 0.508)
		(layer "F.Cu")
		(net "P3V3_NODE1")
	)
	(segment
		(start 154.170888 -175.756316)
		(end 154.170888 -176.594516)
		(width 0.508)
		(layer "F.Cu")
		(net "P3V3_NODE1")
	)
	(segment
		(start 124.082302 -162.464242)
		(end 124.723144 -162.464242)
		(width 0.508)
		(layer "F.Cu")
		(net "P3V3_NODE1")
	)
	(segment
		(start 72.321166 -97.110042)
		(end 72.321166 -97.185988)
		(width 0.508)
		(layer "F.Cu")
		(net "P3V3_NODE1")
	)
	(segment
		(start 155.436062 -172.230288)
		(end 156.239464 -172.230288)
		(width 0.508)
		(layer "F.Cu")
		(net "P3V3_NODE1")
	)
	(segment
		(start 80.845152 -133.961124)
		(end 82.342228 -133.961124)
		(width 0.508)
		(layer "F.Cu")
		(net "P3V3_NODE1")
	)
	(segment
		(start 159.608012 -98.343212)
		(end 159.608012 -98.178366)
		(width 0.4572)
		(layer "F.Cu")
		(net "P3V3_NODE1")
	)
	(segment
		(start 104.67467 -179.363624)
		(end 105.053638 -178.984656)
		(width 0.508)
		(layer "F.Cu")
		(net "P3V3_NODE1")
	)
	(segment
		(start 85.390228 -133.963156)
		(end 85.390228 -134.982204)
		(width 0.508)
		(layer "F.Cu")
		(net "P3V3_NODE1")
	)
	(segment
		(start 153.501852 -86.76894)
		(end 153.501852 -85.92439)
		(width 0.508)
		(layer "F.Cu")
		(net "P3V3_NODE1")
	)
	(segment
		(start 147.98548 -157.619954)
		(end 147.98548 -158.194502)
		(width 0.508)
		(layer "F.Cu")
		(net "P3V3_NODE1")
	)
	(segment
		(start 89.962228 -133.963156)
		(end 89.962228 -134.305802)
		(width 0.508)
		(layer "F.Cu")
		(net "P3V3_NODE1")
	)
	(segment
		(start 154.170888 -176.594516)
		(end 154.859228 -177.282856)
		(width 0.508)
		(layer "F.Cu")
		(net "P3V3_NODE1")
	)
	(segment
		(start 133.49478 -153.608278)
		(end 133.49478 -153.026364)
		(width 0.4572)
		(layer "F.Cu")
		(net "P3V3_NODE1")
	)
	(segment
		(start 128.13792 -134.601458)
		(end 128.005332 -134.46887)
		(width 0.1778)
		(layer "F.Cu")
		(net "P3V3_NODE1")
	)
	(segment
		(start 101.432614 -181.31409)
		(end 101.431598 -181.315106)
		(width 0.4064)
		(layer "F.Cu")
		(net "P3V3_NODE1")
	)
	(segment
		(start 110.744 -171.629324)
		(end 110.72876 -171.614084)
		(width 0.508)
		(layer "F.Cu")
		(net "P3V3_NODE1")
	)
	(segment
		(start 125.464316 -62.780418)
		(end 125.8062 -62.438534)
		(width 0.508)
		(layer "F.Cu")
		(net "P3V3_NODE1")
	)
	(segment
		(start 79.99476 -182.011574)
		(end 79.99476 -181.623462)
		(width 0.508)
		(layer "F.Cu")
		(net "P3V3_NODE1")
	)
	(segment
		(start 77.203046 -182.658766)
		(end 77.524102 -182.979822)
		(width 0.4572)
		(layer "F.Cu")
		(net "P3V3_NODE1")
	)
	(segment
		(start 155.881832 -149.347174)
		(end 155.51658 -148.981922)
		(width 0.254)
		(layer "F.Cu")
		(net "P3V3_NODE1")
	)
	(segment
		(start 25.391872 -96.00692)
		(end 25.391872 -95.061278)
		(width 0.508)
		(layer "F.Cu")
		(net "P3V3_NODE1")
	)
	(segment
		(start 56.166766 -161.528506)
		(end 56.166766 -161.024316)
		(width 0.508)
		(layer "F.Cu")
		(net "P3V3_NODE1")
	)
	(via
		(at 98.087942 -168.92651)
		(size 0.508)
		(drill 0.254)
		(layers "F.Cu" "B.Cu")
		(net "P3V3_NODE1")
	)
	(via
		(at 166.100252 -92.68079)
		(size 0.508)
		(drill 0.254)
		(layers "F.Cu" "B.Cu")
		(net "P3V3_NODE1")
	)
	(via
		(at 129.346452 -154.56281)
		(size 0.508)
		(drill 0.254)
		(layers "F.Cu" "B.Cu")
		(net "P3V3_NODE1")
	)
	(via
		(at 148.717 -157.715204)
		(size 0.508)
		(drill 0.254)
		(layers "F.Cu" "B.Cu")
		(net "P3V3_NODE1")
	)
	(via
		(at 9.99744 -153.566622)
		(size 0.508)
		(drill 0.254)
		(layers "F.Cu" "B.Cu")
		(net "P3V3_NODE1")
	)
	(via
		(at 100.564188 -136.176258)
		(size 0.508)
		(drill 0.254)
		(layers "F.Cu" "B.Cu")
		(net "P3V3_NODE1")
	)
	(via
		(at 149.6187 -172.76064)
		(size 0.508)
		(drill 0.254)
		(layers "F.Cu" "B.Cu")
		(net "P3V3_NODE1")
	)
	(via
		(at 68.940934 -139.658344)
		(size 0.49022)
		(drill 0.254)
		(layers "F.Cu" "B.Cu")
		(net "P3V3_NODE1")
	)
	(via
		(at 77.798676 -167.425624)
		(size 0.508)
		(drill 0.254)
		(layers "F.Cu" "B.Cu")
		(net "P3V3_NODE1")
	)
	(via
		(at 133.49478 -153.026364)
		(size 0.508)
		(drill 0.254)
		(layers "F.Cu" "B.Cu")
		(net "P3V3_NODE1")
	)
	(via
		(at 22.4028 -144.300194)
		(size 0.508)
		(drill 0.254)
		(layers "F.Cu" "B.Cu")
		(net "P3V3_NODE1")
	)
	(via
		(at 63.832486 -120.028462)
		(size 0.508)
		(drill 0.254)
		(layers "F.Cu" "B.Cu")
		(net "P3V3_NODE1")
	)
	(via
		(at 79.75092 -85.296502)
		(size 0.508)
		(drill 0.254)
		(layers "F.Cu" "B.Cu")
		(net "P3V3_NODE1")
	)
	(via
		(at 152.748996 -23.888192)
		(size 0.508)
		(drill 0.254)
		(layers "F.Cu" "B.Cu")
		(net "P3V3_NODE1")
	)
	(via
		(at 147.36572 -37.819076)
		(size 0.508)
		(drill 0.254)
		(layers "F.Cu" "B.Cu")
		(net "P3V3_NODE1")
	)
	(via
		(at 150.658068 -168.612312)
		(size 0.508)
		(drill 0.254)
		(layers "F.Cu" "B.Cu")
		(net "P3V3_NODE1")
	)
	(via
		(at 157.94736 -140.98016)
		(size 0.508)
		(drill 0.254)
		(layers "F.Cu" "B.Cu")
		(net "P3V3_NODE1")
	)
	(via
		(at 159.10052 -21.619718)
		(size 0.508)
		(drill 0.254)
		(layers "F.Cu" "B.Cu")
		(net "P3V3_NODE1")
	)
	(via
		(at 69.463158 -97.8154)
		(size 0.508)
		(drill 0.254)
		(layers "F.Cu" "B.Cu")
		(net "P3V3_NODE1")
	)
	(via
		(at 60.763912 -99.895914)
		(size 0.508)
		(drill 0.254)
		(layers "F.Cu" "B.Cu")
		(net "P3V3_NODE1")
	)
	(via
		(at 98.86696 -5.219192)
		(size 0.508)
		(drill 0.254)
		(layers "F.Cu" "B.Cu")
		(net "P3V3_NODE1")
	)
	(via
		(at 21.08962 -147.994624)
		(size 0.508)
		(drill 0.254)
		(layers "F.Cu" "B.Cu")
		(net "P3V3_NODE1")
	)
	(via
		(at 131.366006 -57.462166)
		(size 0.508)
		(drill 0.254)
		(layers "F.Cu" "B.Cu")
		(net "P3V3_NODE1")
	)
	(via
		(at 25.973278 -42.66057)
		(size 0.508)
		(drill 0.254)
		(layers "F.Cu" "B.Cu")
		(net "P3V3_NODE1")
	)
	(via
		(at 139.63904 -103.441754)
		(size 0.508)
		(drill 0.254)
		(layers "F.Cu" "B.Cu")
		(net "P3V3_NODE1")
	)
	(via
		(at 156.868368 -92.084906)
		(size 0.508)
		(drill 0.254)
		(layers "F.Cu" "B.Cu")
		(net "P3V3_NODE1")
	)
	(via
		(at 50.07102 -159.03829)
		(size 0.508)
		(drill 0.254)
		(layers "F.Cu" "B.Cu")
		(net "P3V3_NODE1")
	)
	(via
		(at 82.263234 -4.270248)
		(size 0.508)
		(drill 0.254)
		(layers "F.Cu" "B.Cu")
		(net "P3V3_NODE1")
	)
	(via
		(at 88.102948 -107.9119)
		(size 0.508)
		(drill 0.254)
		(layers "F.Cu" "B.Cu")
		(net "P3V3_NODE1")
	)
	(via
		(at 60.94095 -138.058144)
		(size 0.49022)
		(drill 0.254)
		(layers "F.Cu" "B.Cu")
		(net "P3V3_NODE1")
	)
	(via
		(at 68.480686 -149.517862)
		(size 0.508)
		(drill 0.254)
		(layers "F.Cu" "B.Cu")
		(net "P3V3_NODE1")
	)
	(via
		(at 110.744 -171.629324)
		(size 0.508)
		(drill 0.254)
		(layers "F.Cu" "B.Cu")
		(net "P3V3_NODE1")
	)
	(via
		(at 60.94095 -137.258044)
		(size 0.49022)
		(drill 0.254)
		(layers "F.Cu" "B.Cu")
		(net "P3V3_NODE1")
	)
	(via
		(at 13.745718 -134.390892)
		(size 0.508)
		(drill 0.254)
		(layers "F.Cu" "B.Cu")
		(net "P3V3_NODE1")
	)
	(via
		(at 47.60214 -167.56507)
		(size 0.508)
		(drill 0.254)
		(layers "F.Cu" "B.Cu")
		(net "P3V3_NODE1")
	)
	(via
		(at 133.75894 -170.760644)
		(size 0.508)
		(drill 0.254)
		(layers "F.Cu" "B.Cu")
		(net "P3V3_NODE1")
	)
	(via
		(at 154.33548 -164.380926)
		(size 0.508)
		(drill 0.254)
		(layers "F.Cu" "B.Cu")
		(net "P3V3_NODE1")
	)
	(via
		(at 93.343984 -175.322992)
		(size 0.508)
		(drill 0.254)
		(layers "F.Cu" "B.Cu")
		(net "P3V3_NODE1")
	)
	(via
		(at 20.86356 -142.432532)
		(size 0.508)
		(drill 0.254)
		(layers "F.Cu" "B.Cu")
		(net "P3V3_NODE1")
	)
	(via
		(at 104.13619 -129.141474)
		(size 0.508)
		(drill 0.254)
		(layers "F.Cu" "B.Cu")
		(net "P3V3_NODE1")
	)
	(via
		(at 170.41876 -155.46578)
		(size 0.508)
		(drill 0.254)
		(layers "F.Cu" "B.Cu")
		(net "P3V3_NODE1")
	)
	(via
		(at 109.438694 -172.505624)
		(size 0.508)
		(drill 0.254)
		(layers "F.Cu" "B.Cu")
		(net "P3V3_NODE1")
	)
	(via
		(at 59.771026 -117.947948)
		(size 0.508)
		(drill 0.254)
		(layers "F.Cu" "B.Cu")
		(net "P3V3_NODE1")
	)
	(via
		(at 136.264904 -60.704222)
		(size 0.508)
		(drill 0.254)
		(layers "F.Cu" "B.Cu")
		(net "P3V3_NODE1")
	)
	(via
		(at 8.69696 -136.389364)
		(size 0.508)
		(drill 0.254)
		(layers "F.Cu" "B.Cu")
		(net "P3V3_NODE1")
	)
	(via
		(at 101.03866 -17.68094)
		(size 0.508)
		(drill 0.254)
		(layers "F.Cu" "B.Cu")
		(net "P3V3_NODE1")
	)
	(via
		(at 94.27718 -180.739796)
		(size 0.508)
		(drill 0.254)
		(layers "F.Cu" "B.Cu")
		(net "P3V3_NODE1")
	)
	(via
		(at 155.07716 -177.282856)
		(size 0.508)
		(drill 0.254)
		(layers "F.Cu" "B.Cu")
		(net "P3V3_NODE1")
	)
	(via
		(at 91.836748 -163.87445)
		(size 0.508)
		(drill 0.254)
		(layers "F.Cu" "B.Cu")
		(net "P3V3_NODE1")
	)
	(via
		(at 69.471286 -119.798846)
		(size 0.508)
		(drill 0.254)
		(layers "F.Cu" "B.Cu")
		(net "P3V3_NODE1")
	)
	(via
		(at 126.84887 -61.690758)
		(size 0.508)
		(drill 0.254)
		(layers "F.Cu" "B.Cu")
		(net "P3V3_NODE1")
	)
	(via
		(at 72.0471 -149.617176)
		(size 0.508)
		(drill 0.254)
		(layers "F.Cu" "B.Cu")
		(net "P3V3_NODE1")
	)
	(via
		(at 126.71298 -169.754296)
		(size 0.508)
		(drill 0.254)
		(layers "F.Cu" "B.Cu")
		(net "P3V3_NODE1")
	)
	(via
		(at 59.260486 -120.028462)
		(size 0.508)
		(drill 0.254)
		(layers "F.Cu" "B.Cu")
		(net "P3V3_NODE1")
	)
	(via
		(at 159.04972 -25.216104)
		(size 0.508)
		(drill 0.254)
		(layers "F.Cu" "B.Cu")
		(net "P3V3_NODE1")
	)
	(via
		(at 44.548044 -144.675606)
		(size 0.508)
		(drill 0.254)
		(layers "F.Cu" "B.Cu")
		(net "P3V3_NODE1")
	)
	(via
		(at 156.583634 -161.59861)
		(size 0.508)
		(drill 0.254)
		(layers "F.Cu" "B.Cu")
		(net "P3V3_NODE1")
	)
	(via
		(at 72.310498 -98.239326)
		(size 0.508)
		(drill 0.254)
		(layers "F.Cu" "B.Cu")
		(net "P3V3_NODE1")
	)
	(via
		(at 21.62556 -148.644102)
		(size 0.508)
		(drill 0.254)
		(layers "F.Cu" "B.Cu")
		(net "P3V3_NODE1")
	)
	(via
		(at 70.54215 -134.059168)
		(size 0.49022)
		(drill 0.254)
		(layers "F.Cu" "B.Cu")
		(net "P3V3_NODE1")
	)
	(via
		(at 12.949174 -14.904974)
		(size 0.508)
		(drill 0.254)
		(layers "F.Cu" "B.Cu")
		(net "P3V3_NODE1")
	)
	(via
		(at 160.89757 -108.511086)
		(size 0.508)
		(drill 0.254)
		(layers "F.Cu" "B.Cu")
		(net "P3V3_NODE1")
	)
	(via
		(at 147.447254 -35.137344)
		(size 0.508)
		(drill 0.254)
		(layers "F.Cu" "B.Cu")
		(net "P3V3_NODE1")
	)
	(via
		(at 4.0259 -155.18892)
		(size 0.508)
		(drill 0.254)
		(layers "F.Cu" "B.Cu")
		(net "P3V3_NODE1")
	)
	(via
		(at 124.725176 -169.571416)
		(size 0.508)
		(drill 0.254)
		(layers "F.Cu" "B.Cu")
		(net "P3V3_NODE1")
	)
	(via
		(at 185.079894 -141.969236)
		(size 0.508)
		(drill 0.254)
		(layers "F.Cu" "B.Cu")
		(net "P3V3_NODE1")
	)
	(via
		(at 60.748672 -170.604688)
		(size 0.508)
		(drill 0.254)
		(layers "F.Cu" "B.Cu")
		(net "P3V3_NODE1")
	)
	(via
		(at 89.35974 -179.5272)
		(size 0.508)
		(drill 0.254)
		(layers "F.Cu" "B.Cu")
		(net "P3V3_NODE1")
	)
	(via
		(at 164.271198 -162.410902)
		(size 0.508)
		(drill 0.254)
		(layers "F.Cu" "B.Cu")
		(net "P3V3_NODE1")
	)
	(via
		(at 15.320772 -16.660622)
		(size 0.508)
		(drill 0.254)
		(layers "F.Cu" "B.Cu")
		(net "P3V3_NODE1")
	)
	(via
		(at 85.34654 -135.025892)
		(size 0.508)
		(drill 0.254)
		(layers "F.Cu" "B.Cu")
		(net "P3V3_NODE1")
	)
	(via
		(at 149.48916 -141.584172)
		(size 0.508)
		(drill 0.254)
		(layers "F.Cu" "B.Cu")
		(net "P3V3_NODE1")
	)
	(via
		(at 138.938 -149.901402)
		(size 0.508)
		(drill 0.254)
		(layers "F.Cu" "B.Cu")
		(net "P3V3_NODE1")
	)
	(via
		(at 20.82292 -141.440154)
		(size 0.508)
		(drill 0.254)
		(layers "F.Cu" "B.Cu")
		(net "P3V3_NODE1")
	)
	(via
		(at 107.194604 -166.848282)
		(size 0.508)
		(drill 0.254)
		(layers "F.Cu" "B.Cu")
		(net "P3V3_NODE1")
	)
	(via
		(at 68.353686 -119.977662)
		(size 0.508)
		(drill 0.254)
		(layers "F.Cu" "B.Cu")
		(net "P3V3_NODE1")
	)
	(via
		(at 149.591522 -25.136602)
		(size 0.508)
		(drill 0.254)
		(layers "F.Cu" "B.Cu")
		(net "P3V3_NODE1")
	)
	(via
		(at 168.9227 -172.884592)
		(size 0.508)
		(drill 0.254)
		(layers "F.Cu" "B.Cu")
		(net "P3V3_NODE1")
	)
	(via
		(at 148.261578 -56.073548)
		(size 0.508)
		(drill 0.254)
		(layers "F.Cu" "B.Cu")
		(net "P3V3_NODE1")
	)
	(via
		(at 151.485854 -149.822408)
		(size 0.508)
		(drill 0.254)
		(layers "F.Cu" "B.Cu")
		(net "P3V3_NODE1")
	)
	(via
		(at 125.21057 -25.25776)
		(size 0.508)
		(drill 0.254)
		(layers "F.Cu" "B.Cu")
		(net "P3V3_NODE1")
	)
	(via
		(at 44.798234 -102.799134)
		(size 0.508)
		(drill 0.254)
		(layers "F.Cu" "B.Cu")
		(net "P3V3_NODE1")
	)
	(via
		(at 182.99303 -141.98346)
		(size 0.508)
		(drill 0.254)
		(layers "F.Cu" "B.Cu")
		(net "P3V3_NODE1")
	)
	(via
		(at 58.818018 -81.722468)
		(size 0.508)
		(drill 0.254)
		(layers "F.Cu" "B.Cu")
		(net "P3V3_NODE1")
	)
	(via
		(at 70.88886 -169.800016)
		(size 0.508)
		(drill 0.254)
		(layers "F.Cu" "B.Cu")
		(net "P3V3_NODE1")
	)
	(via
		(at 185.737754 -141.97965)
		(size 0.508)
		(drill 0.254)
		(layers "F.Cu" "B.Cu")
		(net "P3V3_NODE1")
	)
	(via
		(at 62.511686 -120.00611)
		(size 0.508)
		(drill 0.254)
		(layers "F.Cu" "B.Cu")
		(net "P3V3_NODE1")
	)
	(via
		(at 135.12038 -165.224714)
		(size 0.508)
		(drill 0.254)
		(layers "F.Cu" "B.Cu")
		(net "P3V3_NODE1")
	)
	(via
		(at 82.263234 -7.318248)
		(size 0.508)
		(drill 0.254)
		(layers "F.Cu" "B.Cu")
		(net "P3V3_NODE1")
	)
	(via
		(at 151.923242 -25.913842)
		(size 0.508)
		(drill 0.254)
		(layers "F.Cu" "B.Cu")
		(net "P3V3_NODE1")
	)
	(via
		(at 95.047562 -124.721366)
		(size 0.508)
		(drill 0.254)
		(layers "F.Cu" "B.Cu")
		(net "P3V3_NODE1")
	)
	(via
		(at 160.269936 -158.706566)
		(size 0.508)
		(drill 0.254)
		(layers "F.Cu" "B.Cu")
		(net "P3V3_NODE1")
	)
	(via
		(at 147.833842 -145.095468)
		(size 0.508)
		(drill 0.254)
		(layers "F.Cu" "B.Cu")
		(net "P3V3_NODE1")
	)
	(via
		(at 100.596192 -137.192258)
		(size 0.508)
		(drill 0.254)
		(layers "F.Cu" "B.Cu")
		(net "P3V3_NODE1")
	)
	(via
		(at 127.024892 -154.65679)
		(size 0.508)
		(drill 0.254)
		(layers "F.Cu" "B.Cu")
		(net "P3V3_NODE1")
	)
	(via
		(at 22.453346 -61.986414)
		(size 0.508)
		(drill 0.254)
		(layers "F.Cu" "B.Cu")
		(net "P3V3_NODE1")
	)
	(via
		(at 153.526998 -141.720824)
		(size 0.508)
		(drill 0.254)
		(layers "F.Cu" "B.Cu")
		(net "P3V3_NODE1")
	)
	(via
		(at 77.43698 -166.559738)
		(size 0.508)
		(drill 0.254)
		(layers "F.Cu" "B.Cu")
		(net "P3V3_NODE1")
	)
	(via
		(at 71.06539 -168.624504)
		(size 0.508)
		(drill 0.254)
		(layers "F.Cu" "B.Cu")
		(net "P3V3_NODE1")
	)
	(via
		(at 110.85703 -169.577512)
		(size 0.508)
		(drill 0.254)
		(layers "F.Cu" "B.Cu")
		(net "P3V3_NODE1")
	)
	(via
		(at 20.73529 -132.360416)
		(size 0.508)
		(drill 0.254)
		(layers "F.Cu" "B.Cu")
		(net "P3V3_NODE1")
	)
	(via
		(at 140.039852 -139.9794)
		(size 0.508)
		(drill 0.254)
		(layers "F.Cu" "B.Cu")
		(net "P3V3_NODE1")
	)
	(via
		(at 115.509802 -46.609762)
		(size 0.508)
		(drill 0.254)
		(layers "F.Cu" "B.Cu")
		(net "P3V3_NODE1")
	)
	(via
		(at 105.2957 -179.695856)
		(size 0.508)
		(drill 0.254)
		(layers "F.Cu" "B.Cu")
		(net "P3V3_NODE1")
	)
	(via
		(at 80.602836 -2.78257)
		(size 0.508)
		(drill 0.254)
		(layers "F.Cu" "B.Cu")
		(net "P3V3_NODE1")
	)
	(via
		(at 8.41756 -152.966928)
		(size 0.508)
		(drill 0.254)
		(layers "F.Cu" "B.Cu")
		(net "P3V3_NODE1")
	)
	(via
		(at 21.965666 -63.311786)
		(size 0.508)
		(drill 0.254)
		(layers "F.Cu" "B.Cu")
		(net "P3V3_NODE1")
	)
	(via
		(at 166.95928 -183.790336)
		(size 0.508)
		(drill 0.254)
		(layers "F.Cu" "B.Cu")
		(net "P3V3_NODE1")
	)
	(via
		(at 95.6691 -166.155878)
		(size 0.508)
		(drill 0.254)
		(layers "F.Cu" "B.Cu")
		(net "P3V3_NODE1")
	)
	(via
		(at 80.602836 -7.35457)
		(size 0.508)
		(drill 0.254)
		(layers "F.Cu" "B.Cu")
		(net "P3V3_NODE1")
	)
	(via
		(at 123.88596 -40.95369)
		(size 0.508)
		(drill 0.254)
		(layers "F.Cu" "B.Cu")
		(net "P3V3_NODE1")
	)
	(via
		(at 184.443116 -141.986508)
		(size 0.508)
		(drill 0.254)
		(layers "F.Cu" "B.Cu")
		(net "P3V3_NODE1")
	)
	(via
		(at 51.158394 -179.890674)
		(size 0.508)
		(drill 0.254)
		(layers "F.Cu" "B.Cu")
		(net "P3V3_NODE1")
	)
	(via
		(at 148.218652 -140.26515)
		(size 0.508)
		(drill 0.254)
		(layers "F.Cu" "B.Cu")
		(net "P3V3_NODE1")
	)
	(via
		(at 64.899286 -119.952262)
		(size 0.508)
		(drill 0.254)
		(layers "F.Cu" "B.Cu")
		(net "P3V3_NODE1")
	)
	(via
		(at 51.03114 -165.13937)
		(size 0.508)
		(drill 0.254)
		(layers "F.Cu" "B.Cu")
		(net "P3V3_NODE1")
	)
	(via
		(at 138.465052 -137.09015)
		(size 0.508)
		(drill 0.254)
		(layers "F.Cu" "B.Cu")
		(net "P3V3_NODE1")
	)
	(via
		(at 126.80315 -52.145184)
		(size 0.508)
		(drill 0.254)
		(layers "F.Cu" "B.Cu")
		(net "P3V3_NODE1")
	)
	(via
		(at 64.141096 -130.05816)
		(size 0.49022)
		(drill 0.254)
		(layers "F.Cu" "B.Cu")
		(net "P3V3_NODE1")
	)
	(via
		(at 164.804852 -88.84539)
		(size 0.508)
		(drill 0.254)
		(layers "F.Cu" "B.Cu")
		(net "P3V3_NODE1")
	)
	(via
		(at 143.777462 -159.387286)
		(size 0.508)
		(drill 0.254)
		(layers "F.Cu" "B.Cu")
		(net "P3V3_NODE1")
	)
	(via
		(at 54.763416 -157.982158)
		(size 0.508)
		(drill 0.254)
		(layers "F.Cu" "B.Cu")
		(net "P3V3_NODE1")
	)
	(via
		(at 70.54215 -137.259314)
		(size 0.49022)
		(drill 0.254)
		(layers "F.Cu" "B.Cu")
		(net "P3V3_NODE1")
	)
	(via
		(at 104.7115 -173.531784)
		(size 0.508)
		(drill 0.254)
		(layers "F.Cu" "B.Cu")
		(net "P3V3_NODE1")
	)
	(via
		(at 102.24516 -180.504846)
		(size 0.508)
		(drill 0.254)
		(layers "F.Cu" "B.Cu")
		(net "P3V3_NODE1")
	)
	(via
		(at 64.309498 -151.481028)
		(size 0.508)
		(drill 0.254)
		(layers "F.Cu" "B.Cu")
		(net "P3V3_NODE1")
	)
	(via
		(at 59.52998 -150.683468)
		(size 0.508)
		(drill 0.254)
		(layers "F.Cu" "B.Cu")
		(net "P3V3_NODE1")
	)
	(via
		(at 123.31954 -136.314942)
		(size 0.508)
		(drill 0.254)
		(layers "F.Cu" "B.Cu")
		(net "P3V3_NODE1")
	)
	(via
		(at 133.26745 -59.630564)
		(size 0.508)
		(drill 0.254)
		(layers "F.Cu" "B.Cu")
		(net "P3V3_NODE1")
	)
	(via
		(at 70.54215 -135.659368)
		(size 0.49022)
		(drill 0.254)
		(layers "F.Cu" "B.Cu")
		(net "P3V3_NODE1")
	)
	(via
		(at 107.189778 -165.793928)
		(size 0.508)
		(drill 0.254)
		(layers "F.Cu" "B.Cu")
		(net "P3V3_NODE1")
	)
	(via
		(at 89.18194 -135.08609)
		(size 0.508)
		(drill 0.254)
		(layers "F.Cu" "B.Cu")
		(net "P3V3_NODE1")
	)
	(via
		(at 43.671236 -98.136456)
		(size 0.508)
		(drill 0.254)
		(layers "F.Cu" "B.Cu")
		(net "P3V3_NODE1")
	)
	(via
		(at 95.811594 -170.992038)
		(size 0.508)
		(drill 0.254)
		(layers "F.Cu" "B.Cu")
		(net "P3V3_NODE1")
	)
	(via
		(at 125.042676 -173.316138)
		(size 0.508)
		(drill 0.254)
		(layers "F.Cu" "B.Cu")
		(net "P3V3_NODE1")
	)
	(via
		(at 158.4325 -22.13102)
		(size 0.508)
		(drill 0.254)
		(layers "F.Cu" "B.Cu")
		(net "P3V3_NODE1")
	)
	(via
		(at 136.726676 -40.49141)
		(size 0.508)
		(drill 0.254)
		(layers "F.Cu" "B.Cu")
		(net "P3V3_NODE1")
	)
	(via
		(at 74.011028 -97.906078)
		(size 0.508)
		(drill 0.254)
		(layers "F.Cu" "B.Cu")
		(net "P3V3_NODE1")
	)
	(via
		(at 64.017144 -147.861274)
		(size 0.508)
		(drill 0.254)
		(layers "F.Cu" "B.Cu")
		(net "P3V3_NODE1")
	)
	(via
		(at 134.020052 -149.94255)
		(size 0.508)
		(drill 0.254)
		(layers "F.Cu" "B.Cu")
		(net "P3V3_NODE1")
	)
	(via
		(at 163.255198 -162.410902)
		(size 0.508)
		(drill 0.254)
		(layers "F.Cu" "B.Cu")
		(net "P3V3_NODE1")
	)
	(via
		(at 99.552252 -170.76928)
		(size 0.508)
		(drill 0.254)
		(layers "F.Cu" "B.Cu")
		(net "P3V3_NODE1")
	)
	(via
		(at 147.31492 -173.51756)
		(size 0.508)
		(drill 0.254)
		(layers "F.Cu" "B.Cu")
		(net "P3V3_NODE1")
	)
	(via
		(at 61.444886 -120.028462)
		(size 0.508)
		(drill 0.254)
		(layers "F.Cu" "B.Cu")
		(net "P3V3_NODE1")
	)
	(via
		(at 155.51658 -148.981922)
		(size 0.508)
		(drill 0.254)
		(layers "F.Cu" "B.Cu")
		(net "P3V3_NODE1")
	)
	(via
		(at 136.390888 -61.720222)
		(size 0.508)
		(drill 0.254)
		(layers "F.Cu" "B.Cu")
		(net "P3V3_NODE1")
	)
	(via
		(at 173.61408 -200.42632)
		(size 0.508)
		(drill 0.254)
		(layers "F.Cu" "B.Cu")
		(net "P3V3_NODE1")
	)
	(via
		(at 124.72924 -170.587416)
		(size 0.508)
		(drill 0.254)
		(layers "F.Cu" "B.Cu")
		(net "P3V3_NODE1")
	)
	(via
		(at 130.02514 -162.235388)
		(size 0.508)
		(drill 0.254)
		(layers "F.Cu" "B.Cu")
		(net "P3V3_NODE1")
	)
	(via
		(at 70.7009 -174.576486)
		(size 0.508)
		(drill 0.254)
		(layers "F.Cu" "B.Cu")
		(net "P3V3_NODE1")
	)
	(via
		(at 153.202132 -23.24989)
		(size 0.508)
		(drill 0.254)
		(layers "F.Cu" "B.Cu")
		(net "P3V3_NODE1")
	)
	(via
		(at 70.54215 -136.459214)
		(size 0.49022)
		(drill 0.254)
		(layers "F.Cu" "B.Cu")
		(net "P3V3_NODE1")
	)
	(via
		(at 137.025634 -160.648904)
		(size 0.508)
		(drill 0.254)
		(layers "F.Cu" "B.Cu")
		(net "P3V3_NODE1")
	)
	(via
		(at 36.386008 -145.56867)
		(size 0.508)
		(drill 0.254)
		(layers "F.Cu" "B.Cu")
		(net "P3V3_NODE1")
	)
	(via
		(at 86.406228 -135.073898)
		(size 0.508)
		(drill 0.254)
		(layers "F.Cu" "B.Cu")
		(net "P3V3_NODE1")
	)
	(via
		(at 128.778 -60.706)
		(size 0.508)
		(drill 0.254)
		(layers "F.Cu" "B.Cu")
		(net "P3V3_NODE1")
	)
	(via
		(at 67.541902 -170.630088)
		(size 0.508)
		(drill 0.254)
		(layers "F.Cu" "B.Cu")
		(net "P3V3_NODE1")
	)
	(via
		(at 81.230978 -87.979504)
		(size 0.508)
		(drill 0.254)
		(layers "F.Cu" "B.Cu")
		(net "P3V3_NODE1")
	)
	(via
		(at 122.696224 -172.625512)
		(size 0.508)
		(drill 0.254)
		(layers "F.Cu" "B.Cu")
		(net "P3V3_NODE1")
	)
	(via
		(at 157.229556 -103.721662)
		(size 0.508)
		(drill 0.254)
		(layers "F.Cu" "B.Cu")
		(net "P3V3_NODE1")
	)
	(via
		(at 26.200354 -94.82836)
		(size 0.508)
		(drill 0.254)
		(layers "F.Cu" "B.Cu")
		(net "P3V3_NODE1")
	)
	(via
		(at 71.564246 -134.963154)
		(size 0.6604)
		(drill 0.3302)
		(layers "F.Cu" "B.Cu")
		(net "P3V3_NODE1")
	)
	(via
		(at 173.863 -199.81291)
		(size 0.508)
		(drill 0.254)
		(layers "F.Cu" "B.Cu")
		(net "P3V3_NODE1")
	)
	(via
		(at 128.228344 -166.902638)
		(size 0.508)
		(drill 0.254)
		(layers "F.Cu" "B.Cu")
		(net "P3V3_NODE1")
	)
	(via
		(at 83.19516 -165.971728)
		(size 0.508)
		(drill 0.254)
		(layers "F.Cu" "B.Cu")
		(net "P3V3_NODE1")
	)
	(via
		(at 141.530578 -69.806312)
		(size 0.508)
		(drill 0.254)
		(layers "F.Cu" "B.Cu")
		(net "P3V3_NODE1")
	)
	(via
		(at 146.913346 -148.766784)
		(size 0.508)
		(drill 0.254)
		(layers "F.Cu" "B.Cu")
		(net "P3V3_NODE1")
	)
	(via
		(at 161.182812 -107.940856)
		(size 0.508)
		(drill 0.254)
		(layers "F.Cu" "B.Cu")
		(net "P3V3_NODE1")
	)
	(via
		(at 87.23122 -98.027998)
		(size 0.508)
		(drill 0.254)
		(layers "F.Cu" "B.Cu")
		(net "P3V3_NODE1")
	)
	(via
		(at 61.080142 -139.488672)
		(size 0.6604)
		(drill 0.3302)
		(layers "F.Cu" "B.Cu")
		(net "P3V3_NODE1")
	)
	(via
		(at 41.347644 -144.424146)
		(size 0.508)
		(drill 0.254)
		(layers "F.Cu" "B.Cu")
		(net "P3V3_NODE1")
	)
	(via
		(at 107.45597 -176.965102)
		(size 0.508)
		(drill 0.254)
		(layers "F.Cu" "B.Cu")
		(net "P3V3_NODE1")
	)
	(via
		(at 59.126628 -83.082384)
		(size 0.508)
		(drill 0.254)
		(layers "F.Cu" "B.Cu")
		(net "P3V3_NODE1")
	)
	(via
		(at 4.32308 -150.605236)
		(size 0.508)
		(drill 0.254)
		(layers "F.Cu" "B.Cu")
		(net "P3V3_NODE1")
	)
	(via
		(at 97.27184 -180.703474)
		(size 0.508)
		(drill 0.254)
		(layers "F.Cu" "B.Cu")
		(net "P3V3_NODE1")
	)
	(via
		(at 127.554482 -39.804086)
		(size 0.508)
		(drill 0.254)
		(layers "F.Cu" "B.Cu")
		(net "P3V3_NODE1")
	)
	(via
		(at 108.6866 -172.646086)
		(size 0.508)
		(drill 0.254)
		(layers "F.Cu" "B.Cu")
		(net "P3V3_NODE1")
	)
	(via
		(at 96.466914 -172.581316)
		(size 0.508)
		(drill 0.254)
		(layers "F.Cu" "B.Cu")
		(net "P3V3_NODE1")
	)
	(via
		(at 63.70193 -178.6001)
		(size 0.508)
		(drill 0.254)
		(layers "F.Cu" "B.Cu")
		(net "P3V3_NODE1")
	)
	(via
		(at 56.884062 -117.7417)
		(size 0.508)
		(drill 0.254)
		(layers "F.Cu" "B.Cu")
		(net "P3V3_NODE1")
	)
	(via
		(at 69.964808 -122.737626)
		(size 0.508)
		(drill 0.254)
		(layers "F.Cu" "B.Cu")
		(net "P3V3_NODE1")
	)
	(via
		(at 158.721806 -90.875612)
		(size 0.508)
		(drill 0.254)
		(layers "F.Cu" "B.Cu")
		(net "P3V3_NODE1")
	)
	(via
		(at 168.573196 -106.171746)
		(size 0.508)
		(drill 0.254)
		(layers "F.Cu" "B.Cu")
		(net "P3V3_NODE1")
	)
	(via
		(at 149.277578 -56.064912)
		(size 0.508)
		(drill 0.254)
		(layers "F.Cu" "B.Cu")
		(net "P3V3_NODE1")
	)
	(via
		(at 158.45028 -23.788116)
		(size 0.508)
		(drill 0.254)
		(layers "F.Cu" "B.Cu")
		(net "P3V3_NODE1")
	)
	(via
		(at 131.75615 -43.31335)
		(size 0.508)
		(drill 0.254)
		(layers "F.Cu" "B.Cu")
		(net "P3V3_NODE1")
	)
	(via
		(at 146.83994 -147.865846)
		(size 0.508)
		(drill 0.254)
		(layers "F.Cu" "B.Cu")
		(net "P3V3_NODE1")
	)
	(via
		(at 159.263588 -97.463102)
		(size 0.508)
		(drill 0.254)
		(layers "F.Cu" "B.Cu")
		(net "P3V3_NODE1")
	)
	(via
		(at 91.84132 -165.79977)
		(size 0.508)
		(drill 0.254)
		(layers "F.Cu" "B.Cu")
		(net "P3V3_NODE1")
	)
	(via
		(at 29.72562 -99.054412)
		(size 0.508)
		(drill 0.254)
		(layers "F.Cu" "B.Cu")
		(net "P3V3_NODE1")
	)
	(via
		(at 125.04674 -165.231064)
		(size 0.508)
		(drill 0.254)
		(layers "F.Cu" "B.Cu")
		(net "P3V3_NODE1")
	)
	(via
		(at 161.070798 -162.395408)
		(size 0.508)
		(drill 0.254)
		(layers "F.Cu" "B.Cu")
		(net "P3V3_NODE1")
	)
	(via
		(at 116.586 -50.927)
		(size 0.508)
		(drill 0.254)
		(layers "F.Cu" "B.Cu")
		(net "P3V3_NODE1")
	)
	(via
		(at 110.736888 -166.52113)
		(size 0.508)
		(drill 0.254)
		(layers "F.Cu" "B.Cu")
		(net "P3V3_NODE1")
	)
	(via
		(at 159.10052 -22.483572)
		(size 0.508)
		(drill 0.254)
		(layers "F.Cu" "B.Cu")
		(net "P3V3_NODE1")
	)
	(via
		(at 166.515796 -185.083196)
		(size 0.508)
		(drill 0.254)
		(layers "F.Cu" "B.Cu")
		(net "P3V3_NODE1")
	)
	(via
		(at 45.65396 -144.513554)
		(size 0.508)
		(drill 0.254)
		(layers "F.Cu" "B.Cu")
		(net "P3V3_NODE1")
	)
	(via
		(at 57.973468 -117.774974)
		(size 0.508)
		(drill 0.254)
		(layers "F.Cu" "B.Cu")
		(net "P3V3_NODE1")
	)
	(via
		(at 130.08864 -55.136542)
		(size 0.508)
		(drill 0.254)
		(layers "F.Cu" "B.Cu")
		(net "P3V3_NODE1")
	)
	(via
		(at 150.8379 -26.35377)
		(size 0.508)
		(drill 0.254)
		(layers "F.Cu" "B.Cu")
		(net "P3V3_NODE1")
	)
	(via
		(at 157.835346 -106.7816)
		(size 0.508)
		(drill 0.254)
		(layers "F.Cu" "B.Cu")
		(net "P3V3_NODE1")
	)
	(via
		(at 115.14836 -47.16018)
		(size 0.508)
		(drill 0.254)
		(layers "F.Cu" "B.Cu")
		(net "P3V3_NODE1")
	)
	(via
		(at 127.244602 -41.214294)
		(size 0.508)
		(drill 0.254)
		(layers "F.Cu" "B.Cu")
		(net "P3V3_NODE1")
	)
	(via
		(at 74.088244 -95.294958)
		(size 0.508)
		(drill 0.254)
		(layers "F.Cu" "B.Cu")
		(net "P3V3_NODE1")
	)
	(via
		(at 89.72804 -174.944278)
		(size 0.508)
		(drill 0.254)
		(layers "F.Cu" "B.Cu")
		(net "P3V3_NODE1")
	)
	(via
		(at 40.817546 -149.327616)
		(size 0.508)
		(drill 0.254)
		(layers "F.Cu" "B.Cu")
		(net "P3V3_NODE1")
	)
	(via
		(at 21.58746 -143.074644)
		(size 0.508)
		(drill 0.254)
		(layers "F.Cu" "B.Cu")
		(net "P3V3_NODE1")
	)
	(via
		(at 93.373956 -176.035462)
		(size 0.508)
		(drill 0.254)
		(layers "F.Cu" "B.Cu")
		(net "P3V3_NODE1")
	)
	(via
		(at 65.159128 -97.76333)
		(size 0.508)
		(drill 0.254)
		(layers "F.Cu" "B.Cu")
		(net "P3V3_NODE1")
	)
	(via
		(at 60.352686 -120.003062)
		(size 0.508)
		(drill 0.254)
		(layers "F.Cu" "B.Cu")
		(net "P3V3_NODE1")
	)
	(via
		(at 18.810732 -98.963734)
		(size 0.508)
		(drill 0.254)
		(layers "F.Cu" "B.Cu")
		(net "P3V3_NODE1")
	)
	(via
		(at 73.326498 -97.86366)
		(size 0.508)
		(drill 0.254)
		(layers "F.Cu" "B.Cu")
		(net "P3V3_NODE1")
	)
	(via
		(at 184.810908 -127.0254)
		(size 0.508)
		(drill 0.254)
		(layers "F.Cu" "B.Cu")
		(net "P3V3_NODE1")
	)
	(via
		(at 172.424852 -103.57739)
		(size 0.508)
		(drill 0.254)
		(layers "F.Cu" "B.Cu")
		(net "P3V3_NODE1")
	)
	(via
		(at 140.014452 -145.21815)
		(size 0.508)
		(drill 0.254)
		(layers "F.Cu" "B.Cu")
		(net "P3V3_NODE1")
	)
	(via
		(at 151.21763 -30.534864)
		(size 0.508)
		(drill 0.254)
		(layers "F.Cu" "B.Cu")
		(net "P3V3_NODE1")
	)
	(via
		(at 128.619504 -174.608744)
		(size 0.508)
		(drill 0.254)
		(layers "F.Cu" "B.Cu")
		(net "P3V3_NODE1")
	)
	(via
		(at 45.317664 -149.313646)
		(size 0.508)
		(drill 0.254)
		(layers "F.Cu" "B.Cu")
		(net "P3V3_NODE1")
	)
	(via
		(at 159.08528 -24.405336)
		(size 0.508)
		(drill 0.254)
		(layers "F.Cu" "B.Cu")
		(net "P3V3_NODE1")
	)
	(via
		(at 97.89414 -143.794988)
		(size 0.508)
		(drill 0.254)
		(layers "F.Cu" "B.Cu")
		(net "P3V3_NODE1")
	)
	(via
		(at 153.501852 -85.92439)
		(size 0.508)
		(drill 0.254)
		(layers "F.Cu" "B.Cu")
		(net "P3V3_NODE1")
	)
	(via
		(at 69.46392 -149.657054)
		(size 0.508)
		(drill 0.254)
		(layers "F.Cu" "B.Cu")
		(net "P3V3_NODE1")
	)
	(via
		(at 137.52576 -164.488876)
		(size 0.508)
		(drill 0.254)
		(layers "F.Cu" "B.Cu")
		(net "P3V3_NODE1")
	)
	(via
		(at 121.769886 -173.30547)
		(size 0.508)
		(drill 0.254)
		(layers "F.Cu" "B.Cu")
		(net "P3V3_NODE1")
	)
	(via
		(at 49.88814 -165.13937)
		(size 0.508)
		(drill 0.254)
		(layers "F.Cu" "B.Cu")
		(net "P3V3_NODE1")
	)
	(via
		(at 128.005332 -134.46887)
		(size 0.508)
		(drill 0.254)
		(layers "F.Cu" "B.Cu")
		(net "P3V3_NODE1")
	)
	(via
		(at 41.98366 -98.030792)
		(size 0.508)
		(drill 0.254)
		(layers "F.Cu" "B.Cu")
		(net "P3V3_NODE1")
	)
	(via
		(at 120.636284 -167.481504)
		(size 0.508)
		(drill 0.254)
		(layers "F.Cu" "B.Cu")
		(net "P3V3_NODE1")
	)
	(via
		(at 8.67156 -137.24763)
		(size 0.508)
		(drill 0.254)
		(layers "F.Cu" "B.Cu")
		(net "P3V3_NODE1")
	)
	(via
		(at 143.06042 -38.156388)
		(size 0.508)
		(drill 0.254)
		(layers "F.Cu" "B.Cu")
		(net "P3V3_NODE1")
	)
	(via
		(at 54.713886 -121.730262)
		(size 0.508)
		(drill 0.254)
		(layers "F.Cu" "B.Cu")
		(net "P3V3_NODE1")
	)
	(via
		(at 55.450232 -161.528506)
		(size 0.508)
		(drill 0.254)
		(layers "F.Cu" "B.Cu")
		(net "P3V3_NODE1")
	)
	(via
		(at 154.509724 -91.432634)
		(size 0.508)
		(drill 0.254)
		(layers "F.Cu" "B.Cu")
		(net "P3V3_NODE1")
	)
	(via
		(at 70.54215 -138.059414)
		(size 0.49022)
		(drill 0.254)
		(layers "F.Cu" "B.Cu")
		(net "P3V3_NODE1")
	)
	(via
		(at 157.540452 -92.549726)
		(size 0.508)
		(drill 0.254)
		(layers "F.Cu" "B.Cu")
		(net "P3V3_NODE1")
	)
	(via
		(at 82.263234 -5.032248)
		(size 0.508)
		(drill 0.254)
		(layers "F.Cu" "B.Cu")
		(net "P3V3_NODE1")
	)
	(via
		(at 104.373172 -164.938202)
		(size 0.508)
		(drill 0.254)
		(layers "F.Cu" "B.Cu")
		(net "P3V3_NODE1")
	)
	(via
		(at 77.798676 -169.457624)
		(size 0.508)
		(drill 0.254)
		(layers "F.Cu" "B.Cu")
		(net "P3V3_NODE1")
	)
	(via
		(at 151.210772 -25.108916)
		(size 0.508)
		(drill 0.254)
		(layers "F.Cu" "B.Cu")
		(net "P3V3_NODE1")
	)
	(via
		(at 93.3069 -181.269894)
		(size 0.508)
		(drill 0.254)
		(layers "F.Cu" "B.Cu")
		(net "P3V3_NODE1")
	)
	(via
		(at 45.37964 -98.658172)
		(size 0.508)
		(drill 0.254)
		(layers "F.Cu" "B.Cu")
		(net "P3V3_NODE1")
	)
	(via
		(at 77.005434 -95.052896)
		(size 0.508)
		(drill 0.254)
		(layers "F.Cu" "B.Cu")
		(net "P3V3_NODE1")
	)
	(via
		(at 119.761 -35.052)
		(size 0.508)
		(drill 0.254)
		(layers "F.Cu" "B.Cu")
		(net "P3V3_NODE1")
	)
	(via
		(at 155.116022 -172.550582)
		(size 0.508)
		(drill 0.254)
		(layers "F.Cu" "B.Cu")
		(net "P3V3_NODE1")
	)
	(via
		(at 96.22282 -98.133408)
		(size 0.508)
		(drill 0.254)
		(layers "F.Cu" "B.Cu")
		(net "P3V3_NODE1")
	)
	(via
		(at 147.20316 -36.399216)
		(size 0.508)
		(drill 0.254)
		(layers "F.Cu" "B.Cu")
		(net "P3V3_NODE1")
	)
	(via
		(at 68.141088 -130.05816)
		(size 0.49022)
		(drill 0.254)
		(layers "F.Cu" "B.Cu")
		(net "P3V3_NODE1")
	)
	(via
		(at 96.289622 -167.065706)
		(size 0.508)
		(drill 0.254)
		(layers "F.Cu" "B.Cu")
		(net "P3V3_NODE1")
	)
	(via
		(at 140.040614 -69.662548)
		(size 0.508)
		(drill 0.254)
		(layers "F.Cu" "B.Cu")
		(net "P3V3_NODE1")
	)
	(via
		(at 42.363644 -144.540224)
		(size 0.508)
		(drill 0.254)
		(layers "F.Cu" "B.Cu")
		(net "P3V3_NODE1")
	)
	(via
		(at 64.131444 -170.630088)
		(size 0.508)
		(drill 0.254)
		(layers "F.Cu" "B.Cu")
		(net "P3V3_NODE1")
	)
	(via
		(at 110.626906 -170.593512)
		(size 0.508)
		(drill 0.254)
		(layers "F.Cu" "B.Cu")
		(net "P3V3_NODE1")
	)
	(via
		(at 167.0177 -166.388288)
		(size 0.508)
		(drill 0.254)
		(layers "F.Cu" "B.Cu")
		(net "P3V3_NODE1")
	)
	(via
		(at 67.286886 -120.028462)
		(size 0.508)
		(drill 0.254)
		(layers "F.Cu" "B.Cu")
		(net "P3V3_NODE1")
	)
	(via
		(at 107.244388 -171.507404)
		(size 0.508)
		(drill 0.254)
		(layers "F.Cu" "B.Cu")
		(net "P3V3_NODE1")
	)
	(via
		(at 123.815856 -50.435764)
		(size 0.508)
		(drill 0.254)
		(layers "F.Cu" "B.Cu")
		(net "P3V3_NODE1")
	)
	(via
		(at 99.592638 -171.762674)
		(size 0.508)
		(drill 0.254)
		(layers "F.Cu" "B.Cu")
		(net "P3V3_NODE1")
	)
	(via
		(at 68.141088 -139.658344)
		(size 0.49022)
		(drill 0.254)
		(layers "F.Cu" "B.Cu")
		(net "P3V3_NODE1")
	)
	(via
		(at 122.47372 -164.154612)
		(size 0.508)
		(drill 0.254)
		(layers "F.Cu" "B.Cu")
		(net "P3V3_NODE1")
	)
	(via
		(at 172.462444 -99.735894)
		(size 0.508)
		(drill 0.254)
		(layers "F.Cu" "B.Cu")
		(net "P3V3_NODE1")
	)
	(via
		(at 56.441086 -124.295662)
		(size 0.508)
		(drill 0.254)
		(layers "F.Cu" "B.Cu")
		(net "P3V3_NODE1")
	)
	(via
		(at 90.2335 -106.852466)
		(size 0.508)
		(drill 0.254)
		(layers "F.Cu" "B.Cu")
		(net "P3V3_NODE1")
	)
	(via
		(at 165.411404 -169.237152)
		(size 0.508)
		(drill 0.254)
		(layers "F.Cu" "B.Cu")
		(net "P3V3_NODE1")
	)
	(via
		(at 53.23586 -147.546822)
		(size 0.508)
		(drill 0.254)
		(layers "F.Cu" "B.Cu")
		(net "P3V3_NODE1")
	)
	(via
		(at 156.97708 -177.8)
		(size 0.508)
		(drill 0.254)
		(layers "F.Cu" "B.Cu")
		(net "P3V3_NODE1")
	)
	(via
		(at 137.338054 -149.901148)
		(size 0.508)
		(drill 0.254)
		(layers "F.Cu" "B.Cu")
		(net "P3V3_NODE1")
	)
	(via
		(at 68.941188 -130.05816)
		(size 0.49022)
		(drill 0.254)
		(layers "F.Cu" "B.Cu")
		(net "P3V3_NODE1")
	)
	(via
		(at 66.194686 -120.003062)
		(size 0.508)
		(drill 0.254)
		(layers "F.Cu" "B.Cu")
		(net "P3V3_NODE1")
	)
	(via
		(at 54.053486 -121.679462)
		(size 0.508)
		(drill 0.254)
		(layers "F.Cu" "B.Cu")
		(net "P3V3_NODE1")
	)
	(via
		(at 150.467568 -25.558242)
		(size 0.508)
		(drill 0.254)
		(layers "F.Cu" "B.Cu")
		(net "P3V3_NODE1")
	)
	(via
		(at 81.74228 -181.02072)
		(size 0.508)
		(drill 0.254)
		(layers "F.Cu" "B.Cu")
		(net "P3V3_NODE1")
	)
	(via
		(at 101.703632 -173.023022)
		(size 0.508)
		(drill 0.254)
		(layers "F.Cu" "B.Cu")
		(net "P3V3_NODE1")
	)
	(via
		(at 89.337388 -167.467026)
		(size 0.508)
		(drill 0.254)
		(layers "F.Cu" "B.Cu")
		(net "P3V3_NODE1")
	)
	(via
		(at 93.33992 -179.112926)
		(size 0.508)
		(drill 0.254)
		(layers "F.Cu" "B.Cu")
		(net "P3V3_NODE1")
	)
	(via
		(at 121.412 -53.975)
		(size 0.508)
		(drill 0.254)
		(layers "F.Cu" "B.Cu")
		(net "P3V3_NODE1")
	)
	(via
		(at 166.610538 -13.633958)
		(size 0.508)
		(drill 0.254)
		(layers "F.Cu" "B.Cu")
		(net "P3V3_NODE1")
	)
	(via
		(at 83.087718 -8.08736)
		(size 0.508)
		(drill 0.254)
		(layers "F.Cu" "B.Cu")
		(net "P3V3_NODE1")
	)
	(via
		(at 168.24706 -95.767906)
		(size 0.508)
		(drill 0.254)
		(layers "F.Cu" "B.Cu")
		(net "P3V3_NODE1")
	)
	(via
		(at 154.70124 -140.233654)
		(size 0.508)
		(drill 0.254)
		(layers "F.Cu" "B.Cu")
		(net "P3V3_NODE1")
	)
	(via
		(at 82.263234 -6.556248)
		(size 0.508)
		(drill 0.254)
		(layers "F.Cu" "B.Cu")
		(net "P3V3_NODE1")
	)
	(via
		(at 133.49478 -31.654242)
		(size 0.508)
		(drill 0.254)
		(layers "F.Cu" "B.Cu")
		(net "P3V3_NODE1")
	)
	(via
		(at 90.978228 -134.932674)
		(size 0.508)
		(drill 0.254)
		(layers "F.Cu" "B.Cu")
		(net "P3V3_NODE1")
	)
	(via
		(at 52.17414 -165.10889)
		(size 0.508)
		(drill 0.254)
		(layers "F.Cu" "B.Cu")
		(net "P3V3_NODE1")
	)
	(via
		(at 62.81166 -83.234276)
		(size 0.508)
		(drill 0.254)
		(layers "F.Cu" "B.Cu")
		(net "P3V3_NODE1")
	)
	(via
		(at 11.933174 -14.90726)
		(size 0.508)
		(drill 0.254)
		(layers "F.Cu" "B.Cu")
		(net "P3V3_NODE1")
	)
	(via
		(at 150.293578 -56.15813)
		(size 0.508)
		(drill 0.254)
		(layers "F.Cu" "B.Cu")
		(net "P3V3_NODE1")
	)
	(via
		(at 81.624678 -116.004086)
		(size 0.508)
		(drill 0.254)
		(layers "F.Cu" "B.Cu")
		(net "P3V3_NODE1")
	)
	(via
		(at 64.141096 -139.65809)
		(size 0.49022)
		(drill 0.254)
		(layers "F.Cu" "B.Cu")
		(net "P3V3_NODE1")
	)
	(via
		(at 124.81052 -162.376866)
		(size 0.508)
		(drill 0.254)
		(layers "F.Cu" "B.Cu")
		(net "P3V3_NODE1")
	)
	(via
		(at 127.93472 -167.555164)
		(size 0.508)
		(drill 0.254)
		(layers "F.Cu" "B.Cu")
		(net "P3V3_NODE1")
	)
	(via
		(at 107.600242 -163.930584)
		(size 0.508)
		(drill 0.254)
		(layers "F.Cu" "B.Cu")
		(net "P3V3_NODE1")
	)
	(via
		(at 81.596484 -120.057926)
		(size 0.508)
		(drill 0.254)
		(layers "F.Cu" "B.Cu")
		(net "P3V3_NODE1")
	)
	(via
		(at 157.971998 -141.802104)
		(size 0.508)
		(drill 0.254)
		(layers "F.Cu" "B.Cu")
		(net "P3V3_NODE1")
	)
	(via
		(at 136.78535 -54.20995)
		(size 0.508)
		(drill 0.254)
		(layers "F.Cu" "B.Cu")
		(net "P3V3_NODE1")
	)
	(via
		(at 75.479148 -163.08451)
		(size 0.508)
		(drill 0.254)
		(layers "F.Cu" "B.Cu")
		(net "P3V3_NODE1")
	)
	(via
		(at 89.891108 -169.450512)
		(size 0.508)
		(drill 0.254)
		(layers "F.Cu" "B.Cu")
		(net "P3V3_NODE1")
	)
	(via
		(at 95.048578 -121.749566)
		(size 0.508)
		(drill 0.254)
		(layers "F.Cu" "B.Cu")
		(net "P3V3_NODE1")
	)
	(via
		(at 183.73598 -141.962124)
		(size 0.508)
		(drill 0.254)
		(layers "F.Cu" "B.Cu")
		(net "P3V3_NODE1")
	)
	(via
		(at 38.56228 -97.930716)
		(size 0.508)
		(drill 0.254)
		(layers "F.Cu" "B.Cu")
		(net "P3V3_NODE1")
	)
	(via
		(at 158.39694 -24.66975)
		(size 0.508)
		(drill 0.254)
		(layers "F.Cu" "B.Cu")
		(net "P3V3_NODE1")
	)
	(via
		(at 51.439572 -171.011342)
		(size 0.508)
		(drill 0.254)
		(layers "F.Cu" "B.Cu")
		(net "P3V3_NODE1")
	)
	(via
		(at 141.060424 -168.949624)
		(size 0.508)
		(drill 0.254)
		(layers "F.Cu" "B.Cu")
		(net "P3V3_NODE1")
	)
	(via
		(at 108.2294 -169.642536)
		(size 0.508)
		(drill 0.254)
		(layers "F.Cu" "B.Cu")
		(net "P3V3_NODE1")
	)
	(via
		(at 82.126836 -3.143758)
		(size 0.508)
		(drill 0.254)
		(layers "F.Cu" "B.Cu")
		(net "P3V3_NODE1")
	)
	(via
		(at 57.210198 -170.630088)
		(size 0.508)
		(drill 0.254)
		(layers "F.Cu" "B.Cu")
		(net "P3V3_NODE1")
	)
	(via
		(at 130.914902 -150.1013)
		(size 0.508)
		(drill 0.254)
		(layers "F.Cu" "B.Cu")
		(net "P3V3_NODE1")
	)
	(via
		(at 150.692358 -45.70857)
		(size 0.508)
		(drill 0.254)
		(layers "F.Cu" "B.Cu")
		(net "P3V3_NODE1")
	)
	(via
		(at 149.684232 -26.41346)
		(size 0.508)
		(drill 0.254)
		(layers "F.Cu" "B.Cu")
		(net "P3V3_NODE1")
	)
	(via
		(at 107.437174 -175.349154)
		(size 0.508)
		(drill 0.254)
		(layers "F.Cu" "B.Cu")
		(net "P3V3_NODE1")
	)
	(via
		(at 64.940942 -139.65809)
		(size 0.49022)
		(drill 0.254)
		(layers "F.Cu" "B.Cu")
		(net "P3V3_NODE1")
	)
	(via
		(at 48.74514 -165.11397)
		(size 0.508)
		(drill 0.254)
		(layers "F.Cu" "B.Cu")
		(net "P3V3_NODE1")
	)
	(via
		(at 137.971022 -180.539898)
		(size 0.508)
		(drill 0.254)
		(layers "F.Cu" "B.Cu")
		(net "P3V3_NODE1")
	)
	(via
		(at 20.705064 -146.78787)
		(size 0.508)
		(drill 0.254)
		(layers "F.Cu" "B.Cu")
		(net "P3V3_NODE1")
	)
	(via
		(at 144.747996 -58.87593)
		(size 0.508)
		(drill 0.254)
		(layers "F.Cu" "B.Cu")
		(net "P3V3_NODE1")
	)
	(via
		(at 144.143222 -135.18515)
		(size 0.508)
		(drill 0.254)
		(layers "F.Cu" "B.Cu")
		(net "P3V3_NODE1")
	)
	(via
		(at 164.770054 -158.692596)
		(size 0.508)
		(drill 0.254)
		(layers "F.Cu" "B.Cu")
		(net "P3V3_NODE1")
	)
	(via
		(at 147.07108 -167.1955)
		(size 0.508)
		(drill 0.254)
		(layers "F.Cu" "B.Cu")
		(net "P3V3_NODE1")
	)
	(via
		(at 159.04972 -23.347426)
		(size 0.508)
		(drill 0.254)
		(layers "F.Cu" "B.Cu")
		(net "P3V3_NODE1")
	)
	(via
		(at 70.639686 -149.666452)
		(size 0.508)
		(drill 0.254)
		(layers "F.Cu" "B.Cu")
		(net "P3V3_NODE1")
	)
	(via
		(at 52.399946 -76.999592)
		(size 0.508)
		(drill 0.254)
		(layers "F.Cu" "B.Cu")
		(net "P3V3_NODE1")
	)
	(via
		(at 139.994894 -138.975592)
		(size 0.508)
		(drill 0.254)
		(layers "F.Cu" "B.Cu")
		(net "P3V3_NODE1")
	)
	(via
		(at 161.79546 -98.161856)
		(size 0.508)
		(drill 0.254)
		(layers "F.Cu" "B.Cu")
		(net "P3V3_NODE1")
	)
	(via
		(at 160.054798 -162.385248)
		(size 0.508)
		(drill 0.254)
		(layers "F.Cu" "B.Cu")
		(net "P3V3_NODE1")
	)
	(via
		(at 163.565078 -13.636752)
		(size 0.508)
		(drill 0.254)
		(layers "F.Cu" "B.Cu")
		(net "P3V3_NODE1")
	)
	(via
		(at 124.79528 -58.879486)
		(size 0.508)
		(drill 0.254)
		(layers "F.Cu" "B.Cu")
		(net "P3V3_NODE1")
	)
	(via
		(at 59.341004 -129.258314)
		(size 0.49022)
		(drill 0.254)
		(layers "F.Cu" "B.Cu")
		(net "P3V3_NODE1")
	)
	(via
		(at 148.32838 -36.725606)
		(size 0.508)
		(drill 0.254)
		(layers "F.Cu" "B.Cu")
		(net "P3V3_NODE1")
	)
	(via
		(at 158.50108 -21.143722)
		(size 0.508)
		(drill 0.254)
		(layers "F.Cu" "B.Cu")
		(net "P3V3_NODE1")
	)
	(via
		(at 148.220938 -32.570928)
		(size 0.508)
		(drill 0.254)
		(layers "F.Cu" "B.Cu")
		(net "P3V3_NODE1")
	)
	(via
		(at 46.971458 -97.504504)
		(size 0.508)
		(drill 0.254)
		(layers "F.Cu" "B.Cu")
		(net "P3V3_NODE1")
	)
	(via
		(at 77.524102 -182.979822)
		(size 0.508)
		(drill 0.254)
		(layers "F.Cu" "B.Cu")
		(net "P3V3_NODE1")
	)
	(via
		(at 118.25732 -162.919918)
		(size 0.508)
		(drill 0.254)
		(layers "F.Cu" "B.Cu")
		(net "P3V3_NODE1")
	)
	(via
		(at 99.587304 -119.62638)
		(size 0.508)
		(drill 0.254)
		(layers "F.Cu" "B.Cu")
		(net "P3V3_NODE1")
	)
	(via
		(at 50.276252 -95.717106)
		(size 0.508)
		(drill 0.254)
		(layers "F.Cu" "B.Cu")
		(net "P3V3_NODE1")
	)
	(via
		(at 20.618196 -127.911098)
		(size 0.508)
		(drill 0.254)
		(layers "F.Cu" "B.Cu")
		(net "P3V3_NODE1")
	)
	(via
		(at 139.71016 -61.957966)
		(size 0.508)
		(drill 0.254)
		(layers "F.Cu" "B.Cu")
		(net "P3V3_NODE1")
	)
	(via
		(at 77.798676 -168.441624)
		(size 0.508)
		(drill 0.254)
		(layers "F.Cu" "B.Cu")
		(net "P3V3_NODE1")
	)
	(via
		(at 56.923432 -98.559366)
		(size 0.508)
		(drill 0.254)
		(layers "F.Cu" "B.Cu")
		(net "P3V3_NODE1")
	)
	(via
		(at 126.72568 -133.045962)
		(size 0.508)
		(drill 0.254)
		(layers "F.Cu" "B.Cu")
		(net "P3V3_NODE1")
	)
	(via
		(at 76.92898 -161.031174)
		(size 0.508)
		(drill 0.254)
		(layers "F.Cu" "B.Cu")
		(net "P3V3_NODE1")
	)
	(via
		(at 7.18058 -152.957276)
		(size 0.508)
		(drill 0.254)
		(layers "F.Cu" "B.Cu")
		(net "P3V3_NODE1")
	)
	(via
		(at 148.440902 -143.052292)
		(size 0.508)
		(drill 0.254)
		(layers "F.Cu" "B.Cu")
		(net "P3V3_NODE1")
	)
	(via
		(at 164.717222 -105.974134)
		(size 0.508)
		(drill 0.254)
		(layers "F.Cu" "B.Cu")
		(net "P3V3_NODE1")
	)
	(via
		(at 81.95056 -2.482596)
		(size 0.508)
		(drill 0.254)
		(layers "F.Cu" "B.Cu")
		(net "P3V3_NODE1")
	)
	(via
		(at 18.762472 -101.069902)
		(size 0.508)
		(drill 0.254)
		(layers "F.Cu" "B.Cu")
		(net "P3V3_NODE1")
	)
	(via
		(at 158.42615 -22.967188)
		(size 0.508)
		(drill 0.254)
		(layers "F.Cu" "B.Cu")
		(net "P3V3_NODE1")
	)
	(via
		(at 14.732 -104.810814)
		(size 0.508)
		(drill 0.254)
		(layers "F.Cu" "B.Cu")
		(net "P3V3_NODE1")
	)
	(via
		(at 66.462402 -97.839022)
		(size 0.508)
		(drill 0.254)
		(layers "F.Cu" "B.Cu")
		(net "P3V3_NODE1")
	)
	(via
		(at 116.200428 -46.614842)
		(size 0.508)
		(drill 0.254)
		(layers "F.Cu" "B.Cu")
		(net "P3V3_NODE1")
	)
	(via
		(at 136.93648 -170.212766)
		(size 0.508)
		(drill 0.254)
		(layers "F.Cu" "B.Cu")
		(net "P3V3_NODE1")
	)
	(via
		(at 140.069316 -24.677116)
		(size 0.508)
		(drill 0.254)
		(layers "F.Cu" "B.Cu")
		(net "P3V3_NODE1")
	)
	(via
		(at 64.940942 -130.05816)
		(size 0.49022)
		(drill 0.254)
		(layers "F.Cu" "B.Cu")
		(net "P3V3_NODE1")
	)
	(via
		(at 99.7204 -5.219192)
		(size 0.508)
		(drill 0.254)
		(layers "F.Cu" "B.Cu")
		(net "P3V3_NODE1")
	)
	(via
		(at 55.704486 -124.295662)
		(size 0.508)
		(drill 0.254)
		(layers "F.Cu" "B.Cu")
		(net "P3V3_NODE1")
	)
	(via
		(at 139.075668 -180.726842)
		(size 0.508)
		(drill 0.254)
		(layers "F.Cu" "B.Cu")
		(net "P3V3_NODE1")
	)
	(via
		(at 79.99476 -163.085018)
		(size 0.508)
		(drill 0.254)
		(layers "F.Cu" "B.Cu")
		(net "P3V3_NODE1")
	)
	(via
		(at 47.60214 -165.02761)
		(size 0.508)
		(drill 0.254)
		(layers "F.Cu" "B.Cu")
		(net "P3V3_NODE1")
	)
	(via
		(at 79.24546 -182.270654)
		(size 0.508)
		(drill 0.254)
		(layers "F.Cu" "B.Cu")
		(net "P3V3_NODE1")
	)
	(via
		(at 71.593456 -98.089212)
		(size 0.508)
		(drill 0.254)
		(layers "F.Cu" "B.Cu")
		(net "P3V3_NODE1")
	)
	(via
		(at 173.61408 -201.18832)
		(size 0.508)
		(drill 0.254)
		(layers "F.Cu" "B.Cu")
		(net "P3V3_NODE1")
	)
	(via
		(at 151.3967 -141.621002)
		(size 0.508)
		(drill 0.254)
		(layers "F.Cu" "B.Cu")
		(net "P3V3_NODE1")
	)
	(via
		(at 137.66292 -157.537658)
		(size 0.508)
		(drill 0.254)
		(layers "F.Cu" "B.Cu")
		(net "P3V3_NODE1")
	)
	(via
		(at 140.52042 -103.441754)
		(size 0.508)
		(drill 0.254)
		(layers "F.Cu" "B.Cu")
		(net "P3V3_NODE1")
	)
	(via
		(at 125.9586 -163.018216)
		(size 0.508)
		(drill 0.254)
		(layers "F.Cu" "B.Cu")
		(net "P3V3_NODE1")
	)
	(via
		(at 163.287202 -90.93454)
		(size 0.508)
		(drill 0.254)
		(layers "F.Cu" "B.Cu")
		(net "P3V3_NODE1")
	)
	(via
		(at 126.50216 -171.527724)
		(size 0.508)
		(drill 0.254)
		(layers "F.Cu" "B.Cu")
		(net "P3V3_NODE1")
	)
	(via
		(at 148.292566 -33.586928)
		(size 0.508)
		(drill 0.254)
		(layers "F.Cu" "B.Cu")
		(net "P3V3_NODE1")
	)
	(via
		(at 91.8591 -167.268398)
		(size 0.508)
		(drill 0.254)
		(layers "F.Cu" "B.Cu")
		(net "P3V3_NODE1")
	)
	(via
		(at 50.263806 -170.491404)
		(size 0.508)
		(drill 0.254)
		(layers "F.Cu" "B.Cu")
		(net "P3V3_NODE1")
	)
	(via
		(at 10.657078 -138.003534)
		(size 0.508)
		(drill 0.254)
		(layers "F.Cu" "B.Cu")
		(net "P3V3_NODE1")
	)
	(via
		(at 57.195466 -163.223956)
		(size 0.508)
		(drill 0.254)
		(layers "F.Cu" "B.Cu")
		(net "P3V3_NODE1")
	)
	(via
		(at 140.6525 -104.24668)
		(size 0.508)
		(drill 0.254)
		(layers "F.Cu" "B.Cu")
		(net "P3V3_NODE1")
	)
	(via
		(at 141.060424 -169.965624)
		(size 0.508)
		(drill 0.254)
		(layers "F.Cu" "B.Cu")
		(net "P3V3_NODE1")
	)
	(via
		(at 42.76598 -121.35866)
		(size 0.508)
		(drill 0.254)
		(layers "F.Cu" "B.Cu")
		(net "P3V3_NODE1")
	)
	(via
		(at 130.98145 -59.57697)
		(size 0.508)
		(drill 0.254)
		(layers "F.Cu" "B.Cu")
		(net "P3V3_NODE1")
	)
	(via
		(at 153.553922 -24.101044)
		(size 0.508)
		(drill 0.254)
		(layers "F.Cu" "B.Cu")
		(net "P3V3_NODE1")
	)
	(segment
		(start 168.640252 -96.64954)
		(end 168.640252 -96.161098)
		(width 0.508)
		(layer "B.Cu")
		(net "P3V3_NODE1")
	)
	(segment
		(start 69.463158 -97.8154)
		(end 69.374512 -97.726754)
		(width 0.508)
		(layer "B.Cu")
		(net "P3V3_NODE1")
	)
	(segment
		(start 123.04649 -40.95369)
		(end 123.88596 -40.95369)
		(width 0.4572)
		(layer "B.Cu")
		(net "P3V3_NODE1")
	)
	(segment
		(start 95.288608 -171.515024)
		(end 94.469966 -171.515024)
		(width 0.4572)
		(layer "B.Cu")
		(net "P3V3_NODE1")
	)
	(segment
		(start 94.051882 -171.933108)
		(end 94.051882 -172.124624)
		(width 0.4572)
		(layer "B.Cu")
		(net "P3V3_NODE1")
	)
	(segment
		(start 56.923432 -98.559366)
		(end 56.940704 -98.559366)
		(width 0.508)
		(layer "B.Cu")
		(net "P3V3_NODE1")
	)
	(segment
		(start 64.899286 -120.644412)
		(end 64.899286 -119.952262)
		(width 0.508)
		(layer "B.Cu")
		(net "P3V3_NODE1")
	)
	(segment
		(start 107.188508 -174.156116)
		(end 107.188508 -175.100488)
		(width 0.508)
		(layer "B.Cu")
		(net "P3V3_NODE1")
	)
	(segment
		(start 140.349224 -61.811408)
		(end 140.349224 -60.833254)
		(width 0.508)
		(layer "B.Cu")
		(net "P3V3_NODE1")
	)
	(segment
		(start 164.10178 -158.195772)
		(end 164.27323 -158.195772)
		(width 0.508)
		(layer "B.Cu")
		(net "P3V3_NODE1")
	)
	(segment
		(start 99.830382 -169.780712)
		(end 100.152454 -170.102784)
		(width 0.381)
		(layer "B.Cu")
		(net "P3V3_NODE1")
	)
	(segment
		(start 121.32056 -37.430456)
		(end 121.32056 -38.446456)
		(width 0.4572)
		(layer "B.Cu")
		(net "P3V3_NODE1")
	)
	(segment
		(start 41.48582 -149.82444)
		(end 41.31437 -149.82444)
		(width 0.508)
		(layer "B.Cu")
		(net "P3V3_NODE1")
	)
	(segment
		(start 119.126 -35.54095)
		(end 119.27205 -35.54095)
		(width 0.508)
		(layer "B.Cu")
		(net "P3V3_NODE1")
	)
	(segment
		(start 105.774744 -173.531784)
		(end 104.7115 -173.531784)
		(width 0.508)
		(layer "B.Cu")
		(net "P3V3_NODE1")
	)
	(segment
		(start 61.462666 -119.310912)
		(end 61.462666 -120.010682)
		(width 0.508)
		(layer "B.Cu")
		(net "P3V3_NODE1")
	)
	(segment
		(start 94.86519 -181.616604)
		(end 94.86519 -181.35854)
		(width 0.508)
		(layer "B.Cu")
		(net "P3V3_NODE1")
	)
	(segment
		(start 78.43139 -167.425624)
		(end 77.798676 -167.425624)
		(width 0.508)
		(layer "B.Cu")
		(net "P3V3_NODE1")
	)
	(segment
		(start 127.492252 -135.64362)
		(end 128.005332 -135.13054)
		(width 0.4572)
		(layer "B.Cu")
		(net "P3V3_NODE1")
	)
	(segment
		(start 89.807796 -169.533824)
		(end 88.841072 -169.533824)
		(width 0.254)
		(layer "B.Cu")
		(net "P3V3_NODE1")
	)
	(segment
		(start 140.859002 -139.22375)
		(end 140.243052 -139.22375)
		(width 0.4572)
		(layer "B.Cu")
		(net "P3V3_NODE1")
	)
	(segment
		(start 167.10152 -172.902372)
		(end 165.217602 -172.902372)
		(width 0.3048)
		(layer "B.Cu")
		(net "P3V3_NODE1")
	)
	(segment
		(start 78.43139 -169.457624)
		(end 77.798676 -169.457624)
		(width 0.508)
		(layer "B.Cu")
		(net "P3V3_NODE1")
	)
	(segment
		(start 137.245852 -150.8887)
		(end 137.245852 -149.99335)
		(width 0.4572)
		(layer "B.Cu")
		(net "P3V3_NODE1")
	)
	(segment
		(start 121.32056 -39.22776)
		(end 123.04649 -40.95369)
		(width 0.4572)
		(layer "B.Cu")
		(net "P3V3_NODE1")
	)
	(segment
		(start 118.25732 -162.921696)
		(end 118.44274 -163.107116)
		(width 0.508)
		(layer "B.Cu")
		(net "P3V3_NODE1")
	)
	(segment
		(start 150.658068 -168.612312)
		(end 150.00478 -168.612312)
		(width 0.508)
		(layer "B.Cu")
		(net "P3V3_NODE1")
	)
	(segment
		(start 50.04181 -179.871624)
		(end 51.139344 -179.871624)
		(width 0.254)
		(layer "B.Cu")
		(net "P3V3_NODE1")
	)
	(segment
		(start 95.811594 -170.992038)
		(end 95.288608 -171.515024)
		(width 0.4572)
		(layer "B.Cu")
		(net "P3V3_NODE1")
	)
	(segment
		(start 123.30811 -172.378624)
		(end 122.943112 -172.378624)
		(width 0.508)
		(layer "B.Cu")
		(net "P3V3_NODE1")
	)
	(segment
		(start 124.10821 -173.394624)
		(end 124.96419 -173.394624)
		(width 0.508)
		(layer "B.Cu")
		(net "P3V3_NODE1")
	)
	(segment
		(start 25.08504 -95.964248)
		(end 25.08504 -95.945706)
		(width 0.508)
		(layer "B.Cu")
		(net "P3V3_NODE1")
	)
	(segment
		(start 51.139344 -179.871624)
		(end 51.158394 -179.890674)
		(width 0.254)
		(layer "B.Cu")
		(net "P3V3_NODE1")
	)
	(segment
		(start 133.997446 -164.48405)
		(end 134.73811 -165.224714)
		(width 0.508)
		(layer "B.Cu")
		(net "P3V3_NODE1")
	)
	(segment
		(start 104.17429 -172.994574)
		(end 104.7115 -173.531784)
		(width 0.3302)
		(layer "B.Cu")
		(net "P3V3_NODE1")
	)
	(segment
		(start 65.159128 -97.15754)
		(end 65.14846 -97.146872)
		(width 0.508)
		(layer "B.Cu")
		(net "P3V3_NODE1")
	)
	(segment
		(start 94.051882 -174.156624)
		(end 94.051882 -175.17618)
		(width 0.508)
		(layer "B.Cu")
		(net "P3V3_NODE1")
	)
	(segment
		(start 88.841072 -169.533824)
		(end 88.5571 -169.817796)
		(width 0.254)
		(layer "B.Cu")
		(net "P3V3_NODE1")
	)
	(segment
		(start 166.68242 -184.067196)
		(end 166.95928 -183.790336)
		(width 0.508)
		(layer "B.Cu")
		(net "P3V3_NODE1")
	)
	(segment
		(start 88.5571 -169.817796)
		(end 87.74176 -169.817796)
		(width 0.254)
		(layer "B.Cu")
		(net "P3V3_NODE1")
	)
	(segment
		(start 94.86519 -181.35854)
		(end 94.27718 -180.77053)
		(width 0.508)
		(layer "B.Cu")
		(net "P3V3_NODE1")
	)
	(segment
		(start 120.405906 -163.836096)
		(end 122.155204 -163.836096)
		(width 0.508)
		(layer "B.Cu")
		(net "P3V3_NODE1")
	)
	(segment
		(start 120.996964 -166.805102)
		(end 120.996964 -167.120824)
		(width 0.4572)
		(layer "B.Cu")
		(net "P3V3_NODE1")
	)
	(segment
		(start 94.469966 -171.515024)
		(end 94.051882 -171.933108)
		(width 0.4572)
		(layer "B.Cu")
		(net "P3V3_NODE1")
	)
	(segment
		(start 44.770802 -149.849332)
		(end 44.781978 -149.849332)
		(width 0.508)
		(layer "B.Cu")
		(net "P3V3_NODE1")
	)
	(segment
		(start 79.41945 -162.509708)
		(end 79.99476 -163.085018)
		(width 0.508)
		(layer "B.Cu")
		(net "P3V3_NODE1")
	)
	(segment
		(start 99.552252 -170.76928)
		(end 99.552252 -170.42765)
		(width 0.508)
		(layer "B.Cu")
		(net "P3V3_NODE1")
	)
	(segment
		(start 121.32056 -38.446456)
		(end 121.32056 -39.22776)
		(width 0.4572)
		(layer "B.Cu")
		(net "P3V3_NODE1")
	)
	(segment
		(start 103.506524 -165.166802)
		(end 103.829866 -165.166802)
		(width 0.508)
		(layer "B.Cu")
		(net "P3V3_NODE1")
	)
	(segment
		(start 94.27718 -180.77053)
		(end 94.27718 -180.739796)
		(width 0.508)
		(layer "B.Cu")
		(net "P3V3_NODE1")
	)
	(segment
		(start 168.640252 -96.161098)
		(end 168.24706 -95.767906)
		(width 0.508)
		(layer "B.Cu")
		(net "P3V3_NODE1")
	)
	(segment
		(start 77.43698 -166.559738)
		(end 77.539596 -166.559738)
		(width 0.508)
		(layer "B.Cu")
		(net "P3V3_NODE1")
	)
	(segment
		(start 25.08504 -95.945706)
		(end 26.200354 -94.830392)
		(width 0.508)
		(layer "B.Cu")
		(net "P3V3_NODE1")
	)
	(segment
		(start 131.189222 -57.63895)
		(end 130.570986 -57.63895)
		(width 0.508)
		(layer "B.Cu")
		(net "P3V3_NODE1")
	)
	(segment
		(start 61.044836 -100.176838)
		(end 60.763912 -99.895914)
		(width 0.381)
		(layer "B.Cu")
		(net "P3V3_NODE1")
	)
	(segment
		(start 19.865594 -97.908872)
		(end 23.140416 -97.908872)
		(width 0.508)
		(layer "B.Cu")
		(net "P3V3_NODE1")
	)
	(segment
		(start 140.360146 -61.82233)
		(end 140.349224 -61.811408)
		(width 0.508)
		(layer "B.Cu")
		(net "P3V3_NODE1")
	)
	(segment
		(start 131.366006 -57.462166)
		(end 131.189222 -57.63895)
		(width 0.508)
		(layer "B.Cu")
		(net "P3V3_NODE1")
	)
	(segment
		(start 130.570986 -57.63895)
		(end 130.080512 -57.63895)
		(width 0.3302)
		(layer "B.Cu")
		(net "P3V3_NODE1")
	)
	(segment
		(start 67.286886 -119.158512)
		(end 67.286886 -120.028462)
		(width 0.508)
		(layer "B.Cu")
		(net "P3V3_NODE1")
	)
	(segment
		(start 121.445782 -173.629574)
		(end 121.769886 -173.30547)
		(width 0.3556)
		(layer "B.Cu")
		(net "P3V3_NODE1")
	)
	(segment
		(start 68.353686 -120.644412)
		(end 68.353686 -119.977662)
		(width 0.508)
		(layer "B.Cu")
		(net "P3V3_NODE1")
	)
	(segment
		(start 79.41945 -162.340544)
		(end 79.41945 -162.509708)
		(width 0.508)
		(layer "B.Cu")
		(net "P3V3_NODE1")
	)
	(segment
		(start 67.286886 -120.028462)
		(end 67.286886 -120.644412)
		(width 0.508)
		(layer "B.Cu")
		(net "P3V3_NODE1")
	)
	(segment
		(start 44.781978 -149.849332)
		(end 45.317664 -149.313646)
		(width 0.508)
		(layer "B.Cu")
		(net "P3V3_NODE1")
	)
	(segment
		(start 139.227052 -150.190454)
		(end 138.938 -149.901402)
		(width 0.4572)
		(layer "B.Cu")
		(net "P3V3_NODE1")
	)
	(segment
		(start 155.998164 -149.76983)
		(end 155.51658 -149.288246)
		(width 0.508)
		(layer "B.Cu")
		(net "P3V3_NODE1")
	)
	(segment
		(start 138.541252 -136.2456)
		(end 138.541252 -137.01395)
		(width 0.4572)
		(layer "B.Cu")
		(net "P3V3_NODE1")
	)
	(segment
		(start 165.47973 -158.608522)
		(end 164.854128 -158.608522)
		(width 0.508)
		(layer "B.Cu")
		(net "P3V3_NODE1")
	)
	(segment
		(start 106.188002 -173.118526)
		(end 105.774744 -173.531784)
		(width 0.508)
		(layer "B.Cu")
		(net "P3V3_NODE1")
	)
	(segment
		(start 68.379086 -119.952262)
		(end 68.353686 -119.977662)
		(width 0.508)
		(layer "B.Cu")
		(net "P3V3_NODE1")
	)
	(segment
		(start 87.74176 -169.817796)
		(end 87.74176 -169.819574)
		(width 0.254)
		(layer "B.Cu")
		(net "P3V3_NODE1")
	)
	(segment
		(start 132.41528 -43.31335)
		(end 131.75615 -43.31335)
		(width 0.508)
		(layer "B.Cu")
		(net "P3V3_NODE1")
	)
	(segment
		(start 107.188508 -175.100488)
		(end 107.437174 -175.349154)
		(width 0.508)
		(layer "B.Cu")
		(net "P3V3_NODE1")
	)
	(segment
		(start 141.522196 -69.13118)
		(end 141.522196 -69.79793)
		(width 0.508)
		(layer "B.Cu")
		(net "P3V3_NODE1")
	)
	(segment
		(start 120.996964 -167.120824)
		(end 120.636284 -167.481504)
		(width 0.4572)
		(layer "B.Cu")
		(net "P3V3_NODE1")
	)
	(segment
		(start 137.571988 -163.812474)
		(end 137.571988 -164.442648)
		(width 0.508)
		(layer "B.Cu")
		(net "P3V3_NODE1")
	)
	(segment
		(start 137.245852 -149.99335)
		(end 137.338054 -149.901148)
		(width 0.4572)
		(layer "B.Cu")
		(net "P3V3_NODE1")
	)
	(segment
		(start 169.757852 -154.804872)
		(end 170.41876 -155.46578)
		(width 0.508)
		(layer "B.Cu")
		(net "P3V3_NODE1")
	)
	(segment
		(start 40.733472 -149.41169)
		(end 40.817546 -149.327616)
		(width 0.508)
		(layer "B.Cu")
		(net "P3V3_NODE1")
	)
	(segment
		(start 29.72562 -99.054412)
		(end 29.72562 -98.353626)
		(width 0.508)
		(layer "B.Cu")
		(net "P3V3_NODE1")
	)
	(segment
		(start 127.287274 -40.071294)
		(end 127.554482 -39.804086)
		(width 0.508)
		(layer "B.Cu")
		(net "P3V3_NODE1")
	)
	(segment
		(start 150.417276 -169.946574)
		(end 150.98776 -169.946574)
		(width 0.254)
		(layer "B.Cu")
		(net "P3V3_NODE1")
	)
	(segment
		(start 129.159 -60.706)
		(end 128.778 -60.706)
		(width 0.508)
		(layer "B.Cu")
		(net "P3V3_NODE1")
	)
	(segment
		(start 26.200354 -94.830392)
		(end 26.200354 -94.82836)
		(width 0.508)
		(layer "B.Cu")
		(net "P3V3_NODE1")
	)
	(segment
		(start 63.527686 -147.06981)
		(end 64.017144 -147.559268)
		(width 0.508)
		(layer "B.Cu")
		(net "P3V3_NODE1")
	)
	(segment
		(start 102.157022 -171.750482)
		(end 102.157022 -172.569632)
		(width 0.4064)
		(layer "B.Cu")
		(net "P3V3_NODE1")
	)
	(segment
		(start 90.399108 -168.942512)
		(end 89.891108 -169.450512)
		(width 0.508)
		(layer "B.Cu")
		(net "P3V3_NODE1")
	)
	(segment
		(start 104.79532 -180.89372)
		(end 104.79532 -180.196236)
		(width 0.508)
		(layer "B.Cu")
		(net "P3V3_NODE1")
	)
	(segment
		(start 15.850616 -134.106158)
		(end 14.030452 -134.106158)
		(width 0.508)
		(layer "B.Cu")
		(net "P3V3_NODE1")
	)
	(segment
		(start 52.30876 -179.890674)
		(end 51.158394 -179.890674)
		(width 0.3556)
		(layer "B.Cu")
		(net "P3V3_NODE1")
	)
	(segment
		(start 63.832486 -120.028462)
		(end 63.832486 -119.183912)
		(width 0.508)
		(layer "B.Cu")
		(net "P3V3_NODE1")
	)
	(segment
		(start 102.24516 -180.504846)
		(end 102.24516 -180.581046)
		(width 0.508)
		(layer "B.Cu")
		(net "P3V3_NODE1")
	)
	(segment
		(start 156.428948 -149.76983)
		(end 155.998164 -149.76983)
		(width 0.508)
		(layer "B.Cu")
		(net "P3V3_NODE1")
	)
	(segment
		(start 83.155536 -165.971728)
		(end 82.838036 -165.654228)
		(width 0.3556)
		(layer "B.Cu")
		(net "P3V3_NODE1")
	)
	(segment
		(start 168.462452 -105.752646)
		(end 168.573196 -105.86339)
		(width 0.508)
		(layer "B.Cu")
		(net "P3V3_NODE1")
	)
	(segment
		(start 140.243052 -139.22375)
		(end 139.994894 -138.975592)
		(width 0.4572)
		(layer "B.Cu")
		(net "P3V3_NODE1")
	)
	(segment
		(start 98.087942 -168.204388)
		(end 98.087942 -168.92651)
		(width 0.508)
		(layer "B.Cu")
		(net "P3V3_NODE1")
	)
	(segment
		(start 155.77058 -148.727922)
		(end 155.51658 -148.981922)
		(width 0.508)
		(layer "B.Cu")
		(net "P3V3_NODE1")
	)
	(segment
		(start 122.943112 -172.378624)
		(end 122.696224 -172.625512)
		(width 0.508)
		(layer "B.Cu")
		(net "P3V3_NODE1")
	)
	(segment
		(start 132.450586 -30.610048)
		(end 133.49478 -31.654242)
		(width 0.508)
		(layer "B.Cu")
		(net "P3V3_NODE1")
	)
	(segment
		(start 66.194686 -120.003062)
		(end 66.194686 -120.644412)
		(width 0.508)
		(layer "B.Cu")
		(net "P3V3_NODE1")
	)
	(segment
		(start 100.295964 -171.758102)
		(end 100.291392 -171.762674)
		(width 0.508)
		(layer "B.Cu")
		(net "P3V3_NODE1")
	)
	(segment
		(start 14.030452 -134.106158)
		(end 13.745718 -134.390892)
		(width 0.508)
		(layer "B.Cu")
		(net "P3V3_NODE1")
	)
	(segment
		(start 99.552252 -170.42765)
		(end 99.059746 -169.935144)
		(width 0.508)
		(layer "B.Cu")
		(net "P3V3_NODE1")
	)
	(segment
		(start 101.937566 -165.251892)
		(end 102.832662 -165.251892)
		(width 0.508)
		(layer "B.Cu")
		(net "P3V3_NODE1")
	)
	(segment
		(start 65.14846 -97.146872)
		(end 65.198498 -97.096834)
		(width 0.508)
		(layer "B.Cu")
		(net "P3V3_NODE1")
	)
	(segment
		(start 100.291392 -171.762674)
		(end 99.592638 -171.762674)
		(width 0.508)
		(layer "B.Cu")
		(net "P3V3_NODE1")
	)
	(segment
		(start 110.04931 -172.505624)
		(end 109.438694 -172.505624)
		(width 0.508)
		(layer "B.Cu")
		(net "P3V3_NODE1")
	)
	(segment
		(start 93.490796 -175.17618)
		(end 93.343984 -175.322992)
		(width 0.508)
		(layer "B.Cu")
		(net "P3V3_NODE1")
	)
	(segment
		(start 49.283112 -158.250382)
		(end 50.07102 -159.03829)
		(width 0.508)
		(layer "B.Cu")
		(net "P3V3_NODE1")
	)
	(segment
		(start 142.819628 -37.915596)
		(end 143.06042 -38.156388)
		(width 0.508)
		(layer "B.Cu")
		(net "P3V3_NODE1")
	)
	(segment
		(start 168.9227 -172.884592)
		(end 167.902636 -172.884592)
		(width 0.508)
		(layer "B.Cu")
		(net "P3V3_NODE1")
	)
	(segment
		(start 75.51547 -163.120832)
		(end 75.479148 -163.08451)
		(width 0.508)
		(layer "B.Cu")
		(net "P3V3_NODE1")
	)
	(segment
		(start 66.214498 -97.591118)
		(end 66.462402 -97.839022)
		(width 0.508)
		(layer "B.Cu")
		(net "P3V3_NODE1")
	)
	(segment
		(start 136.78535 -54.8894)
		(end 136.78535 -54.20995)
		(width 0.508)
		(layer "B.Cu")
		(net "P3V3_NODE1")
	)
	(segment
		(start 102.832662 -165.251892)
		(end 102.917752 -165.166802)
		(width 0.508)
		(layer "B.Cu")
		(net "P3V3_NODE1")
	)
	(segment
		(start 65.159128 -97.76333)
		(end 65.159128 -97.15754)
		(width 0.508)
		(layer "B.Cu")
		(net "P3V3_NODE1")
	)
	(segment
		(start 171.650406 -99.735894)
		(end 172.462444 -99.735894)
		(width 0.508)
		(layer "B.Cu")
		(net "P3V3_NODE1")
	)
	(segment
		(start 63.16726 -99.589082)
		(end 62.579504 -100.176838)
		(width 0.381)
		(layer "B.Cu")
		(net "P3V3_NODE1")
	)
	(segment
		(start 141.67231 -169.965624)
		(end 141.060424 -169.965624)
		(width 0.508)
		(layer "B.Cu")
		(net "P3V3_NODE1")
	)
	(segment
		(start 118.44274 -163.107116)
		(end 119.676926 -163.107116)
		(width 0.508)
		(layer "B.Cu")
		(net "P3V3_NODE1")
	)
	(segment
		(start 141.005052 -145.161)
		(end 140.071602 -145.161)
		(width 0.4572)
		(layer "B.Cu")
		(net "P3V3_NODE1")
	)
	(segment
		(start 133.997446 -163.884356)
		(end 133.997446 -164.48405)
		(width 0.508)
		(layer "B.Cu")
		(net "P3V3_NODE1")
	)
	(segment
		(start 144.747996 -59.56808)
		(end 144.747996 -58.87593)
		(width 0.508)
		(layer "B.Cu")
		(net "P3V3_NODE1")
	)
	(segment
		(start 23.140416 -97.908872)
		(end 25.08504 -95.964248)
		(width 0.508)
		(layer "B.Cu")
		(net "P3V3_NODE1")
	)
	(segment
		(start 82.838036 -165.654228)
		(end 81.906872 -165.654228)
		(width 0.3556)
		(layer "B.Cu")
		(net "P3V3_NODE1")
	)
	(segment
		(start 97.50044 -167.954706)
		(end 97.937066 -167.954706)
		(width 0.508)
		(layer "B.Cu")
		(net "P3V3_NODE1")
	)
	(segment
		(start 83.19516 -165.971728)
		(end 83.155536 -165.971728)
		(width 0.3556)
		(layer "B.Cu")
		(net "P3V3_NODE1")
	)
	(segment
		(start 133.969252 -150.9141)
		(end 133.969252 -149.99335)
		(width 0.4572)
		(layer "B.Cu")
		(net "P3V3_NODE1")
	)
	(segment
		(start 119.676926 -163.107116)
		(end 120.405906 -163.836096)
		(width 0.508)
		(layer "B.Cu")
		(net "P3V3_NODE1")
	)
	(segment
		(start 104.79532 -180.196236)
		(end 105.2957 -179.695856)
		(width 0.508)
		(layer "B.Cu")
		(net "P3V3_NODE1")
	)
	(segment
		(start 168.573196 -105.86339)
		(end 168.573196 -106.171746)
		(width 0.508)
		(layer "B.Cu")
		(net "P3V3_NODE1")
	)
	(segment
		(start 99.059746 -169.780712)
		(end 99.830382 -169.780712)
		(width 0.381)
		(layer "B.Cu")
		(net "P3V3_NODE1")
	)
	(segment
		(start 130.080512 -57.63895)
		(end 129.554986 -57.178956)
		(width 0.3302)
		(layer "B.Cu")
		(net "P3V3_NODE1")
	)
	(segment
		(start 133.969252 -149.99335)
		(end 134.020052 -149.94255)
		(width 0.4572)
		(layer "B.Cu")
		(net "P3V3_NODE1")
	)
	(segment
		(start 63.832486 -120.644412)
		(end 63.832486 -120.028462)
		(width 0.508)
		(layer "B.Cu")
		(net "P3V3_NODE1")
	)
	(segment
		(start 78.43139 -166.409624)
		(end 78.43139 -165.393624)
		(width 0.508)
		(layer "B.Cu")
		(net "P3V3_NODE1")
	)
	(segment
		(start 156.43733 -148.727922)
		(end 155.77058 -148.727922)
		(width 0.508)
		(layer "B.Cu")
		(net "P3V3_NODE1")
	)
	(segment
		(start 164.717222 -105.33507)
		(end 164.717222 -105.974134)
		(width 0.508)
		(layer "B.Cu")
		(net "P3V3_NODE1")
	)
	(segment
		(start 168.462452 -105.27284)
		(end 168.462452 -105.752646)
		(width 0.508)
		(layer "B.Cu")
		(net "P3V3_NODE1")
	)
	(segment
		(start 167.1193 -172.884592)
		(end 167.10152 -172.902372)
		(width 0.508)
		(layer "B.Cu")
		(net "P3V3_NODE1")
	)
	(segment
		(start 62.102492 -178.6001)
		(end 63.70193 -178.6001)
		(width 0.508)
		(layer "B.Cu")
		(net "P3V3_NODE1")
	)
	(segment
		(start 171.580302 -99.66579)
		(end 171.650406 -99.735894)
		(width 0.508)
		(layer "B.Cu")
		(net "P3V3_NODE1")
	)
	(segment
		(start 139.71016 -61.957966)
		(end 139.845796 -61.82233)
		(width 0.508)
		(layer "B.Cu")
		(net "P3V3_NODE1")
	)
	(segment
		(start 155.51658 -149.288246)
		(end 155.51658 -148.981922)
		(width 0.508)
		(layer "B.Cu")
		(net "P3V3_NODE1")
	)
	(segment
		(start 69.262498 -97.458276)
		(end 69.262498 -97.096834)
		(width 0.508)
		(layer "B.Cu")
		(net "P3V3_NODE1")
	)
	(segment
		(start 47.74438 -97.504504)
		(end 46.971458 -97.504504)
		(width 0.508)
		(layer "B.Cu")
		(net "P3V3_NODE1")
	)
	(segment
		(start 126.439676 -40.071294)
		(end 127.287274 -40.071294)
		(width 0.508)
		(layer "B.Cu")
		(net "P3V3_NODE1")
	)
	(segment
		(start 104.296718 -181.392322)
		(end 104.79532 -180.89372)
		(width 0.508)
		(layer "B.Cu")
		(net "P3V3_NODE1")
	)
	(segment
		(start 93.70568 -182.094886)
		(end 93.70568 -181.668674)
		(width 0.508)
		(layer "B.Cu")
		(net "P3V3_NODE1")
	)
	(segment
		(start 103.36276 -172.994574)
		(end 104.17429 -172.994574)
		(width 0.3302)
		(layer "B.Cu")
		(net "P3V3_NODE1")
	)
	(segment
		(start 94.051882 -175.17618)
		(end 93.490796 -175.17618)
		(width 0.508)
		(layer "B.Cu")
		(net "P3V3_NODE1")
	)
	(segment
		(start 164.854128 -158.608522)
		(end 164.770054 -158.692596)
		(width 0.508)
		(layer "B.Cu")
		(net "P3V3_NODE1")
	)
	(segment
		(start 140.071602 -145.161)
		(end 140.014452 -145.21815)
		(width 0.4572)
		(layer "B.Cu")
		(net "P3V3_NODE1")
	)
	(segment
		(start 92.68968 -182.094886)
		(end 92.68968 -181.887114)
		(width 0.508)
		(layer "B.Cu")
		(net "P3V3_NODE1")
	)
	(segment
		(start 102.24516 -180.581046)
		(end 103.056436 -181.392322)
		(width 0.508)
		(layer "B.Cu")
		(net "P3V3_NODE1")
	)
	(segment
		(start 138.541252 -137.01395)
		(end 138.465052 -137.09015)
		(width 0.4572)
		(layer "B.Cu")
		(net "P3V3_NODE1")
	)
	(segment
		(start 162.003994 -98.37039)
		(end 161.79546 -98.161856)
		(width 0.508)
		(layer "B.Cu")
		(net "P3V3_NODE1")
	)
	(segment
		(start 78.268068 -166.573962)
		(end 78.43139 -166.41064)
		(width 0.508)
		(layer "B.Cu")
		(net "P3V3_NODE1")
	)
	(segment
		(start 160.805622 -158.17088)
		(end 160.269936 -158.706566)
		(width 0.508)
		(layer "B.Cu")
		(net "P3V3_NODE1")
	)
	(segment
		(start 66.214498 -97.096834)
		(end 66.214498 -97.591118)
		(width 0.508)
		(layer "B.Cu")
		(net "P3V3_NODE1")
	)
	(segment
		(start 171.580302 -103.32339)
		(end 171.834302 -103.57739)
		(width 0.508)
		(layer "B.Cu")
		(net "P3V3_NODE1")
	)
	(segment
		(start 137.569956 -40.49141)
		(end 136.726676 -40.49141)
		(width 0.508)
		(layer "B.Cu")
		(net "P3V3_NODE1")
	)
	(segment
		(start 139.845796 -61.82233)
		(end 140.360146 -61.82233)
		(width 0.508)
		(layer "B.Cu")
		(net "P3V3_NODE1")
	)
	(segment
		(start 69.471286 -119.798846)
		(end 69.471286 -119.158512)
		(width 0.508)
		(layer "B.Cu")
		(net "P3V3_NODE1")
	)
	(segment
		(start 124.71019 -173.648624)
		(end 124.96419 -173.394624)
		(width 0.508)
		(layer "B.Cu")
		(net "P3V3_NODE1")
	)
	(segment
		(start 128.005332 -135.13054)
		(end 128.005332 -134.46887)
		(width 0.4572)
		(layer "B.Cu")
		(net "P3V3_NODE1")
	)
	(segment
		(start 40.10787 -149.41169)
		(end 40.733472 -149.41169)
		(width 0.508)
		(layer "B.Cu")
		(net "P3V3_NODE1")
	)
	(segment
		(start 18.168874 -99.605592)
		(end 18.810732 -98.963734)
		(width 0.508)
		(layer "B.Cu")
		(net "P3V3_NODE1")
	)
	(segment
		(start 137.571988 -164.442648)
		(end 137.52576 -164.488876)
		(width 0.508)
		(layer "B.Cu")
		(net "P3V3_NODE1")
	)
	(segment
		(start 69.262498 -97.61474)
		(end 69.262498 -97.458276)
		(width 0.381)
		(layer "B.Cu")
		(net "P3V3_NODE1")
	)
	(segment
		(start 66.194686 -119.158512)
		(end 66.194686 -120.003062)
		(width 0.508)
		(layer "B.Cu")
		(net "P3V3_NODE1")
	)
	(segment
		(start 119.36476 -173.629574)
		(end 121.445782 -173.629574)
		(width 0.3556)
		(layer "B.Cu")
		(net "P3V3_NODE1")
	)
	(segment
		(start 57.437274 -98.062796)
		(end 57.437274 -97.46361)
		(width 0.508)
		(layer "B.Cu")
		(net "P3V3_NODE1")
	)
	(segment
		(start 136.724136 -54.950614)
		(end 136.78535 -54.8894)
		(width 0.3302)
		(layer "B.Cu")
		(net "P3V3_NODE1")
	)
	(segment
		(start 102.917752 -165.166802)
		(end 103.506524 -165.166802)
		(width 0.508)
		(layer "B.Cu")
		(net "P3V3_NODE1")
	)
	(segment
		(start 77.539596 -166.559738)
		(end 77.55382 -166.573962)
		(width 0.508)
		(layer "B.Cu")
		(net "P3V3_NODE1")
	)
	(segment
		(start 78.43139 -166.41064)
		(end 78.43139 -166.409624)
		(width 0.508)
		(layer "B.Cu")
		(net "P3V3_NODE1")
	)
	(segment
		(start 164.27323 -158.195772)
		(end 164.770054 -158.692596)
		(width 0.508)
		(layer "B.Cu")
		(net "P3V3_NODE1")
	)
	(segment
		(start 18.762472 -101.069902)
		(end 18.168874 -100.476304)
		(width 0.508)
		(layer "B.Cu")
		(net "P3V3_NODE1")
	)
	(segment
		(start 63.527686 -146.788886)
		(end 63.527686 -147.06981)
		(width 0.508)
		(layer "B.Cu")
		(net "P3V3_NODE1")
	)
	(segment
		(start 124.10821 -173.394624)
		(end 124.71019 -173.648624)
		(width 0.508)
		(layer "B.Cu")
		(net "P3V3_NODE1")
	)
	(segment
		(start 129.54 -59.83605)
		(end 129.54 -60.325)
		(width 0.508)
		(layer "B.Cu")
		(net "P3V3_NODE1")
	)
	(segment
		(start 57.437274 -97.46361)
		(end 57.070498 -97.096834)
		(width 0.508)
		(layer "B.Cu")
		(net "P3V3_NODE1")
	)
	(segment
		(start 89.891108 -169.450512)
		(end 89.807796 -169.533824)
		(width 0.254)
		(layer "B.Cu")
		(net "P3V3_NODE1")
	)
	(segment
		(start 97.937066 -167.954706)
		(end 98.087942 -168.204388)
		(width 0.508)
		(layer "B.Cu")
		(net "P3V3_NODE1")
	)
	(segment
		(start 139.227052 -150.8887)
		(end 139.227052 -150.190454)
		(width 0.4572)
		(layer "B.Cu")
		(net "P3V3_NODE1")
	)
	(segment
		(start 64.899286 -119.952262)
		(end 64.899286 -119.158512)
		(width 0.508)
		(layer "B.Cu")
		(net "P3V3_NODE1")
	)
	(segment
		(start 165.652958 -185.083196)
		(end 166.515796 -185.083196)
		(width 0.508)
		(layer "B.Cu")
		(net "P3V3_NODE1")
	)
	(segment
		(start 78.43139 -168.441624)
		(end 77.798676 -168.441624)
		(width 0.508)
		(layer "B.Cu")
		(net "P3V3_NODE1")
	)
	(segment
		(start 49.81702 -159.29229)
		(end 50.07102 -159.03829)
		(width 0.508)
		(layer "B.Cu")
		(net "P3V3_NODE1")
	)
	(segment
		(start 29.72562 -98.353626)
		(end 26.200354 -94.82836)
		(width 0.508)
		(layer "B.Cu")
		(net "P3V3_NODE1")
	)
	(segment
		(start 49.15027 -159.29229)
		(end 49.81702 -159.29229)
		(width 0.508)
		(layer "B.Cu")
		(net "P3V3_NODE1")
	)
	(segment
		(start 59.771026 -118.647972)
		(end 59.771026 -117.947948)
		(width 0.508)
		(layer "B.Cu")
		(net "P3V3_NODE1")
	)
	(segment
		(start 150.00478 -169.534078)
		(end 150.417276 -169.946574)
		(width 0.254)
		(layer "B.Cu")
		(net "P3V3_NODE1")
	)
	(segment
		(start 165.411658 -184.067196)
		(end 166.68242 -184.067196)
		(width 0.508)
		(layer "B.Cu")
		(net "P3V3_NODE1")
	)
	(segment
		(start 160.816798 -158.17088)
		(end 160.805622 -158.17088)
		(width 0.508)
		(layer "B.Cu")
		(net "P3V3_NODE1")
	)
	(segment
		(start 93.70568 -181.668674)
		(end 93.3069 -181.269894)
		(width 0.508)
		(layer "B.Cu")
		(net "P3V3_NODE1")
	)
	(segment
		(start 41.31437 -149.82444)
		(end 40.817546 -149.327616)
		(width 0.508)
		(layer "B.Cu")
		(net "P3V3_NODE1")
	)
	(segment
		(start 61.462666 -120.010682)
		(end 61.444886 -120.028462)
		(width 0.508)
		(layer "B.Cu")
		(net "P3V3_NODE1")
	)
	(segment
		(start 130.96621 -30.610048)
		(end 132.450586 -30.610048)
		(width 0.508)
		(layer "B.Cu")
		(net "P3V3_NODE1")
	)
	(segment
		(start 99.059746 -169.935144)
		(end 99.059746 -169.780712)
		(width 0.508)
		(layer "B.Cu")
		(net "P3V3_NODE1")
	)
	(segment
		(start 18.810732 -98.963734)
		(end 19.865594 -97.908872)
		(width 0.508)
		(layer "B.Cu")
		(net "P3V3_NODE1")
	)
	(segment
		(start 18.168874 -100.476304)
		(end 18.168874 -99.605592)
		(width 0.508)
		(layer "B.Cu")
		(net "P3V3_NODE1")
	)
	(segment
		(start 124.96419 -173.394624)
		(end 125.042676 -173.316138)
		(width 0.508)
		(layer "B.Cu")
		(net "P3V3_NODE1")
	)
	(segment
		(start 122.155204 -163.836096)
		(end 122.47372 -164.154612)
		(width 0.508)
		(layer "B.Cu")
		(net "P3V3_NODE1")
	)
	(segment
		(start 92.68968 -181.887114)
		(end 93.3069 -181.269894)
		(width 0.508)
		(layer "B.Cu")
		(net "P3V3_NODE1")
	)
	(segment
		(start 141.67231 -168.949624)
		(end 141.060424 -168.949624)
		(width 0.508)
		(layer "B.Cu")
		(net "P3V3_NODE1")
	)
	(segment
		(start 130.914902 -151.03475)
		(end 130.914902 -150.1013)
		(width 0.4572)
		(layer "B.Cu")
		(net "P3V3_NODE1")
	)
	(segment
		(start 62.506606 -120.01119)
		(end 62.511686 -120.00611)
		(width 0.508)
		(layer "B.Cu")
		(net "P3V3_NODE1")
	)
	(segment
		(start 62.579504 -100.176838)
		(end 61.044836 -100.176838)
		(width 0.381)
		(layer "B.Cu")
		(net "P3V3_NODE1")
	)
	(segment
		(start 142.201646 -37.915596)
		(end 142.819628 -37.915596)
		(width 0.508)
		(layer "B.Cu")
		(net "P3V3_NODE1")
	)
	(segment
		(start 129.554986 -57.178956)
		(end 129.554986 -56.207406)
		(width 0.3302)
		(layer "B.Cu")
		(net "P3V3_NODE1")
	)
	(segment
		(start 102.157022 -172.569632)
		(end 101.703632 -173.023022)
		(width 0.4064)
		(layer "B.Cu")
		(net "P3V3_NODE1")
	)
	(segment
		(start 167.902636 -172.884592)
		(end 167.1193 -172.884592)
		(width 0.508)
		(layer "B.Cu")
		(net "P3V3_NODE1")
	)
	(segment
		(start 103.829866 -165.166802)
		(end 104.058466 -164.938202)
		(width 0.508)
		(layer "B.Cu")
		(net "P3V3_NODE1")
	)
	(segment
		(start 171.834302 -103.57739)
		(end 172.424852 -103.57739)
		(width 0.508)
		(layer "B.Cu")
		(net "P3V3_NODE1")
	)
	(segment
		(start 119.27205 -35.54095)
		(end 119.761 -35.052)
		(width 0.508)
		(layer "B.Cu")
		(net "P3V3_NODE1")
	)
	(segment
		(start 62.506606 -120.657366)
		(end 62.506606 -120.01119)
		(width 0.508)
		(layer "B.Cu")
		(net "P3V3_NODE1")
	)
	(segment
		(start 100.152454 -170.102784)
		(end 100.688394 -170.102784)
		(width 0.381)
		(layer "B.Cu")
		(net "P3V3_NODE1")
	)
	(segment
		(start 134.73811 -165.224714)
		(end 135.12038 -165.224714)
		(width 0.508)
		(layer "B.Cu")
		(net "P3V3_NODE1")
	)
	(segment
		(start 61.444886 -120.644412)
		(end 61.444886 -120.028462)
		(width 0.508)
		(layer "B.Cu")
		(net "P3V3_NODE1")
	)
	(segment
		(start 121.412 -53.35905)
		(end 121.412 -53.975)
		(width 0.508)
		(layer "B.Cu")
		(net "P3V3_NODE1")
	)
	(segment
		(start 162.728402 -98.37039)
		(end 162.003994 -98.37039)
		(width 0.508)
		(layer "B.Cu")
		(net "P3V3_NODE1")
	)
	(segment
		(start 49.158652 -158.250382)
		(end 49.283112 -158.250382)
		(width 0.508)
		(layer "B.Cu")
		(net "P3V3_NODE1")
	)
	(segment
		(start 90.41257 -168.942512)
		(end 90.399108 -168.942512)
		(width 0.508)
		(layer "B.Cu")
		(net "P3V3_NODE1")
	)
	(segment
		(start 150.00478 -168.612312)
		(end 150.00478 -169.534078)
		(width 0.254)
		(layer "B.Cu")
		(net "P3V3_NODE1")
	)
	(segment
		(start 141.522196 -69.79793)
		(end 141.530578 -69.806312)
		(width 0.508)
		(layer "B.Cu")
		(net "P3V3_NODE1")
	)
	(segment
		(start 169.534078 -154.804872)
		(end 169.757852 -154.804872)
		(width 0.508)
		(layer "B.Cu")
		(net "P3V3_NODE1")
	)
	(segment
		(start 69.374512 -97.726754)
		(end 69.262498 -97.61474)
		(width 0.381)
		(layer "B.Cu")
		(net "P3V3_NODE1")
	)
	(segment
		(start 164.804852 -105.24744)
		(end 164.717222 -105.33507)
		(width 0.508)
		(layer "B.Cu")
		(net "P3V3_NODE1")
	)
	(segment
		(start 103.056436 -181.392322)
		(end 104.296718 -181.392322)
		(width 0.508)
		(layer "B.Cu")
		(net "P3V3_NODE1")
	)
	(segment
		(start 129.54 -60.325)
		(end 129.159 -60.706)
		(width 0.508)
		(layer "B.Cu")
		(net "P3V3_NODE1")
	)
	(segment
		(start 121.32056 -37.430456)
		(end 121.32056 -36.414456)
		(width 0.4572)
		(layer "B.Cu")
		(net "P3V3_NODE1")
	)
	(segment
		(start 56.940704 -98.559366)
		(end 57.437274 -98.062796)
		(width 0.508)
		(layer "B.Cu")
		(net "P3V3_NODE1")
	)
	(segment
		(start 77.55382 -166.573962)
		(end 78.268068 -166.573962)
		(width 0.508)
		(layer "B.Cu")
		(net "P3V3_NODE1")
	)
	(segment
		(start 68.379086 -119.158512)
		(end 68.379086 -119.952262)
		(width 0.508)
		(layer "B.Cu")
		(net "P3V3_NODE1")
	)
	(segment
		(start 104.058466 -164.938202)
		(end 104.373172 -164.938202)
		(width 0.508)
		(layer "B.Cu")
		(net "P3V3_NODE1")
	)
	(segment
		(start 140.039852 -139.9794)
		(end 139.252452 -139.9794)
		(width 0.4572)
		(layer "B.Cu")
		(net "P3V3_NODE1")
	)
	(segment
		(start 64.017144 -147.559268)
		(end 64.017144 -147.861274)
		(width 0.508)
		(layer "B.Cu")
		(net "P3V3_NODE1")
	)
	(segment
		(start 121.32056 -35.398456)
		(end 121.32056 -36.414456)
		(width 0.4572)
		(layer "B.Cu")
		(net "P3V3_NODE1")
	)
	(segment
		(start 134.922006 -54.950614)
		(end 136.724136 -54.950614)
		(width 0.3302)
		(layer "B.Cu")
		(net "P3V3_NODE1")
	)
	(segment
		(start 116.586 -51.54295)
		(end 116.586 -50.927)
		(width 0.508)
		(layer "B.Cu")
		(net "P3V3_NODE1")
	)
	(segment
		(start 126.439676 -41.214294)
		(end 127.244602 -41.214294)
		(width 0.508)
		(layer "B.Cu")
		(net "P3V3_NODE1")
	)
	(segment
		(start 76.34605 -163.120832)
		(end 75.51547 -163.120832)
		(width 0.508)
		(layer "B.Cu")
		(net "P3V3_NODE1")
	)
	(segment
		(start 118.25732 -162.919918)
		(end 118.25732 -162.921696)
		(width 0.508)
		(layer "B.Cu")
		(net "P3V3_NODE1")
	)
	(segment
		(start 37.52469 -145.56867)
		(end 36.386008 -145.56867)
		(width 0.508)
		(layer "B.Cu")
		(net "P3V3_NODE1")
	)
	(segment
		(start 60.748672 -170.74134)
		(end 60.748672 -170.604688)
		(width 0.508)
		(layer "In2.Cu")
		(net "P3V3_NODE1")
	)
	(segment
		(start 59.53252 -171.377356)
		(end 60.305188 -170.604688)
		(width 0.508)
		(layer "In2.Cu")
		(net "P3V3_NODE1")
	)
	(segment
		(start 90.762328 -180.10124)
		(end 90.188288 -179.5272)
		(width 0.508)
		(layer "In2.Cu")
		(net "P3V3_NODE1")
	)
	(segment
		(start 57.210198 -170.630088)
		(end 57.957466 -171.377356)
		(width 0.508)
		(layer "In2.Cu")
		(net "P3V3_NODE1")
	)
	(segment
		(start 15.02156 -104.810814)
		(end 18.762472 -101.069902)
		(width 0.508)
		(layer "In2.Cu")
		(net "P3V3_NODE1")
	)
	(segment
		(start 72.841612 -171.759626)
		(end 73.761854 -171.759626)
		(width 0.508)
		(layer "In2.Cu")
		(net "P3V3_NODE1")
	)
	(segment
		(start 66.31686 -171.85513)
		(end 66.31686 -176.324514)
		(width 0.508)
		(layer "In2.Cu")
		(net "P3V3_NODE1")
	)
	(segment
		(start 70.7009 -174.576486)
		(end 70.7009 -173.900338)
		(width 0.508)
		(layer "In2.Cu")
		(net "P3V3_NODE1")
	)
	(segment
		(start 63.336424 -171.425108)
		(end 61.43244 -171.425108)
		(width 0.508)
		(layer "In2.Cu")
		(net "P3V3_NODE1")
	)
	(segment
		(start 81.149444 -180.427884)
		(end 81.74228 -181.02072)
		(width 0.508)
		(layer "In2.Cu")
		(net "P3V3_NODE1")
	)
	(segment
		(start 75.22845 -170.29303)
		(end 76.96327 -170.29303)
		(width 0.508)
		(layer "In2.Cu")
		(net "P3V3_NODE1")
	)
	(segment
		(start 94.27718 -180.739796)
		(end 94.99219 -180.024786)
		(width 0.508)
		(layer "In2.Cu")
		(net "P3V3_NODE1")
	)
	(segment
		(start 80.13192 -180.82768)
		(end 80.531716 -180.427884)
		(width 0.508)
		(layer "In2.Cu")
		(net "P3V3_NODE1")
	)
	(segment
		(start 64.58966 -171.337732)
		(end 64.131444 -170.879516)
		(width 0.508)
		(layer "In2.Cu")
		(net "P3V3_NODE1")
	)
	(segment
		(start 95.815658 -180.024786)
		(end 96.494346 -180.703474)
		(width 0.508)
		(layer "In2.Cu")
		(net "P3V3_NODE1")
	)
	(segment
		(start 89.35974 -179.5272)
		(end 83.2358 -179.5272)
		(width 0.508)
		(layer "In2.Cu")
		(net "P3V3_NODE1")
	)
	(segment
		(start 64.131444 -170.879516)
		(end 64.131444 -170.630088)
		(width 0.508)
		(layer "In2.Cu")
		(net "P3V3_NODE1")
	)
	(segment
		(start 14.732 -104.810814)
		(end 15.02156 -104.810814)
		(width 0.508)
		(layer "In2.Cu")
		(net "P3V3_NODE1")
	)
	(segment
		(start 90.188288 -179.5272)
		(end 89.35974 -179.5272)
		(width 0.508)
		(layer "In2.Cu")
		(net "P3V3_NODE1")
	)
	(segment
		(start 66.834258 -171.337732)
		(end 66.31686 -171.85513)
		(width 0.508)
		(layer "In2.Cu")
		(net "P3V3_NODE1")
	)
	(segment
		(start 79.24546 -182.270654)
		(end 80.13192 -181.384194)
		(width 0.508)
		(layer "In2.Cu")
		(net "P3V3_NODE1")
	)
	(segment
		(start 83.2358 -179.5272)
		(end 81.74228 -181.02072)
		(width 0.508)
		(layer "In2.Cu")
		(net "P3V3_NODE1")
	)
	(segment
		(start 64.131444 -170.630088)
		(end 63.336424 -171.425108)
		(width 0.508)
		(layer "In2.Cu")
		(net "P3V3_NODE1")
	)
	(segment
		(start 78.536292 -182.979822)
		(end 79.24546 -182.270654)
		(width 0.508)
		(layer "In2.Cu")
		(net "P3V3_NODE1")
	)
	(segment
		(start 61.43244 -171.425108)
		(end 60.748672 -170.74134)
		(width 0.508)
		(layer "In2.Cu")
		(net "P3V3_NODE1")
	)
	(segment
		(start 80.13192 -181.384194)
		(end 80.13192 -180.82768)
		(width 0.508)
		(layer "In2.Cu")
		(net "P3V3_NODE1")
	)
	(segment
		(start 77.524102 -182.979822)
		(end 78.536292 -182.979822)
		(width 0.508)
		(layer "In2.Cu")
		(net "P3V3_NODE1")
	)
	(segment
		(start 64.041274 -178.6001)
		(end 63.70193 -178.6001)
		(width 0.508)
		(layer "In2.Cu")
		(net "P3V3_NODE1")
	)
	(segment
		(start 67.541902 -170.630088)
		(end 66.834258 -171.337732)
		(width 0.508)
		(layer "In2.Cu")
		(net "P3V3_NODE1")
	)
	(segment
		(start 92.138246 -180.10124)
		(end 90.762328 -180.10124)
		(width 0.508)
		(layer "In2.Cu")
		(net "P3V3_NODE1")
	)
	(segment
		(start 70.7009 -173.900338)
		(end 72.841612 -171.759626)
		(width 0.508)
		(layer "In2.Cu")
		(net "P3V3_NODE1")
	)
	(segment
		(start 93.3069 -181.269894)
		(end 92.138246 -180.10124)
		(width 0.508)
		(layer "In2.Cu")
		(net "P3V3_NODE1")
	)
	(segment
		(start 66.31686 -176.324514)
		(end 64.041274 -178.6001)
		(width 0.508)
		(layer "In2.Cu")
		(net "P3V3_NODE1")
	)
	(segment
		(start 73.761854 -171.759626)
		(end 75.22845 -170.29303)
		(width 0.508)
		(layer "In2.Cu")
		(net "P3V3_NODE1")
	)
	(segment
		(start 93.3069 -181.269894)
		(end 93.747082 -181.269894)
		(width 0.508)
		(layer "In2.Cu")
		(net "P3V3_NODE1")
	)
	(segment
		(start 60.305188 -170.604688)
		(end 60.748672 -170.604688)
		(width 0.508)
		(layer "In2.Cu")
		(net "P3V3_NODE1")
	)
	(segment
		(start 80.531716 -180.427884)
		(end 81.149444 -180.427884)
		(width 0.508)
		(layer "In2.Cu")
		(net "P3V3_NODE1")
	)
	(segment
		(start 96.494346 -180.703474)
		(end 97.27184 -180.703474)
		(width 0.508)
		(layer "In2.Cu")
		(net "P3V3_NODE1")
	)
	(segment
		(start 66.834258 -171.337732)
		(end 64.58966 -171.337732)
		(width 0.508)
		(layer "In2.Cu")
		(net "P3V3_NODE1")
	)
	(segment
		(start 94.99219 -180.024786)
		(end 95.815658 -180.024786)
		(width 0.508)
		(layer "In2.Cu")
		(net "P3V3_NODE1")
	)
	(segment
		(start 76.96327 -170.29303)
		(end 77.798676 -169.457624)
		(width 0.508)
		(layer "In2.Cu")
		(net "P3V3_NODE1")
	)
	(segment
		(start 93.747082 -181.269894)
		(end 94.27718 -180.739796)
		(width 0.508)
		(layer "In2.Cu")
		(net "P3V3_NODE1")
	)
	(segment
		(start 57.957466 -171.377356)
		(end 59.53252 -171.377356)
		(width 0.508)
		(layer "In2.Cu")
		(net "P3V3_NODE1")
	)
	(segment
		(start 85.32114 -173.28642)
		(end 85.68055 -173.64583)
		(width 0.508)
		(layer "In6.Cu")
		(net "P3V3_NODE1")
	)
	(segment
		(start 83.09102 -173.28642)
		(end 85.32114 -173.28642)
		(width 0.508)
		(layer "In6.Cu")
		(net "P3V3_NODE1")
	)
	(segment
		(start 56.148224 -81.171796)
		(end 53.29936 -78.322932)
		(width 0.508)
		(layer "In6.Cu")
		(net "P3V3_NODE1")
	)
	(segment
		(start 98.69678 -142.858744)
		(end 97.89414 -143.661384)
		(width 0.508)
		(layer "In6.Cu")
		(net "P3V3_NODE1")
	)
	(segment
		(start 101.03866 -126.620524)
		(end 98.69678 -128.962404)
		(width 0.508)
		(layer "In6.Cu")
		(net "P3V3_NODE1")
	)
	(segment
		(start 101.03866 -121.077736)
		(end 101.03866 -126.620524)
		(width 0.508)
		(layer "In6.Cu")
		(net "P3V3_NODE1")
	)
	(segment
		(start 77.798676 -169.457624)
		(end 79.262224 -169.457624)
		(width 0.508)
		(layer "In6.Cu")
		(net "P3V3_NODE1")
	)
	(segment
		(start 99.587304 -119.62638)
		(end 101.03866 -121.077736)
		(width 0.508)
		(layer "In6.Cu")
		(net "P3V3_NODE1")
	)
	(segment
		(start 53.29936 -77.836776)
		(end 52.462176 -76.999592)
		(width 0.508)
		(layer "In6.Cu")
		(net "P3V3_NODE1")
	)
	(segment
		(start 85.68055 -173.64583)
		(end 88.429592 -173.64583)
		(width 0.508)
		(layer "In6.Cu")
		(net "P3V3_NODE1")
	)
	(segment
		(start 79.262224 -169.457624)
		(end 83.09102 -173.28642)
		(width 0.508)
		(layer "In6.Cu")
		(net "P3V3_NODE1")
	)
	(segment
		(start 98.69678 -128.962404)
		(end 98.69678 -142.858744)
		(width 0.508)
		(layer "In6.Cu")
		(net "P3V3_NODE1")
	)
	(segment
		(start 58.818018 -81.722468)
		(end 58.267346 -81.171796)
		(width 0.508)
		(layer "In6.Cu")
		(net "P3V3_NODE1")
	)
	(segment
		(start 52.462176 -76.999592)
		(end 52.399946 -76.999592)
		(width 0.508)
		(layer "In6.Cu")
		(net "P3V3_NODE1")
	)
	(segment
		(start 53.29936 -78.322932)
		(end 53.29936 -77.836776)
		(width 0.508)
		(layer "In6.Cu")
		(net "P3V3_NODE1")
	)
	(segment
		(start 58.267346 -81.171796)
		(end 56.148224 -81.171796)
		(width 0.508)
		(layer "In6.Cu")
		(net "P3V3_NODE1")
	)
	(segment
		(start 97.89414 -143.661384)
		(end 97.89414 -143.794988)
		(width 0.508)
		(layer "In6.Cu")
		(net "P3V3_NODE1")
	)
	(segment
		(start 88.429592 -173.64583)
		(end 89.72804 -174.944278)
		(width 0.508)
		(layer "In6.Cu")
		(net "P3V3_NODE1")
	)
	(segment
		(start 92.325444 -98.28657)
		(end 96.069658 -98.28657)
		(width 0.508)
		(layer "In7.Cu")
		(net "P3V3_NODE1")
	)
	(segment
		(start 97.27184 -173.386242)
		(end 96.466914 -172.581316)
		(width 0.508)
		(layer "In7.Cu")
		(net "P3V3_NODE1")
	)
	(segment
		(start 97.27184 -180.703474)
		(end 97.27184 -173.386242)
		(width 0.508)
		(layer "In7.Cu")
		(net "P3V3_NODE1")
	)
	(segment
		(start 92.230194 -98.19132)
		(end 92.325444 -98.28657)
		(width 0.508)
		(layer "In7.Cu")
		(net "P3V3_NODE1")
	)
	(segment
		(start 87.23122 -98.027998)
		(end 87.394542 -98.19132)
		(width 0.508)
		(layer "In7.Cu")
		(net "P3V3_NODE1")
	)
	(segment
		(start 96.069658 -98.28657)
		(end 96.22282 -98.133408)
		(width 0.508)
		(layer "In7.Cu")
		(net "P3V3_NODE1")
	)
	(segment
		(start 87.394542 -98.19132)
		(end 92.230194 -98.19132)
		(width 0.508)
		(layer "In7.Cu")
		(net "P3V3_NODE1")
	)
	(segment
		(start 108.871512 -131.002278)
		(end 108.871512 -132.372862)
		(width 0.1778)
		(layer "F.Cu")
		(net "VR_PVCCP_NODE1_PHASE1")
	)
	(via
		(at 111.179864 -120.97893)
		(size 0.508)
		(drill 0.254)
		(layers "F.Cu" "B.Cu")
		(net "VR_PVCCP_NODE1_PHASE1")
	)
	(segment
		(start 59.741816 -128.059434)
		(end 59.741816 -128.058926)
		(width 0.1016)
		(layer "F.Cu")
		(net "FM_BMC_NODE1_RESET_L")
	)
	(segment
		(start 166.33317 -119.39651)
		(end 166.33317 -118.867682)
		(width 0.1016)
		(layer "F.Cu")
		(net "FM_BMC_NODE1_RESET_L")
	)
	(segment
		(start 59.741816 -128.058926)
		(end 59.341004 -127.658114)
		(width 0.1016)
		(layer "F.Cu")
		(net "FM_BMC_NODE1_RESET_L")
	)
	(segment
		(start 47.957486 -123.21667)
		(end 49.149 -124.408184)
		(width 0.1016)
		(layer "F.Cu")
		(net "FM_BMC_NODE1_RESET_L")
	)
	(segment
		(start 46.09338 -123.21667)
		(end 47.957486 -123.21667)
		(width 0.1016)
		(layer "F.Cu")
		(net "FM_BMC_NODE1_RESET_L")
	)
	(segment
		(start 166.33317 -118.867682)
		(end 165.63594 -118.170452)
		(width 0.1016)
		(layer "F.Cu")
		(net "FM_BMC_NODE1_RESET_L")
	)
	(via
		(at 59.341004 -127.658114)
		(size 0.49022)
		(drill 0.254)
		(layers "F.Cu" "B.Cu")
		(net "FM_BMC_NODE1_RESET_L")
	)
	(via
		(at 49.149 -124.408184)
		(size 0.508)
		(drill 0.254)
		(layers "F.Cu" "B.Cu")
		(net "FM_BMC_NODE1_RESET_L")
	)
	(via
		(at 71.17334 -117.033548)
		(size 0.508)
		(drill 0.254)
		(layers "F.Cu" "B.Cu")
		(net "FM_BMC_NODE1_RESET_L")
	)
	(via
		(at 165.63594 -118.170452)
		(size 0.508)
		(drill 0.254)
		(layers "F.Cu" "B.Cu")
		(net "FM_BMC_NODE1_RESET_L")
	)
	(segment
		(start 62.284356 -118.590822)
		(end 61.133482 -117.439948)
		(width 0.1016)
		(layer "B.Cu")
		(net "FM_BMC_NODE1_RESET_L")
	)
	(segment
		(start 59.263026 -117.737382)
		(end 59.26074 -117.737382)
		(width 0.1016)
		(layer "B.Cu")
		(net "FM_BMC_NODE1_RESET_L")
	)
	(segment
		(start 61.133482 -117.439948)
		(end 59.56046 -117.439948)
		(width 0.1016)
		(layer "B.Cu")
		(net "FM_BMC_NODE1_RESET_L")
	)
	(segment
		(start 58.828686 -122.653044)
		(end 59.120786 -122.945144)
		(width 0.1016)
		(layer "B.Cu")
		(net "FM_BMC_NODE1_RESET_L")
	)
	(segment
		(start 58.828686 -118.91391)
		(end 58.828686 -122.653044)
		(width 0.1016)
		(layer "B.Cu")
		(net "FM_BMC_NODE1_RESET_L")
	)
	(segment
		(start 59.26074 -118.481856)
		(end 58.828686 -118.91391)
		(width 0.1016)
		(layer "B.Cu")
		(net "FM_BMC_NODE1_RESET_L")
	)
	(segment
		(start 62.861444 -118.590822)
		(end 62.284356 -118.590822)
		(width 0.1016)
		(layer "B.Cu")
		(net "FM_BMC_NODE1_RESET_L")
	)
	(segment
		(start 63.500254 -117.952012)
		(end 62.861444 -118.590822)
		(width 0.1016)
		(layer "B.Cu")
		(net "FM_BMC_NODE1_RESET_L")
	)
	(segment
		(start 59.26074 -117.737382)
		(end 59.26074 -118.481856)
		(width 0.1016)
		(layer "B.Cu")
		(net "FM_BMC_NODE1_RESET_L")
	)
	(segment
		(start 59.120786 -126.991618)
		(end 59.341004 -127.211836)
		(width 0.1016)
		(layer "B.Cu")
		(net "FM_BMC_NODE1_RESET_L")
	)
	(segment
		(start 70.758304 -117.033548)
		(end 69.83984 -117.952012)
		(width 0.1016)
		(layer "B.Cu")
		(net "FM_BMC_NODE1_RESET_L")
	)
	(segment
		(start 59.120786 -122.945144)
		(end 59.120786 -126.991618)
		(width 0.1016)
		(layer "B.Cu")
		(net "FM_BMC_NODE1_RESET_L")
	)
	(segment
		(start 69.83984 -117.952012)
		(end 63.500254 -117.952012)
		(width 0.1016)
		(layer "B.Cu")
		(net "FM_BMC_NODE1_RESET_L")
	)
	(segment
		(start 71.17334 -117.033548)
		(end 70.758304 -117.033548)
		(width 0.1016)
		(layer "B.Cu")
		(net "FM_BMC_NODE1_RESET_L")
	)
	(segment
		(start 59.56046 -117.439948)
		(end 59.263026 -117.737382)
		(width 0.1016)
		(layer "B.Cu")
		(net "FM_BMC_NODE1_RESET_L")
	)
	(segment
		(start 59.341004 -127.211836)
		(end 59.341004 -127.658114)
		(width 0.1016)
		(layer "B.Cu")
		(net "FM_BMC_NODE1_RESET_L")
	)
	(segment
		(start 58.010552 -126.327662)
		(end 56.579262 -126.327662)
		(width 0.1143)
		(layer "In2.Cu")
		(net "FM_BMC_NODE1_RESET_L")
	)
	(segment
		(start 59.341004 -127.658114)
		(end 58.010552 -126.327662)
		(width 0.1143)
		(layer "In2.Cu")
		(net "FM_BMC_NODE1_RESET_L")
	)
	(segment
		(start 49.73447 -124.993654)
		(end 49.149 -124.408184)
		(width 0.1143)
		(layer "In2.Cu")
		(net "FM_BMC_NODE1_RESET_L")
	)
	(segment
		(start 55.245254 -124.993654)
		(end 49.73447 -124.993654)
		(width 0.1143)
		(layer "In2.Cu")
		(net "FM_BMC_NODE1_RESET_L")
	)
	(segment
		(start 56.579262 -126.327662)
		(end 55.245254 -124.993654)
		(width 0.1143)
		(layer "In2.Cu")
		(net "FM_BMC_NODE1_RESET_L")
	)
	(segment
		(start 109.570266 -112.728756)
		(end 107.012486 -112.728756)
		(width 0.1143)
		(layer "In6.Cu")
		(net "FM_BMC_NODE1_RESET_L")
	)
	(segment
		(start 93.021404 -119.470678)
		(end 85.291676 -119.470678)
		(width 0.1143)
		(layer "In6.Cu")
		(net "FM_BMC_NODE1_RESET_L")
	)
	(segment
		(start 133.992874 -124.111258)
		(end 129.95402 -124.111258)
		(width 0.1143)
		(layer "In6.Cu")
		(net "FM_BMC_NODE1_RESET_L")
	)
	(segment
		(start 164.774372 -117.308884)
		(end 162.103308 -117.308884)
		(width 0.1143)
		(layer "In6.Cu")
		(net "FM_BMC_NODE1_RESET_L")
	)
	(segment
		(start 129.95402 -124.111258)
		(end 126.084076 -120.241314)
		(width 0.1143)
		(layer "In6.Cu")
		(net "FM_BMC_NODE1_RESET_L")
	)
	(segment
		(start 126.084076 -120.241314)
		(end 126.084076 -119.190262)
		(width 0.1143)
		(layer "In6.Cu")
		(net "FM_BMC_NODE1_RESET_L")
	)
	(segment
		(start 160.76422 -117.821202)
		(end 159.504634 -119.080788)
		(width 0.1143)
		(layer "In6.Cu")
		(net "FM_BMC_NODE1_RESET_L")
	)
	(segment
		(start 93.28404 -119.208042)
		(end 93.021404 -119.470678)
		(width 0.1143)
		(layer "In6.Cu")
		(net "FM_BMC_NODE1_RESET_L")
	)
	(segment
		(start 85.291676 -119.470678)
		(end 83.03133 -117.210332)
		(width 0.1143)
		(layer "In6.Cu")
		(net "FM_BMC_NODE1_RESET_L")
	)
	(segment
		(start 159.504634 -119.080788)
		(end 152.81529 -119.080788)
		(width 0.1143)
		(layer "In6.Cu")
		(net "FM_BMC_NODE1_RESET_L")
	)
	(segment
		(start 148.45792 -123.438158)
		(end 137.635996 -123.438158)
		(width 0.1143)
		(layer "In6.Cu")
		(net "FM_BMC_NODE1_RESET_L")
	)
	(segment
		(start 165.63594 -118.170452)
		(end 164.774372 -117.308884)
		(width 0.1143)
		(layer "In6.Cu")
		(net "FM_BMC_NODE1_RESET_L")
	)
	(segment
		(start 96.87814 -117.898164)
		(end 95.568262 -119.208042)
		(width 0.1143)
		(layer "In6.Cu")
		(net "FM_BMC_NODE1_RESET_L")
	)
	(segment
		(start 137.29843 -123.100592)
		(end 135.00354 -123.100592)
		(width 0.1143)
		(layer "In6.Cu")
		(net "FM_BMC_NODE1_RESET_L")
	)
	(segment
		(start 106.281728 -113.459514)
		(end 100.81514 -113.459514)
		(width 0.1143)
		(layer "In6.Cu")
		(net "FM_BMC_NODE1_RESET_L")
	)
	(segment
		(start 107.012486 -112.728756)
		(end 106.281728 -113.459514)
		(width 0.1143)
		(layer "In6.Cu")
		(net "FM_BMC_NODE1_RESET_L")
	)
	(segment
		(start 161.59099 -117.821202)
		(end 160.76422 -117.821202)
		(width 0.1143)
		(layer "In6.Cu")
		(net "FM_BMC_NODE1_RESET_L")
	)
	(segment
		(start 95.568262 -119.208042)
		(end 93.28404 -119.208042)
		(width 0.1143)
		(layer "In6.Cu")
		(net "FM_BMC_NODE1_RESET_L")
	)
	(segment
		(start 152.81529 -119.080788)
		(end 148.45792 -123.438158)
		(width 0.1143)
		(layer "In6.Cu")
		(net "FM_BMC_NODE1_RESET_L")
	)
	(segment
		(start 76.02728 -117.210332)
		(end 75.850496 -117.033548)
		(width 0.1143)
		(layer "In6.Cu")
		(net "FM_BMC_NODE1_RESET_L")
	)
	(segment
		(start 100.81514 -113.459514)
		(end 96.87814 -117.396514)
		(width 0.1143)
		(layer "In6.Cu")
		(net "FM_BMC_NODE1_RESET_L")
	)
	(segment
		(start 75.850496 -117.033548)
		(end 71.17334 -117.033548)
		(width 0.1143)
		(layer "In6.Cu")
		(net "FM_BMC_NODE1_RESET_L")
	)
	(segment
		(start 137.635996 -123.438158)
		(end 137.29843 -123.100592)
		(width 0.1143)
		(layer "In6.Cu")
		(net "FM_BMC_NODE1_RESET_L")
	)
	(segment
		(start 83.03133 -117.210332)
		(end 76.02728 -117.210332)
		(width 0.1143)
		(layer "In6.Cu")
		(net "FM_BMC_NODE1_RESET_L")
	)
	(segment
		(start 109.882432 -112.41659)
		(end 109.570266 -112.728756)
		(width 0.1143)
		(layer "In6.Cu")
		(net "FM_BMC_NODE1_RESET_L")
	)
	(segment
		(start 162.103308 -117.308884)
		(end 161.59099 -117.821202)
		(width 0.1143)
		(layer "In6.Cu")
		(net "FM_BMC_NODE1_RESET_L")
	)
	(segment
		(start 126.084076 -119.190262)
		(end 119.310404 -112.41659)
		(width 0.1143)
		(layer "In6.Cu")
		(net "FM_BMC_NODE1_RESET_L")
	)
	(segment
		(start 96.87814 -117.396514)
		(end 96.87814 -117.898164)
		(width 0.1143)
		(layer "In6.Cu")
		(net "FM_BMC_NODE1_RESET_L")
	)
	(segment
		(start 119.310404 -112.41659)
		(end 109.882432 -112.41659)
		(width 0.1143)
		(layer "In6.Cu")
		(net "FM_BMC_NODE1_RESET_L")
	)
	(segment
		(start 135.00354 -123.100592)
		(end 133.992874 -124.111258)
		(width 0.1143)
		(layer "In6.Cu")
		(net "FM_BMC_NODE1_RESET_L")
	)
	(segment
		(start 44.833032 -136.963658)
		(end 44.22267 -137.57402)
		(width 0.1016)
		(layer "F.Cu")
		(net "BMC_NODE1_DDR_D3")
	)
	(segment
		(start 57.930288 -135.259572)
		(end 57.553352 -134.882636)
		(width 0.1016)
		(layer "F.Cu")
		(net "BMC_NODE1_DDR_D3")
	)
	(segment
		(start 56.40705 -135.624062)
		(end 54.639972 -135.624062)
		(width 0.1016)
		(layer "F.Cu")
		(net "BMC_NODE1_DDR_D3")
	)
	(segment
		(start 54.639972 -135.624062)
		(end 53.934868 -136.329166)
		(width 0.1016)
		(layer "F.Cu")
		(net "BMC_NODE1_DDR_D3")
	)
	(segment
		(start 57.148476 -134.882636)
		(end 56.40705 -135.624062)
		(width 0.1016)
		(layer "F.Cu")
		(net "BMC_NODE1_DDR_D3")
	)
	(segment
		(start 57.553352 -134.882636)
		(end 57.148476 -134.882636)
		(width 0.1016)
		(layer "F.Cu")
		(net "BMC_NODE1_DDR_D3")
	)
	(segment
		(start 58.14187 -135.259572)
		(end 57.930288 -135.259572)
		(width 0.1016)
		(layer "F.Cu")
		(net "BMC_NODE1_DDR_D3")
	)
	(segment
		(start 44.22267 -137.57402)
		(end 44.22267 -137.74166)
		(width 0.1016)
		(layer "F.Cu")
		(net "BMC_NODE1_DDR_D3")
	)
	(via
		(at 53.934868 -136.329166)
		(size 0.508)
		(drill 0.254)
		(layers "F.Cu" "B.Cu")
		(net "BMC_NODE1_DDR_D3")
	)
	(via
		(at 44.22267 -137.74166)
		(size 0.49022)
		(drill 0.254)
		(layers "F.Cu" "B.Cu")
		(net "BMC_NODE1_DDR_D3")
	)
	(segment
		(start 47.194724 -138.997182)
		(end 47.660814 -138.997182)
		(width 0.1143)
		(layer "In7.Cu")
		(net "BMC_NODE1_DDR_D3")
	)
	(segment
		(start 48.196754 -138.461242)
		(end 49.804066 -138.461242)
		(width 0.1143)
		(layer "In7.Cu")
		(net "BMC_NODE1_DDR_D3")
	)
	(segment
		(start 52.215542 -138.853164)
		(end 54.085998 -136.982708)
		(width 0.1143)
		(layer "In7.Cu")
		(net "BMC_NODE1_DDR_D3")
	)
	(segment
		(start 44.22267 -137.74166)
		(end 44.40809 -137.92708)
		(width 0.1143)
		(layer "In7.Cu")
		(net "BMC_NODE1_DDR_D3")
	)
	(segment
		(start 55.164482 -136.497822)
		(end 54.995826 -136.329166)
		(width 0.1143)
		(layer "In7.Cu")
		(net "BMC_NODE1_DDR_D3")
	)
	(segment
		(start 44.40809 -137.92708)
		(end 45.20819 -137.92708)
		(width 0.1143)
		(layer "In7.Cu")
		(net "BMC_NODE1_DDR_D3")
	)
	(segment
		(start 45.949362 -138.668252)
		(end 47.194724 -138.997182)
		(width 0.1143)
		(layer "In7.Cu")
		(net "BMC_NODE1_DDR_D3")
	)
	(segment
		(start 47.660814 -138.997182)
		(end 48.196754 -138.461242)
		(width 0.1143)
		(layer "In7.Cu")
		(net "BMC_NODE1_DDR_D3")
	)
	(segment
		(start 54.085998 -136.982708)
		(end 54.869334 -136.982708)
		(width 0.1143)
		(layer "In7.Cu")
		(net "BMC_NODE1_DDR_D3")
	)
	(segment
		(start 49.804066 -138.461242)
		(end 50.195988 -138.853164)
		(width 0.1143)
		(layer "In7.Cu")
		(net "BMC_NODE1_DDR_D3")
	)
	(segment
		(start 50.195988 -138.853164)
		(end 52.215542 -138.853164)
		(width 0.1143)
		(layer "In7.Cu")
		(net "BMC_NODE1_DDR_D3")
	)
	(segment
		(start 45.20819 -137.92708)
		(end 45.949362 -138.668252)
		(width 0.1143)
		(layer "In7.Cu")
		(net "BMC_NODE1_DDR_D3")
	)
	(segment
		(start 54.869334 -136.982708)
		(end 55.164482 -136.68756)
		(width 0.1143)
		(layer "In7.Cu")
		(net "BMC_NODE1_DDR_D3")
	)
	(segment
		(start 54.995826 -136.329166)
		(end 53.934868 -136.329166)
		(width 0.1143)
		(layer "In7.Cu")
		(net "BMC_NODE1_DDR_D3")
	)
	(segment
		(start 55.164482 -136.68756)
		(end 55.164482 -136.497822)
		(width 0.1143)
		(layer "In7.Cu")
		(net "BMC_NODE1_DDR_D3")
	)
	(segment
		(start 170.337988 -129.615692)
		(end 166.497762 -129.615692)
		(width 0.1016)
		(layer "F.Cu")
		(net "H_CPU_NODE1_THRMTRIP_L")
	)
	(segment
		(start 166.17696 -129.936748)
		(end 166.17696 -129.938272)
		(width 0.1016)
		(layer "F.Cu")
		(net "H_CPU_NODE1_THRMTRIP_L")
	)
	(segment
		(start 171.452286 -130.72999)
		(end 170.337988 -129.615692)
		(width 0.1016)
		(layer "F.Cu")
		(net "H_CPU_NODE1_THRMTRIP_L")
	)
	(segment
		(start 70.583044 -76.563728)
		(end 70.36308 -76.783692)
		(width 0.1016)
		(layer "F.Cu")
		(net "H_CPU_NODE1_THRMTRIP_L")
	)
	(segment
		(start 166.497762 -129.615692)
		(end 166.17696 -129.936748)
		(width 0.1016)
		(layer "F.Cu")
		(net "H_CPU_NODE1_THRMTRIP_L")
	)
	(segment
		(start 171.452286 -131.92125)
		(end 170.765724 -132.607812)
		(width 0.1016)
		(layer "F.Cu")
		(net "H_CPU_NODE1_THRMTRIP_L")
	)
	(segment
		(start 70.583044 -76.269342)
		(end 70.583044 -76.563728)
		(width 0.1016)
		(layer "F.Cu")
		(net "H_CPU_NODE1_THRMTRIP_L")
	)
	(segment
		(start 170.765724 -132.607812)
		(end 170.765724 -133.240272)
		(width 0.1016)
		(layer "F.Cu")
		(net "H_CPU_NODE1_THRMTRIP_L")
	)
	(segment
		(start 171.452286 -131.92125)
		(end 171.452286 -130.72999)
		(width 0.1016)
		(layer "F.Cu")
		(net "H_CPU_NODE1_THRMTRIP_L")
	)
	(via
		(at 166.17696 -129.938272)
		(size 0.508)
		(drill 0.254)
		(layers "F.Cu" "B.Cu")
		(net "H_CPU_NODE1_THRMTRIP_L")
	)
	(via
		(at 70.36308 -76.783692)
		(size 0.508)
		(drill 0.254)
		(layers "F.Cu" "B.Cu")
		(net "H_CPU_NODE1_THRMTRIP_L")
	)
	(segment
		(start 166.17696 -129.938272)
		(end 165.153086 -128.914398)
		(width 0.1143)
		(layer "In7.Cu")
		(net "H_CPU_NODE1_THRMTRIP_L")
	)
	(segment
		(start 165.153086 -128.914398)
		(end 163.3474 -128.914398)
		(width 0.1143)
		(layer "In7.Cu")
		(net "H_CPU_NODE1_THRMTRIP_L")
	)
	(segment
		(start 94.063058 -74.784204)
		(end 89.142062 -74.784204)
		(width 0.1143)
		(layer "In7.Cu")
		(net "H_CPU_NODE1_THRMTRIP_L")
	)
	(segment
		(start 159.972502 -125.5395)
		(end 158.836106 -125.5395)
		(width 0.1143)
		(layer "In7.Cu")
		(net "H_CPU_NODE1_THRMTRIP_L")
	)
	(segment
		(start 140.805916 -101.254814)
		(end 126.42342 -101.254814)
		(width 0.1143)
		(layer "In7.Cu")
		(net "H_CPU_NODE1_THRMTRIP_L")
	)
	(segment
		(start 158.836106 -125.5395)
		(end 152.13838 -118.841774)
		(width 0.1143)
		(layer "In7.Cu")
		(net "H_CPU_NODE1_THRMTRIP_L")
	)
	(segment
		(start 109.891576 -84.72297)
		(end 103.208582 -84.72297)
		(width 0.1143)
		(layer "In7.Cu")
		(net "H_CPU_NODE1_THRMTRIP_L")
	)
	(segment
		(start 78.816962 -77.814678)
		(end 78.614524 -77.814678)
		(width 0.1143)
		(layer "In7.Cu")
		(net "H_CPU_NODE1_THRMTRIP_L")
	)
	(segment
		(start 78.294484 -78.134718)
		(end 76.148438 -78.134718)
		(width 0.1143)
		(layer "In7.Cu")
		(net "H_CPU_NODE1_THRMTRIP_L")
	)
	(segment
		(start 70.692772 -76.454)
		(end 70.36308 -76.783692)
		(width 0.1143)
		(layer "In7.Cu")
		(net "H_CPU_NODE1_THRMTRIP_L")
	)
	(segment
		(start 163.3474 -128.914398)
		(end 159.972502 -125.5395)
		(width 0.1143)
		(layer "In7.Cu")
		(net "H_CPU_NODE1_THRMTRIP_L")
	)
	(segment
		(start 152.13838 -113.468912)
		(end 146.95678 -108.287312)
		(width 0.1143)
		(layer "In7.Cu")
		(net "H_CPU_NODE1_THRMTRIP_L")
	)
	(segment
		(start 89.142062 -74.784204)
		(end 86.985856 -76.94041)
		(width 0.1143)
		(layer "In7.Cu")
		(net "H_CPU_NODE1_THRMTRIP_L")
	)
	(segment
		(start 103.208582 -84.72297)
		(end 98.80092 -80.315308)
		(width 0.1143)
		(layer "In7.Cu")
		(net "H_CPU_NODE1_THRMTRIP_L")
	)
	(segment
		(start 146.95678 -108.287312)
		(end 146.95678 -107.405678)
		(width 0.1143)
		(layer "In7.Cu")
		(net "H_CPU_NODE1_THRMTRIP_L")
	)
	(segment
		(start 79.156306 -77.475334)
		(end 78.816962 -77.814678)
		(width 0.1143)
		(layer "In7.Cu")
		(net "H_CPU_NODE1_THRMTRIP_L")
	)
	(segment
		(start 98.80092 -80.315308)
		(end 98.80092 -79.522066)
		(width 0.1143)
		(layer "In7.Cu")
		(net "H_CPU_NODE1_THRMTRIP_L")
	)
	(segment
		(start 75.135994 -79.147162)
		(end 74.32167 -79.147162)
		(width 0.1143)
		(layer "In7.Cu")
		(net "H_CPU_NODE1_THRMTRIP_L")
	)
	(segment
		(start 71.628508 -76.454)
		(end 70.692772 -76.454)
		(width 0.1143)
		(layer "In7.Cu")
		(net "H_CPU_NODE1_THRMTRIP_L")
	)
	(segment
		(start 126.42342 -101.254814)
		(end 109.891576 -84.72297)
		(width 0.1143)
		(layer "In7.Cu")
		(net "H_CPU_NODE1_THRMTRIP_L")
	)
	(segment
		(start 146.95678 -107.405678)
		(end 140.805916 -101.254814)
		(width 0.1143)
		(layer "In7.Cu")
		(net "H_CPU_NODE1_THRMTRIP_L")
	)
	(segment
		(start 86.985856 -76.94041)
		(end 86.036658 -76.94041)
		(width 0.1143)
		(layer "In7.Cu")
		(net "H_CPU_NODE1_THRMTRIP_L")
	)
	(segment
		(start 78.614524 -77.814678)
		(end 78.294484 -78.134718)
		(width 0.1143)
		(layer "In7.Cu")
		(net "H_CPU_NODE1_THRMTRIP_L")
	)
	(segment
		(start 76.148438 -78.134718)
		(end 75.135994 -79.147162)
		(width 0.1143)
		(layer "In7.Cu")
		(net "H_CPU_NODE1_THRMTRIP_L")
	)
	(segment
		(start 152.13838 -118.841774)
		(end 152.13838 -113.468912)
		(width 0.1143)
		(layer "In7.Cu")
		(net "H_CPU_NODE1_THRMTRIP_L")
	)
	(segment
		(start 86.036658 -76.94041)
		(end 85.501734 -77.475334)
		(width 0.1143)
		(layer "In7.Cu")
		(net "H_CPU_NODE1_THRMTRIP_L")
	)
	(segment
		(start 85.501734 -77.475334)
		(end 79.156306 -77.475334)
		(width 0.1143)
		(layer "In7.Cu")
		(net "H_CPU_NODE1_THRMTRIP_L")
	)
	(segment
		(start 98.80092 -79.522066)
		(end 94.063058 -74.784204)
		(width 0.1143)
		(layer "In7.Cu")
		(net "H_CPU_NODE1_THRMTRIP_L")
	)
	(segment
		(start 74.32167 -79.147162)
		(end 71.628508 -76.454)
		(width 0.1143)
		(layer "In7.Cu")
		(net "H_CPU_NODE1_THRMTRIP_L")
	)
	(segment
		(start 51.11496 -154.25039)
		(end 51.352196 -154.25039)
		(width 0.127)
		(layer "F.Cu")
		(net "P2E_CPU_NIC1_NODE1_TX_DP")
	)
	(segment
		(start 49.117504 -154.673046)
		(end 49.671224 -154.673046)
		(width 0.127)
		(layer "F.Cu")
		(net "P2E_CPU_NIC1_NODE1_TX_DP")
	)
	(segment
		(start 51.352196 -154.25039)
		(end 51.822096 -154.72029)
		(width 0.127)
		(layer "F.Cu")
		(net "P2E_CPU_NIC1_NODE1_TX_DP")
	)
	(segment
		(start 49.671224 -154.673046)
		(end 49.76622 -154.57805)
		(width 0.127)
		(layer "F.Cu")
		(net "P2E_CPU_NIC1_NODE1_TX_DP")
	)
	(segment
		(start 50.7873 -154.57805)
		(end 51.11496 -154.25039)
		(width 0.127)
		(layer "F.Cu")
		(net "P2E_CPU_NIC1_NODE1_TX_DP")
	)
	(segment
		(start 49.76622 -154.57805)
		(end 50.7873 -154.57805)
		(width 0.127)
		(layer "F.Cu")
		(net "P2E_CPU_NIC1_NODE1_TX_DP")
	)
	(via
		(at 32.9311 -64.875156)
		(size 0.508)
		(drill 0.254)
		(layers "F.Cu" "B.Cu")
		(net "P2E_CPU_NIC1_NODE1_TX_DP")
	)
	(via
		(at 51.822096 -154.72029)
		(size 0.508)
		(drill 0.254)
		(layers "F.Cu" "B.Cu")
		(net "P2E_CPU_NIC1_NODE1_TX_DP")
	)
	(segment
		(start 33.4137 -64.392556)
		(end 35.11423 -64.392556)
		(width 0.127)
		(layer "B.Cu")
		(net "P2E_CPU_NIC1_NODE1_TX_DP")
	)
	(segment
		(start 32.9311 -64.875156)
		(end 33.4137 -64.392556)
		(width 0.127)
		(layer "B.Cu")
		(net "P2E_CPU_NIC1_NODE1_TX_DP")
	)
	(segment
		(start 35.11423 -64.392556)
		(end 35.46983 -64.748156)
		(width 0.127)
		(layer "B.Cu")
		(net "P2E_CPU_NIC1_NODE1_TX_DP")
	)
	(segment
		(start 41.27627 -154.950668)
		(end 45.060616 -155.091638)
		(width 0.127)
		(layer "In7.Cu")
		(net "P2E_CPU_NIC1_NODE1_TX_DP")
	)
	(segment
		(start 8.193278 -131.653788)
		(end 10.136124 -135.17245)
		(width 0.127)
		(layer "In7.Cu")
		(net "P2E_CPU_NIC1_NODE1_TX_DP")
	)
	(segment
		(start 18.254218 -140.488416)
		(end 21.328126 -140.83538)
		(width 0.127)
		(layer "In7.Cu")
		(net "P2E_CPU_NIC1_NODE1_TX_DP")
	)
	(segment
		(start 12.04849 -102.276402)
		(end 10.912348 -102.32644)
		(width 0.127)
		(layer "In7.Cu")
		(net "P2E_CPU_NIC1_NODE1_TX_DP")
	)
	(segment
		(start 51.822096 -154.35834)
		(end 51.822096 -154.72029)
		(width 0.127)
		(layer "In7.Cu")
		(net "P2E_CPU_NIC1_NODE1_TX_DP")
	)
	(segment
		(start 49.810416 -154.967432)
		(end 51.077114 -154.23134)
		(width 0.127)
		(layer "In7.Cu")
		(net "P2E_CPU_NIC1_NODE1_TX_DP")
	)
	(segment
		(start 33.295082 -65.730882)
		(end 32.366712 -65.973706)
		(width 0.127)
		(layer "In7.Cu")
		(net "P2E_CPU_NIC1_NODE1_TX_DP")
	)
	(segment
		(start 51.077114 -154.23134)
		(end 51.695096 -154.23134)
		(width 0.127)
		(layer "In7.Cu")
		(net "P2E_CPU_NIC1_NODE1_TX_DP")
	)
	(segment
		(start 39.125398 -154.404822)
		(end 41.27627 -154.950668)
		(width 0.127)
		(layer "In7.Cu")
		(net "P2E_CPU_NIC1_NODE1_TX_DP")
	)
	(segment
		(start 30.153864 -67.102736)
		(end 28.76296 -69.279516)
		(width 0.127)
		(layer "In7.Cu")
		(net "P2E_CPU_NIC1_NODE1_TX_DP")
	)
	(segment
		(start 16.639794 -139.724638)
		(end 18.254218 -140.488416)
		(width 0.127)
		(layer "In7.Cu")
		(net "P2E_CPU_NIC1_NODE1_TX_DP")
	)
	(segment
		(start 25.472644 -79.336138)
		(end 15.77594 -91.021916)
		(width 0.127)
		(layer "In7.Cu")
		(net "P2E_CPU_NIC1_NODE1_TX_DP")
	)
	(segment
		(start 28.76296 -69.279516)
		(end 25.472644 -79.336138)
		(width 0.127)
		(layer "In7.Cu")
		(net "P2E_CPU_NIC1_NODE1_TX_DP")
	)
	(segment
		(start 8.37438 -110.86592)
		(end 8.37438 -120.089676)
		(width 0.127)
		(layer "In7.Cu")
		(net "P2E_CPU_NIC1_NODE1_TX_DP")
	)
	(segment
		(start 21.328126 -140.83538)
		(end 21.785326 -141.218158)
		(width 0.127)
		(layer "In7.Cu")
		(net "P2E_CPU_NIC1_NODE1_TX_DP")
	)
	(segment
		(start 33.965388 -64.570864)
		(end 34.011362 -65.113916)
		(width 0.127)
		(layer "In7.Cu")
		(net "P2E_CPU_NIC1_NODE1_TX_DP")
	)
	(segment
		(start 14.331442 -99.93122)
		(end 14.145768 -100.400866)
		(width 0.127)
		(layer "In7.Cu")
		(net "P2E_CPU_NIC1_NODE1_TX_DP")
	)
	(segment
		(start 32.9311 -64.875156)
		(end 33.42005 -64.386206)
		(width 0.127)
		(layer "In7.Cu")
		(net "P2E_CPU_NIC1_NODE1_TX_DP")
	)
	(segment
		(start 8.288274 -107.107736)
		(end 8.37438 -110.86592)
		(width 0.127)
		(layer "In7.Cu")
		(net "P2E_CPU_NIC1_NODE1_TX_DP")
	)
	(segment
		(start 45.060616 -155.091638)
		(end 49.810416 -154.967432)
		(width 0.127)
		(layer "In7.Cu")
		(net "P2E_CPU_NIC1_NODE1_TX_DP")
	)
	(segment
		(start 9.245092 -104.048814)
		(end 8.288274 -107.107736)
		(width 0.127)
		(layer "In7.Cu")
		(net "P2E_CPU_NIC1_NODE1_TX_DP")
	)
	(segment
		(start 51.695096 -154.23134)
		(end 51.822096 -154.35834)
		(width 0.127)
		(layer "In7.Cu")
		(net "P2E_CPU_NIC1_NODE1_TX_DP")
	)
	(segment
		(start 33.736026 -64.386206)
		(end 33.965388 -64.570864)
		(width 0.127)
		(layer "In7.Cu")
		(net "P2E_CPU_NIC1_NODE1_TX_DP")
	)
	(segment
		(start 34.011362 -65.113916)
		(end 33.898332 -65.443354)
		(width 0.127)
		(layer "In7.Cu")
		(net "P2E_CPU_NIC1_NODE1_TX_DP")
	)
	(segment
		(start 32.352996 -152.940512)
		(end 39.125398 -154.404822)
		(width 0.127)
		(layer "In7.Cu")
		(net "P2E_CPU_NIC1_NODE1_TX_DP")
	)
	(segment
		(start 15.276576 -94.096332)
		(end 14.331442 -99.93122)
		(width 0.127)
		(layer "In7.Cu")
		(net "P2E_CPU_NIC1_NODE1_TX_DP")
	)
	(segment
		(start 8.37438 -120.089676)
		(end 8.193278 -131.653788)
		(width 0.127)
		(layer "In7.Cu")
		(net "P2E_CPU_NIC1_NODE1_TX_DP")
	)
	(segment
		(start 12.870688 -101.86543)
		(end 12.04849 -102.276402)
		(width 0.127)
		(layer "In7.Cu")
		(net "P2E_CPU_NIC1_NODE1_TX_DP")
	)
	(segment
		(start 15.77594 -91.021916)
		(end 15.276576 -94.096332)
		(width 0.127)
		(layer "In7.Cu")
		(net "P2E_CPU_NIC1_NODE1_TX_DP")
	)
	(segment
		(start 32.366712 -65.973706)
		(end 30.153864 -67.102736)
		(width 0.127)
		(layer "In7.Cu")
		(net "P2E_CPU_NIC1_NODE1_TX_DP")
	)
	(segment
		(start 10.136124 -135.17245)
		(end 11.524742 -136.426702)
		(width 0.127)
		(layer "In7.Cu")
		(net "P2E_CPU_NIC1_NODE1_TX_DP")
	)
	(segment
		(start 33.42005 -64.386206)
		(end 33.736026 -64.386206)
		(width 0.127)
		(layer "In7.Cu")
		(net "P2E_CPU_NIC1_NODE1_TX_DP")
	)
	(segment
		(start 11.524742 -136.426702)
		(end 13.917168 -138.988546)
		(width 0.127)
		(layer "In7.Cu")
		(net "P2E_CPU_NIC1_NODE1_TX_DP")
	)
	(segment
		(start 33.898332 -65.443354)
		(end 33.295082 -65.730882)
		(width 0.127)
		(layer "In7.Cu")
		(net "P2E_CPU_NIC1_NODE1_TX_DP")
	)
	(segment
		(start 13.917168 -138.988546)
		(end 16.639794 -139.724638)
		(width 0.127)
		(layer "In7.Cu")
		(net "P2E_CPU_NIC1_NODE1_TX_DP")
	)
	(segment
		(start 14.145768 -100.400866)
		(end 12.870688 -101.86543)
		(width 0.127)
		(layer "In7.Cu")
		(net "P2E_CPU_NIC1_NODE1_TX_DP")
	)
	(segment
		(start 21.785326 -141.218158)
		(end 32.352996 -152.940512)
		(width 0.127)
		(layer "In7.Cu")
		(net "P2E_CPU_NIC1_NODE1_TX_DP")
	)
	(segment
		(start 10.912348 -102.32644)
		(end 9.245092 -104.048814)
		(width 0.127)
		(layer "In7.Cu")
		(net "P2E_CPU_NIC1_NODE1_TX_DP")
	)
	(segment
		(start 106.071416 -137.9347)
		(end 106.071416 -137.42289)
		(width 0.1778)
		(layer "F.Cu")
		(net "VR_PVCCP_NODE1_IBIAS")
	)
	(segment
		(start 102.701344 -138.50112)
		(end 103.589836 -138.50112)
		(width 0.1778)
		(layer "F.Cu")
		(net "VR_PVCCP_NODE1_IBIAS")
	)
	(segment
		(start 104.625394 -138.481562)
		(end 105.524554 -138.481562)
		(width 0.1778)
		(layer "F.Cu")
		(net "VR_PVCCP_NODE1_IBIAS")
	)
	(segment
		(start 105.524554 -138.481562)
		(end 106.071416 -137.9347)
		(width 0.1778)
		(layer "F.Cu")
		(net "VR_PVCCP_NODE1_IBIAS")
	)
	(segment
		(start 104.605836 -138.50112)
		(end 104.625394 -138.481562)
		(width 0.1778)
		(layer "F.Cu")
		(net "VR_PVCCP_NODE1_IBIAS")
	)
	(segment
		(start 103.589836 -138.50112)
		(end 104.605836 -138.50112)
		(width 0.1778)
		(layer "F.Cu")
		(net "VR_PVCCP_NODE1_IBIAS")
	)
	(via
		(at 102.701344 -138.50112)
		(size 0.508)
		(drill 0.254)
		(layers "F.Cu" "B.Cu")
		(net "VR_PVCCP_NODE1_IBIAS")
	)
	(segment
		(start 50.497486 -135.702548)
		(end 50.218086 -135.981948)
		(width 0.1016)
		(layer "F.Cu")
		(net "TP_BMC_NODE1_DDR3_MA15")
	)
	(segment
		(start 45.249592 -132.579364)
		(end 47.420784 -132.579364)
		(width 0.1016)
		(layer "F.Cu")
		(net "TP_BMC_NODE1_DDR3_MA15")
	)
	(segment
		(start 47.474886 -132.525262)
		(end 49.798732 -132.525262)
		(width 0.1016)
		(layer "F.Cu")
		(net "TP_BMC_NODE1_DDR3_MA15")
	)
	(segment
		(start 47.420784 -132.579364)
		(end 47.474886 -132.525262)
		(width 0.1016)
		(layer "F.Cu")
		(net "TP_BMC_NODE1_DDR3_MA15")
	)
	(segment
		(start 49.798732 -132.525262)
		(end 50.497486 -133.224016)
		(width 0.1016)
		(layer "F.Cu")
		(net "TP_BMC_NODE1_DDR3_MA15")
	)
	(segment
		(start 44.833032 -132.163566)
		(end 44.833794 -132.163566)
		(width 0.1016)
		(layer "F.Cu")
		(net "TP_BMC_NODE1_DDR3_MA15")
	)
	(segment
		(start 50.218086 -135.981948)
		(end 50.218086 -144.135856)
		(width 0.1016)
		(layer "F.Cu")
		(net "TP_BMC_NODE1_DDR3_MA15")
	)
	(segment
		(start 50.497486 -133.224016)
		(end 50.497486 -135.702548)
		(width 0.1016)
		(layer "F.Cu")
		(net "TP_BMC_NODE1_DDR3_MA15")
	)
	(segment
		(start 44.833794 -132.163566)
		(end 45.249592 -132.579364)
		(width 0.1016)
		(layer "F.Cu")
		(net "TP_BMC_NODE1_DDR3_MA15")
	)
	(via
		(at 50.218086 -144.135856)
		(size 0.508)
		(drill 0.254)
		(layers "F.Cu" "B.Cu")
		(net "TP_BMC_NODE1_DDR3_MA15")
	)
	(segment
		(start 61.743082 -68.510658)
		(end 61.369702 -68.884038)
		(width 0.3048)
		(layer "F.Cu")
		(net "PV_VDDR_VCCCLK_DDR3_NODE1")
	)
	(segment
		(start 61.743082 -69.257418)
		(end 61.369702 -68.884038)
		(width 0.3048)
		(layer "F.Cu")
		(net "PV_VDDR_VCCCLK_DDR3_NODE1")
	)
	(segment
		(start 61.743082 -69.265038)
		(end 61.743082 -69.257418)
		(width 0.3048)
		(layer "F.Cu")
		(net "PV_VDDR_VCCCLK_DDR3_NODE1")
	)
	(segment
		(start 61.743082 -68.503038)
		(end 61.743082 -68.510658)
		(width 0.3048)
		(layer "F.Cu")
		(net "PV_VDDR_VCCCLK_DDR3_NODE1")
	)
	(via
		(at 61.369702 -68.884038)
		(size 0.508)
		(drill 0.254)
		(layers "F.Cu" "B.Cu")
		(net "PV_VDDR_VCCCLK_DDR3_NODE1")
	)
	(via
		(at 66.300096 -71.286878)
		(size 0.6604)
		(drill 0.3302)
		(layers "F.Cu" "B.Cu")
		(net "PV_VDDR_VCCCLK_DDR3_NODE1")
	)
	(segment
		(start 64.074294 -69.16039)
		(end 63.81496 -69.16039)
		(width 0.381)
		(layer "B.Cu")
		(net "PV_VDDR_VCCCLK_DDR3_NODE1")
	)
	(segment
		(start 65.668144 -70.388734)
		(end 65.422018 -70.388734)
		(width 0.1016)
		(layer "B.Cu")
		(net "PV_VDDR_VCCCLK_DDR3_NODE1")
	)
	(segment
		(start 64.31407 -69.810376)
		(end 64.074294 -69.5706)
		(width 0.1016)
		(layer "B.Cu")
		(net "PV_VDDR_VCCCLK_DDR3_NODE1")
	)
	(segment
		(start 66.300096 -71.020686)
		(end 65.668144 -70.388734)
		(width 0.1016)
		(layer "B.Cu")
		(net "PV_VDDR_VCCCLK_DDR3_NODE1")
	)
	(segment
		(start 65.422018 -70.388734)
		(end 64.84366 -69.810376)
		(width 0.1016)
		(layer "B.Cu")
		(net "PV_VDDR_VCCCLK_DDR3_NODE1")
	)
	(segment
		(start 63.454788 -68.800218)
		(end 63.15075 -68.800218)
		(width 0.381)
		(layer "B.Cu")
		(net "PV_VDDR_VCCCLK_DDR3_NODE1")
	)
	(segment
		(start 63.114936 -68.764404)
		(end 63.15075 -68.800218)
		(width 0.381)
		(layer "B.Cu")
		(net "PV_VDDR_VCCCLK_DDR3_NODE1")
	)
	(segment
		(start 63.81496 -69.16039)
		(end 63.454788 -68.800218)
		(width 0.381)
		(layer "B.Cu")
		(net "PV_VDDR_VCCCLK_DDR3_NODE1")
	)
	(segment
		(start 61.489336 -68.764404)
		(end 62.09792 -68.764404)
		(width 0.381)
		(layer "B.Cu")
		(net "PV_VDDR_VCCCLK_DDR3_NODE1")
	)
	(segment
		(start 61.369702 -68.884038)
		(end 61.489336 -68.764404)
		(width 0.381)
		(layer "B.Cu")
		(net "PV_VDDR_VCCCLK_DDR3_NODE1")
	)
	(segment
		(start 64.84366 -69.810376)
		(end 64.31407 -69.810376)
		(width 0.1016)
		(layer "B.Cu")
		(net "PV_VDDR_VCCCLK_DDR3_NODE1")
	)
	(segment
		(start 62.09792 -68.764404)
		(end 63.114936 -68.764404)
		(width 0.381)
		(layer "B.Cu")
		(net "PV_VDDR_VCCCLK_DDR3_NODE1")
	)
	(segment
		(start 66.300096 -71.286878)
		(end 66.300096 -71.020686)
		(width 0.1016)
		(layer "B.Cu")
		(net "PV_VDDR_VCCCLK_DDR3_NODE1")
	)
	(segment
		(start 64.074294 -69.5706)
		(end 64.074294 -69.16039)
		(width 0.1016)
		(layer "B.Cu")
		(net "PV_VDDR_VCCCLK_DDR3_NODE1")
	)
	(segment
		(start 49.117504 -154.17292)
		(end 49.70399 -154.17292)
		(width 0.127)
		(layer "F.Cu")
		(net "P2E_CPU_NIC1_NODE1_TX_DN")
	)
	(segment
		(start 49.80432 -154.27325)
		(end 50.660808 -154.27325)
		(width 0.127)
		(layer "F.Cu")
		(net "P2E_CPU_NIC1_NODE1_TX_DN")
	)
	(segment
		(start 50.988468 -153.94559)
		(end 51.326796 -153.94559)
		(width 0.127)
		(layer "F.Cu")
		(net "P2E_CPU_NIC1_NODE1_TX_DN")
	)
	(segment
		(start 49.70399 -154.17292)
		(end 49.80432 -154.27325)
		(width 0.127)
		(layer "F.Cu")
		(net "P2E_CPU_NIC1_NODE1_TX_DN")
	)
	(segment
		(start 50.660808 -154.27325)
		(end 50.988468 -153.94559)
		(width 0.127)
		(layer "F.Cu")
		(net "P2E_CPU_NIC1_NODE1_TX_DN")
	)
	(segment
		(start 51.326796 -153.94559)
		(end 51.822096 -153.45029)
		(width 0.127)
		(layer "F.Cu")
		(net "P2E_CPU_NIC1_NODE1_TX_DN")
	)
	(via
		(at 32.9311 -63.605156)
		(size 0.508)
		(drill 0.254)
		(layers "F.Cu" "B.Cu")
		(net "P2E_CPU_NIC1_NODE1_TX_DN")
	)
	(via
		(at 51.822096 -153.45029)
		(size 0.508)
		(drill 0.254)
		(layers "F.Cu" "B.Cu")
		(net "P2E_CPU_NIC1_NODE1_TX_DN")
	)
	(segment
		(start 32.9311 -63.605156)
		(end 33.4137 -64.087756)
		(width 0.127)
		(layer "B.Cu")
		(net "P2E_CPU_NIC1_NODE1_TX_DN")
	)
	(segment
		(start 35.11423 -64.087756)
		(end 35.46983 -63.732156)
		(width 0.127)
		(layer "B.Cu")
		(net "P2E_CPU_NIC1_NODE1_TX_DN")
	)
	(segment
		(start 33.4137 -64.087756)
		(end 35.11423 -64.087756)
		(width 0.127)
		(layer "B.Cu")
		(net "P2E_CPU_NIC1_NODE1_TX_DN")
	)
	(segment
		(start 16.74622 -139.450572)
		(end 16.74622 -139.451588)
		(width 0.127)
		(layer "In7.Cu")
		(net "P2E_CPU_NIC1_NODE1_TX_DN")
	)
	(segment
		(start 41.31818 -154.659838)
		(end 45.06214 -154.799284)
		(width 0.127)
		(layer "In7.Cu")
		(net "P2E_CPU_NIC1_NODE1_TX_DN")
	)
	(segment
		(start 25.732994 -79.479902)
		(end 16.051784 -91.147392)
		(width 0.127)
		(layer "In7.Cu")
		(net "P2E_CPU_NIC1_NODE1_TX_DN")
	)
	(segment
		(start 29.029152 -69.4055)
		(end 25.732994 -79.479902)
		(width 0.127)
		(layer "In7.Cu")
		(net "P2E_CPU_NIC1_NODE1_TX_DN")
	)
	(segment
		(start 32.9311 -63.605156)
		(end 33.42005 -64.094106)
		(width 0.127)
		(layer "In7.Cu")
		(net "P2E_CPU_NIC1_NODE1_TX_DN")
	)
	(segment
		(start 10.36828 -134.9883)
		(end 11.72972 -136.218168)
		(width 0.127)
		(layer "In7.Cu")
		(net "P2E_CPU_NIC1_NODE1_TX_DN")
	)
	(segment
		(start 14.39926 -100.555044)
		(end 13.05306 -102.100888)
		(width 0.127)
		(layer "In7.Cu")
		(net "P2E_CPU_NIC1_NODE1_TX_DN")
	)
	(segment
		(start 13.05306 -102.100888)
		(end 12.12342 -102.565708)
		(width 0.127)
		(layer "In7.Cu")
		(net "P2E_CPU_NIC1_NODE1_TX_DN")
	)
	(segment
		(start 51.695096 -153.93924)
		(end 51.822096 -153.81224)
		(width 0.127)
		(layer "In7.Cu")
		(net "P2E_CPU_NIC1_NODE1_TX_DN")
	)
	(segment
		(start 12.12342 -102.565708)
		(end 11.04138 -102.613206)
		(width 0.127)
		(layer "In7.Cu")
		(net "P2E_CPU_NIC1_NODE1_TX_DN")
	)
	(segment
		(start 18.335244 -140.203428)
		(end 21.448268 -140.554964)
		(width 0.127)
		(layer "In7.Cu")
		(net "P2E_CPU_NIC1_NODE1_TX_DN")
	)
	(segment
		(start 32.50692 -152.674828)
		(end 39.1922 -154.120342)
		(width 0.127)
		(layer "In7.Cu")
		(net "P2E_CPU_NIC1_NODE1_TX_DN")
	)
	(segment
		(start 49.72812 -154.677364)
		(end 50.998374 -153.93924)
		(width 0.127)
		(layer "In7.Cu")
		(net "P2E_CPU_NIC1_NODE1_TX_DN")
	)
	(segment
		(start 9.50341 -104.20223)
		(end 8.581644 -107.149138)
		(width 0.127)
		(layer "In7.Cu")
		(net "P2E_CPU_NIC1_NODE1_TX_DN")
	)
	(segment
		(start 33.83915 -64.094106)
		(end 34.246058 -64.421512)
		(width 0.127)
		(layer "In7.Cu")
		(net "P2E_CPU_NIC1_NODE1_TX_DN")
	)
	(segment
		(start 8.66648 -110.862364)
		(end 8.66648 -120.092216)
		(width 0.127)
		(layer "In7.Cu")
		(net "P2E_CPU_NIC1_NODE1_TX_DN")
	)
	(segment
		(start 21.98878 -141.007084)
		(end 32.50692 -152.674828)
		(width 0.127)
		(layer "In7.Cu")
		(net "P2E_CPU_NIC1_NODE1_TX_DN")
	)
	(segment
		(start 45.06214 -154.799284)
		(end 49.72812 -154.677364)
		(width 0.127)
		(layer "In7.Cu")
		(net "P2E_CPU_NIC1_NODE1_TX_DN")
	)
	(segment
		(start 51.822096 -153.81224)
		(end 51.822096 -153.45029)
		(width 0.127)
		(layer "In7.Cu")
		(net "P2E_CPU_NIC1_NODE1_TX_DN")
	)
	(segment
		(start 16.74622 -139.451588)
		(end 18.335244 -140.203428)
		(width 0.127)
		(layer "In7.Cu")
		(net "P2E_CPU_NIC1_NODE1_TX_DN")
	)
	(segment
		(start 14.073886 -138.728196)
		(end 16.74622 -139.450572)
		(width 0.127)
		(layer "In7.Cu")
		(net "P2E_CPU_NIC1_NODE1_TX_DN")
	)
	(segment
		(start 34.246058 -64.421512)
		(end 34.30778 -65.150492)
		(width 0.127)
		(layer "In7.Cu")
		(net "P2E_CPU_NIC1_NODE1_TX_DN")
	)
	(segment
		(start 33.42005 -64.094106)
		(end 33.83915 -64.094106)
		(width 0.127)
		(layer "In7.Cu")
		(net "P2E_CPU_NIC1_NODE1_TX_DN")
	)
	(segment
		(start 11.04138 -102.613206)
		(end 9.50341 -104.20223)
		(width 0.127)
		(layer "In7.Cu")
		(net "P2E_CPU_NIC1_NODE1_TX_DN")
	)
	(segment
		(start 50.998374 -153.93924)
		(end 51.695096 -153.93924)
		(width 0.127)
		(layer "In7.Cu")
		(net "P2E_CPU_NIC1_NODE1_TX_DN")
	)
	(segment
		(start 34.30778 -65.150492)
		(end 34.13506 -65.654428)
		(width 0.127)
		(layer "In7.Cu")
		(net "P2E_CPU_NIC1_NODE1_TX_DN")
	)
	(segment
		(start 32.47136 -66.24828)
		(end 30.357572 -67.327018)
		(width 0.127)
		(layer "In7.Cu")
		(net "P2E_CPU_NIC1_NODE1_TX_DN")
	)
	(segment
		(start 39.1922 -154.120342)
		(end 41.31818 -154.659838)
		(width 0.127)
		(layer "In7.Cu")
		(net "P2E_CPU_NIC1_NODE1_TX_DN")
	)
	(segment
		(start 21.448268 -140.554964)
		(end 21.98878 -141.007084)
		(width 0.127)
		(layer "In7.Cu")
		(net "P2E_CPU_NIC1_NODE1_TX_DN")
	)
	(segment
		(start 33.39592 -66.006726)
		(end 32.47136 -66.24828)
		(width 0.127)
		(layer "In7.Cu")
		(net "P2E_CPU_NIC1_NODE1_TX_DN")
	)
	(segment
		(start 16.051784 -91.147392)
		(end 15.56512 -94.143068)
		(width 0.127)
		(layer "In7.Cu")
		(net "P2E_CPU_NIC1_NODE1_TX_DN")
	)
	(segment
		(start 30.357572 -67.327018)
		(end 29.029152 -69.4055)
		(width 0.127)
		(layer "In7.Cu")
		(net "P2E_CPU_NIC1_NODE1_TX_DN")
	)
	(segment
		(start 11.72972 -136.218168)
		(end 14.073886 -138.728196)
		(width 0.127)
		(layer "In7.Cu")
		(net "P2E_CPU_NIC1_NODE1_TX_DN")
	)
	(segment
		(start 8.66648 -120.092216)
		(end 8.486648 -131.580636)
		(width 0.127)
		(layer "In7.Cu")
		(net "P2E_CPU_NIC1_NODE1_TX_DN")
	)
	(segment
		(start 34.13506 -65.654428)
		(end 33.39592 -66.006726)
		(width 0.127)
		(layer "In7.Cu")
		(net "P2E_CPU_NIC1_NODE1_TX_DN")
	)
	(segment
		(start 15.56512 -94.143068)
		(end 14.614906 -100.009198)
		(width 0.127)
		(layer "In7.Cu")
		(net "P2E_CPU_NIC1_NODE1_TX_DN")
	)
	(segment
		(start 8.581644 -107.149138)
		(end 8.66648 -110.862364)
		(width 0.127)
		(layer "In7.Cu")
		(net "P2E_CPU_NIC1_NODE1_TX_DN")
	)
	(segment
		(start 8.486648 -131.580636)
		(end 10.36828 -134.9883)
		(width 0.127)
		(layer "In7.Cu")
		(net "P2E_CPU_NIC1_NODE1_TX_DN")
	)
	(segment
		(start 14.614906 -100.009198)
		(end 14.39926 -100.555044)
		(width 0.127)
		(layer "In7.Cu")
		(net "P2E_CPU_NIC1_NODE1_TX_DN")
	)
	(segment
		(start 43.358054 -82.018378)
		(end 43.616626 -81.759806)
		(width 0.1016)
		(layer "F.Cu")
		(net "PD_CPU_NODE1_RP2_PERP")
	)
	(segment
		(start 43.94073 -77.243178)
		(end 44.138088 -77.440536)
		(width 0.1016)
		(layer "F.Cu")
		(net "PD_CPU_NODE1_RP2_PERP")
	)
	(segment
		(start 44.831 -78.287626)
		(end 44.889674 -78.287626)
		(width 0.1016)
		(layer "F.Cu")
		(net "PD_CPU_NODE1_RP2_PERP")
	)
	(segment
		(start 45.076618 -80.152748)
		(end 44.822618 -80.406748)
		(width 0.1016)
		(layer "F.Cu")
		(net "PD_CPU_NODE1_RP2_PERP")
	)
	(segment
		(start 42.804334 -80.86725)
		(end 42.424858 -81.246726)
		(width 0.1016)
		(layer "F.Cu")
		(net "PD_CPU_NODE1_RP2_PERP")
	)
	(segment
		(start 43.315128 -77.243178)
		(end 43.94073 -77.243178)
		(width 0.1016)
		(layer "F.Cu")
		(net "PD_CPU_NODE1_RP2_PERP")
	)
	(segment
		(start 42.880026 -81.798668)
		(end 43.099736 -82.018378)
		(width 0.1016)
		(layer "F.Cu")
		(net "PD_CPU_NODE1_RP2_PERP")
	)
	(segment
		(start 39.76497 -79.224124)
		(end 40.578532 -78.410562)
		(width 0.1016)
		(layer "F.Cu")
		(net "PD_CPU_NODE1_RP2_PERP")
	)
	(segment
		(start 44.692316 -78.148942)
		(end 44.831 -78.287626)
		(width 0.1016)
		(layer "F.Cu")
		(net "PD_CPU_NODE1_RP2_PERP")
	)
	(segment
		(start 44.289218 -82.021426)
		(end 44.289218 -82.433668)
		(width 0.1016)
		(layer "F.Cu")
		(net "PD_CPU_NODE1_RP2_PERP")
	)
	(segment
		(start 42.908728 -77.193394)
		(end 43.265344 -77.193394)
		(width 0.1016)
		(layer "F.Cu")
		(net "PD_CPU_NODE1_RP2_PERP")
	)
	(segment
		(start 42.618152 -77.48397)
		(end 42.908728 -77.193394)
		(width 0.1016)
		(layer "F.Cu")
		(net "PD_CPU_NODE1_RP2_PERP")
	)
	(segment
		(start 45.132498 -78.874366)
		(end 45.076618 -78.930246)
		(width 0.1016)
		(layer "F.Cu")
		(net "PD_CPU_NODE1_RP2_PERP")
	)
	(segment
		(start 43.205908 -80.86725)
		(end 42.804334 -80.86725)
		(width 0.1016)
		(layer "F.Cu")
		(net "PD_CPU_NODE1_RP2_PERP")
	)
	(segment
		(start 43.912536 -82.81035)
		(end 43.796204 -82.81035)
		(width 0.1016)
		(layer "F.Cu")
		(net "PD_CPU_NODE1_RP2_PERP")
	)
	(segment
		(start 44.240196 -80.406748)
		(end 43.937428 -80.709516)
		(width 0.1016)
		(layer "F.Cu")
		(net "PD_CPU_NODE1_RP2_PERP")
	)
	(segment
		(start 45.076618 -78.930246)
		(end 45.076618 -80.152748)
		(width 0.1016)
		(layer "F.Cu")
		(net "PD_CPU_NODE1_RP2_PERP")
	)
	(segment
		(start 45.132498 -78.53045)
		(end 45.132498 -78.874366)
		(width 0.1016)
		(layer "F.Cu")
		(net "PD_CPU_NODE1_RP2_PERP")
	)
	(segment
		(start 44.372276 -78.148942)
		(end 44.692316 -78.148942)
		(width 0.1016)
		(layer "F.Cu")
		(net "PD_CPU_NODE1_RP2_PERP")
	)
	(segment
		(start 37.01288 -79.079344)
		(end 37.15766 -79.224124)
		(width 0.1016)
		(layer "F.Cu")
		(net "PD_CPU_NODE1_RP2_PERP")
	)
	(segment
		(start 43.265344 -77.193394)
		(end 43.315128 -77.243178)
		(width 0.1016)
		(layer "F.Cu")
		(net "PD_CPU_NODE1_RP2_PERP")
	)
	(segment
		(start 43.616626 -81.759806)
		(end 44.027598 -81.759806)
		(width 0.1016)
		(layer "F.Cu")
		(net "PD_CPU_NODE1_RP2_PERP")
	)
	(segment
		(start 42.359834 -78.410562)
		(end 42.361612 -78.408784)
		(width 0.1016)
		(layer "F.Cu")
		(net "PD_CPU_NODE1_RP2_PERP")
	)
	(segment
		(start 43.796204 -78.072234)
		(end 43.796204 -78.307438)
		(width 0.1016)
		(layer "F.Cu")
		(net "PD_CPU_NODE1_RP2_PERP")
	)
	(segment
		(start 42.361612 -77.48397)
		(end 42.618152 -77.48397)
		(width 0.1016)
		(layer "F.Cu")
		(net "PD_CPU_NODE1_RP2_PERP")
	)
	(segment
		(start 43.937428 -80.709516)
		(end 43.779694 -80.86725)
		(width 0.1016)
		(layer "F.Cu")
		(net "PD_CPU_NODE1_RP2_PERP")
	)
	(segment
		(start 42.700448 -81.798668)
		(end 42.880026 -81.798668)
		(width 0.1016)
		(layer "F.Cu")
		(net "PD_CPU_NODE1_RP2_PERP")
	)
	(segment
		(start 44.21378 -78.307438)
		(end 44.372276 -78.148942)
		(width 0.1016)
		(layer "F.Cu")
		(net "PD_CPU_NODE1_RP2_PERP")
	)
	(segment
		(start 44.138088 -77.73035)
		(end 43.796204 -78.072234)
		(width 0.1016)
		(layer "F.Cu")
		(net "PD_CPU_NODE1_RP2_PERP")
	)
	(segment
		(start 42.424858 -81.523078)
		(end 42.700448 -81.798668)
		(width 0.1016)
		(layer "F.Cu")
		(net "PD_CPU_NODE1_RP2_PERP")
	)
	(segment
		(start 44.027598 -81.759806)
		(end 44.289218 -82.021426)
		(width 0.1016)
		(layer "F.Cu")
		(net "PD_CPU_NODE1_RP2_PERP")
	)
	(segment
		(start 44.138088 -77.440536)
		(end 44.138088 -77.73035)
		(width 0.1016)
		(layer "F.Cu")
		(net "PD_CPU_NODE1_RP2_PERP")
	)
	(segment
		(start 42.361612 -78.408784)
		(end 42.361612 -77.48397)
		(width 0.1016)
		(layer "F.Cu")
		(net "PD_CPU_NODE1_RP2_PERP")
	)
	(segment
		(start 43.779694 -80.86725)
		(end 43.205908 -80.86725)
		(width 0.1016)
		(layer "F.Cu")
		(net "PD_CPU_NODE1_RP2_PERP")
	)
	(segment
		(start 43.699176 -82.907378)
		(end 43.099736 -82.907378)
		(width 0.1016)
		(layer "F.Cu")
		(net "PD_CPU_NODE1_RP2_PERP")
	)
	(segment
		(start 36.57854 -79.079344)
		(end 37.01288 -79.079344)
		(width 0.1016)
		(layer "F.Cu")
		(net "PD_CPU_NODE1_RP2_PERP")
	)
	(segment
		(start 44.889674 -78.287626)
		(end 45.132498 -78.53045)
		(width 0.1016)
		(layer "F.Cu")
		(net "PD_CPU_NODE1_RP2_PERP")
	)
	(segment
		(start 43.099736 -82.018378)
		(end 43.358054 -82.018378)
		(width 0.1016)
		(layer "F.Cu")
		(net "PD_CPU_NODE1_RP2_PERP")
	)
	(segment
		(start 36.069778 -78.877922)
		(end 36.377118 -78.877922)
		(width 0.1016)
		(layer "F.Cu")
		(net "PD_CPU_NODE1_RP2_PERP")
	)
	(segment
		(start 36.377118 -78.877922)
		(end 36.57854 -79.079344)
		(width 0.1016)
		(layer "F.Cu")
		(net "PD_CPU_NODE1_RP2_PERP")
	)
	(segment
		(start 44.289218 -82.433668)
		(end 43.912536 -82.81035)
		(width 0.1016)
		(layer "F.Cu")
		(net "PD_CPU_NODE1_RP2_PERP")
	)
	(segment
		(start 43.796204 -82.81035)
		(end 43.699176 -82.907378)
		(width 0.1016)
		(layer "F.Cu")
		(net "PD_CPU_NODE1_RP2_PERP")
	)
	(segment
		(start 43.796204 -78.307438)
		(end 44.21378 -78.307438)
		(width 0.1016)
		(layer "F.Cu")
		(net "PD_CPU_NODE1_RP2_PERP")
	)
	(segment
		(start 40.578532 -78.410562)
		(end 42.359834 -78.410562)
		(width 0.1016)
		(layer "F.Cu")
		(net "PD_CPU_NODE1_RP2_PERP")
	)
	(segment
		(start 42.424858 -81.246726)
		(end 42.424858 -81.523078)
		(width 0.1016)
		(layer "F.Cu")
		(net "PD_CPU_NODE1_RP2_PERP")
	)
	(segment
		(start 44.822618 -80.406748)
		(end 44.240196 -80.406748)
		(width 0.1016)
		(layer "F.Cu")
		(net "PD_CPU_NODE1_RP2_PERP")
	)
	(segment
		(start 37.15766 -79.224124)
		(end 39.76497 -79.224124)
		(width 0.1016)
		(layer "F.Cu")
		(net "PD_CPU_NODE1_RP2_PERP")
	)
	(via
		(at 37.01288 -79.079344)
		(size 0.508)
		(drill 0.254)
		(layers "F.Cu" "B.Cu")
		(net "PD_CPU_NODE1_RP2_PERP")
	)
	(segment
		(start 113.215166 -134.885684)
		(end 113.194846 -134.906004)
		(width 0.254)
		(layer "F.Cu")
		(net "VR_PVCCP_NODE1_COMP")
	)
	(segment
		(start 111.223298 -134.697978)
		(end 109.996478 -134.697978)
		(width 0.1778)
		(layer "F.Cu")
		(net "VR_PVCCP_NODE1_COMP")
	)
	(segment
		(start 113.194846 -134.906004)
		(end 112.179354 -134.906004)
		(width 0.254)
		(layer "F.Cu")
		(net "VR_PVCCP_NODE1_COMP")
	)
	(segment
		(start 111.431324 -134.906004)
		(end 111.359188 -134.833868)
		(width 0.254)
		(layer "F.Cu")
		(net "VR_PVCCP_NODE1_COMP")
	)
	(segment
		(start 112.179354 -134.906004)
		(end 111.431324 -134.906004)
		(width 0.254)
		(layer "F.Cu")
		(net "VR_PVCCP_NODE1_COMP")
	)
	(segment
		(start 113.888012 -134.885684)
		(end 114.221514 -135.219186)
		(width 0.254)
		(layer "F.Cu")
		(net "VR_PVCCP_NODE1_COMP")
	)
	(segment
		(start 111.359188 -134.833868)
		(end 111.223298 -134.697978)
		(width 0.1778)
		(layer "F.Cu")
		(net "VR_PVCCP_NODE1_COMP")
	)
	(segment
		(start 114.221514 -135.219186)
		(end 114.221514 -135.012938)
		(width 0.254)
		(layer "F.Cu")
		(net "VR_PVCCP_NODE1_COMP")
	)
	(segment
		(start 114.221514 -135.012938)
		(end 114.682016 -134.552436)
		(width 0.254)
		(layer "F.Cu")
		(net "VR_PVCCP_NODE1_COMP")
	)
	(segment
		(start 113.215166 -134.885684)
		(end 113.888012 -134.885684)
		(width 0.254)
		(layer "F.Cu")
		(net "VR_PVCCP_NODE1_COMP")
	)
	(via
		(at 114.682016 -134.552436)
		(size 0.508)
		(drill 0.254)
		(layers "F.Cu" "B.Cu")
		(net "VR_PVCCP_NODE1_COMP")
	)
	(segment
		(start 36.539678 -170.551856)
		(end 37.113464 -169.97807)
		(width 0.508)
		(layer "F.Cu")
		(net "P12V_AUX_EN")
	)
	(segment
		(start 33.612836 -183.44134)
		(end 33.639252 -183.414924)
		(width 0.508)
		(layer "F.Cu")
		(net "P12V_AUX_EN")
	)
	(segment
		(start 33.639252 -183.414924)
		(end 33.639252 -182.215282)
		(width 0.254)
		(layer "F.Cu")
		(net "P12V_AUX_EN")
	)
	(segment
		(start 33.612836 -185.3565)
		(end 33.612836 -186.177428)
		(width 0.508)
		(layer "F.Cu")
		(net "P12V_AUX_EN")
	)
	(segment
		(start 33.612836 -184.2135)
		(end 33.612836 -183.44134)
		(width 0.508)
		(layer "F.Cu")
		(net "P12V_AUX_EN")
	)
	(segment
		(start 36.130738 -170.551856)
		(end 36.539678 -170.551856)
		(width 0.508)
		(layer "F.Cu")
		(net "P12V_AUX_EN")
	)
	(segment
		(start 44.625006 -181.780942)
		(end 43.473116 -181.780942)
		(width 0.508)
		(layer "F.Cu")
		(net "P12V_AUX_EN")
	)
	(segment
		(start 37.113464 -169.97807)
		(end 37.6428 -169.97807)
		(width 0.508)
		(layer "F.Cu")
		(net "P12V_AUX_EN")
	)
	(via
		(at 37.6428 -169.97807)
		(size 0.508)
		(drill 0.254)
		(layers "F.Cu" "B.Cu")
		(net "P12V_AUX_EN")
	)
	(via
		(at 43.473116 -181.780942)
		(size 0.508)
		(drill 0.254)
		(layers "F.Cu" "B.Cu")
		(net "P12V_AUX_EN")
	)
	(via
		(at 33.612836 -186.177428)
		(size 0.508)
		(drill 0.254)
		(layers "F.Cu" "B.Cu")
		(net "P12V_AUX_EN")
	)
	(via
		(at 45.461428 -174.912274)
		(size 0.508)
		(drill 0.254)
		(layers "F.Cu" "B.Cu")
		(net "P12V_AUX_EN")
	)
	(segment
		(start 41.853104 -169.97807)
		(end 37.6428 -169.97807)
		(width 0.508)
		(layer "In2.Cu")
		(net "P12V_AUX_EN")
	)
	(segment
		(start 33.61182 -184.0103)
		(end 33.61182 -186.177428)
		(width 0.4572)
		(layer "In2.Cu")
		(net "P12V_AUX_EN")
	)
	(segment
		(start 43.473116 -181.780942)
		(end 42.090594 -183.163464)
		(width 0.4572)
		(layer "In2.Cu")
		(net "P12V_AUX_EN")
	)
	(segment
		(start 45.461428 -174.912274)
		(end 45.461428 -172.359828)
		(width 0.508)
		(layer "In2.Cu")
		(net "P12V_AUX_EN")
	)
	(segment
		(start 43.4848 -181.780942)
		(end 43.473116 -181.780942)
		(width 0.508)
		(layer "In2.Cu")
		(net "P12V_AUX_EN")
	)
	(segment
		(start 33.61182 -186.177428)
		(end 33.612836 -186.177428)
		(width 0.4572)
		(layer "In2.Cu")
		(net "P12V_AUX_EN")
	)
	(segment
		(start 42.42689 -170.551856)
		(end 41.853104 -169.97807)
		(width 0.508)
		(layer "In2.Cu")
		(net "P12V_AUX_EN")
	)
	(segment
		(start 43.7388 -176.634902)
		(end 43.7388 -181.526942)
		(width 0.508)
		(layer "In2.Cu")
		(net "P12V_AUX_EN")
	)
	(segment
		(start 42.090594 -183.163464)
		(end 34.458656 -183.163464)
		(width 0.4572)
		(layer "In2.Cu")
		(net "P12V_AUX_EN")
	)
	(segment
		(start 43.653456 -170.551856)
		(end 42.42689 -170.551856)
		(width 0.508)
		(layer "In2.Cu")
		(net "P12V_AUX_EN")
	)
	(segment
		(start 45.461428 -172.359828)
		(end 43.653456 -170.551856)
		(width 0.508)
		(layer "In2.Cu")
		(net "P12V_AUX_EN")
	)
	(segment
		(start 43.7388 -181.526942)
		(end 43.4848 -181.780942)
		(width 0.508)
		(layer "In2.Cu")
		(net "P12V_AUX_EN")
	)
	(segment
		(start 45.461428 -174.912274)
		(end 43.7388 -176.634902)
		(width 0.508)
		(layer "In2.Cu")
		(net "P12V_AUX_EN")
	)
	(segment
		(start 34.458656 -183.163464)
		(end 33.61182 -184.0103)
		(width 0.4572)
		(layer "In2.Cu")
		(net "P12V_AUX_EN")
	)
	(segment
		(start 59.741816 -137.659618)
		(end 59.73953 -137.659618)
		(width 0.1016)
		(layer "F.Cu")
		(net "BMC_NODE1_DDR_D15")
	)
	(segment
		(start 59.73953 -137.659618)
		(end 59.341004 -138.058144)
		(width 0.1016)
		(layer "F.Cu")
		(net "BMC_NODE1_DDR_D15")
	)
	(segment
		(start 40.83304 -140.96365)
		(end 41.721786 -141.547342)
		(width 0.1016)
		(layer "F.Cu")
		(net "BMC_NODE1_DDR_D15")
	)
	(via
		(at 59.341004 -138.058144)
		(size 0.49022)
		(drill 0.254)
		(layers "F.Cu" "B.Cu")
		(net "BMC_NODE1_DDR_D15")
	)
	(via
		(at 41.721786 -141.547342)
		(size 0.508)
		(drill 0.254)
		(layers "F.Cu" "B.Cu")
		(net "BMC_NODE1_DDR_D15")
	)
	(segment
		(start 58.165492 -137.658348)
		(end 58.941208 -137.658348)
		(width 0.1016)
		(layer "In7.Cu")
		(net "BMC_NODE1_DDR_D15")
	)
	(segment
		(start 51.492658 -142.462504)
		(end 51.92268 -142.032482)
		(width 0.1143)
		(layer "In7.Cu")
		(net "BMC_NODE1_DDR_D15")
	)
	(segment
		(start 57.012332 -138.811508)
		(end 58.165492 -137.658348)
		(width 0.1143)
		(layer "In7.Cu")
		(net "BMC_NODE1_DDR_D15")
	)
	(segment
		(start 41.986454 -141.413992)
		(end 43.226736 -141.413992)
		(width 0.1143)
		(layer "In7.Cu")
		(net "BMC_NODE1_DDR_D15")
	)
	(segment
		(start 54.557168 -142.032482)
		(end 54.8132 -141.77645)
		(width 0.1143)
		(layer "In7.Cu")
		(net "BMC_NODE1_DDR_D15")
	)
	(segment
		(start 45.79239 -142.462504)
		(end 51.492658 -142.462504)
		(width 0.1143)
		(layer "In7.Cu")
		(net "BMC_NODE1_DDR_D15")
	)
	(segment
		(start 54.8132 -141.77645)
		(end 57.012332 -138.811508)
		(width 0.1143)
		(layer "In7.Cu")
		(net "BMC_NODE1_DDR_D15")
	)
	(segment
		(start 58.941208 -137.658348)
		(end 59.341004 -138.058144)
		(width 0.1143)
		(layer "In7.Cu")
		(net "BMC_NODE1_DDR_D15")
	)
	(segment
		(start 44.308014 -141.971776)
		(end 45.79239 -142.462504)
		(width 0.1143)
		(layer "In7.Cu")
		(net "BMC_NODE1_DDR_D15")
	)
	(segment
		(start 43.226736 -141.413992)
		(end 44.308014 -141.971776)
		(width 0.1143)
		(layer "In7.Cu")
		(net "BMC_NODE1_DDR_D15")
	)
	(segment
		(start 51.92268 -142.032482)
		(end 54.557168 -142.032482)
		(width 0.1143)
		(layer "In7.Cu")
		(net "BMC_NODE1_DDR_D15")
	)
	(segment
		(start 41.721786 -141.547342)
		(end 41.986454 -141.413992)
		(width 0.1143)
		(layer "In7.Cu")
		(net "BMC_NODE1_DDR_D15")
	)
	(segment
		(start 58.864246 -68.889372)
		(end 58.957972 -68.983098)
		(width 0.3048)
		(layer "F.Cu")
		(net "P1V5_SFRPLL_NODE1")
	)
	(segment
		(start 58.497978 -68.503038)
		(end 58.957972 -68.963032)
		(width 0.3048)
		(layer "F.Cu")
		(net "P1V5_SFRPLL_NODE1")
	)
	(segment
		(start 58.470546 -68.503038)
		(end 58.497978 -68.503038)
		(width 0.3048)
		(layer "F.Cu")
		(net "P1V5_SFRPLL_NODE1")
	)
	(segment
		(start 58.470546 -69.265038)
		(end 58.864246 -68.871338)
		(width 0.3048)
		(layer "F.Cu")
		(net "P1V5_SFRPLL_NODE1")
	)
	(segment
		(start 58.957972 -68.963032)
		(end 58.957972 -68.983098)
		(width 0.3048)
		(layer "F.Cu")
		(net "P1V5_SFRPLL_NODE1")
	)
	(segment
		(start 58.864246 -68.871338)
		(end 58.864246 -68.889372)
		(width 0.3048)
		(layer "F.Cu")
		(net "P1V5_SFRPLL_NODE1")
	)
	(via
		(at 52.857654 -69.343778)
		(size 0.6604)
		(drill 0.3302)
		(layers "F.Cu" "B.Cu")
		(net "P1V5_SFRPLL_NODE1")
	)
	(via
		(at 58.957972 -68.983098)
		(size 0.508)
		(drill 0.254)
		(layers "F.Cu" "B.Cu")
		(net "P1V5_SFRPLL_NODE1")
	)
	(segment
		(start 53.57241 -70.924166)
		(end 53.04409 -70.395846)
		(width 0.1016)
		(layer "B.Cu")
		(net "P1V5_SFRPLL_NODE1")
	)
	(segment
		(start 58.957972 -68.983098)
		(end 57.80151 -68.983098)
		(width 0.381)
		(layer "B.Cu")
		(net "P1V5_SFRPLL_NODE1")
	)
	(segment
		(start 53.04409 -70.395846)
		(end 53.04409 -69.530214)
		(width 0.1016)
		(layer "B.Cu")
		(net "P1V5_SFRPLL_NODE1")
	)
	(segment
		(start 55.935372 -69.211698)
		(end 55.935372 -69.512688)
		(width 0.381)
		(layer "B.Cu")
		(net "P1V5_SFRPLL_NODE1")
	)
	(segment
		(start 56.298592 -68.848478)
		(end 57.37733 -68.848478)
		(width 0.381)
		(layer "B.Cu")
		(net "P1V5_SFRPLL_NODE1")
	)
	(segment
		(start 55.136288 -70.724522)
		(end 54.936644 -70.924166)
		(width 0.1016)
		(layer "B.Cu")
		(net "P1V5_SFRPLL_NODE1")
	)
	(segment
		(start 55.136288 -70.311772)
		(end 55.136288 -70.502018)
		(width 0.381)
		(layer "B.Cu")
		(net "P1V5_SFRPLL_NODE1")
	)
	(segment
		(start 55.136288 -70.502018)
		(end 55.136288 -70.724522)
		(width 0.1016)
		(layer "B.Cu")
		(net "P1V5_SFRPLL_NODE1")
	)
	(segment
		(start 53.04409 -69.530214)
		(end 52.857654 -69.343778)
		(width 0.1016)
		(layer "B.Cu")
		(net "P1V5_SFRPLL_NODE1")
	)
	(segment
		(start 57.80151 -68.983098)
		(end 57.65673 -69.127878)
		(width 0.381)
		(layer "B.Cu")
		(net "P1V5_SFRPLL_NODE1")
	)
	(segment
		(start 55.935372 -69.211698)
		(end 56.298592 -68.848478)
		(width 0.381)
		(layer "B.Cu")
		(net "P1V5_SFRPLL_NODE1")
	)
	(segment
		(start 55.935372 -69.512688)
		(end 55.136288 -70.311772)
		(width 0.381)
		(layer "B.Cu")
		(net "P1V5_SFRPLL_NODE1")
	)
	(segment
		(start 54.936644 -70.924166)
		(end 53.57241 -70.924166)
		(width 0.1016)
		(layer "B.Cu")
		(net "P1V5_SFRPLL_NODE1")
	)
	(segment
		(start 57.37733 -68.848478)
		(end 57.65673 -69.127878)
		(width 0.381)
		(layer "B.Cu")
		(net "P1V5_SFRPLL_NODE1")
	)
	(segment
		(start 109.271562 -132.355082)
		(end 109.271562 -131.8006)
		(width 0.1778)
		(layer "F.Cu")
		(net "VR_PVCCP_NODE1_UGATE1")
	)
	(via
		(at 109.54512 -130.612642)
		(size 0.508)
		(drill 0.254)
		(layers "F.Cu" "B.Cu")
		(net "VR_PVCCP_NODE1_UGATE1")
	)
	(via
		(at 109.564424 -131.276344)
		(size 0.508)
		(drill 0.254)
		(layers "F.Cu" "B.Cu")
		(net "VR_PVCCP_NODE1_UGATE1")
	)
	(via
		(at 113.73358 -123.26366)
		(size 0.508)
		(drill 0.254)
		(layers "F.Cu" "B.Cu")
		(net "VR_PVCCP_NODE1_UGATE1")
	)
	(via
		(at 113.00968 -123.255786)
		(size 0.508)
		(drill 0.254)
		(layers "F.Cu" "B.Cu")
		(net "VR_PVCCP_NODE1_UGATE1")
	)
	(segment
		(start 58.14187 -137.659618)
		(end 57.70753 -138.093958)
		(width 0.10414)
		(layer "F.Cu")
		(net "BMC_NODE1_DDR_DQS1_DP")
	)
	(segment
		(start 56.032908 -139.235942)
		(end 52.352194 -139.235942)
		(width 0.10414)
		(layer "F.Cu")
		(net "BMC_NODE1_DDR_DQS1_DP")
	)
	(segment
		(start 57.70753 -138.093958)
		(end 57.174892 -138.093958)
		(width 0.10414)
		(layer "F.Cu")
		(net "BMC_NODE1_DDR_DQS1_DP")
	)
	(segment
		(start 45.237146 -139.767818)
		(end 44.833032 -139.363704)
		(width 0.10414)
		(layer "F.Cu")
		(net "BMC_NODE1_DDR_DQS1_DP")
	)
	(segment
		(start 52.142644 -139.445492)
		(end 52.142644 -139.98702)
		(width 0.10414)
		(layer "F.Cu")
		(net "BMC_NODE1_DDR_DQS1_DP")
	)
	(segment
		(start 52.352194 -139.235942)
		(end 52.142644 -139.445492)
		(width 0.10414)
		(layer "F.Cu")
		(net "BMC_NODE1_DDR_DQS1_DP")
	)
	(segment
		(start 57.174892 -138.093958)
		(end 56.032908 -139.235942)
		(width 0.10414)
		(layer "F.Cu")
		(net "BMC_NODE1_DDR_DQS1_DP")
	)
	(via
		(at 52.142644 -139.98702)
		(size 0.508)
		(drill 0.254)
		(layers "F.Cu" "B.Cu")
		(net "BMC_NODE1_DDR_DQS1_DP")
	)
	(via
		(at 45.237146 -139.767818)
		(size 0.49022)
		(drill 0.254)
		(layers "F.Cu" "B.Cu")
		(net "BMC_NODE1_DDR_DQS1_DP")
	)
	(segment
		(start 45.237146 -139.767818)
		(end 45.3898 -139.920472)
		(width 0.10414)
		(layer "In2.Cu")
		(net "BMC_NODE1_DDR_DQS1_DP")
	)
	(segment
		(start 51.89728 -139.603226)
		(end 51.89728 -139.741656)
		(width 0.10414)
		(layer "In2.Cu")
		(net "BMC_NODE1_DDR_DQS1_DP")
	)
	(segment
		(start 45.3898 -139.920472)
		(end 45.591476 -139.920472)
		(width 0.10414)
		(layer "In2.Cu")
		(net "BMC_NODE1_DDR_DQS1_DP")
	)
	(segment
		(start 48.631856 -140.959332)
		(end 48.792384 -141.11986)
		(width 0.10414)
		(layer "In2.Cu")
		(net "BMC_NODE1_DDR_DQS1_DP")
	)
	(segment
		(start 49.243996 -139.76096)
		(end 49.752758 -139.252198)
		(width 0.10414)
		(layer "In2.Cu")
		(net "BMC_NODE1_DDR_DQS1_DP")
	)
	(segment
		(start 46.182026 -139.329922)
		(end 48.309276 -139.329922)
		(width 0.10414)
		(layer "In2.Cu")
		(net "BMC_NODE1_DDR_DQS1_DP")
	)
	(segment
		(start 51.546252 -139.252198)
		(end 51.89728 -139.603226)
		(width 0.10414)
		(layer "In2.Cu")
		(net "BMC_NODE1_DDR_DQS1_DP")
	)
	(segment
		(start 51.89728 -139.741656)
		(end 52.142644 -139.98702)
		(width 0.10414)
		(layer "In2.Cu")
		(net "BMC_NODE1_DDR_DQS1_DP")
	)
	(segment
		(start 48.309276 -139.329922)
		(end 48.631856 -139.652502)
		(width 0.10414)
		(layer "In2.Cu")
		(net "BMC_NODE1_DDR_DQS1_DP")
	)
	(segment
		(start 48.792384 -141.11986)
		(end 49.045368 -141.11986)
		(width 0.10414)
		(layer "In2.Cu")
		(net "BMC_NODE1_DDR_DQS1_DP")
	)
	(segment
		(start 45.591476 -139.920472)
		(end 46.182026 -139.329922)
		(width 0.10414)
		(layer "In2.Cu")
		(net "BMC_NODE1_DDR_DQS1_DP")
	)
	(segment
		(start 49.045368 -141.11986)
		(end 49.243996 -140.921232)
		(width 0.10414)
		(layer "In2.Cu")
		(net "BMC_NODE1_DDR_DQS1_DP")
	)
	(segment
		(start 49.752758 -139.252198)
		(end 51.546252 -139.252198)
		(width 0.10414)
		(layer "In2.Cu")
		(net "BMC_NODE1_DDR_DQS1_DP")
	)
	(segment
		(start 49.243996 -140.921232)
		(end 49.243996 -139.76096)
		(width 0.10414)
		(layer "In2.Cu")
		(net "BMC_NODE1_DDR_DQS1_DP")
	)
	(segment
		(start 48.631856 -139.652502)
		(end 48.631856 -140.959332)
		(width 0.10414)
		(layer "In2.Cu")
		(net "BMC_NODE1_DDR_DQS1_DP")
	)
	(segment
		(start 106.285792 -64.508634)
		(end 107.210352 -64.508634)
		(width 0.1016)
		(layer "F.Cu")
		(net "XDP_CPU_NODE1_PWROK_STALL_L")
	)
	(segment
		(start 175.010318 -123.365768)
		(end 174.510446 -123.86564)
		(width 0.1016)
		(layer "F.Cu")
		(net "XDP_CPU_NODE1_PWROK_STALL_L")
	)
	(segment
		(start 105.888028 -64.906398)
		(end 106.285792 -64.508634)
		(width 0.1016)
		(layer "F.Cu")
		(net "XDP_CPU_NODE1_PWROK_STALL_L")
	)
	(segment
		(start 104.73182 -64.906398)
		(end 105.888028 -64.906398)
		(width 0.1016)
		(layer "F.Cu")
		(net "XDP_CPU_NODE1_PWROK_STALL_L")
	)
	(segment
		(start 107.210352 -64.508634)
		(end 107.322112 -64.396874)
		(width 0.1016)
		(layer "F.Cu")
		(net "XDP_CPU_NODE1_PWROK_STALL_L")
	)
	(via
		(at 107.322112 -64.396874)
		(size 0.508)
		(drill 0.254)
		(layers "F.Cu" "B.Cu")
		(net "XDP_CPU_NODE1_PWROK_STALL_L")
	)
	(via
		(at 113.16716 -73.368662)
		(size 0.508)
		(drill 0.254)
		(layers "F.Cu" "B.Cu")
		(net "XDP_CPU_NODE1_PWROK_STALL_L")
	)
	(via
		(at 174.510446 -123.86564)
		(size 0.49022)
		(drill 0.254)
		(layers "F.Cu" "B.Cu")
		(net "XDP_CPU_NODE1_PWROK_STALL_L")
	)
	(segment
		(start 108.904786 -69.046852)
		(end 113.16716 -73.309226)
		(width 0.1016)
		(layer "B.Cu")
		(net "XDP_CPU_NODE1_PWROK_STALL_L")
	)
	(segment
		(start 106.14914 -68.244466)
		(end 107.405932 -66.987674)
		(width 0.1016)
		(layer "B.Cu")
		(net "XDP_CPU_NODE1_PWROK_STALL_L")
	)
	(segment
		(start 104.808274 -68.244466)
		(end 106.14914 -68.244466)
		(width 0.1016)
		(layer "B.Cu")
		(net "XDP_CPU_NODE1_PWROK_STALL_L")
	)
	(segment
		(start 107.405932 -66.987674)
		(end 107.405932 -65.864994)
		(width 0.1016)
		(layer "B.Cu")
		(net "XDP_CPU_NODE1_PWROK_STALL_L")
	)
	(segment
		(start 107.405932 -65.864994)
		(end 107.322112 -65.781174)
		(width 0.1016)
		(layer "B.Cu")
		(net "XDP_CPU_NODE1_PWROK_STALL_L")
	)
	(segment
		(start 107.322112 -65.781174)
		(end 107.322112 -64.396874)
		(width 0.1016)
		(layer "B.Cu")
		(net "XDP_CPU_NODE1_PWROK_STALL_L")
	)
	(segment
		(start 104.808274 -69.273674)
		(end 105.109772 -69.273674)
		(width 0.1016)
		(layer "B.Cu")
		(net "XDP_CPU_NODE1_PWROK_STALL_L")
	)
	(segment
		(start 105.336594 -69.046852)
		(end 108.904786 -69.046852)
		(width 0.1016)
		(layer "B.Cu")
		(net "XDP_CPU_NODE1_PWROK_STALL_L")
	)
	(segment
		(start 113.16716 -73.309226)
		(end 113.16716 -73.368662)
		(width 0.1016)
		(layer "B.Cu")
		(net "XDP_CPU_NODE1_PWROK_STALL_L")
	)
	(segment
		(start 104.808274 -68.244466)
		(end 104.808274 -69.273674)
		(width 0.1016)
		(layer "B.Cu")
		(net "XDP_CPU_NODE1_PWROK_STALL_L")
	)
	(segment
		(start 105.109772 -69.273674)
		(end 105.336594 -69.046852)
		(width 0.1016)
		(layer "B.Cu")
		(net "XDP_CPU_NODE1_PWROK_STALL_L")
	)
	(segment
		(start 104.808274 -67.228466)
		(end 104.808274 -68.244466)
		(width 0.1016)
		(layer "B.Cu")
		(net "XDP_CPU_NODE1_PWROK_STALL_L")
	)
	(segment
		(start 113.34242 -73.543922)
		(end 113.16716 -73.368662)
		(width 0.1143)
		(layer "In7.Cu")
		(net "XDP_CPU_NODE1_PWROK_STALL_L")
	)
	(segment
		(start 174.264066 -123.86564)
		(end 173.834806 -124.2949)
		(width 0.1143)
		(layer "In7.Cu")
		(net "XDP_CPU_NODE1_PWROK_STALL_L")
	)
	(segment
		(start 162.69462 -123.126246)
		(end 162.3314 -122.763026)
		(width 0.1143)
		(layer "In7.Cu")
		(net "XDP_CPU_NODE1_PWROK_STALL_L")
	)
	(segment
		(start 173.834806 -124.2949)
		(end 167.42918 -124.2949)
		(width 0.1143)
		(layer "In7.Cu")
		(net "XDP_CPU_NODE1_PWROK_STALL_L")
	)
	(segment
		(start 166.260526 -123.126246)
		(end 162.69462 -123.126246)
		(width 0.1143)
		(layer "In7.Cu")
		(net "XDP_CPU_NODE1_PWROK_STALL_L")
	)
	(segment
		(start 141.143228 -98.216974)
		(end 129.85115 -98.216974)
		(width 0.1143)
		(layer "In7.Cu")
		(net "XDP_CPU_NODE1_PWROK_STALL_L")
	)
	(segment
		(start 159.978852 -122.763026)
		(end 155.5877 -118.371874)
		(width 0.1143)
		(layer "In7.Cu")
		(net "XDP_CPU_NODE1_PWROK_STALL_L")
	)
	(segment
		(start 162.3314 -122.763026)
		(end 159.978852 -122.763026)
		(width 0.1143)
		(layer "In7.Cu")
		(net "XDP_CPU_NODE1_PWROK_STALL_L")
	)
	(segment
		(start 155.5877 -112.661446)
		(end 141.143228 -98.216974)
		(width 0.1143)
		(layer "In7.Cu")
		(net "XDP_CPU_NODE1_PWROK_STALL_L")
	)
	(segment
		(start 129.85115 -98.216974)
		(end 113.34242 -81.708244)
		(width 0.1143)
		(layer "In7.Cu")
		(net "XDP_CPU_NODE1_PWROK_STALL_L")
	)
	(segment
		(start 155.5877 -118.371874)
		(end 155.5877 -112.661446)
		(width 0.1143)
		(layer "In7.Cu")
		(net "XDP_CPU_NODE1_PWROK_STALL_L")
	)
	(segment
		(start 174.510446 -123.86564)
		(end 174.264066 -123.86564)
		(width 0.1143)
		(layer "In7.Cu")
		(net "XDP_CPU_NODE1_PWROK_STALL_L")
	)
	(segment
		(start 113.34242 -81.708244)
		(end 113.34242 -73.543922)
		(width 0.1143)
		(layer "In7.Cu")
		(net "XDP_CPU_NODE1_PWROK_STALL_L")
	)
	(segment
		(start 167.42918 -124.2949)
		(end 166.260526 -123.126246)
		(width 0.1143)
		(layer "In7.Cu")
		(net "XDP_CPU_NODE1_PWROK_STALL_L")
	)
	(segment
		(start 57.121552 -69.265038)
		(end 56.986678 -69.399912)
		(width 0.3048)
		(layer "F.Cu")
		(net "P1V05_VCCACLK_DDR3_NODE1")
	)
	(segment
		(start 57.770522 -69.265038)
		(end 57.121552 -69.265038)
		(width 0.3048)
		(layer "F.Cu")
		(net "P1V05_VCCACLK_DDR3_NODE1")
	)
	(segment
		(start 57.770522 -70.027038)
		(end 57.613804 -70.027038)
		(width 0.3048)
		(layer "F.Cu")
		(net "P1V05_VCCACLK_DDR3_NODE1")
	)
	(segment
		(start 57.613804 -70.027038)
		(end 56.986678 -69.399912)
		(width 0.3048)
		(layer "F.Cu")
		(net "P1V05_VCCACLK_DDR3_NODE1")
	)
	(via
		(at 55.676546 -73.239376)
		(size 0.6604)
		(drill 0.3302)
		(layers "F.Cu" "B.Cu")
		(net "P1V05_VCCACLK_DDR3_NODE1")
	)
	(via
		(at 56.986678 -69.399912)
		(size 0.508)
		(drill 0.254)
		(layers "F.Cu" "B.Cu")
		(net "P1V05_VCCACLK_DDR3_NODE1")
	)
	(segment
		(start 56.392572 -71.062596)
		(end 56.119522 -70.789546)
		(width 0.3048)
		(layer "B.Cu")
		(net "P1V05_VCCACLK_DDR3_NODE1")
	)
	(segment
		(start 56.119522 -70.789546)
		(end 56.119522 -70.354698)
		(width 0.3048)
		(layer "B.Cu")
		(net "P1V05_VCCACLK_DDR3_NODE1")
	)
	(segment
		(start 56.935878 -69.399912)
		(end 56.986678 -69.399912)
		(width 0.3048)
		(layer "B.Cu")
		(net "P1V05_VCCACLK_DDR3_NODE1")
	)
	(segment
		(start 55.676546 -73.239376)
		(end 55.813198 -73.102724)
		(width 0.1016)
		(layer "B.Cu")
		(net "P1V05_VCCACLK_DDR3_NODE1")
	)
	(segment
		(start 56.392572 -71.351648)
		(end 56.392572 -71.062596)
		(width 0.3048)
		(layer "B.Cu")
		(net "P1V05_VCCACLK_DDR3_NODE1")
	)
	(segment
		(start 56.119522 -70.216268)
		(end 56.935878 -69.399912)
		(width 0.3048)
		(layer "B.Cu")
		(net "P1V05_VCCACLK_DDR3_NODE1")
	)
	(segment
		(start 55.813198 -73.102724)
		(end 55.813198 -71.875396)
		(width 0.1016)
		(layer "B.Cu")
		(net "P1V05_VCCACLK_DDR3_NODE1")
	)
	(segment
		(start 56.119522 -70.354698)
		(end 56.119522 -70.216268)
		(width 0.3048)
		(layer "B.Cu")
		(net "P1V05_VCCACLK_DDR3_NODE1")
	)
	(segment
		(start 56.336946 -71.351648)
		(end 56.392572 -71.351648)
		(width 0.1016)
		(layer "B.Cu")
		(net "P1V05_VCCACLK_DDR3_NODE1")
	)
	(segment
		(start 55.813198 -71.875396)
		(end 56.336946 -71.351648)
		(width 0.1016)
		(layer "B.Cu")
		(net "P1V05_VCCACLK_DDR3_NODE1")
	)
	(segment
		(start 43.796204 -77.607414)
		(end 43.501818 -77.607414)
		(width 0.1016)
		(layer "F.Cu")
		(net "PD_CPU_NODE1_RP2_PERN")
	)
	(segment
		(start 43.56354 -79.614268)
		(end 43.56354 -80.093312)
		(width 0.1016)
		(layer "F.Cu")
		(net "PD_CPU_NODE1_RP2_PERN")
	)
	(segment
		(start 42.248328 -81.092294)
		(end 42.248328 -80.920082)
		(width 0.1016)
		(layer "F.Cu")
		(net "PD_CPU_NODE1_RP2_PERN")
	)
	(segment
		(start 43.796204 -82.110326)
		(end 43.371262 -82.535268)
		(width 0.1016)
		(layer "F.Cu")
		(net "PD_CPU_NODE1_RP2_PERN")
	)
	(segment
		(start 42.607738 -80.560672)
		(end 42.248328 -80.920082)
		(width 0.1016)
		(layer "F.Cu")
		(net "PD_CPU_NODE1_RP2_PERN")
	)
	(segment
		(start 43.420538 -78.404466)
		(end 43.69054 -78.674468)
		(width 0.1016)
		(layer "F.Cu")
		(net "PD_CPU_NODE1_RP2_PERN")
	)
	(segment
		(start 40.206422 -80.992218)
		(end 40.021002 -81.177638)
		(width 0.1016)
		(layer "F.Cu")
		(net "PD_CPU_NODE1_RP2_PERN")
	)
	(segment
		(start 43.501818 -77.607414)
		(end 43.40987 -77.515466)
		(width 0.1016)
		(layer "F.Cu")
		(net "PD_CPU_NODE1_RP2_PERN")
	)
	(segment
		(start 43.45813 -80.198722)
		(end 43.450764 -80.198722)
		(width 0.1016)
		(layer "F.Cu")
		(net "PD_CPU_NODE1_RP2_PERN")
	)
	(segment
		(start 44.07154 -79.360268)
		(end 43.81754 -79.360268)
		(width 0.1016)
		(layer "F.Cu")
		(net "PD_CPU_NODE1_RP2_PERN")
	)
	(segment
		(start 44.12234 -78.674468)
		(end 44.30014 -78.852268)
		(width 0.1016)
		(layer "F.Cu")
		(net "PD_CPU_NODE1_RP2_PERN")
	)
	(segment
		(start 39.59098 -81.177638)
		(end 38.588696 -82.179922)
		(width 0.1016)
		(layer "F.Cu")
		(net "PD_CPU_NODE1_RP2_PERN")
	)
	(segment
		(start 43.450764 -80.198722)
		(end 43.088814 -80.560672)
		(width 0.1016)
		(layer "F.Cu")
		(net "PD_CPU_NODE1_RP2_PERN")
	)
	(segment
		(start 43.69054 -78.674468)
		(end 44.12234 -78.674468)
		(width 0.1016)
		(layer "F.Cu")
		(net "PD_CPU_NODE1_RP2_PERN")
	)
	(segment
		(start 43.088814 -80.560672)
		(end 42.607738 -80.560672)
		(width 0.1016)
		(layer "F.Cu")
		(net "PD_CPU_NODE1_RP2_PERN")
	)
	(segment
		(start 43.56354 -80.093312)
		(end 43.45813 -80.198722)
		(width 0.1016)
		(layer "F.Cu")
		(net "PD_CPU_NODE1_RP2_PERN")
	)
	(segment
		(start 42.361612 -82.911696)
		(end 42.361612 -81.986882)
		(width 0.1016)
		(layer "F.Cu")
		(net "PD_CPU_NODE1_RP2_PERN")
	)
	(segment
		(start 40.021002 -81.177638)
		(end 39.59098 -81.177638)
		(width 0.1016)
		(layer "F.Cu")
		(net "PD_CPU_NODE1_RP2_PERN")
	)
	(segment
		(start 43.40987 -77.515466)
		(end 43.099736 -77.515466)
		(width 0.1016)
		(layer "F.Cu")
		(net "PD_CPU_NODE1_RP2_PERN")
	)
	(segment
		(start 43.81754 -79.360268)
		(end 43.56354 -79.614268)
		(width 0.1016)
		(layer "F.Cu")
		(net "PD_CPU_NODE1_RP2_PERN")
	)
	(segment
		(start 44.30014 -78.852268)
		(end 44.30014 -79.131668)
		(width 0.1016)
		(layer "F.Cu")
		(net "PD_CPU_NODE1_RP2_PERN")
	)
	(segment
		(start 42.361612 -82.911696)
		(end 42.359834 -82.913474)
		(width 0.1016)
		(layer "F.Cu")
		(net "PD_CPU_NODE1_RP2_PERN")
	)
	(segment
		(start 36.069778 -82.179922)
		(end 37.1094 -82.179922)
		(width 0.1016)
		(layer "F.Cu")
		(net "PD_CPU_NODE1_RP2_PERN")
	)
	(segment
		(start 42.176954 -81.802224)
		(end 42.176954 -81.163668)
		(width 0.1016)
		(layer "F.Cu")
		(net "PD_CPU_NODE1_RP2_PERN")
	)
	(segment
		(start 43.099736 -78.404466)
		(end 43.420538 -78.404466)
		(width 0.1016)
		(layer "F.Cu")
		(net "PD_CPU_NODE1_RP2_PERN")
	)
	(segment
		(start 43.099736 -77.515466)
		(end 43.099736 -78.404466)
		(width 0.1016)
		(layer "F.Cu")
		(net "PD_CPU_NODE1_RP2_PERN")
	)
	(segment
		(start 44.30014 -79.131668)
		(end 44.07154 -79.360268)
		(width 0.1016)
		(layer "F.Cu")
		(net "PD_CPU_NODE1_RP2_PERN")
	)
	(segment
		(start 41.631616 -80.920082)
		(end 41.55948 -80.992218)
		(width 0.1016)
		(layer "F.Cu")
		(net "PD_CPU_NODE1_RP2_PERN")
	)
	(segment
		(start 43.371262 -82.535268)
		(end 42.73804 -82.535268)
		(width 0.1016)
		(layer "F.Cu")
		(net "PD_CPU_NODE1_RP2_PERN")
	)
	(segment
		(start 42.361612 -81.986882)
		(end 42.176954 -81.802224)
		(width 0.1016)
		(layer "F.Cu")
		(net "PD_CPU_NODE1_RP2_PERN")
	)
	(segment
		(start 42.248328 -80.920082)
		(end 41.631616 -80.920082)
		(width 0.1016)
		(layer "F.Cu")
		(net "PD_CPU_NODE1_RP2_PERN")
	)
	(segment
		(start 42.176954 -81.163668)
		(end 42.248328 -81.092294)
		(width 0.1016)
		(layer "F.Cu")
		(net "PD_CPU_NODE1_RP2_PERN")
	)
	(segment
		(start 42.447464 -82.82559)
		(end 42.361612 -82.911696)
		(width 0.1016)
		(layer "F.Cu")
		(net "PD_CPU_NODE1_RP2_PERN")
	)
	(segment
		(start 42.73804 -82.535268)
		(end 42.447464 -82.82559)
		(width 0.1016)
		(layer "F.Cu")
		(net "PD_CPU_NODE1_RP2_PERN")
	)
	(segment
		(start 41.55948 -80.992218)
		(end 40.206422 -80.992218)
		(width 0.1016)
		(layer "F.Cu")
		(net "PD_CPU_NODE1_RP2_PERN")
	)
	(segment
		(start 38.588696 -82.179922)
		(end 37.1094 -82.179922)
		(width 0.1016)
		(layer "F.Cu")
		(net "PD_CPU_NODE1_RP2_PERN")
	)
	(via
		(at 37.1094 -82.179922)
		(size 0.508)
		(drill 0.254)
		(layers "F.Cu" "B.Cu")
		(net "PD_CPU_NODE1_RP2_PERN")
	)
	(segment
		(start 173.010322 -125.365764)
		(end 173.010322 -126.15545)
		(width 0.1016)
		(layer "F.Cu")
		(net "H_CPU_NODE1_VR_HOT_L")
	)
	(segment
		(start 173.010322 -126.15545)
		(end 171.235624 -127.930148)
		(width 0.1016)
		(layer "F.Cu")
		(net "H_CPU_NODE1_VR_HOT_L")
	)
	(segment
		(start 100.71608 -144.130776)
		(end 100.71608 -143.392906)
		(width 0.1016)
		(layer "F.Cu")
		(net "H_CPU_NODE1_VR_HOT_L")
	)
	(segment
		(start 105.671366 -137.76833)
		(end 105.466388 -137.973308)
		(width 0.1016)
		(layer "F.Cu")
		(net "H_CPU_NODE1_VR_HOT_L")
	)
	(segment
		(start 105.466388 -137.973308)
		(end 103.471218 -137.973308)
		(width 0.1016)
		(layer "F.Cu")
		(net "H_CPU_NODE1_VR_HOT_L")
	)
	(segment
		(start 101.57079 -138.07694)
		(end 101.752146 -138.07694)
		(width 0.1016)
		(layer "F.Cu")
		(net "H_CPU_NODE1_VR_HOT_L")
	)
	(segment
		(start 100.30206 -139.34567)
		(end 101.57079 -138.07694)
		(width 0.1016)
		(layer "F.Cu")
		(net "H_CPU_NODE1_VR_HOT_L")
	)
	(segment
		(start 102.460298 -137.368788)
		(end 102.460298 -137.192258)
		(width 0.1016)
		(layer "F.Cu")
		(net "H_CPU_NODE1_VR_HOT_L")
	)
	(segment
		(start 100.30206 -142.978886)
		(end 100.30206 -139.34567)
		(width 0.1016)
		(layer "F.Cu")
		(net "H_CPU_NODE1_VR_HOT_L")
	)
	(segment
		(start 100.71608 -143.392906)
		(end 100.30206 -142.978886)
		(width 0.1016)
		(layer "F.Cu")
		(net "H_CPU_NODE1_VR_HOT_L")
	)
	(segment
		(start 105.671366 -137.44067)
		(end 105.671366 -137.76833)
		(width 0.1016)
		(layer "F.Cu")
		(net "H_CPU_NODE1_VR_HOT_L")
	)
	(segment
		(start 102.690168 -137.192258)
		(end 102.460298 -137.192258)
		(width 0.1016)
		(layer "F.Cu")
		(net "H_CPU_NODE1_VR_HOT_L")
	)
	(segment
		(start 103.471218 -137.973308)
		(end 102.690168 -137.192258)
		(width 0.1016)
		(layer "F.Cu")
		(net "H_CPU_NODE1_VR_HOT_L")
	)
	(segment
		(start 101.752146 -138.07694)
		(end 102.460298 -137.368788)
		(width 0.1016)
		(layer "F.Cu")
		(net "H_CPU_NODE1_VR_HOT_L")
	)
	(via
		(at 171.235624 -127.930148)
		(size 0.508)
		(drill 0.254)
		(layers "F.Cu" "B.Cu")
		(net "H_CPU_NODE1_VR_HOT_L")
	)
	(via
		(at 100.71608 -144.130776)
		(size 0.508)
		(drill 0.254)
		(layers "F.Cu" "B.Cu")
		(net "H_CPU_NODE1_VR_HOT_L")
	)
	(segment
		(start 132.40766 -133.3627)
		(end 141.646402 -133.3627)
		(width 0.1143)
		(layer "In6.Cu")
		(net "H_CPU_NODE1_VR_HOT_L")
	)
	(segment
		(start 115.770914 -142.174976)
		(end 116.46662 -141.47927)
		(width 0.1143)
		(layer "In6.Cu")
		(net "H_CPU_NODE1_VR_HOT_L")
	)
	(segment
		(start 169.352722 -129.81305)
		(end 171.235624 -127.930148)
		(width 0.1143)
		(layer "In6.Cu")
		(net "H_CPU_NODE1_VR_HOT_L")
	)
	(segment
		(start 115.29695 -142.174976)
		(end 115.770914 -142.174976)
		(width 0.1143)
		(layer "In6.Cu")
		(net "H_CPU_NODE1_VR_HOT_L")
	)
	(segment
		(start 122.306334 -135.166608)
		(end 130.603752 -135.166608)
		(width 0.1143)
		(layer "In6.Cu")
		(net "H_CPU_NODE1_VR_HOT_L")
	)
	(segment
		(start 130.603752 -135.166608)
		(end 132.40766 -133.3627)
		(width 0.1143)
		(layer "In6.Cu")
		(net "H_CPU_NODE1_VR_HOT_L")
	)
	(segment
		(start 162.58159 -131.68757)
		(end 168.001442 -131.68757)
		(width 0.1143)
		(layer "In6.Cu")
		(net "H_CPU_NODE1_VR_HOT_L")
	)
	(segment
		(start 149.483826 -132.91566)
		(end 161.3535 -132.91566)
		(width 0.1143)
		(layer "In6.Cu")
		(net "H_CPU_NODE1_VR_HOT_L")
	)
	(segment
		(start 141.646402 -133.3627)
		(end 142.916402 -134.6327)
		(width 0.1143)
		(layer "In6.Cu")
		(net "H_CPU_NODE1_VR_HOT_L")
	)
	(segment
		(start 168.001442 -131.68757)
		(end 169.352722 -130.33629)
		(width 0.1143)
		(layer "In6.Cu")
		(net "H_CPU_NODE1_VR_HOT_L")
	)
	(segment
		(start 113.34115 -144.130776)
		(end 115.29695 -142.174976)
		(width 0.1143)
		(layer "In6.Cu")
		(net "H_CPU_NODE1_VR_HOT_L")
	)
	(segment
		(start 169.352722 -130.33629)
		(end 169.352722 -129.81305)
		(width 0.1143)
		(layer "In6.Cu")
		(net "H_CPU_NODE1_VR_HOT_L")
	)
	(segment
		(start 147.766786 -134.6327)
		(end 149.483826 -132.91566)
		(width 0.1143)
		(layer "In6.Cu")
		(net "H_CPU_NODE1_VR_HOT_L")
	)
	(segment
		(start 116.46662 -141.006322)
		(end 122.306334 -135.166608)
		(width 0.1143)
		(layer "In6.Cu")
		(net "H_CPU_NODE1_VR_HOT_L")
	)
	(segment
		(start 142.916402 -134.6327)
		(end 147.766786 -134.6327)
		(width 0.1143)
		(layer "In6.Cu")
		(net "H_CPU_NODE1_VR_HOT_L")
	)
	(segment
		(start 100.71608 -144.130776)
		(end 113.34115 -144.130776)
		(width 0.1143)
		(layer "In6.Cu")
		(net "H_CPU_NODE1_VR_HOT_L")
	)
	(segment
		(start 116.46662 -141.47927)
		(end 116.46662 -141.006322)
		(width 0.1143)
		(layer "In6.Cu")
		(net "H_CPU_NODE1_VR_HOT_L")
	)
	(segment
		(start 161.3535 -132.91566)
		(end 162.58159 -131.68757)
		(width 0.1143)
		(layer "In6.Cu")
		(net "H_CPU_NODE1_VR_HOT_L")
	)
	(segment
		(start 41.63314 -130.56362)
		(end 41.215564 -131.33578)
		(width 0.1016)
		(layer "F.Cu")
		(net "BMC_NODE1_DDR_MA2")
	)
	(segment
		(start 40.96004 -131.7498)
		(end 40.731948 -131.7498)
		(width 0.1016)
		(layer "F.Cu")
		(net "BMC_NODE1_DDR_MA2")
	)
	(segment
		(start 60.541916 -132.059426)
		(end 60.541916 -132.058918)
		(width 0.1016)
		(layer "F.Cu")
		(net "BMC_NODE1_DDR_MA2")
	)
	(segment
		(start 40.731948 -131.7498)
		(end 40.607742 -131.874006)
		(width 0.1016)
		(layer "F.Cu")
		(net "BMC_NODE1_DDR_MA2")
	)
	(segment
		(start 40.607742 -131.874006)
		(end 40.606726 -131.877816)
		(width 0.1016)
		(layer "F.Cu")
		(net "BMC_NODE1_DDR_MA2")
	)
	(segment
		(start 41.215564 -131.494276)
		(end 40.96004 -131.7498)
		(width 0.1016)
		(layer "F.Cu")
		(net "BMC_NODE1_DDR_MA2")
	)
	(segment
		(start 60.541916 -132.058918)
		(end 60.141104 -131.658106)
		(width 0.1016)
		(layer "F.Cu")
		(net "BMC_NODE1_DDR_MA2")
	)
	(segment
		(start 40.606726 -131.877816)
		(end 40.48506 -131.999482)
		(width 0.1016)
		(layer "F.Cu")
		(net "BMC_NODE1_DDR_MA2")
	)
	(segment
		(start 40.48506 -131.999482)
		(end 40.431466 -132.560822)
		(width 0.1016)
		(layer "F.Cu")
		(net "BMC_NODE1_DDR_MA2")
	)
	(segment
		(start 41.215564 -131.33578)
		(end 41.215564 -131.494276)
		(width 0.1016)
		(layer "F.Cu")
		(net "BMC_NODE1_DDR_MA2")
	)
	(via
		(at 60.141104 -131.658106)
		(size 0.49022)
		(drill 0.254)
		(layers "F.Cu" "B.Cu")
		(net "BMC_NODE1_DDR_MA2")
	)
	(via
		(at 40.431466 -132.560822)
		(size 0.49022)
		(drill 0.254)
		(layers "F.Cu" "B.Cu")
		(net "BMC_NODE1_DDR_MA2")
	)
	(segment
		(start 59.740546 -132.583428)
		(end 59.740546 -132.31622)
		(width 0.1016)
		(layer "In2.Cu")
		(net "BMC_NODE1_DDR_MA2")
	)
	(segment
		(start 56.872124 -135.802624)
		(end 57.27065 -135.404098)
		(width 0.1143)
		(layer "In2.Cu")
		(net "BMC_NODE1_DDR_MA2")
	)
	(segment
		(start 59.740546 -134.120382)
		(end 59.740546 -133.914642)
		(width 0.1016)
		(layer "In2.Cu")
		(net "BMC_NODE1_DDR_MA2")
	)
	(segment
		(start 47.747174 -135.19785)
		(end 48.10506 -135.3566)
		(width 0.1143)
		(layer "In2.Cu")
		(net "BMC_NODE1_DDR_MA2")
	)
	(segment
		(start 42.8625 -134.976108)
		(end 44.038012 -135.40867)
		(width 0.1143)
		(layer "In2.Cu")
		(net "BMC_NODE1_DDR_MA2")
	)
	(segment
		(start 57.27065 -135.404098)
		(end 58.97372 -134.615936)
		(width 0.1143)
		(layer "In2.Cu")
		(net "BMC_NODE1_DDR_MA2")
	)
	(segment
		(start 59.740546 -133.42747)
		(end 59.740546 -133.11378)
		(width 0.1016)
		(layer "In2.Cu")
		(net "BMC_NODE1_DDR_MA2")
	)
	(segment
		(start 48.10506 -135.3566)
		(end 48.27778 -135.433054)
		(width 0.1143)
		(layer "In2.Cu")
		(net "BMC_NODE1_DDR_MA2")
	)
	(segment
		(start 44.038012 -135.40867)
		(end 45.65142 -135.40867)
		(width 0.1143)
		(layer "In2.Cu")
		(net "BMC_NODE1_DDR_MA2")
	)
	(segment
		(start 48.27778 -135.433054)
		(end 49.78781 -135.802624)
		(width 0.1143)
		(layer "In2.Cu")
		(net "BMC_NODE1_DDR_MA2")
	)
	(segment
		(start 42.846752 -134.976108)
		(end 42.8625 -134.976108)
		(width 0.1143)
		(layer "In2.Cu")
		(net "BMC_NODE1_DDR_MA2")
	)
	(segment
		(start 46.90491 -135.19785)
		(end 47.747174 -135.19785)
		(width 0.1143)
		(layer "In2.Cu")
		(net "BMC_NODE1_DDR_MA2")
	)
	(segment
		(start 59.740546 -132.058664)
		(end 60.141104 -131.658106)
		(width 0.1143)
		(layer "In2.Cu")
		(net "BMC_NODE1_DDR_MA2")
	)
	(segment
		(start 59.740546 -132.31622)
		(end 59.740546 -132.058664)
		(width 0.1143)
		(layer "In2.Cu")
		(net "BMC_NODE1_DDR_MA2")
	)
	(segment
		(start 45.65142 -135.40867)
		(end 46.90491 -135.19785)
		(width 0.1143)
		(layer "In2.Cu")
		(net "BMC_NODE1_DDR_MA2")
	)
	(segment
		(start 40.431466 -132.560822)
		(end 42.846752 -134.976108)
		(width 0.1143)
		(layer "In2.Cu")
		(net "BMC_NODE1_DDR_MA2")
	)
	(segment
		(start 59.740546 -133.914642)
		(end 59.740546 -133.42747)
		(width 0.1143)
		(layer "In2.Cu")
		(net "BMC_NODE1_DDR_MA2")
	)
	(segment
		(start 58.97372 -134.615936)
		(end 59.455558 -134.53999)
		(width 0.1143)
		(layer "In2.Cu")
		(net "BMC_NODE1_DDR_MA2")
	)
	(segment
		(start 59.740546 -133.11378)
		(end 59.740546 -132.583428)
		(width 0.1143)
		(layer "In2.Cu")
		(net "BMC_NODE1_DDR_MA2")
	)
	(segment
		(start 59.740546 -134.255002)
		(end 59.740546 -134.120382)
		(width 0.1143)
		(layer "In2.Cu")
		(net "BMC_NODE1_DDR_MA2")
	)
	(segment
		(start 49.78781 -135.802624)
		(end 56.872124 -135.802624)
		(width 0.1143)
		(layer "In2.Cu")
		(net "BMC_NODE1_DDR_MA2")
	)
	(segment
		(start 59.455558 -134.53999)
		(end 59.740546 -134.255002)
		(width 0.1143)
		(layer "In2.Cu")
		(net "BMC_NODE1_DDR_MA2")
	)
	(segment
		(start 60.456826 -68.882006)
		(end 60.456826 -68.884038)
		(width 0.3048)
		(layer "F.Cu")
		(net "P1V05_VCCPLL_DDR3_NODE1")
	)
	(segment
		(start 60.456826 -68.884038)
		(end 60.456826 -69.646038)
		(width 0.3048)
		(layer "F.Cu")
		(net "P1V05_VCCPLL_DDR3_NODE1")
	)
	(segment
		(start 60.850526 -68.488306)
		(end 60.456826 -68.882006)
		(width 0.3048)
		(layer "F.Cu")
		(net "P1V05_VCCPLL_DDR3_NODE1")
	)
	(via
		(at 60.100972 -68.627498)
		(size 0.6604)
		(drill 0.3302)
		(layers "F.Cu" "B.Cu")
		(net "P1V05_VCCPLL_DDR3_NODE1")
	)
	(via
		(at 60.850526 -68.488306)
		(size 0.508)
		(drill 0.254)
		(layers "F.Cu" "B.Cu")
		(net "P1V05_VCCPLL_DDR3_NODE1")
	)
	(segment
		(start 59.45124 -69.733668)
		(end 60.42914 -69.733668)
		(width 0.381)
		(layer "B.Cu")
		(net "P1V05_VCCPLL_DDR3_NODE1")
	)
	(segment
		(start 60.42914 -69.733668)
		(end 60.42914 -69.184266)
		(width 0.381)
		(layer "B.Cu")
		(net "P1V05_VCCPLL_DDR3_NODE1")
	)
	(segment
		(start 60.100972 -68.856098)
		(end 60.100972 -68.627498)
		(width 0.381)
		(layer "B.Cu")
		(net "P1V05_VCCPLL_DDR3_NODE1")
	)
	(segment
		(start 60.850526 -68.488306)
		(end 60.240164 -68.488306)
		(width 0.381)
		(layer "B.Cu")
		(net "P1V05_VCCPLL_DDR3_NODE1")
	)
	(segment
		(start 60.240164 -68.488306)
		(end 60.100972 -68.627498)
		(width 0.381)
		(layer "B.Cu")
		(net "P1V05_VCCPLL_DDR3_NODE1")
	)
	(segment
		(start 60.42914 -69.184266)
		(end 60.100972 -68.856098)
		(width 0.381)
		(layer "B.Cu")
		(net "P1V05_VCCPLL_DDR3_NODE1")
	)
	(segment
		(start 45.808392 -64.785748)
		(end 45.700696 -64.893444)
		(width 0.127)
		(layer "F.Cu")
		(net "P2E_CPU_NIC1_NODE1_TX_C_DN")
	)
	(segment
		(start 45.700696 -65.123314)
		(end 46.018704 -65.441322)
		(width 0.127)
		(layer "F.Cu")
		(net "P2E_CPU_NIC1_NODE1_TX_C_DN")
	)
	(segment
		(start 45.700696 -64.893444)
		(end 45.700696 -65.123314)
		(width 0.127)
		(layer "F.Cu")
		(net "P2E_CPU_NIC1_NODE1_TX_C_DN")
	)
	(via
		(at 46.018704 -65.441322)
		(size 0.508)
		(drill 0.254)
		(layers "F.Cu" "B.Cu")
		(net "P2E_CPU_NIC1_NODE1_TX_C_DN")
	)
	(segment
		(start 39.458138 -64.087756)
		(end 40.447722 -65.07734)
		(width 0.127)
		(layer "B.Cu")
		(net "P2E_CPU_NIC1_NODE1_TX_C_DN")
	)
	(segment
		(start 45.775372 -65.44564)
		(end 46.016164 -65.44564)
		(width 0.127)
		(layer "B.Cu")
		(net "P2E_CPU_NIC1_NODE1_TX_C_DN")
	)
	(segment
		(start 41.3385 -65.07734)
		(end 42.459148 -63.956692)
		(width 0.127)
		(layer "B.Cu")
		(net "P2E_CPU_NIC1_NODE1_TX_C_DN")
	)
	(segment
		(start 36.62553 -64.087756)
		(end 39.458138 -64.087756)
		(width 0.127)
		(layer "B.Cu")
		(net "P2E_CPU_NIC1_NODE1_TX_C_DN")
	)
	(segment
		(start 46.016164 -65.44564)
		(end 46.018704 -65.4431)
		(width 0.127)
		(layer "B.Cu")
		(net "P2E_CPU_NIC1_NODE1_TX_C_DN")
	)
	(segment
		(start 40.447722 -65.07734)
		(end 41.3385 -65.07734)
		(width 0.127)
		(layer "B.Cu")
		(net "P2E_CPU_NIC1_NODE1_TX_C_DN")
	)
	(segment
		(start 36.26993 -63.732156)
		(end 36.62553 -64.087756)
		(width 0.127)
		(layer "B.Cu")
		(net "P2E_CPU_NIC1_NODE1_TX_C_DN")
	)
	(segment
		(start 45.52188 -65.192148)
		(end 45.775372 -65.44564)
		(width 0.127)
		(layer "B.Cu")
		(net "P2E_CPU_NIC1_NODE1_TX_C_DN")
	)
	(segment
		(start 42.459148 -63.956692)
		(end 44.736004 -63.956692)
		(width 0.127)
		(layer "B.Cu")
		(net "P2E_CPU_NIC1_NODE1_TX_C_DN")
	)
	(segment
		(start 45.52188 -64.725804)
		(end 45.52188 -65.192148)
		(width 0.127)
		(layer "B.Cu")
		(net "P2E_CPU_NIC1_NODE1_TX_C_DN")
	)
	(segment
		(start 44.736004 -63.956692)
		(end 45.52188 -64.725804)
		(width 0.127)
		(layer "B.Cu")
		(net "P2E_CPU_NIC1_NODE1_TX_C_DN")
	)
	(segment
		(start 46.018704 -65.4431)
		(end 46.018704 -65.441322)
		(width 0.127)
		(layer "B.Cu")
		(net "P2E_CPU_NIC1_NODE1_TX_C_DN")
	)
	(segment
		(start 107.671362 -137.42289)
		(end 107.671362 -139.422378)
		(width 0.1778)
		(layer "F.Cu")
		(net "VR_PVCCP_NODE1_TSEN")
	)
	(segment
		(start 107.65663 -139.947142)
		(end 107.326176 -139.947142)
		(width 0.254)
		(layer "F.Cu")
		(net "VR_PVCCP_NODE1_TSEN")
	)
	(segment
		(start 106.47426 -141.839188)
		(end 106.47426 -141.990318)
		(width 0.254)
		(layer "F.Cu")
		(net "VR_PVCCP_NODE1_TSEN")
	)
	(segment
		(start 107.326176 -139.947142)
		(end 107.075224 -140.198094)
		(width 0.254)
		(layer "F.Cu")
		(net "VR_PVCCP_NODE1_TSEN")
	)
	(segment
		(start 107.075224 -141.238224)
		(end 106.904282 -141.409166)
		(width 0.254)
		(layer "F.Cu")
		(net "VR_PVCCP_NODE1_TSEN")
	)
	(segment
		(start 107.672886 -139.423902)
		(end 107.65663 -139.440158)
		(width 0.254)
		(layer "F.Cu")
		(net "VR_PVCCP_NODE1_TSEN")
	)
	(segment
		(start 107.671362 -139.422378)
		(end 107.672886 -139.423902)
		(width 0.1778)
		(layer "F.Cu")
		(net "VR_PVCCP_NODE1_TSEN")
	)
	(segment
		(start 106.47807 -141.994128)
		(end 106.47426 -141.990318)
		(width 0.254)
		(layer "F.Cu")
		(net "VR_PVCCP_NODE1_TSEN")
	)
	(segment
		(start 107.075224 -140.198094)
		(end 107.075224 -141.238224)
		(width 0.254)
		(layer "F.Cu")
		(net "VR_PVCCP_NODE1_TSEN")
	)
	(segment
		(start 106.904282 -141.409166)
		(end 106.47426 -141.839188)
		(width 0.254)
		(layer "F.Cu")
		(net "VR_PVCCP_NODE1_TSEN")
	)
	(segment
		(start 107.652566 -141.994128)
		(end 106.47807 -141.994128)
		(width 0.254)
		(layer "F.Cu")
		(net "VR_PVCCP_NODE1_TSEN")
	)
	(segment
		(start 107.65663 -139.440158)
		(end 107.65663 -139.947142)
		(width 0.254)
		(layer "F.Cu")
		(net "VR_PVCCP_NODE1_TSEN")
	)
	(via
		(at 106.904282 -141.409166)
		(size 0.508)
		(drill 0.254)
		(layers "F.Cu" "B.Cu")
		(net "VR_PVCCP_NODE1_TSEN")
	)
	(segment
		(start 161.362644 -131.24942)
		(end 161.393632 -131.218432)
		(width 0.1016)
		(layer "F.Cu")
		(net "LED_CPU_NODE1_CPLD_D")
	)
	(segment
		(start 160.567878 -129.85242)
		(end 161.393632 -129.85242)
		(width 0.1016)
		(layer "F.Cu")
		(net "LED_CPU_NODE1_CPLD_D")
	)
	(segment
		(start 161.393632 -131.218432)
		(end 161.393632 -129.85242)
		(width 0.1016)
		(layer "F.Cu")
		(net "LED_CPU_NODE1_CPLD_D")
	)
	(via
		(at 160.567878 -129.85242)
		(size 0.508)
		(drill 0.254)
		(layers "F.Cu" "B.Cu")
		(net "LED_CPU_NODE1_CPLD_D")
	)
	(segment
		(start 46.002702 -135.733282)
		(end 46.85157 -135.733282)
		(width 0.1016)
		(layer "F.Cu")
		(net "BMC_NODE1_DDR_D6")
	)
	(segment
		(start 46.85157 -135.733282)
		(end 46.950122 -135.63473)
		(width 0.1016)
		(layer "F.Cu")
		(net "BMC_NODE1_DDR_D6")
	)
	(segment
		(start 60.541916 -135.259572)
		(end 60.53963 -135.259572)
		(width 0.1016)
		(layer "F.Cu")
		(net "BMC_NODE1_DDR_D6")
	)
	(segment
		(start 60.53963 -135.259572)
		(end 60.141104 -135.658098)
		(width 0.1016)
		(layer "F.Cu")
		(net "BMC_NODE1_DDR_D6")
	)
	(segment
		(start 45.633132 -135.363712)
		(end 46.002702 -135.733282)
		(width 0.1016)
		(layer "F.Cu")
		(net "BMC_NODE1_DDR_D6")
	)
	(via
		(at 46.950122 -135.63473)
		(size 0.508)
		(drill 0.254)
		(layers "F.Cu" "B.Cu")
		(net "BMC_NODE1_DDR_D6")
	)
	(via
		(at 60.141104 -135.658098)
		(size 0.49022)
		(drill 0.254)
		(layers "F.Cu" "B.Cu")
		(net "BMC_NODE1_DDR_D6")
	)
	(segment
		(start 46.950122 -135.087868)
		(end 47.914306 -134.123684)
		(width 0.1143)
		(layer "In7.Cu")
		(net "BMC_NODE1_DDR_D6")
	)
	(segment
		(start 50.819304 -132.62737)
		(end 50.819304 -134.92988)
		(width 0.1143)
		(layer "In7.Cu")
		(net "BMC_NODE1_DDR_D6")
	)
	(segment
		(start 50.029872 -131.837938)
		(end 50.819304 -132.62737)
		(width 0.1143)
		(layer "In7.Cu")
		(net "BMC_NODE1_DDR_D6")
	)
	(segment
		(start 46.950122 -135.63473)
		(end 46.950122 -135.087868)
		(width 0.1143)
		(layer "In7.Cu")
		(net "BMC_NODE1_DDR_D6")
	)
	(segment
		(start 49.07534 -132.277866)
		(end 49.07534 -132.02031)
		(width 0.1143)
		(layer "In7.Cu")
		(net "BMC_NODE1_DDR_D6")
	)
	(segment
		(start 47.914306 -133.41604)
		(end 48.247808 -133.082538)
		(width 0.1143)
		(layer "In7.Cu")
		(net "BMC_NODE1_DDR_D6")
	)
	(segment
		(start 49.257712 -132.460238)
		(end 49.07534 -132.277866)
		(width 0.1143)
		(layer "In7.Cu")
		(net "BMC_NODE1_DDR_D6")
	)
	(segment
		(start 51.639724 -135.7503)
		(end 56.712358 -135.7503)
		(width 0.1143)
		(layer "In7.Cu")
		(net "BMC_NODE1_DDR_D6")
	)
	(segment
		(start 59.70397 -135.220964)
		(end 60.141104 -135.658098)
		(width 0.1143)
		(layer "In7.Cu")
		(net "BMC_NODE1_DDR_D6")
	)
	(segment
		(start 50.819304 -134.92988)
		(end 51.639724 -135.7503)
		(width 0.1143)
		(layer "In7.Cu")
		(net "BMC_NODE1_DDR_D6")
	)
	(segment
		(start 47.914306 -134.123684)
		(end 47.914306 -133.41604)
		(width 0.1143)
		(layer "In7.Cu")
		(net "BMC_NODE1_DDR_D6")
	)
	(segment
		(start 48.247808 -133.082538)
		(end 49.645062 -133.082538)
		(width 0.1143)
		(layer "In7.Cu")
		(net "BMC_NODE1_DDR_D6")
	)
	(segment
		(start 49.257712 -131.837938)
		(end 50.029872 -131.837938)
		(width 0.1143)
		(layer "In7.Cu")
		(net "BMC_NODE1_DDR_D6")
	)
	(segment
		(start 56.712358 -135.7503)
		(end 57.241694 -135.220964)
		(width 0.1143)
		(layer "In7.Cu")
		(net "BMC_NODE1_DDR_D6")
	)
	(segment
		(start 49.567338 -132.460238)
		(end 49.257712 -132.460238)
		(width 0.1143)
		(layer "In7.Cu")
		(net "BMC_NODE1_DDR_D6")
	)
	(segment
		(start 49.817782 -132.710682)
		(end 49.567338 -132.460238)
		(width 0.1143)
		(layer "In7.Cu")
		(net "BMC_NODE1_DDR_D6")
	)
	(segment
		(start 49.645062 -133.082538)
		(end 49.817782 -132.909818)
		(width 0.1143)
		(layer "In7.Cu")
		(net "BMC_NODE1_DDR_D6")
	)
	(segment
		(start 57.241694 -135.220964)
		(end 59.70397 -135.220964)
		(width 0.1143)
		(layer "In7.Cu")
		(net "BMC_NODE1_DDR_D6")
	)
	(segment
		(start 49.07534 -132.02031)
		(end 49.257712 -131.837938)
		(width 0.1143)
		(layer "In7.Cu")
		(net "BMC_NODE1_DDR_D6")
	)
	(segment
		(start 49.817782 -132.909818)
		(end 49.817782 -132.710682)
		(width 0.1143)
		(layer "In7.Cu")
		(net "BMC_NODE1_DDR_D6")
	)
	(segment
		(start 64.520064 -77.932026)
		(end 64.517778 -77.932026)
		(width 0.3048)
		(layer "F.Cu")
		(net "P1V05_VCCPLLCPU1SIO_NODE1")
	)
	(segment
		(start 64.896492 -77.555598)
		(end 64.520064 -77.932026)
		(width 0.3048)
		(layer "F.Cu")
		(net "P1V05_VCCPLLCPU1SIO_NODE1")
	)
	(segment
		(start 64.93002 -77.555598)
		(end 64.896492 -77.555598)
		(width 0.3048)
		(layer "F.Cu")
		(net "P1V05_VCCPLLCPU1SIO_NODE1")
	)
	(via
		(at 85.672422 -80.43164)
		(size 0.508)
		(drill 0.254)
		(layers "F.Cu" "B.Cu")
		(net "P1V05_VCCPLLCPU1SIO_NODE1")
	)
	(via
		(at 64.517778 -77.932026)
		(size 0.508)
		(drill 0.254)
		(layers "F.Cu" "B.Cu")
		(net "P1V05_VCCPLLCPU1SIO_NODE1")
	)
	(segment
		(start 82.88274 -80.287368)
		(end 83.6676 -79.502508)
		(width 0.508)
		(layer "In6.Cu")
		(net "P1V05_VCCPLLCPU1SIO_NODE1")
	)
	(segment
		(start 65.408556 -79.863188)
		(end 74.05243 -79.863188)
		(width 0.508)
		(layer "In6.Cu")
		(net "P1V05_VCCPLLCPU1SIO_NODE1")
	)
	(segment
		(start 74.05243 -79.863188)
		(end 74.47661 -80.287368)
		(width 0.508)
		(layer "In6.Cu")
		(net "P1V05_VCCPLLCPU1SIO_NODE1")
	)
	(segment
		(start 64.517778 -78.97241)
		(end 65.408556 -79.863188)
		(width 0.508)
		(layer "In6.Cu")
		(net "P1V05_VCCPLLCPU1SIO_NODE1")
	)
	(segment
		(start 83.6676 -79.502508)
		(end 85.046312 -79.502508)
		(width 0.508)
		(layer "In6.Cu")
		(net "P1V05_VCCPLLCPU1SIO_NODE1")
	)
	(segment
		(start 85.672422 -80.128618)
		(end 85.672422 -80.43164)
		(width 0.508)
		(layer "In6.Cu")
		(net "P1V05_VCCPLLCPU1SIO_NODE1")
	)
	(segment
		(start 64.517778 -77.932026)
		(end 64.517778 -78.97241)
		(width 0.508)
		(layer "In6.Cu")
		(net "P1V05_VCCPLLCPU1SIO_NODE1")
	)
	(segment
		(start 85.046312 -79.502508)
		(end 85.672422 -80.128618)
		(width 0.508)
		(layer "In6.Cu")
		(net "P1V05_VCCPLLCPU1SIO_NODE1")
	)
	(segment
		(start 74.47661 -80.287368)
		(end 82.88274 -80.287368)
		(width 0.508)
		(layer "In6.Cu")
		(net "P1V05_VCCPLLCPU1SIO_NODE1")
	)
	(segment
		(start 44.64939 -65.455038)
		(end 44.642024 -65.447672)
		(width 0.127)
		(layer "F.Cu")
		(net "P2E_CPU_NIC1_NODE1_TX_C_DP")
	)
	(segment
		(start 45.418248 -65.455038)
		(end 44.64939 -65.455038)
		(width 0.127)
		(layer "F.Cu")
		(net "P2E_CPU_NIC1_NODE1_TX_C_DP")
	)
	(via
		(at 44.642024 -65.447672)
		(size 0.508)
		(drill 0.254)
		(layers "F.Cu" "B.Cu")
		(net "P2E_CPU_NIC1_NODE1_TX_C_DP")
	)
	(segment
		(start 38.495986 -64.522096)
		(end 38.625526 -64.392556)
		(width 0.127)
		(layer "B.Cu")
		(net "P2E_CPU_NIC1_NODE1_TX_C_DP")
	)
	(segment
		(start 44.611544 -64.261492)
		(end 45.21708 -64.854074)
		(width 0.127)
		(layer "B.Cu")
		(net "P2E_CPU_NIC1_NODE1_TX_C_DP")
	)
	(segment
		(start 38.114986 -64.522096)
		(end 38.495986 -64.522096)
		(width 0.127)
		(layer "B.Cu")
		(net "P2E_CPU_NIC1_NODE1_TX_C_DP")
	)
	(segment
		(start 39.331646 -64.392556)
		(end 40.32123 -65.38214)
		(width 0.127)
		(layer "B.Cu")
		(net "P2E_CPU_NIC1_NODE1_TX_C_DP")
	)
	(segment
		(start 36.62553 -64.392556)
		(end 36.964366 -64.392556)
		(width 0.127)
		(layer "B.Cu")
		(net "P2E_CPU_NIC1_NODE1_TX_C_DP")
	)
	(segment
		(start 36.26993 -64.748156)
		(end 36.62553 -64.392556)
		(width 0.127)
		(layer "B.Cu")
		(net "P2E_CPU_NIC1_NODE1_TX_C_DP")
	)
	(segment
		(start 42.58564 -64.261492)
		(end 43.19016 -64.261492)
		(width 0.127)
		(layer "B.Cu")
		(net "P2E_CPU_NIC1_NODE1_TX_C_DP")
	)
	(segment
		(start 40.32123 -65.38214)
		(end 41.464992 -65.38214)
		(width 0.127)
		(layer "B.Cu")
		(net "P2E_CPU_NIC1_NODE1_TX_C_DP")
	)
	(segment
		(start 43.33748 -64.408812)
		(end 43.71848 -64.408812)
		(width 0.127)
		(layer "B.Cu")
		(net "P2E_CPU_NIC1_NODE1_TX_C_DP")
	)
	(segment
		(start 45.21708 -64.854074)
		(end 45.21708 -65.289684)
		(width 0.127)
		(layer "B.Cu")
		(net "P2E_CPU_NIC1_NODE1_TX_C_DP")
	)
	(segment
		(start 37.604446 -64.392556)
		(end 37.985446 -64.392556)
		(width 0.127)
		(layer "B.Cu")
		(net "P2E_CPU_NIC1_NODE1_TX_C_DP")
	)
	(segment
		(start 37.474906 -64.522096)
		(end 37.604446 -64.392556)
		(width 0.127)
		(layer "B.Cu")
		(net "P2E_CPU_NIC1_NODE1_TX_C_DP")
	)
	(segment
		(start 44.642024 -65.45199)
		(end 44.642024 -65.447672)
		(width 0.127)
		(layer "B.Cu")
		(net "P2E_CPU_NIC1_NODE1_TX_C_DP")
	)
	(segment
		(start 43.19016 -64.261492)
		(end 43.33748 -64.408812)
		(width 0.127)
		(layer "B.Cu")
		(net "P2E_CPU_NIC1_NODE1_TX_C_DP")
	)
	(segment
		(start 45.054774 -65.45199)
		(end 44.642024 -65.45199)
		(width 0.127)
		(layer "B.Cu")
		(net "P2E_CPU_NIC1_NODE1_TX_C_DP")
	)
	(segment
		(start 43.71848 -64.408812)
		(end 43.8658 -64.261492)
		(width 0.127)
		(layer "B.Cu")
		(net "P2E_CPU_NIC1_NODE1_TX_C_DP")
	)
	(segment
		(start 43.8658 -64.261492)
		(end 44.611544 -64.261492)
		(width 0.127)
		(layer "B.Cu")
		(net "P2E_CPU_NIC1_NODE1_TX_C_DP")
	)
	(segment
		(start 37.985446 -64.392556)
		(end 38.114986 -64.522096)
		(width 0.127)
		(layer "B.Cu")
		(net "P2E_CPU_NIC1_NODE1_TX_C_DP")
	)
	(segment
		(start 38.625526 -64.392556)
		(end 39.331646 -64.392556)
		(width 0.127)
		(layer "B.Cu")
		(net "P2E_CPU_NIC1_NODE1_TX_C_DP")
	)
	(segment
		(start 36.964366 -64.392556)
		(end 37.093906 -64.522096)
		(width 0.127)
		(layer "B.Cu")
		(net "P2E_CPU_NIC1_NODE1_TX_C_DP")
	)
	(segment
		(start 41.464992 -65.38214)
		(end 42.58564 -64.261492)
		(width 0.127)
		(layer "B.Cu")
		(net "P2E_CPU_NIC1_NODE1_TX_C_DP")
	)
	(segment
		(start 37.093906 -64.522096)
		(end 37.474906 -64.522096)
		(width 0.127)
		(layer "B.Cu")
		(net "P2E_CPU_NIC1_NODE1_TX_C_DP")
	)
	(segment
		(start 45.21708 -65.289684)
		(end 45.054774 -65.45199)
		(width 0.127)
		(layer "B.Cu")
		(net "P2E_CPU_NIC1_NODE1_TX_C_DP")
	)
	(segment
		(start 42.248836 -131.365244)
		(end 42.351452 -131.057142)
		(width 0.1016)
		(layer "F.Cu")
		(net "BMC_NODE1_DDR_BA0")
	)
	(segment
		(start 59.741816 -132.859526)
		(end 59.741816 -132.859018)
		(width 0.1016)
		(layer "F.Cu")
		(net "BMC_NODE1_DDR_BA0")
	)
	(segment
		(start 41.751504 -131.760976)
		(end 42.248836 -131.365244)
		(width 0.1016)
		(layer "F.Cu")
		(net "BMC_NODE1_DDR_BA0")
	)
	(segment
		(start 40.83304 -132.163566)
		(end 41.225216 -131.931918)
		(width 0.1016)
		(layer "F.Cu")
		(net "BMC_NODE1_DDR_BA0")
	)
	(segment
		(start 41.520618 -131.794504)
		(end 41.751504 -131.760976)
		(width 0.1016)
		(layer "F.Cu")
		(net "BMC_NODE1_DDR_BA0")
	)
	(segment
		(start 41.225216 -131.931918)
		(end 41.520618 -131.794504)
		(width 0.1016)
		(layer "F.Cu")
		(net "BMC_NODE1_DDR_BA0")
	)
	(segment
		(start 42.351452 -131.057142)
		(end 42.720006 -130.640074)
		(width 0.1016)
		(layer "F.Cu")
		(net "BMC_NODE1_DDR_BA0")
	)
	(segment
		(start 59.741816 -132.859018)
		(end 59.341004 -132.458206)
		(width 0.1016)
		(layer "F.Cu")
		(net "BMC_NODE1_DDR_BA0")
	)
	(via
		(at 59.341004 -132.458206)
		(size 0.49022)
		(drill 0.254)
		(layers "F.Cu" "B.Cu")
		(net "BMC_NODE1_DDR_BA0")
	)
	(via
		(at 42.720006 -130.640074)
		(size 0.508)
		(drill 0.254)
		(layers "F.Cu" "B.Cu")
		(net "BMC_NODE1_DDR_BA0")
	)
	(segment
		(start 46.011084 -132.449824)
		(end 46.631352 -132.3848)
		(width 0.1143)
		(layer "In2.Cu")
		(net "BMC_NODE1_DDR_BA0")
	)
	(segment
		(start 57.138316 -133.187694)
		(end 58.053478 -132.85724)
		(width 0.1016)
		(layer "In2.Cu")
		(net "BMC_NODE1_DDR_BA0")
	)
	(segment
		(start 42.720006 -130.640074)
		(end 42.654982 -131.511294)
		(width 0.1143)
		(layer "In2.Cu")
		(net "BMC_NODE1_DDR_BA0")
	)
	(segment
		(start 52.695856 -132.3848)
		(end 52.88026 -132.569204)
		(width 0.1143)
		(layer "In2.Cu")
		(net "BMC_NODE1_DDR_BA0")
	)
	(segment
		(start 42.932604 -132.449824)
		(end 46.011084 -132.449824)
		(width 0.1143)
		(layer "In2.Cu")
		(net "BMC_NODE1_DDR_BA0")
	)
	(segment
		(start 56.958992 -133.367018)
		(end 57.138316 -133.187694)
		(width 0.1016)
		(layer "In2.Cu")
		(net "BMC_NODE1_DDR_BA0")
	)
	(segment
		(start 52.88026 -132.569204)
		(end 53.53304 -132.804662)
		(width 0.1143)
		(layer "In2.Cu")
		(net "BMC_NODE1_DDR_BA0")
	)
	(segment
		(start 58.794904 -132.766562)
		(end 59.341004 -132.458206)
		(width 0.1016)
		(layer "In2.Cu")
		(net "BMC_NODE1_DDR_BA0")
	)
	(segment
		(start 46.631352 -132.3848)
		(end 52.695856 -132.3848)
		(width 0.1143)
		(layer "In2.Cu")
		(net "BMC_NODE1_DDR_BA0")
	)
	(segment
		(start 53.53304 -132.804662)
		(end 55.855616 -132.804662)
		(width 0.1143)
		(layer "In2.Cu")
		(net "BMC_NODE1_DDR_BA0")
	)
	(segment
		(start 42.654982 -132.172202)
		(end 42.932604 -132.449824)
		(width 0.1143)
		(layer "In2.Cu")
		(net "BMC_NODE1_DDR_BA0")
	)
	(segment
		(start 56.417972 -133.367018)
		(end 56.958992 -133.367018)
		(width 0.1016)
		(layer "In2.Cu")
		(net "BMC_NODE1_DDR_BA0")
	)
	(segment
		(start 58.634376 -132.85724)
		(end 58.74385 -132.800852)
		(width 0.1016)
		(layer "In2.Cu")
		(net "BMC_NODE1_DDR_BA0")
	)
	(segment
		(start 58.74385 -132.800852)
		(end 58.794904 -132.766562)
		(width 0.1016)
		(layer "In2.Cu")
		(net "BMC_NODE1_DDR_BA0")
	)
	(segment
		(start 55.855616 -132.804662)
		(end 56.417972 -133.367018)
		(width 0.1016)
		(layer "In2.Cu")
		(net "BMC_NODE1_DDR_BA0")
	)
	(segment
		(start 42.654982 -131.511294)
		(end 42.654982 -132.172202)
		(width 0.1143)
		(layer "In2.Cu")
		(net "BMC_NODE1_DDR_BA0")
	)
	(segment
		(start 58.053478 -132.85724)
		(end 58.634376 -132.85724)
		(width 0.1016)
		(layer "In2.Cu")
		(net "BMC_NODE1_DDR_BA0")
	)
	(segment
		(start 176.01057 -123.365768)
		(end 176.010316 -123.365768)
		(width 0.1016)
		(layer "F.Cu")
		(net "FM_CPU_NODE1_XDP_PG_RST")
	)
	(segment
		(start 176.010316 -123.365768)
		(end 175.510444 -123.86564)
		(width 0.1016)
		(layer "F.Cu")
		(net "FM_CPU_NODE1_XDP_PG_RST")
	)
	(via
		(at 114.75466 -76.232766)
		(size 0.508)
		(drill 0.254)
		(layers "F.Cu" "B.Cu")
		(net "FM_CPU_NODE1_XDP_PG_RST")
	)
	(via
		(at 175.510444 -123.86564)
		(size 0.49022)
		(drill 0.254)
		(layers "F.Cu" "B.Cu")
		(net "FM_CPU_NODE1_XDP_PG_RST")
	)
	(segment
		(start 101.815392 -64.332104)
		(end 100.888292 -65.259204)
		(width 0.1016)
		(layer "B.Cu")
		(net "FM_CPU_NODE1_XDP_PG_RST")
	)
	(segment
		(start 103.516684 -64.132206)
		(end 103.176832 -63.792354)
		(width 0.1016)
		(layer "B.Cu")
		(net "FM_CPU_NODE1_XDP_PG_RST")
	)
	(segment
		(start 101.815392 -64.104774)
		(end 101.815392 -64.332104)
		(width 0.1016)
		(layer "B.Cu")
		(net "FM_CPU_NODE1_XDP_PG_RST")
	)
	(segment
		(start 108.023152 -70.287134)
		(end 110.663482 -72.927464)
		(width 0.1016)
		(layer "B.Cu")
		(net "FM_CPU_NODE1_XDP_PG_RST")
	)
	(segment
		(start 102.836472 -70.287134)
		(end 108.023152 -70.287134)
		(width 0.1016)
		(layer "B.Cu")
		(net "FM_CPU_NODE1_XDP_PG_RST")
	)
	(segment
		(start 104.008174 -64.132206)
		(end 103.516684 -64.132206)
		(width 0.1016)
		(layer "B.Cu")
		(net "FM_CPU_NODE1_XDP_PG_RST")
	)
	(segment
		(start 110.663482 -72.927464)
		(end 111.216186 -72.927464)
		(width 0.1016)
		(layer "B.Cu")
		(net "FM_CPU_NODE1_XDP_PG_RST")
	)
	(segment
		(start 100.888292 -65.259204)
		(end 100.888292 -68.338954)
		(width 0.1016)
		(layer "B.Cu")
		(net "FM_CPU_NODE1_XDP_PG_RST")
	)
	(segment
		(start 102.127812 -63.792354)
		(end 101.815392 -64.104774)
		(width 0.1016)
		(layer "B.Cu")
		(net "FM_CPU_NODE1_XDP_PG_RST")
	)
	(segment
		(start 111.216186 -72.927464)
		(end 114.521488 -76.232766)
		(width 0.1016)
		(layer "B.Cu")
		(net "FM_CPU_NODE1_XDP_PG_RST")
	)
	(segment
		(start 114.521488 -76.232766)
		(end 114.75466 -76.232766)
		(width 0.1016)
		(layer "B.Cu")
		(net "FM_CPU_NODE1_XDP_PG_RST")
	)
	(segment
		(start 100.888292 -68.338954)
		(end 102.836472 -70.287134)
		(width 0.1016)
		(layer "B.Cu")
		(net "FM_CPU_NODE1_XDP_PG_RST")
	)
	(segment
		(start 103.176832 -63.792354)
		(end 102.127812 -63.792354)
		(width 0.1016)
		(layer "B.Cu")
		(net "FM_CPU_NODE1_XDP_PG_RST")
	)
	(segment
		(start 162.5981 -122.517916)
		(end 164.758878 -122.517916)
		(width 0.1143)
		(layer "In7.Cu")
		(net "FM_CPU_NODE1_XDP_PG_RST")
	)
	(segment
		(start 166.057834 -122.22607)
		(end 167.752522 -123.920758)
		(width 0.1143)
		(layer "In7.Cu")
		(net "FM_CPU_NODE1_XDP_PG_RST")
	)
	(segment
		(start 129.961386 -97.95002)
		(end 141.253464 -97.95002)
		(width 0.1143)
		(layer "In7.Cu")
		(net "FM_CPU_NODE1_XDP_PG_RST")
	)
	(segment
		(start 155.8544 -118.261384)
		(end 160.089342 -122.496326)
		(width 0.1143)
		(layer "In7.Cu")
		(net "FM_CPU_NODE1_XDP_PG_RST")
	)
	(segment
		(start 167.752522 -123.920758)
		(end 168.115742 -123.920758)
		(width 0.1143)
		(layer "In7.Cu")
		(net "FM_CPU_NODE1_XDP_PG_RST")
	)
	(segment
		(start 141.253464 -97.95002)
		(end 155.8544 -112.550956)
		(width 0.1143)
		(layer "In7.Cu")
		(net "FM_CPU_NODE1_XDP_PG_RST")
	)
	(segment
		(start 114.75466 -76.232766)
		(end 114.75466 -82.743294)
		(width 0.1143)
		(layer "In7.Cu")
		(net "FM_CPU_NODE1_XDP_PG_RST")
	)
	(segment
		(start 175.081184 -123.43638)
		(end 175.510444 -123.86564)
		(width 0.1143)
		(layer "In7.Cu")
		(net "FM_CPU_NODE1_XDP_PG_RST")
	)
	(segment
		(start 168.115742 -123.920758)
		(end 168.60012 -123.43638)
		(width 0.1143)
		(layer "In7.Cu")
		(net "FM_CPU_NODE1_XDP_PG_RST")
	)
	(segment
		(start 165.050724 -122.22607)
		(end 166.057834 -122.22607)
		(width 0.1143)
		(layer "In7.Cu")
		(net "FM_CPU_NODE1_XDP_PG_RST")
	)
	(segment
		(start 162.57651 -122.496326)
		(end 162.5981 -122.517916)
		(width 0.1143)
		(layer "In7.Cu")
		(net "FM_CPU_NODE1_XDP_PG_RST")
	)
	(segment
		(start 114.75466 -82.743294)
		(end 129.961386 -97.95002)
		(width 0.1143)
		(layer "In7.Cu")
		(net "FM_CPU_NODE1_XDP_PG_RST")
	)
	(segment
		(start 160.089342 -122.496326)
		(end 162.57651 -122.496326)
		(width 0.1143)
		(layer "In7.Cu")
		(net "FM_CPU_NODE1_XDP_PG_RST")
	)
	(segment
		(start 168.60012 -123.43638)
		(end 175.081184 -123.43638)
		(width 0.1143)
		(layer "In7.Cu")
		(net "FM_CPU_NODE1_XDP_PG_RST")
	)
	(segment
		(start 155.8544 -112.550956)
		(end 155.8544 -118.261384)
		(width 0.1143)
		(layer "In7.Cu")
		(net "FM_CPU_NODE1_XDP_PG_RST")
	)
	(segment
		(start 164.758878 -122.517916)
		(end 165.050724 -122.22607)
		(width 0.1143)
		(layer "In7.Cu")
		(net "FM_CPU_NODE1_XDP_PG_RST")
	)
	(segment
		(start 52.799996 -77.399642)
		(end 52.399946 -77.799692)
		(width 0.254)
		(layer "F.Cu")
		(net "P1V8_VCCASFRHPLL_NODE1")
	)
	(via
		(at 52.399946 -77.799692)
		(size 0.508)
		(drill 0.254)
		(layers "F.Cu" "B.Cu")
		(net "P1V8_VCCASFRHPLL_NODE1")
	)
	(via
		(at 37.85108 -77.088492)
		(size 0.508)
		(drill 0.254)
		(layers "F.Cu" "B.Cu")
		(net "P1V8_VCCASFRHPLL_NODE1")
	)
	(via
		(at 39.263574 -78.426818)
		(size 0.508)
		(drill 0.254)
		(layers "F.Cu" "B.Cu")
		(net "P1V8_VCCASFRHPLL_NODE1")
	)
	(segment
		(start 52.399946 -77.799692)
		(end 50.643536 -77.799692)
		(width 0.508)
		(layer "In6.Cu")
		(net "P1V8_VCCASFRHPLL_NODE1")
	)
	(segment
		(start 50.47869 -77.634846)
		(end 43.183556 -77.634846)
		(width 0.508)
		(layer "In6.Cu")
		(net "P1V8_VCCASFRHPLL_NODE1")
	)
	(segment
		(start 39.83355 -77.856842)
		(end 39.263574 -78.426818)
		(width 0.508)
		(layer "In6.Cu")
		(net "P1V8_VCCASFRHPLL_NODE1")
	)
	(segment
		(start 43.183556 -77.634846)
		(end 42.96156 -77.856842)
		(width 0.508)
		(layer "In6.Cu")
		(net "P1V8_VCCASFRHPLL_NODE1")
	)
	(segment
		(start 42.96156 -77.856842)
		(end 39.83355 -77.856842)
		(width 0.508)
		(layer "In6.Cu")
		(net "P1V8_VCCASFRHPLL_NODE1")
	)
	(segment
		(start 50.643536 -77.799692)
		(end 50.47869 -77.634846)
		(width 0.508)
		(layer "In6.Cu")
		(net "P1V8_VCCASFRHPLL_NODE1")
	)
	(segment
		(start 46.180248 -68.117974)
		(end 46.59376 -68.531486)
		(width 0.127)
		(layer "F.Cu")
		(net "TP_CPU_NODE1_RP0_PETN5")
	)
	(segment
		(start 46.180248 -68.084446)
		(end 46.180248 -68.117974)
		(width 0.127)
		(layer "F.Cu")
		(net "TP_CPU_NODE1_RP0_PETN5")
	)
	(segment
		(start 46.59376 -68.531486)
		(end 46.59376 -68.533264)
		(width 0.127)
		(layer "F.Cu")
		(net "TP_CPU_NODE1_RP0_PETN5")
	)
	(via
		(at 46.59376 -68.533264)
		(size 0.508)
		(drill 0.254)
		(layers "F.Cu" "B.Cu")
		(net "TP_CPU_NODE1_RP0_PETN5")
	)
	(segment
		(start 53.592222 -78.191868)
		(end 53.600096 -78.199742)
		(width 0.3048)
		(layer "F.Cu")
		(net "P1V05_NODE1")
	)
	(segment
		(start 60.400946 -72.999092)
		(end 60.000896 -72.599042)
		(width 0.254)
		(layer "F.Cu")
		(net "P1V05_NODE1")
	)
	(segment
		(start 60.409328 -71.407274)
		(end 60.000896 -70.998842)
		(width 0.3048)
		(layer "F.Cu")
		(net "P1V05_NODE1")
	)
	(segment
		(start 50.371248 -77.315822)
		(end 50.371248 -78.015846)
		(width 0.3048)
		(layer "F.Cu")
		(net "P1V05_NODE1")
	)
	(segment
		(start 57.200546 -79.399892)
		(end 56.800496 -78.999842)
		(width 0.3556)
		(layer "F.Cu")
		(net "P1V05_NODE1")
	)
	(segment
		(start 51.811682 -69.646038)
		(end 51.811682 -70.010528)
		(width 0.3048)
		(layer "F.Cu")
		(net "P1V05_NODE1")
	)
	(segment
		(start 169.643298 -104.839008)
		(end 169.643298 -105.720134)
		(width 0.1778)
		(layer "F.Cu")
		(net "P1V05_NODE1")
	)
	(segment
		(start 170.765724 -134.040372)
		(end 169.831258 -134.040372)
		(width 0.508)
		(layer "F.Cu")
		(net "P1V05_NODE1")
	)
	(segment
		(start 52.68087 -78.318868)
		(end 52.799996 -78.199742)
		(width 0.3048)
		(layer "F.Cu")
		(net "P1V05_NODE1")
	)
	(segment
		(start 58.400696 -78.199742)
		(end 58.400696 -78.14056)
		(width 0.3048)
		(layer "F.Cu")
		(net "P1V05_NODE1")
	)
	(segment
		(start 52.799996 -78.191868)
		(end 53.592222 -78.191868)
		(width 0.3048)
		(layer "F.Cu")
		(net "P1V05_NODE1")
	)
	(segment
		(start 61.601096 -74.999342)
		(end 62.001146 -75.399392)
		(width 0.3048)
		(layer "F.Cu")
		(net "P1V05_NODE1")
	)
	(segment
		(start 53.200046 -72.999092)
		(end 52.799996 -72.599042)
		(width 0.3048)
		(layer "F.Cu")
		(net "P1V05_NODE1")
	)
	(segment
		(start 64.74968 -71.021702)
		(end 64.74968 -71.357744)
		(width 0.254)
		(layer "F.Cu")
		(net "P1V05_NODE1")
	)
	(segment
		(start 64.74968 -71.357744)
		(end 64.575436 -71.531988)
		(width 0.254)
		(layer "F.Cu")
		(net "P1V05_NODE1")
	)
	(segment
		(start 50.371248 -78.015846)
		(end 50.363628 -78.015846)
		(width 0.3048)
		(layer "F.Cu")
		(net "P1V05_NODE1")
	)
	(segment
		(start 15.66672 -112.127284)
		(end 15.26286 -112.531144)
		(width 0.254)
		(layer "F.Cu")
		(net "P1V05_NODE1")
	)
	(segment
		(start 58.800746 -75.399392)
		(end 58.400696 -74.999342)
		(width 0.254)
		(layer "F.Cu")
		(net "P1V05_NODE1")
	)
	(segment
		(start 57.600596 -79.799942)
		(end 57.200546 -79.399892)
		(width 0.3556)
		(layer "F.Cu")
		(net "P1V05_NODE1")
	)
	(segment
		(start 52.799996 -78.199742)
		(end 52.799996 -78.191868)
		(width 0.3048)
		(layer "F.Cu")
		(net "P1V05_NODE1")
	)
	(segment
		(start 58.400696 -71.798942)
		(end 58.800746 -72.198992)
		(width 0.3556)
		(layer "F.Cu")
		(net "P1V05_NODE1")
	)
	(segment
		(start 51.599846 -72.999092)
		(end 51.999896 -72.599042)
		(width 0.3048)
		(layer "F.Cu")
		(net "P1V05_NODE1")
	)
	(segment
		(start 61.601096 -73.399142)
		(end 61.201046 -72.999092)
		(width 0.3048)
		(layer "F.Cu")
		(net "P1V05_NODE1")
	)
	(segment
		(start 51.071272 -78.015846)
		(end 51.816 -78.015846)
		(width 0.3048)
		(layer "F.Cu")
		(net "P1V05_NODE1")
	)
	(segment
		(start 103.081074 -140.485114)
		(end 102.762812 -140.166852)
		(width 0.4572)
		(layer "F.Cu")
		(net "P1V05_NODE1")
	)
	(segment
		(start 50.363628 -78.015846)
		(end 49.990248 -78.389226)
		(width 0.3048)
		(layer "F.Cu")
		(net "P1V05_NODE1")
	)
	(segment
		(start 15.26286 -112.531144)
		(end 15.26286 -115.278662)
		(width 0.254)
		(layer "F.Cu")
		(net "P1V05_NODE1")
	)
	(segment
		(start 166.043356 -105.595674)
		(end 166.026846 -106.065828)
		(width 0.1778)
		(layer "F.Cu")
		(net "P1V05_NODE1")
	)
	(segment
		(start 60.40247 -74.597768)
		(end 60.800996 -74.199242)
		(width 0.3048)
		(layer "F.Cu")
		(net "P1V05_NODE1")
	)
	(segment
		(start 61.601096 -78.999842)
		(end 62.401196 -79.799942)
		(width 0.3048)
		(layer "F.Cu")
		(net "P1V05_NODE1")
	)
	(segment
		(start 171.14647 -98.535744)
		(end 172.014134 -98.535744)
		(width 0.1778)
		(layer "F.Cu")
		(net "P1V05_NODE1")
	)
	(segment
		(start 11.301222 -131.590288)
		(end 12.23645 -131.590288)
		(width 0.254)
		(layer "F.Cu")
		(net "P1V05_NODE1")
	)
	(segment
		(start 56.400446 -76.199492)
		(end 56.800496 -76.599542)
		(width 0.254)
		(layer "F.Cu")
		(net "P1V05_NODE1")
	)
	(segment
		(start 49.990248 -78.389226)
		(end 50.102516 -78.389226)
		(width 0.3048)
		(layer "F.Cu")
		(net "P1V05_NODE1")
	)
	(segment
		(start 55.600346 -71.398892)
		(end 56.000396 -70.998842)
		(width 0.254)
		(layer "F.Cu")
		(net "P1V05_NODE1")
	)
	(segment
		(start 54.970172 -70.768718)
		(end 55.200296 -70.998842)
		(width 0.254)
		(layer "F.Cu")
		(net "P1V05_NODE1")
	)
	(segment
		(start 172.348652 -100.93579)
		(end 172.501052 -101.08819)
		(width 0.1778)
		(layer "F.Cu")
		(net "P1V05_NODE1")
	)
	(segment
		(start 62.001146 -72.999092)
		(end 61.601096 -72.599042)
		(width 0.3048)
		(layer "F.Cu")
		(net "P1V05_NODE1")
	)
	(segment
		(start 54.400196 -72.599042)
		(end 54.000146 -72.999092)
		(width 0.3556)
		(layer "F.Cu")
		(net "P1V05_NODE1")
	)
	(segment
		(start 54.400196 -70.998842)
		(end 54.400196 -70.96506)
		(width 0.254)
		(layer "F.Cu")
		(net "P1V05_NODE1")
	)
	(segment
		(start 64.72682 -70.998842)
		(end 64.74968 -71.021702)
		(width 0.254)
		(layer "F.Cu")
		(net "P1V05_NODE1")
	)
	(segment
		(start 51.816 -78.015846)
		(end 51.999896 -78.199742)
		(width 0.3048)
		(layer "F.Cu")
		(net "P1V05_NODE1")
	)
	(segment
		(start 57.200546 -77.799692)
		(end 56.800496 -78.199742)
		(width 0.3048)
		(layer "F.Cu")
		(net "P1V05_NODE1")
	)
	(segment
		(start 51.811682 -70.010528)
		(end 52.099972 -70.298818)
		(width 0.3048)
		(layer "F.Cu")
		(net "P1V05_NODE1")
	)
	(segment
		(start 52.399946 -72.999092)
		(end 52.799996 -72.599042)
		(width 0.254)
		(layer "F.Cu")
		(net "P1V05_NODE1")
	)
	(segment
		(start 57.600596 -72.599042)
		(end 57.200546 -72.198992)
		(width 0.3556)
		(layer "F.Cu")
		(net "P1V05_NODE1")
	)
	(segment
		(start 60.000896 -73.399142)
		(end 60.400946 -72.999092)
		(width 0.254)
		(layer "F.Cu")
		(net "P1V05_NODE1")
	)
	(segment
		(start 59.200796 -74.199242)
		(end 59.17946 -74.199242)
		(width 0.3048)
		(layer "F.Cu")
		(net "P1V05_NODE1")
	)
	(segment
		(start 178.600354 -136.278112)
		(end 178.097434 -136.781032)
		(width 0.508)
		(layer "F.Cu")
		(net "P1V05_NODE1")
	)
	(segment
		(start 54.596538 -70.768718)
		(end 54.970172 -70.768718)
		(width 0.254)
		(layer "F.Cu")
		(net "P1V05_NODE1")
	)
	(segment
		(start 53.834538 -70.768718)
		(end 54.170072 -70.768718)
		(width 0.254)
		(layer "F.Cu")
		(net "P1V05_NODE1")
	)
	(segment
		(start 51.999896 -74.199242)
		(end 51.928014 -74.199242)
		(width 0.254)
		(layer "F.Cu")
		(net "P1V05_NODE1")
	)
	(segment
		(start 169.643298 -105.720134)
		(end 169.869866 -105.946702)
		(width 0.1778)
		(layer "F.Cu")
		(net "P1V05_NODE1")
	)
	(segment
		(start 103.081074 -140.818108)
		(end 103.081074 -140.485114)
		(width 0.4572)
		(layer "F.Cu")
		(net "P1V05_NODE1")
	)
	(segment
		(start 162.14471 -99.735894)
		(end 161.985452 -99.576636)
		(width 0.1778)
		(layer "F.Cu")
		(net "P1V05_NODE1")
	)
	(segment
		(start 178.097434 -136.781032)
		(end 178.09718 -136.781032)
		(width 0.508)
		(layer "F.Cu")
		(net "P1V05_NODE1")
	)
	(segment
		(start 56.000396 -74.199242)
		(end 55.200296 -74.199242)
		(width 0.3048)
		(layer "F.Cu")
		(net "P1V05_NODE1")
	)
	(segment
		(start 56.000396 -74.199242)
		(end 56.800496 -74.999342)
		(width 0.254)
		(layer "F.Cu")
		(net "P1V05_NODE1")
	)
	(segment
		(start 60.800996 -70.998842)
		(end 60.800996 -71.023988)
		(width 0.3048)
		(layer "F.Cu")
		(net "P1V05_NODE1")
	)
	(segment
		(start 54.57317 -72.426068)
		(end 54.400196 -72.599042)
		(width 0.3556)
		(layer "F.Cu")
		(net "P1V05_NODE1")
	)
	(segment
		(start 58.400696 -78.999842)
		(end 58.800746 -79.399892)
		(width 0.3556)
		(layer "F.Cu")
		(net "P1V05_NODE1")
	)
	(segment
		(start 15.22476 -115.320572)
		(end 14.48562 -116.059712)
		(width 0.254)
		(layer "F.Cu")
		(net "P1V05_NODE1")
	)
	(segment
		(start 52.799996 -69.934328)
		(end 52.711096 -69.845174)
		(width 0.3048)
		(layer "F.Cu")
		(net "P1V05_NODE1")
	)
	(segment
		(start 54.400196 -78.199742)
		(end 54.400196 -78.198726)
		(width 0.3048)
		(layer "F.Cu")
		(net "P1V05_NODE1")
	)
	(segment
		(start 92.716604 -83.724242)
		(end 92.716604 -84.449412)
		(width 0.4572)
		(layer "F.Cu")
		(net "P1V05_NODE1")
	)
	(segment
		(start 171.14647 -100.93579)
		(end 172.348652 -100.93579)
		(width 0.1778)
		(layer "F.Cu")
		(net "P1V05_NODE1")
	)
	(segment
		(start 55.200296 -77.399642)
		(end 55.600346 -77.799692)
		(width 0.3556)
		(layer "F.Cu")
		(net "P1V05_NODE1")
	)
	(segment
		(start 56.000396 -72.599042)
		(end 56.400446 -72.999092)
		(width 0.3556)
		(layer "F.Cu")
		(net "P1V05_NODE1")
	)
	(segment
		(start 100.496624 -130.253232)
		(end 100.50526 -130.244596)
		(width 0.508)
		(layer "F.Cu")
		(net "P1V05_NODE1")
	)
	(segment
		(start 60.400946 -79.399892)
		(end 60.800996 -79.799942)
		(width 0.3048)
		(layer "F.Cu")
		(net "P1V05_NODE1")
	)
	(segment
		(start 54.800246 -73.799192)
		(end 55.200296 -74.199242)
		(width 0.254)
		(layer "F.Cu")
		(net "P1V05_NODE1")
	)
	(segment
		(start 169.869866 -105.946702)
		(end 169.869866 -105.95229)
		(width 0.1778)
		(layer "F.Cu")
		(net "P1V05_NODE1")
	)
	(segment
		(start 62.401196 -72.599042)
		(end 63.201296 -72.599042)
		(width 0.254)
		(layer "F.Cu")
		(net "P1V05_NODE1")
	)
	(segment
		(start 163.340034 -100.93579)
		(end 161.98596 -100.93579)
		(width 0.1778)
		(layer "F.Cu")
		(net "P1V05_NODE1")
	)
	(segment
		(start 51.352704 -74.324718)
		(end 51.071272 -74.043286)
		(width 0.254)
		(layer "F.Cu")
		(net "P1V05_NODE1")
	)
	(segment
		(start 55.200296 -72.599042)
		(end 55.027322 -72.426068)
		(width 0.3556)
		(layer "F.Cu")
		(net "P1V05_NODE1")
	)
	(segment
		(start 65.630044 -74.283062)
		(end 64.93002 -74.283062)
		(width 0.3048)
		(layer "F.Cu")
		(net "P1V05_NODE1")
	)
	(segment
		(start 56.800496 -78.199742)
		(end 56.400446 -77.799692)
		(width 0.254)
		(layer "F.Cu")
		(net "P1V05_NODE1")
	)
	(segment
		(start 161.98596 -100.93579)
		(end 161.953956 -100.903786)
		(width 0.1778)
		(layer "F.Cu")
		(net "P1V05_NODE1")
	)
	(segment
		(start 57.600596 -74.199242)
		(end 57.585102 -74.199242)
		(width 0.3048)
		(layer "F.Cu")
		(net "P1V05_NODE1")
	)
	(segment
		(start 11.375644 -116.059712)
		(end 9.513824 -117.921532)
		(width 0.254)
		(layer "F.Cu")
		(net "P1V05_NODE1")
	)
	(segment
		(start 58.400696 -78.14056)
		(end 58.660538 -77.880718)
		(width 0.3048)
		(layer "F.Cu")
		(net "P1V05_NODE1")
	)
	(segment
		(start 64.04229 -70.998842)
		(end 64.575436 -71.531988)
		(width 0.254)
		(layer "F.Cu")
		(net "P1V05_NODE1")
	)
	(segment
		(start 64.001396 -72.599042)
		(end 63.601346 -72.999092)
		(width 0.254)
		(layer "F.Cu")
		(net "P1V05_NODE1")
	)
	(segment
		(start 52.119022 -78.318868)
		(end 52.68087 -78.318868)
		(width 0.3048)
		(layer "F.Cu")
		(net "P1V05_NODE1")
	)
	(segment
		(start 59.200796 -74.199242)
		(end 58.800746 -74.599292)
		(width 0.254)
		(layer "F.Cu")
		(net "P1V05_NODE1")
	)
	(segment
		(start 57.600596 -70.998842)
		(end 58.400696 -71.798942)
		(width 0.3556)
		(layer "F.Cu")
		(net "P1V05_NODE1")
	)
	(segment
		(start 53.600096 -70.998842)
		(end 53.604414 -70.998842)
		(width 0.254)
		(layer "F.Cu")
		(net "P1V05_NODE1")
	)
	(segment
		(start 51.071272 -78.015846)
		(end 50.371248 -78.015846)
		(width 0.3048)
		(layer "F.Cu")
		(net "P1V05_NODE1")
	)
	(segment
		(start 62.401196 -74.185526)
		(end 62.00394 -73.78827)
		(width 0.3048)
		(layer "F.Cu")
		(net "P1V05_NODE1")
	)
	(segment
		(start 60.000896 -74.999342)
		(end 60.000896 -74.987912)
		(width 0.3048)
		(layer "F.Cu")
		(net "P1V05_NODE1")
	)
	(segment
		(start 64.501522 -73.799192)
		(end 64.401446 -73.799192)
		(width 0.3048)
		(layer "F.Cu")
		(net "P1V05_NODE1")
	)
	(segment
		(start 60.000896 -74.987912)
		(end 60.39104 -74.597768)
		(width 0.3048)
		(layer "F.Cu")
		(net "P1V05_NODE1")
	)
	(segment
		(start 65.249044 -72.785224)
		(end 65.391538 -72.927718)
		(width 0.254)
		(layer "F.Cu")
		(net "P1V05_NODE1")
	)
	(segment
		(start 51.071272 -74.043286)
		(end 50.371248 -74.043286)
		(width 0.254)
		(layer "F.Cu")
		(net "P1V05_NODE1")
	)
	(segment
		(start 51.999896 -78.199742)
		(end 52.119022 -78.318868)
		(width 0.3048)
		(layer "F.Cu")
		(net "P1V05_NODE1")
	)
	(segment
		(start 59.17946 -74.199242)
		(end 58.7883 -73.808082)
		(width 0.3048)
		(layer "F.Cu")
		(net "P1V05_NODE1")
	)
	(segment
		(start 58.881772 -77.880718)
		(end 59.200796 -78.199742)
		(width 0.3048)
		(layer "F.Cu")
		(net "P1V05_NODE1")
	)
	(segment
		(start 64.70142 -70.973442)
		(end 64.72682 -70.998842)
		(width 0.254)
		(layer "F.Cu")
		(net "P1V05_NODE1")
	)
	(segment
		(start 15.22476 -115.316762)
		(end 15.22476 -115.320572)
		(width 0.254)
		(layer "F.Cu")
		(net "P1V05_NODE1")
	)
	(segment
		(start 51.802538 -74.324718)
		(end 51.352704 -74.324718)
		(width 0.254)
		(layer "F.Cu")
		(net "P1V05_NODE1")
	)
	(segment
		(start 9.513824 -117.921532)
		(end 9.513824 -129.80289)
		(width 0.254)
		(layer "F.Cu")
		(net "P1V05_NODE1")
	)
	(segment
		(start 53.600096 -78.199742)
		(end 53.604668 -78.199742)
		(width 0.3048)
		(layer "F.Cu")
		(net "P1V05_NODE1")
	)
	(segment
		(start 60.800996 -71.023988)
		(end 60.41771 -71.407274)
		(width 0.3048)
		(layer "F.Cu")
		(net "P1V05_NODE1")
	)
	(segment
		(start 115.146836 -65.40373)
		(end 115.15344 -65.410334)
		(width 0.508)
		(layer "F.Cu")
		(net "P1V05_NODE1")
	)
	(segment
		(start 54.400196 -74.199242)
		(end 54.800246 -73.799192)
		(width 0.254)
		(layer "F.Cu")
		(net "P1V05_NODE1")
	)
	(segment
		(start 61.601096 -73.399142)
		(end 61.201046 -73.799192)
		(width 0.3048)
		(layer "F.Cu")
		(net "P1V05_NODE1")
	)
	(segment
		(start 101.639116 -135.132064)
		(end 100.6729 -135.132064)
		(width 0.4572)
		(layer "F.Cu")
		(net "P1V05_NODE1")
	)
	(segment
		(start 59.200796 -72.599042)
		(end 58.800746 -72.198992)
		(width 0.3556)
		(layer "F.Cu")
		(net "P1V05_NODE1")
	)
	(segment
		(start 56.800496 -74.999342)
		(end 56.800496 -74.983848)
		(width 0.3048)
		(layer "F.Cu")
		(net "P1V05_NODE1")
	)
	(segment
		(start 15.26286 -115.278662)
		(end 15.22476 -115.316762)
		(width 0.254)
		(layer "F.Cu")
		(net "P1V05_NODE1")
	)
	(segment
		(start 101.558598 -131.139438)
		(end 100.496624 -131.139438)
		(width 0.508)
		(layer "F.Cu")
		(net "P1V05_NODE1")
	)
	(segment
		(start 66.011044 -72.308212)
		(end 65.391538 -72.927718)
		(width 0.254)
		(layer "F.Cu")
		(net "P1V05_NODE1")
	)
	(segment
		(start 50.752248 -72.236838)
		(end 51.158648 -72.643238)
		(width 0.254)
		(layer "F.Cu")
		(net "P1V05_NODE1")
	)
	(segment
		(start 170.750992 -135.24738)
		(end 169.881042 -135.24738)
		(width 0.508)
		(layer "F.Cu")
		(net "P1V05_NODE1")
	)
	(segment
		(start 55.600346 -77.799692)
		(end 56.000396 -77.399642)
		(width 0.254)
		(layer "F.Cu")
		(net "P1V05_NODE1")
	)
	(segment
		(start 60.800996 -74.199242)
		(end 61.201046 -73.799192)
		(width 0.3048)
		(layer "F.Cu")
		(net "P1V05_NODE1")
	)
	(segment
		(start 61.601096 -72.599042)
		(end 61.201046 -72.999092)
		(width 0.254)
		(layer "F.Cu")
		(net "P1V05_NODE1")
	)
	(segment
		(start 58.660538 -77.880718)
		(end 58.881772 -77.880718)
		(width 0.3048)
		(layer "F.Cu")
		(net "P1V05_NODE1")
	)
	(segment
		(start 53.600096 -72.599042)
		(end 53.200046 -72.999092)
		(width 0.254)
		(layer "F.Cu")
		(net "P1V05_NODE1")
	)
	(segment
		(start 178.600354 -135.991346)
		(end 178.600354 -136.278112)
		(width 0.508)
		(layer "F.Cu")
		(net "P1V05_NODE1")
	)
	(segment
		(start 171.14647 -102.135686)
		(end 172.461682 -102.135686)
		(width 0.1778)
		(layer "F.Cu")
		(net "P1V05_NODE1")
	)
	(segment
		(start 50.371248 -74.043286)
		(end 50.004218 -74.410316)
		(width 0.254)
		(layer "F.Cu")
		(net "P1V05_NODE1")
	)
	(segment
		(start 14.48562 -116.059712)
		(end 11.375644 -116.059712)
		(width 0.254)
		(layer "F.Cu")
		(net "P1V05_NODE1")
	)
	(segment
		(start 51.071272 -78.015846)
		(end 51.071272 -77.315822)
		(width 0.3048)
		(layer "F.Cu")
		(net "P1V05_NODE1")
	)
	(segment
		(start 61.201046 -72.999092)
		(end 60.800996 -72.599042)
		(width 0.254)
		(layer "F.Cu")
		(net "P1V05_NODE1")
	)
	(segment
		(start 53.604414 -70.998842)
		(end 53.834538 -70.768718)
		(width 0.254)
		(layer "F.Cu")
		(net "P1V05_NODE1")
	)
	(segment
		(start 163.340034 -99.735894)
		(end 162.14471 -99.735894)
		(width 0.1778)
		(layer "F.Cu")
		(net "P1V05_NODE1")
	)
	(segment
		(start 58.800746 -76.199492)
		(end 59.200796 -76.599542)
		(width 0.3556)
		(layer "F.Cu")
		(net "P1V05_NODE1")
	)
	(segment
		(start 59.200796 -75.799442)
		(end 58.800746 -75.399392)
		(width 0.254)
		(layer "F.Cu")
		(net "P1V05_NODE1")
	)
	(segment
		(start 51.158648 -72.643238)
		(end 51.514502 -72.999092)
		(width 0.254)
		(layer "F.Cu")
		(net "P1V05_NODE1")
	)
	(segment
		(start 58.400696 -74.999342)
		(end 58.800746 -74.599292)
		(width 0.254)
		(layer "F.Cu")
		(net "P1V05_NODE1")
	)
	(segment
		(start 61.614812 -73.399142)
		(end 62.00394 -73.78827)
		(width 0.3048)
		(layer "F.Cu")
		(net "P1V05_NODE1")
	)
	(segment
		(start 62.401196 -70.998842)
		(end 63.201296 -70.998842)
		(width 0.3048)
		(layer "F.Cu")
		(net "P1V05_NODE1")
	)
	(segment
		(start 114.446304 -62.271148)
		(end 115.21948 -62.271148)
		(width 0.508)
		(layer "F.Cu")
		(net "P1V05_NODE1")
	)
	(segment
		(start 56.000396 -77.399642)
		(end 56.400446 -77.799692)
		(width 0.3048)
		(layer "F.Cu")
		(net "P1V05_NODE1")
	)
	(segment
		(start 168.043352 -97.032572)
		(end 168.043352 -96.299274)
		(width 0.1778)
		(layer "F.Cu")
		(net "P1V05_NODE1")
	)
	(segment
		(start 59.200796 -70.998842)
		(end 59.600846 -71.398892)
		(width 0.3048)
		(layer "F.Cu")
		(net "P1V05_NODE1")
	)
	(segment
		(start 58.800746 -76.199492)
		(end 59.200796 -75.799442)
		(width 0.254)
		(layer "F.Cu")
		(net "P1V05_NODE1")
	)
	(segment
		(start 66.011044 -72.296782)
		(end 66.011044 -72.308212)
		(width 0.254)
		(layer "F.Cu")
		(net "P1V05_NODE1")
	)
	(segment
		(start 62.001146 -72.999092)
		(end 62.401196 -72.599042)
		(width 0.3048)
		(layer "F.Cu")
		(net "P1V05_NODE1")
	)
	(segment
		(start 61.201046 -78.599792)
		(end 61.601096 -78.999842)
		(width 0.3556)
		(layer "F.Cu")
		(net "P1V05_NODE1")
	)
	(segment
		(start 57.600596 -75.799442)
		(end 56.800496 -74.999342)
		(width 0.3048)
		(layer "F.Cu")
		(net "P1V05_NODE1")
	)
	(segment
		(start 50.004218 -74.410316)
		(end 50.004218 -74.762868)
		(width 0.254)
		(layer "F.Cu")
		(net "P1V05_NODE1")
	)
	(segment
		(start 57.585102 -74.199242)
		(end 57.19064 -74.593704)
		(width 0.3048)
		(layer "F.Cu")
		(net "P1V05_NODE1")
	)
	(segment
		(start 55.027322 -72.426068)
		(end 54.57317 -72.426068)
		(width 0.3556)
		(layer "F.Cu")
		(net "P1V05_NODE1")
	)
	(segment
		(start 64.001396 -70.998842)
		(end 64.04229 -70.998842)
		(width 0.254)
		(layer "F.Cu")
		(net "P1V05_NODE1")
	)
	(segment
		(start 59.600846 -71.398892)
		(end 60.000896 -70.998842)
		(width 0.3048)
		(layer "F.Cu")
		(net "P1V05_NODE1")
	)
	(segment
		(start 57.600596 -74.199242)
		(end 57.200546 -73.799192)
		(width 0.3048)
		(layer "F.Cu")
		(net "P1V05_NODE1")
	)
	(segment
		(start 56.800496 -74.983848)
		(end 57.19064 -74.593704)
		(width 0.3048)
		(layer "F.Cu")
		(net "P1V05_NODE1")
	)
	(segment
		(start 63.201296 -70.998842)
		(end 63.90132 -70.298818)
		(width 0.254)
		(layer "F.Cu")
		(net "P1V05_NODE1")
	)
	(segment
		(start 115.189508 -65.410334)
		(end 115.624356 -65.845182)
		(width 0.508)
		(layer "F.Cu")
		(net "P1V05_NODE1")
	)
	(segment
		(start 54.400196 -70.96506)
		(end 54.596538 -70.768718)
		(width 0.254)
		(layer "F.Cu")
		(net "P1V05_NODE1")
	)
	(segment
		(start 63.201296 -72.599042)
		(end 63.601346 -72.999092)
		(width 0.254)
		(layer "F.Cu")
		(net "P1V05_NODE1")
	)
	(segment
		(start 60.41771 -71.407274)
		(end 60.409328 -71.407274)
		(width 0.3048)
		(layer "F.Cu")
		(net "P1V05_NODE1")
	)
	(segment
		(start 56.400446 -72.999092)
		(end 56.800496 -73.399142)
		(width 0.3556)
		(layer "F.Cu")
		(net "P1V05_NODE1")
	)
	(segment
		(start 166.043356 -104.839008)
		(end 166.043356 -105.595674)
		(width 0.1778)
		(layer "F.Cu")
		(net "P1V05_NODE1")
	)
	(segment
		(start 64.93002 -74.22769)
		(end 64.501522 -73.799192)
		(width 0.3048)
		(layer "F.Cu")
		(net "P1V05_NODE1")
	)
	(segment
		(start 61.601096 -70.998842)
		(end 62.001146 -71.398892)
		(width 0.3048)
		(layer "F.Cu")
		(net "P1V05_NODE1")
	)
	(segment
		(start 172.014134 -98.535744)
		(end 172.198284 -98.351594)
		(width 0.1778)
		(layer "F.Cu")
		(net "P1V05_NODE1")
	)
	(segment
		(start 52.799996 -70.298818)
		(end 52.799996 -69.934328)
		(width 0.3048)
		(layer "F.Cu")
		(net "P1V05_NODE1")
	)
	(segment
		(start 50.752248 -72.057006)
		(end 50.752248 -72.236838)
		(width 0.254)
		(layer "F.Cu")
		(net "P1V05_NODE1")
	)
	(segment
		(start 9.513824 -129.80289)
		(end 11.301222 -131.590288)
		(width 0.254)
		(layer "F.Cu")
		(net "P1V05_NODE1")
	)
	(segment
		(start 51.514502 -72.999092)
		(end 51.599846 -72.999092)
		(width 0.254)
		(layer "F.Cu")
		(net "P1V05_NODE1")
	)
	(segment
		(start 62.801246 -75.399392)
		(end 63.201296 -74.999342)
		(width 0.3048)
		(layer "F.Cu")
		(net "P1V05_NODE1")
	)
	(segment
		(start 52.799996 -70.998842)
		(end 52.799996 -70.298818)
		(width 0.3048)
		(layer "F.Cu")
		(net "P1V05_NODE1")
	)
	(segment
		(start 115.15344 -65.410334)
		(end 115.189508 -65.410334)
		(width 0.508)
		(layer "F.Cu")
		(net "P1V05_NODE1")
	)
	(segment
		(start 61.601096 -73.399142)
		(end 61.614812 -73.399142)
		(width 0.3048)
		(layer "F.Cu")
		(net "P1V05_NODE1")
	)
	(segment
		(start 55.200296 -72.599042)
		(end 56.000396 -72.599042)
		(width 0.3048)
		(layer "F.Cu")
		(net "P1V05_NODE1")
	)
	(segment
		(start 50.102516 -78.389226)
		(end 50.51552 -78.80223)
		(width 0.3048)
		(layer "F.Cu")
		(net "P1V05_NODE1")
	)
	(segment
		(start 64.70142 -70.298818)
		(end 64.70142 -70.973442)
		(width 0.254)
		(layer "F.Cu")
		(net "P1V05_NODE1")
	)
	(segment
		(start 167.243252 -104.839008)
		(end 167.243252 -105.651554)
		(width 0.1778)
		(layer "F.Cu")
		(net "P1V05_NODE1")
	)
	(segment
		(start 64.001396 -70.298818)
		(end 64.70142 -70.298818)
		(width 0.254)
		(layer "F.Cu")
		(net "P1V05_NODE1")
	)
	(segment
		(start 172.461682 -102.135686)
		(end 172.724318 -102.398322)
		(width 0.1778)
		(layer "F.Cu")
		(net "P1V05_NODE1")
	)
	(segment
		(start 58.400696 -73.399142)
		(end 58.400696 -73.420478)
		(width 0.3048)
		(layer "F.Cu")
		(net "P1V05_NODE1")
	)
	(segment
		(start 167.243252 -105.651554)
		(end 167.20693 -106.086148)
		(width 0.1778)
		(layer "F.Cu")
		(net "P1V05_NODE1")
	)
	(segment
		(start 60.000896 -78.999842)
		(end 60.400946 -79.399892)
		(width 0.3048)
		(layer "F.Cu")
		(net "P1V05_NODE1")
	)
	(segment
		(start 64.93002 -74.283062)
		(end 64.93002 -74.22769)
		(width 0.3048)
		(layer "F.Cu")
		(net "P1V05_NODE1")
	)
	(segment
		(start 63.601346 -71.398892)
		(end 64.001396 -70.998842)
		(width 0.3048)
		(layer "F.Cu")
		(net "P1V05_NODE1")
	)
	(segment
		(start 60.800996 -70.998842)
		(end 61.601096 -70.998842)
		(width 0.3048)
		(layer "F.Cu")
		(net "P1V05_NODE1")
	)
	(segment
		(start 60.39104 -74.597768)
		(end 60.40247 -74.597768)
		(width 0.3048)
		(layer "F.Cu")
		(net "P1V05_NODE1")
	)
	(segment
		(start 63.90132 -70.298818)
		(end 64.001396 -70.298818)
		(width 0.254)
		(layer "F.Cu")
		(net "P1V05_NODE1")
	)
	(segment
		(start 51.999896 -72.599042)
		(end 52.399946 -72.999092)
		(width 0.254)
		(layer "F.Cu")
		(net "P1V05_NODE1")
	)
	(segment
		(start 53.200046 -71.398892)
		(end 52.799996 -70.998842)
		(width 0.3048)
		(layer "F.Cu")
		(net "P1V05_NODE1")
	)
	(segment
		(start 62.401196 -74.199242)
		(end 62.401196 -74.185526)
		(width 0.3048)
		(layer "F.Cu")
		(net "P1V05_NODE1")
	)
	(segment
		(start 18.411952 -112.127284)
		(end 15.66672 -112.127284)
		(width 0.254)
		(layer "F.Cu")
		(net "P1V05_NODE1")
	)
	(segment
		(start 59.200796 -78.199742)
		(end 60.000896 -78.999842)
		(width 0.3048)
		(layer "F.Cu")
		(net "P1V05_NODE1")
	)
	(segment
		(start 61.601096 -73.399142)
		(end 62.001146 -72.999092)
		(width 0.3048)
		(layer "F.Cu")
		(net "P1V05_NODE1")
	)
	(segment
		(start 53.200046 -71.398892)
		(end 53.600096 -70.998842)
		(width 0.254)
		(layer "F.Cu")
		(net "P1V05_NODE1")
	)
	(segment
		(start 51.928014 -74.199242)
		(end 51.802538 -74.324718)
		(width 0.254)
		(layer "F.Cu")
		(net "P1V05_NODE1")
	)
	(segment
		(start 57.600596 -77.399642)
		(end 57.200546 -77.799692)
		(width 0.3048)
		(layer "F.Cu")
		(net "P1V05_NODE1")
	)
	(segment
		(start 53.600096 -74.199242)
		(end 53.200046 -73.799192)
		(width 0.254)
		(layer "F.Cu")
		(net "P1V05_NODE1")
	)
	(segment
		(start 58.400696 -75.799442)
		(end 58.800746 -75.399392)
		(width 0.3048)
		(layer "F.Cu")
		(net "P1V05_NODE1")
	)
	(segment
		(start 60.400946 -72.999092)
		(end 60.800996 -72.599042)
		(width 0.3048)
		(layer "F.Cu")
		(net "P1V05_NODE1")
	)
	(segment
		(start 52.711096 -69.845174)
		(end 52.511706 -69.646038)
		(width 0.3048)
		(layer "F.Cu")
		(net "P1V05_NODE1")
	)
	(segment
		(start 58.400696 -73.420478)
		(end 58.7883 -73.808082)
		(width 0.3048)
		(layer "F.Cu")
		(net "P1V05_NODE1")
	)
	(segment
		(start 56.000396 -75.799442)
		(end 56.400446 -76.199492)
		(width 0.254)
		(layer "F.Cu")
		(net "P1V05_NODE1")
	)
	(segment
		(start 54.400196 -78.198726)
		(end 54.00294 -77.80147)
		(width 0.3048)
		(layer "F.Cu")
		(net "P1V05_NODE1")
	)
	(segment
		(start 57.200546 -73.799192)
		(end 56.800496 -73.399142)
		(width 0.3048)
		(layer "F.Cu")
		(net "P1V05_NODE1")
	)
	(segment
		(start 115.624356 -65.845182)
		(end 116.0272 -65.845182)
		(width 0.508)
		(layer "F.Cu")
		(net "P1V05_NODE1")
	)
	(segment
		(start 58.400696 -75.799442)
		(end 58.800746 -76.199492)
		(width 0.3556)
		(layer "F.Cu")
		(net "P1V05_NODE1")
	)
	(segment
		(start 53.200046 -73.799192)
		(end 52.799996 -74.199242)
		(width 0.254)
		(layer "F.Cu")
		(net "P1V05_NODE1")
	)
	(segment
		(start 50.371248 -77.315822)
		(end 51.071272 -77.315822)
		(width 0.3048)
		(layer "F.Cu")
		(net "P1V05_NODE1")
	)
	(segment
		(start 52.511706 -69.646038)
		(end 51.811682 -69.646038)
		(width 0.3048)
		(layer "F.Cu")
		(net "P1V05_NODE1")
	)
	(segment
		(start 100.496624 -131.139438)
		(end 100.496624 -130.253232)
		(width 0.508)
		(layer "F.Cu")
		(net "P1V05_NODE1")
	)
	(segment
		(start 53.604668 -78.199742)
		(end 54.00294 -77.80147)
		(width 0.3048)
		(layer "F.Cu")
		(net "P1V05_NODE1")
	)
	(segment
		(start 57.200546 -72.198992)
		(end 56.800496 -71.798942)
		(width 0.3048)
		(layer "F.Cu")
		(net "P1V05_NODE1")
	)
	(segment
		(start 63.601346 -71.398892)
		(end 63.201296 -70.998842)
		(width 0.254)
		(layer "F.Cu")
		(net "P1V05_NODE1")
	)
	(segment
		(start 54.170072 -70.768718)
		(end 54.400196 -70.998842)
		(width 0.254)
		(layer "F.Cu")
		(net "P1V05_NODE1")
	)
	(segment
		(start 65.249044 -72.296782)
		(end 65.249044 -72.785224)
		(width 0.254)
		(layer "F.Cu")
		(net "P1V05_NODE1")
	)
	(segment
		(start 58.800746 -79.399892)
		(end 59.200796 -79.799942)
		(width 0.3556)
		(layer "F.Cu")
		(net "P1V05_NODE1")
	)
	(segment
		(start 62.001146 -71.398892)
		(end 62.401196 -70.998842)
		(width 0.3048)
		(layer "F.Cu")
		(net "P1V05_NODE1")
	)
	(segment
		(start 54.000146 -72.999092)
		(end 53.600096 -72.599042)
		(width 0.3048)
		(layer "F.Cu")
		(net "P1V05_NODE1")
	)
	(segment
		(start 168.043352 -96.299274)
		(end 167.523922 -95.779844)
		(width 0.1778)
		(layer "F.Cu")
		(net "P1V05_NODE1")
	)
	(via
		(at 57.19064 -74.593704)
		(size 0.508)
		(drill 0.254)
		(layers "F.Cu" "B.Cu")
		(net "P1V05_NODE1")
	)
	(via
		(at 17.924272 -114.561366)
		(size 0.508)
		(drill 0.254)
		(layers "F.Cu" "B.Cu")
		(net "P1V05_NODE1")
	)
	(via
		(at 92.95638 -75.995276)
		(size 0.508)
		(drill 0.254)
		(layers "F.Cu" "B.Cu")
		(net "P1V05_NODE1")
	)
	(via
		(at 63.601346 -71.398892)
		(size 0.508)
		(drill 0.254)
		(layers "F.Cu" "B.Cu")
		(net "P1V05_NODE1")
	)
	(via
		(at 47.728378 -78.431136)
		(size 0.508)
		(drill 0.254)
		(layers "F.Cu" "B.Cu")
		(net "P1V05_NODE1")
	)
	(via
		(at 64.401446 -73.799192)
		(size 0.508)
		(drill 0.254)
		(layers "F.Cu" "B.Cu")
		(net "P1V05_NODE1")
	)
	(via
		(at 43.938952 -77.652626)
		(size 0.6604)
		(drill 0.3302)
		(layers "F.Cu" "B.Cu")
		(net "P1V05_NODE1")
	)
	(via
		(at 125.03404 -122.637804)
		(size 0.508)
		(drill 0.254)
		(layers "F.Cu" "B.Cu")
		(net "P1V05_NODE1")
	)
	(via
		(at 45.82414 -77.435964)
		(size 0.6604)
		(drill 0.3302)
		(layers "F.Cu" "B.Cu")
		(net "P1V05_NODE1")
	)
	(via
		(at 62.801246 -75.399392)
		(size 0.508)
		(drill 0.254)
		(layers "F.Cu" "B.Cu")
		(net "P1V05_NODE1")
	)
	(via
		(at 21.8567 -112.631728)
		(size 0.508)
		(drill 0.254)
		(layers "F.Cu" "B.Cu")
		(net "P1V05_NODE1")
	)
	(via
		(at 167.523922 -95.779844)
		(size 0.508)
		(drill 0.254)
		(layers "F.Cu" "B.Cu")
		(net "P1V05_NODE1")
	)
	(via
		(at 92.51188 -75.38593)
		(size 0.508)
		(drill 0.254)
		(layers "F.Cu" "B.Cu")
		(net "P1V05_NODE1")
	)
	(via
		(at 58.800746 -79.399892)
		(size 0.508)
		(drill 0.254)
		(layers "F.Cu" "B.Cu")
		(net "P1V05_NODE1")
	)
	(via
		(at 21.8567 -108.894372)
		(size 0.508)
		(drill 0.254)
		(layers "F.Cu" "B.Cu")
		(net "P1V05_NODE1")
	)
	(via
		(at 89.891362 -79.775558)
		(size 0.508)
		(drill 0.254)
		(layers "F.Cu" "B.Cu")
		(net "P1V05_NODE1")
	)
	(via
		(at 56.400446 -72.999092)
		(size 0.508)
		(drill 0.254)
		(layers "F.Cu" "B.Cu")
		(net "P1V05_NODE1")
	)
	(via
		(at 20.44446 -107.61726)
		(size 0.508)
		(drill 0.254)
		(layers "F.Cu" "B.Cu")
		(net "P1V05_NODE1")
	)
	(via
		(at 45.445934 -76.68768)
		(size 0.508)
		(drill 0.254)
		(layers "F.Cu" "B.Cu")
		(net "P1V05_NODE1")
	)
	(via
		(at 46.207934 -76.68768)
		(size 0.508)
		(drill 0.254)
		(layers "F.Cu" "B.Cu")
		(net "P1V05_NODE1")
	)
	(via
		(at 57.200546 -72.198992)
		(size 0.508)
		(drill 0.254)
		(layers "F.Cu" "B.Cu")
		(net "P1V05_NODE1")
	)
	(via
		(at 169.869866 -105.95229)
		(size 0.508)
		(drill 0.254)
		(layers "F.Cu" "B.Cu")
		(net "P1V05_NODE1")
	)
	(via
		(at 172.724318 -102.398322)
		(size 0.508)
		(drill 0.254)
		(layers "F.Cu" "B.Cu")
		(net "P1V05_NODE1")
	)
	(via
		(at 62.00394 -73.78827)
		(size 0.508)
		(drill 0.254)
		(layers "F.Cu" "B.Cu")
		(net "P1V05_NODE1")
	)
	(via
		(at 172.501052 -101.08819)
		(size 0.508)
		(drill 0.254)
		(layers "F.Cu" "B.Cu")
		(net "P1V05_NODE1")
	)
	(via
		(at 51.599846 -72.999092)
		(size 0.508)
		(drill 0.254)
		(layers "F.Cu" "B.Cu")
		(net "P1V05_NODE1")
	)
	(via
		(at 116.0272 -65.845182)
		(size 0.508)
		(drill 0.254)
		(layers "F.Cu" "B.Cu")
		(net "P1V05_NODE1")
	)
	(via
		(at 61.201046 -78.599792)
		(size 0.508)
		(drill 0.254)
		(layers "F.Cu" "B.Cu")
		(net "P1V05_NODE1")
	)
	(via
		(at 22.867874 -107.110022)
		(size 0.508)
		(drill 0.254)
		(layers "F.Cu" "B.Cu")
		(net "P1V05_NODE1")
	)
	(via
		(at 50.51552 -78.80223)
		(size 0.508)
		(drill 0.254)
		(layers "F.Cu" "B.Cu")
		(net "P1V05_NODE1")
	)
	(via
		(at 178.09718 -136.781032)
		(size 0.508)
		(drill 0.254)
		(layers "F.Cu" "B.Cu")
		(net "P1V05_NODE1")
	)
	(via
		(at 20.44446 -108.37926)
		(size 0.508)
		(drill 0.254)
		(layers "F.Cu" "B.Cu")
		(net "P1V05_NODE1")
	)
	(via
		(at 57.200546 -73.799192)
		(size 0.508)
		(drill 0.254)
		(layers "F.Cu" "B.Cu")
		(net "P1V05_NODE1")
	)
	(via
		(at 60.41771 -71.407274)
		(size 0.508)
		(drill 0.254)
		(layers "F.Cu" "B.Cu")
		(net "P1V05_NODE1")
	)
	(via
		(at 167.20693 -106.086148)
		(size 0.508)
		(drill 0.254)
		(layers "F.Cu" "B.Cu")
		(net "P1V05_NODE1")
	)
	(via
		(at 54.000146 -72.999092)
		(size 0.508)
		(drill 0.254)
		(layers "F.Cu" "B.Cu")
		(net "P1V05_NODE1")
	)
	(via
		(at 20.2946 -111.555022)
		(size 0.508)
		(drill 0.254)
		(layers "F.Cu" "B.Cu")
		(net "P1V05_NODE1")
	)
	(via
		(at 169.831258 -134.040372)
		(size 0.508)
		(drill 0.254)
		(layers "F.Cu" "B.Cu")
		(net "P1V05_NODE1")
	)
	(via
		(at 54.00294 -77.80147)
		(size 0.508)
		(drill 0.254)
		(layers "F.Cu" "B.Cu")
		(net "P1V05_NODE1")
	)
	(via
		(at 64.575436 -71.531988)
		(size 0.508)
		(drill 0.254)
		(layers "F.Cu" "B.Cu")
		(net "P1V05_NODE1")
	)
	(via
		(at 62.001146 -71.398892)
		(size 0.508)
		(drill 0.254)
		(layers "F.Cu" "B.Cu")
		(net "P1V05_NODE1")
	)
	(via
		(at 165.87978 -108.585)
		(size 0.508)
		(drill 0.254)
		(layers "F.Cu" "B.Cu")
		(net "P1V05_NODE1")
	)
	(via
		(at 48.527716 -74.783696)
		(size 0.508)
		(drill 0.254)
		(layers "F.Cu" "B.Cu")
		(net "P1V05_NODE1")
	)
	(via
		(at 123.13412 -79.77886)
		(size 0.508)
		(drill 0.254)
		(layers "F.Cu" "B.Cu")
		(net "P1V05_NODE1")
	)
	(via
		(at 125.6919 -80.196182)
		(size 0.508)
		(drill 0.254)
		(layers "F.Cu" "B.Cu")
		(net "P1V05_NODE1")
	)
	(via
		(at 90.63609 -79.729076)
		(size 0.508)
		(drill 0.254)
		(layers "F.Cu" "B.Cu")
		(net "P1V05_NODE1")
	)
	(via
		(at 20.984718 -114.62385)
		(size 0.508)
		(drill 0.254)
		(layers "F.Cu" "B.Cu")
		(net "P1V05_NODE1")
	)
	(via
		(at 55.600346 -71.398892)
		(size 0.508)
		(drill 0.254)
		(layers "F.Cu" "B.Cu")
		(net "P1V05_NODE1")
	)
	(via
		(at 21.8567 -110.35538)
		(size 0.508)
		(drill 0.254)
		(layers "F.Cu" "B.Cu")
		(net "P1V05_NODE1")
	)
	(via
		(at 161.953956 -100.903786)
		(size 0.508)
		(drill 0.254)
		(layers "F.Cu" "B.Cu")
		(net "P1V05_NODE1")
	)
	(via
		(at 58.800746 -74.599292)
		(size 0.508)
		(drill 0.254)
		(layers "F.Cu" "B.Cu")
		(net "P1V05_NODE1")
	)
	(via
		(at 21.8567 -113.393728)
		(size 0.508)
		(drill 0.254)
		(layers "F.Cu" "B.Cu")
		(net "P1V05_NODE1")
	)
	(via
		(at 58.800746 -72.198992)
		(size 0.508)
		(drill 0.254)
		(layers "F.Cu" "B.Cu")
		(net "P1V05_NODE1")
	)
	(via
		(at 49.990248 -78.389226)
		(size 0.508)
		(drill 0.254)
		(layers "F.Cu" "B.Cu")
		(net "P1V05_NODE1")
	)
	(via
		(at 125.72492 -122.676666)
		(size 0.508)
		(drill 0.254)
		(layers "F.Cu" "B.Cu")
		(net "P1V05_NODE1")
	)
	(via
		(at 62.001146 -72.999092)
		(size 0.508)
		(drill 0.254)
		(layers "F.Cu" "B.Cu")
		(net "P1V05_NODE1")
	)
	(via
		(at 84.957412 -76.099416)
		(size 0.508)
		(drill 0.254)
		(layers "F.Cu" "B.Cu")
		(net "P1V05_NODE1")
	)
	(via
		(at 60.400946 -79.399892)
		(size 0.508)
		(drill 0.254)
		(layers "F.Cu" "B.Cu")
		(net "P1V05_NODE1")
	)
	(via
		(at 58.7883 -73.808082)
		(size 0.508)
		(drill 0.254)
		(layers "F.Cu" "B.Cu")
		(net "P1V05_NODE1")
	)
	(via
		(at 47.858172 -70.837298)
		(size 0.508)
		(drill 0.254)
		(layers "F.Cu" "B.Cu")
		(net "P1V05_NODE1")
	)
	(via
		(at 95.00616 -77.46492)
		(size 0.508)
		(drill 0.254)
		(layers "F.Cu" "B.Cu")
		(net "P1V05_NODE1")
	)
	(via
		(at 20.44446 -106.85526)
		(size 0.508)
		(drill 0.254)
		(layers "F.Cu" "B.Cu")
		(net "P1V05_NODE1")
	)
	(via
		(at 54.800246 -73.799192)
		(size 0.508)
		(drill 0.254)
		(layers "F.Cu" "B.Cu")
		(net "P1V05_NODE1")
	)
	(via
		(at 44.683934 -76.68768)
		(size 0.508)
		(drill 0.254)
		(layers "F.Cu" "B.Cu")
		(net "P1V05_NODE1")
	)
	(via
		(at 20.2946 -113.079022)
		(size 0.508)
		(drill 0.254)
		(layers "F.Cu" "B.Cu")
		(net "P1V05_NODE1")
	)
	(via
		(at 17.162272 -114.561366)
		(size 0.508)
		(drill 0.254)
		(layers "F.Cu" "B.Cu")
		(net "P1V05_NODE1")
	)
	(via
		(at 115.21948 -62.271148)
		(size 0.508)
		(drill 0.254)
		(layers "F.Cu" "B.Cu")
		(net "P1V05_NODE1")
	)
	(via
		(at 52.399946 -72.999092)
		(size 0.508)
		(drill 0.254)
		(layers "F.Cu" "B.Cu")
		(net "P1V05_NODE1")
	)
	(via
		(at 22.920452 -106.330242)
		(size 0.508)
		(drill 0.254)
		(layers "F.Cu" "B.Cu")
		(net "P1V05_NODE1")
	)
	(via
		(at 47.95774 -76.707492)
		(size 0.508)
		(drill 0.254)
		(layers "F.Cu" "B.Cu")
		(net "P1V05_NODE1")
	)
	(via
		(at 94.90456 -76.473812)
		(size 0.508)
		(drill 0.254)
		(layers "F.Cu" "B.Cu")
		(net "P1V05_NODE1")
	)
	(via
		(at 65.391538 -72.927718)
		(size 0.508)
		(drill 0.254)
		(layers "F.Cu" "B.Cu")
		(net "P1V05_NODE1")
	)
	(via
		(at 166.026846 -106.065828)
		(size 0.508)
		(drill 0.254)
		(layers "F.Cu" "B.Cu")
		(net "P1V05_NODE1")
	)
	(via
		(at 21.8567 -111.11738)
		(size 0.508)
		(drill 0.254)
		(layers "F.Cu" "B.Cu")
		(net "P1V05_NODE1")
	)
	(via
		(at 57.200546 -77.799692)
		(size 0.508)
		(drill 0.254)
		(layers "F.Cu" "B.Cu")
		(net "P1V05_NODE1")
	)
	(via
		(at 22.508718 -114.62385)
		(size 0.508)
		(drill 0.254)
		(layers "F.Cu" "B.Cu")
		(net "P1V05_NODE1")
	)
	(via
		(at 57.200546 -79.399892)
		(size 0.508)
		(drill 0.254)
		(layers "F.Cu" "B.Cu")
		(net "P1V05_NODE1")
	)
	(via
		(at 56.400446 -77.799692)
		(size 0.508)
		(drill 0.254)
		(layers "F.Cu" "B.Cu")
		(net "P1V05_NODE1")
	)
	(via
		(at 48.755046 -76.704698)
		(size 0.508)
		(drill 0.254)
		(layers "F.Cu" "B.Cu")
		(net "P1V05_NODE1")
	)
	(via
		(at 161.985452 -99.576636)
		(size 0.508)
		(drill 0.254)
		(layers "F.Cu" "B.Cu")
		(net "P1V05_NODE1")
	)
	(via
		(at 96.96704 -125.985016)
		(size 0.508)
		(drill 0.254)
		(layers "F.Cu" "B.Cu")
		(net "P1V05_NODE1")
	)
	(via
		(at 83.445604 -78.408784)
		(size 0.508)
		(drill 0.254)
		(layers "F.Cu" "B.Cu")
		(net "P1V05_NODE1")
	)
	(via
		(at 20.2946 -112.317022)
		(size 0.508)
		(drill 0.254)
		(layers "F.Cu" "B.Cu")
		(net "P1V05_NODE1")
	)
	(via
		(at 100.50526 -130.244596)
		(size 0.508)
		(drill 0.254)
		(layers "F.Cu" "B.Cu")
		(net "P1V05_NODE1")
	)
	(via
		(at 56.400446 -76.199492)
		(size 0.508)
		(drill 0.254)
		(layers "F.Cu" "B.Cu")
		(net "P1V05_NODE1")
	)
	(via
		(at 58.800746 -75.399392)
		(size 0.508)
		(drill 0.254)
		(layers "F.Cu" "B.Cu")
		(net "P1V05_NODE1")
	)
	(via
		(at 172.198284 -98.351594)
		(size 0.508)
		(drill 0.254)
		(layers "F.Cu" "B.Cu")
		(net "P1V05_NODE1")
	)
	(via
		(at 60.39104 -74.597768)
		(size 0.508)
		(drill 0.254)
		(layers "F.Cu" "B.Cu")
		(net "P1V05_NODE1")
	)
	(via
		(at 53.200046 -72.999092)
		(size 0.508)
		(drill 0.254)
		(layers "F.Cu" "B.Cu")
		(net "P1V05_NODE1")
	)
	(via
		(at 58.800746 -76.199492)
		(size 0.508)
		(drill 0.254)
		(layers "F.Cu" "B.Cu")
		(net "P1V05_NODE1")
	)
	(via
		(at 61.201046 -72.999092)
		(size 0.508)
		(drill 0.254)
		(layers "F.Cu" "B.Cu")
		(net "P1V05_NODE1")
	)
	(via
		(at 112.140492 -67.749674)
		(size 0.508)
		(drill 0.254)
		(layers "F.Cu" "B.Cu")
		(net "P1V05_NODE1")
	)
	(via
		(at 50.004218 -74.762868)
		(size 0.508)
		(drill 0.254)
		(layers "F.Cu" "B.Cu")
		(net "P1V05_NODE1")
	)
	(via
		(at 60.400946 -72.999092)
		(size 0.508)
		(drill 0.254)
		(layers "F.Cu" "B.Cu")
		(net "P1V05_NODE1")
	)
	(via
		(at 53.200046 -71.398892)
		(size 0.508)
		(drill 0.254)
		(layers "F.Cu" "B.Cu")
		(net "P1V05_NODE1")
	)
	(via
		(at 92.716604 -84.449412)
		(size 0.508)
		(drill 0.254)
		(layers "F.Cu" "B.Cu")
		(net "P1V05_NODE1")
	)
	(via
		(at 63.601346 -72.999092)
		(size 0.508)
		(drill 0.254)
		(layers "F.Cu" "B.Cu")
		(net "P1V05_NODE1")
	)
	(via
		(at 62.001146 -75.399392)
		(size 0.508)
		(drill 0.254)
		(layers "F.Cu" "B.Cu")
		(net "P1V05_NODE1")
	)
	(via
		(at 59.600846 -71.398892)
		(size 0.508)
		(drill 0.254)
		(layers "F.Cu" "B.Cu")
		(net "P1V05_NODE1")
	)
	(via
		(at 102.762812 -140.166852)
		(size 0.508)
		(drill 0.254)
		(layers "F.Cu" "B.Cu")
		(net "P1V05_NODE1")
	)
	(via
		(at 21.8567 -107.978448)
		(size 0.508)
		(drill 0.254)
		(layers "F.Cu" "B.Cu")
		(net "P1V05_NODE1")
	)
	(via
		(at 61.201046 -73.799192)
		(size 0.508)
		(drill 0.254)
		(layers "F.Cu" "B.Cu")
		(net "P1V05_NODE1")
	)
	(via
		(at 16.400272 -114.561366)
		(size 0.508)
		(drill 0.254)
		(layers "F.Cu" "B.Cu")
		(net "P1V05_NODE1")
	)
	(via
		(at 21.746718 -114.62385)
		(size 0.508)
		(drill 0.254)
		(layers "F.Cu" "B.Cu")
		(net "P1V05_NODE1")
	)
	(via
		(at 46.546516 -74.935842)
		(size 0.508)
		(drill 0.254)
		(layers "F.Cu" "B.Cu")
		(net "P1V05_NODE1")
	)
	(via
		(at 169.881042 -135.24738)
		(size 0.508)
		(drill 0.254)
		(layers "F.Cu" "B.Cu")
		(net "P1V05_NODE1")
	)
	(via
		(at 100.6729 -135.132064)
		(size 0.508)
		(drill 0.254)
		(layers "F.Cu" "B.Cu")
		(net "P1V05_NODE1")
	)
	(via
		(at 55.600346 -77.799692)
		(size 0.508)
		(drill 0.254)
		(layers "F.Cu" "B.Cu")
		(net "P1V05_NODE1")
	)
	(via
		(at 53.200046 -73.799192)
		(size 0.508)
		(drill 0.254)
		(layers "F.Cu" "B.Cu")
		(net "P1V05_NODE1")
	)
	(segment
		(start 167.523922 -96.54921)
		(end 167.523922 -95.779844)
		(width 0.508)
		(layer "B.Cu")
		(net "P1V05_NODE1")
	)
	(segment
		(start 83.98891 -79.014066)
		(end 83.445604 -78.47076)
		(width 0.4572)
		(layer "B.Cu")
		(net "P1V05_NODE1")
	)
	(segment
		(start 48.01997 -78.722728)
		(end 47.728378 -78.431136)
		(width 0.4572)
		(layer "B.Cu")
		(net "P1V05_NODE1")
	)
	(segment
		(start 162.44316 -121.264426)
		(end 162.44316 -114.3889)
		(width 0.508)
		(layer "B.Cu")
		(net "P1V05_NODE1")
	)
	(segment
		(start 159.41548 -127.249682)
		(end 159.41548 -124.292106)
		(width 0.508)
		(layer "B.Cu")
		(net "P1V05_NODE1")
	)
	(segment
		(start 165.998652 -105.27284)
		(end 166.026846 -105.301034)
		(width 0.508)
		(layer "B.Cu")
		(net "P1V05_NODE1")
	)
	(segment
		(start 162.023552 -100.83419)
		(end 161.953956 -100.903786)
		(width 0.508)
		(layer "B.Cu")
		(net "P1V05_NODE1")
	)
	(segment
		(start 172.379386 -102.05339)
		(end 172.724318 -102.398322)
		(width 0.508)
		(layer "B.Cu")
		(net "P1V05_NODE1")
	)
	(segment
		(start 171.827698 -98.351594)
		(end 172.198284 -98.351594)
		(width 0.508)
		(layer "B.Cu")
		(net "P1V05_NODE1")
	)
	(segment
		(start 169.554652 -105.24744)
		(end 169.554652 -105.480104)
		(width 0.508)
		(layer "B.Cu")
		(net "P1V05_NODE1")
	)
	(segment
		(start 161.998406 -99.58959)
		(end 161.985452 -99.576636)
		(width 0.508)
		(layer "B.Cu")
		(net "P1V05_NODE1")
	)
	(segment
		(start 167.73398 -132.484368)
		(end 163.256976 -132.484368)
		(width 0.508)
		(layer "B.Cu")
		(net "P1V05_NODE1")
	)
	(segment
		(start 171.580302 -102.05339)
		(end 172.379386 -102.05339)
		(width 0.508)
		(layer "B.Cu")
		(net "P1V05_NODE1")
	)
	(segment
		(start 52.49672 -81.4832)
		(end 52.7304 -81.4832)
		(width 0.381)
		(layer "B.Cu")
		(net "P1V05_NODE1")
	)
	(segment
		(start 169.869866 -105.795318)
		(end 169.869866 -105.95229)
		(width 0.508)
		(layer "B.Cu")
		(net "P1V05_NODE1")
	)
	(segment
		(start 169.831258 -134.040372)
		(end 169.289984 -134.040372)
		(width 0.508)
		(layer "B.Cu")
		(net "P1V05_NODE1")
	)
	(segment
		(start 162.44316 -114.3889)
		(end 165.87978 -110.95228)
		(width 0.508)
		(layer "B.Cu")
		(net "P1V05_NODE1")
	)
	(segment
		(start 171.580302 -100.98659)
		(end 172.399452 -100.98659)
		(width 0.508)
		(layer "B.Cu")
		(net "P1V05_NODE1")
	)
	(segment
		(start 167.217852 -106.075226)
		(end 167.20693 -106.086148)
		(width 0.508)
		(layer "B.Cu")
		(net "P1V05_NODE1")
	)
	(segment
		(start 166.026846 -105.301034)
		(end 166.026846 -106.065828)
		(width 0.508)
		(layer "B.Cu")
		(net "P1V05_NODE1")
	)
	(segment
		(start 110.686342 -67.425062)
		(end 111.81588 -67.425062)
		(width 0.508)
		(layer "B.Cu")
		(net "P1V05_NODE1")
	)
	(segment
		(start 169.554652 -105.480104)
		(end 169.869866 -105.795318)
		(width 0.508)
		(layer "B.Cu")
		(net "P1V05_NODE1")
	)
	(segment
		(start 172.399452 -100.98659)
		(end 172.501052 -101.08819)
		(width 0.508)
		(layer "B.Cu")
		(net "P1V05_NODE1")
	)
	(segment
		(start 162.728402 -100.83419)
		(end 162.023552 -100.83419)
		(width 0.508)
		(layer "B.Cu")
		(net "P1V05_NODE1")
	)
	(segment
		(start 161.7726 -130.999992)
		(end 161.7726 -129.606802)
		(width 0.508)
		(layer "B.Cu")
		(net "P1V05_NODE1")
	)
	(segment
		(start 167.624252 -96.64954)
		(end 167.523922 -96.54921)
		(width 0.508)
		(layer "B.Cu")
		(net "P1V05_NODE1")
	)
	(segment
		(start 163.256976 -132.484368)
		(end 161.7726 -130.999992)
		(width 0.508)
		(layer "B.Cu")
		(net "P1V05_NODE1")
	)
	(segment
		(start 167.217852 -105.24744)
		(end 167.217852 -106.075226)
		(width 0.508)
		(layer "B.Cu")
		(net "P1V05_NODE1")
	)
	(segment
		(start 83.445604 -78.47076)
		(end 83.445604 -78.408784)
		(width 0.4572)
		(layer "B.Cu")
		(net "P1V05_NODE1")
	)
	(segment
		(start 111.81588 -67.425062)
		(end 112.140492 -67.749674)
		(width 0.508)
		(layer "B.Cu")
		(net "P1V05_NODE1")
	)
	(segment
		(start 83.98891 -79.213456)
		(end 83.98891 -79.014066)
		(width 0.4572)
		(layer "B.Cu")
		(net "P1V05_NODE1")
	)
	(segment
		(start 162.728402 -99.58959)
		(end 161.998406 -99.58959)
		(width 0.508)
		(layer "B.Cu")
		(net "P1V05_NODE1")
	)
	(segment
		(start 161.7726 -129.606802)
		(end 159.41548 -127.249682)
		(width 0.508)
		(layer "B.Cu")
		(net "P1V05_NODE1")
	)
	(segment
		(start 52.7304 -81.4832)
		(end 54.069488 -80.144112)
		(width 0.381)
		(layer "B.Cu")
		(net "P1V05_NODE1")
	)
	(segment
		(start 48.01997 -79.147162)
		(end 48.01997 -78.722728)
		(width 0.4572)
		(layer "B.Cu")
		(net "P1V05_NODE1")
	)
	(segment
		(start 169.289984 -134.040372)
		(end 167.73398 -132.484368)
		(width 0.508)
		(layer "B.Cu")
		(net "P1V05_NODE1")
	)
	(segment
		(start 165.87978 -110.95228)
		(end 165.87978 -108.585)
		(width 0.508)
		(layer "B.Cu")
		(net "P1V05_NODE1")
	)
	(segment
		(start 171.580302 -98.59899)
		(end 171.827698 -98.351594)
		(width 0.508)
		(layer "B.Cu")
		(net "P1V05_NODE1")
	)
	(segment
		(start 159.41548 -124.292106)
		(end 162.44316 -121.264426)
		(width 0.508)
		(layer "B.Cu")
		(net "P1V05_NODE1")
	)
	(segment
		(start 54.069488 -80.144112)
		(end 54.069488 -79.531718)
		(width 0.381)
		(layer "B.Cu")
		(net "P1V05_NODE1")
	)
	(segment
		(start 118.128542 -103.040942)
		(end 117.642132 -102.554532)
		(width 0.508)
		(layer "In2.Cu")
		(net "P1V05_NODE1")
	)
	(segment
		(start 96.48825 -118.108984)
		(end 96.199706 -118.397528)
		(width 0.508)
		(layer "In2.Cu")
		(net "P1V05_NODE1")
	)
	(segment
		(start 117.642132 -102.554532)
		(end 117.642132 -99.034092)
		(width 0.508)
		(layer "In2.Cu")
		(net "P1V05_NODE1")
	)
	(segment
		(start 100.5205 -94.201488)
		(end 100.5205 -99.465384)
		(width 0.508)
		(layer "In2.Cu")
		(net "P1V05_NODE1")
	)
	(segment
		(start 96.46666 -119.193818)
		(end 96.46666 -124.61621)
		(width 0.508)
		(layer "In2.Cu")
		(net "P1V05_NODE1")
	)
	(segment
		(start 124.83592 -110.113826)
		(end 124.83592 -106.277664)
		(width 0.508)
		(layer "In2.Cu")
		(net "P1V05_NODE1")
	)
	(segment
		(start 124.83592 -106.277664)
		(end 121.599198 -103.040942)
		(width 0.508)
		(layer "In2.Cu")
		(net "P1V05_NODE1")
	)
	(segment
		(start 125.03404 -116.23929)
		(end 124.24918 -115.45443)
		(width 0.508)
		(layer "In2.Cu")
		(net "P1V05_NODE1")
	)
	(segment
		(start 105.467912 -89.254076)
		(end 100.5205 -94.201488)
		(width 0.508)
		(layer "In2.Cu")
		(net "P1V05_NODE1")
	)
	(segment
		(start 100.5205 -99.465384)
		(end 96.56572 -103.420164)
		(width 0.508)
		(layer "In2.Cu")
		(net "P1V05_NODE1")
	)
	(segment
		(start 96.48825 -110.714282)
		(end 96.48825 -118.108984)
		(width 0.508)
		(layer "In2.Cu")
		(net "P1V05_NODE1")
	)
	(segment
		(start 117.642132 -99.034092)
		(end 125.6919 -90.984324)
		(width 0.508)
		(layer "In2.Cu")
		(net "P1V05_NODE1")
	)
	(segment
		(start 96.56572 -103.420164)
		(end 96.56572 -103.946452)
		(width 0.508)
		(layer "In2.Cu")
		(net "P1V05_NODE1")
	)
	(segment
		(start 125.03404 -122.637804)
		(end 125.03404 -116.23929)
		(width 0.508)
		(layer "In2.Cu")
		(net "P1V05_NODE1")
	)
	(segment
		(start 96.87814 -110.324392)
		(end 96.48825 -110.714282)
		(width 0.508)
		(layer "In2.Cu")
		(net "P1V05_NODE1")
	)
	(segment
		(start 125.6919 -90.984324)
		(end 125.6919 -80.196182)
		(width 0.508)
		(layer "In2.Cu")
		(net "P1V05_NODE1")
	)
	(segment
		(start 96.46666 -124.61621)
		(end 96.96704 -125.11659)
		(width 0.508)
		(layer "In2.Cu")
		(net "P1V05_NODE1")
	)
	(segment
		(start 123.13412 -79.77886)
		(end 119.792242 -79.77886)
		(width 0.508)
		(layer "In2.Cu")
		(net "P1V05_NODE1")
	)
	(segment
		(start 119.792242 -79.77886)
		(end 110.317026 -89.254076)
		(width 0.508)
		(layer "In2.Cu")
		(net "P1V05_NODE1")
	)
	(segment
		(start 96.199706 -118.397528)
		(end 96.199706 -118.926864)
		(width 0.508)
		(layer "In2.Cu")
		(net "P1V05_NODE1")
	)
	(segment
		(start 124.24918 -110.700566)
		(end 124.83592 -110.113826)
		(width 0.508)
		(layer "In2.Cu")
		(net "P1V05_NODE1")
	)
	(segment
		(start 121.599198 -103.040942)
		(end 118.128542 -103.040942)
		(width 0.508)
		(layer "In2.Cu")
		(net "P1V05_NODE1")
	)
	(segment
		(start 110.317026 -89.254076)
		(end 105.467912 -89.254076)
		(width 0.508)
		(layer "In2.Cu")
		(net "P1V05_NODE1")
	)
	(segment
		(start 96.96704 -125.11659)
		(end 96.96704 -125.985016)
		(width 0.508)
		(layer "In2.Cu")
		(net "P1V05_NODE1")
	)
	(segment
		(start 96.87814 -104.258872)
		(end 96.87814 -110.324392)
		(width 0.508)
		(layer "In2.Cu")
		(net "P1V05_NODE1")
	)
	(segment
		(start 124.24918 -115.45443)
		(end 124.24918 -110.700566)
		(width 0.508)
		(layer "In2.Cu")
		(net "P1V05_NODE1")
	)
	(segment
		(start 96.56572 -103.946452)
		(end 96.87814 -104.258872)
		(width 0.508)
		(layer "In2.Cu")
		(net "P1V05_NODE1")
	)
	(segment
		(start 96.199706 -118.926864)
		(end 96.46666 -119.193818)
		(width 0.508)
		(layer "In2.Cu")
		(net "P1V05_NODE1")
	)
	(segment
		(start 169.831258 -134.040372)
		(end 169.881042 -134.090156)
		(width 0.508)
		(layer "In6.Cu")
		(net "P1V05_NODE1")
	)
	(segment
		(start 169.881042 -135.24738)
		(end 176.563528 -135.24738)
		(width 0.508)
		(layer "In6.Cu")
		(net "P1V05_NODE1")
	)
	(segment
		(start 176.563528 -135.24738)
		(end 178.09718 -136.781032)
		(width 0.508)
		(layer "In6.Cu")
		(net "P1V05_NODE1")
	)
	(segment
		(start 169.881042 -134.090156)
		(end 169.881042 -135.24738)
		(width 0.508)
		(layer "In6.Cu")
		(net "P1V05_NODE1")
	)
	(segment
		(start 100.50526 -130.687826)
		(end 100.50526 -130.244596)
		(width 0.508)
		(layer "In7.Cu")
		(net "P1V05_NODE1")
	)
	(segment
		(start 100.11664 -129.855976)
		(end 100.50526 -130.244596)
		(width 0.508)
		(layer "In7.Cu")
		(net "P1V05_NODE1")
	)
	(segment
		(start 101.85654 -139.26058)
		(end 101.85654 -136.545574)
		(width 0.508)
		(layer "In7.Cu")
		(net "P1V05_NODE1")
	)
	(segment
		(start 101.85654 -136.545574)
		(end 100.6729 -135.361934)
		(width 0.508)
		(layer "In7.Cu")
		(net "P1V05_NODE1")
	)
	(segment
		(start 101.74478 -134.060184)
		(end 101.74478 -131.927346)
		(width 0.508)
		(layer "In7.Cu")
		(net "P1V05_NODE1")
	)
	(segment
		(start 96.96704 -125.985016)
		(end 100.11664 -129.134616)
		(width 0.508)
		(layer "In7.Cu")
		(net "P1V05_NODE1")
	)
	(segment
		(start 101.74478 -131.927346)
		(end 100.50526 -130.687826)
		(width 0.508)
		(layer "In7.Cu")
		(net "P1V05_NODE1")
	)
	(segment
		(start 102.762812 -140.166852)
		(end 101.85654 -139.26058)
		(width 0.508)
		(layer "In7.Cu")
		(net "P1V05_NODE1")
	)
	(segment
		(start 100.11664 -129.134616)
		(end 100.11664 -129.855976)
		(width 0.508)
		(layer "In7.Cu")
		(net "P1V05_NODE1")
	)
	(segment
		(start 100.6729 -135.132064)
		(end 101.74478 -134.060184)
		(width 0.508)
		(layer "In7.Cu")
		(net "P1V05_NODE1")
	)
	(segment
		(start 100.6729 -135.361934)
		(end 100.6729 -135.132064)
		(width 0.508)
		(layer "In7.Cu")
		(net "P1V05_NODE1")
	)
	(segment
		(start 112.73663 -126.916942)
		(end 112.73663 -129.44729)
		(width 0.4572)
		(layer "F.Cu")
		(net "SW_VR_PVCCP_NODE1_VIN_FLT")
	)
	(segment
		(start 112.550956 -126.731268)
		(end 112.73663 -126.916942)
		(width 0.4572)
		(layer "F.Cu")
		(net "SW_VR_PVCCP_NODE1_VIN_FLT")
	)
	(via
		(at 114.506502 -125.220222)
		(size 0.508)
		(drill 0.254)
		(layers "F.Cu" "B.Cu")
		(net "SW_VR_PVCCP_NODE1_VIN_FLT")
	)
	(via
		(at 118.441978 -125.901704)
		(size 0.508)
		(drill 0.254)
		(layers "F.Cu" "B.Cu")
		(net "SW_VR_PVCCP_NODE1_VIN_FLT")
	)
	(via
		(at 115.51158 -125.879098)
		(size 0.508)
		(drill 0.254)
		(layers "F.Cu" "B.Cu")
		(net "SW_VR_PVCCP_NODE1_VIN_FLT")
	)
	(via
		(at 113.080546 -125.62586)
		(size 0.508)
		(drill 0.254)
		(layers "F.Cu" "B.Cu")
		(net "SW_VR_PVCCP_NODE1_VIN_FLT")
	)
	(via
		(at 113.122964 -124.626878)
		(size 0.508)
		(drill 0.254)
		(layers "F.Cu" "B.Cu")
		(net "SW_VR_PVCCP_NODE1_VIN_FLT")
	)
	(via
		(at 116.214398 -125.868684)
		(size 0.508)
		(drill 0.254)
		(layers "F.Cu" "B.Cu")
		(net "SW_VR_PVCCP_NODE1_VIN_FLT")
	)
	(via
		(at 117.73916 -125.912118)
		(size 0.508)
		(drill 0.254)
		(layers "F.Cu" "B.Cu")
		(net "SW_VR_PVCCP_NODE1_VIN_FLT")
	)
	(segment
		(start 96.891348 -170.927268)
		(end 96.183704 -170.219624)
		(width 0.1016)
		(layer "F.Cu")
		(net "FAN1_TACH_IN")
	)
	(segment
		(start 96.183704 -170.219624)
		(end 95.526098 -170.219624)
		(width 0.1016)
		(layer "F.Cu")
		(net "FAN1_TACH_IN")
	)
	(segment
		(start 94.851982 -170.219624)
		(end 95.526098 -170.219624)
		(width 0.1016)
		(layer "F.Cu")
		(net "FAN1_TACH_IN")
	)
	(segment
		(start 97.728532 -170.927268)
		(end 96.891348 -170.927268)
		(width 0.1016)
		(layer "F.Cu")
		(net "FAN1_TACH_IN")
	)
	(via
		(at 95.526098 -170.219624)
		(size 0.508)
		(drill 0.254)
		(layers "F.Cu" "B.Cu")
		(net "FAN1_TACH_IN")
	)
	(segment
		(start 41.544748 -129.363724)
		(end 41.870122 -129.363724)
		(width 0.1016)
		(layer "F.Cu")
		(net "BMC_NODE1_DDR_MA7")
	)
	(segment
		(start 42.416222 -128.817624)
		(end 42.416222 -128.811274)
		(width 0.1016)
		(layer "F.Cu")
		(net "BMC_NODE1_DDR_MA7")
	)
	(segment
		(start 42.416222 -128.811274)
		(end 43.155362 -127.658876)
		(width 0.1016)
		(layer "F.Cu")
		(net "BMC_NODE1_DDR_MA7")
	)
	(segment
		(start 55.717186 -128.03505)
		(end 52.885086 -128.03505)
		(width 0.1016)
		(layer "F.Cu")
		(net "BMC_NODE1_DDR_MA7")
	)
	(segment
		(start 44.458128 -126.345188)
		(end 48.711612 -126.345188)
		(width 0.1016)
		(layer "F.Cu")
		(net "BMC_NODE1_DDR_MA7")
	)
	(segment
		(start 49.966372 -127.599948)
		(end 50.76063 -127.897382)
		(width 0.1016)
		(layer "F.Cu")
		(net "BMC_NODE1_DDR_MA7")
	)
	(segment
		(start 43.155362 -127.647954)
		(end 44.458128 -126.345188)
		(width 0.1016)
		(layer "F.Cu")
		(net "BMC_NODE1_DDR_MA7")
	)
	(segment
		(start 48.711612 -126.345188)
		(end 49.966372 -127.599948)
		(width 0.1016)
		(layer "F.Cu")
		(net "BMC_NODE1_DDR_MA7")
	)
	(segment
		(start 43.155362 -127.658876)
		(end 43.155362 -127.647954)
		(width 0.1016)
		(layer "F.Cu")
		(net "BMC_NODE1_DDR_MA7")
	)
	(segment
		(start 41.201086 -129.557018)
		(end 41.544748 -129.363724)
		(width 0.1016)
		(layer "F.Cu")
		(net "BMC_NODE1_DDR_MA7")
	)
	(segment
		(start 41.870122 -129.363724)
		(end 42.416222 -128.817624)
		(width 0.1016)
		(layer "F.Cu")
		(net "BMC_NODE1_DDR_MA7")
	)
	(segment
		(start 40.83304 -129.763774)
		(end 41.201086 -129.557018)
		(width 0.1016)
		(layer "F.Cu")
		(net "BMC_NODE1_DDR_MA7")
	)
	(segment
		(start 50.76063 -127.897382)
		(end 51.127914 -128.03505)
		(width 0.1016)
		(layer "F.Cu")
		(net "BMC_NODE1_DDR_MA7")
	)
	(segment
		(start 57.34177 -129.659634)
		(end 55.717186 -128.03505)
		(width 0.1016)
		(layer "F.Cu")
		(net "BMC_NODE1_DDR_MA7")
	)
	(segment
		(start 51.127914 -128.03505)
		(end 52.885086 -128.03505)
		(width 0.1016)
		(layer "F.Cu")
		(net "BMC_NODE1_DDR_MA7")
	)
	(via
		(at 52.885086 -128.03505)
		(size 0.762)
		(drill 0.381)
		(layers "F.Cu" "B.Cu")
		(net "BMC_NODE1_DDR_MA7")
	)
	(segment
		(start 156.656532 -105.17378)
		(end 155.30195 -105.17378)
		(width 0.1016)
		(layer "F.Cu")
		(net "FM_CPLD_NODE1_USB_PERST_L")
	)
	(segment
		(start 155.2067 -106.744262)
		(end 155.2067 -107.464098)
		(width 0.1016)
		(layer "F.Cu")
		(net "FM_CPLD_NODE1_USB_PERST_L")
	)
	(segment
		(start 154.79522 -105.68051)
		(end 154.79522 -106.332782)
		(width 0.1016)
		(layer "F.Cu")
		(net "FM_CPLD_NODE1_USB_PERST_L")
	)
	(segment
		(start 155.30195 -105.17378)
		(end 154.79522 -105.68051)
		(width 0.1016)
		(layer "F.Cu")
		(net "FM_CPLD_NODE1_USB_PERST_L")
	)
	(segment
		(start 173.010322 -118.365524)
		(end 172.51045 -117.865652)
		(width 0.1016)
		(layer "F.Cu")
		(net "FM_CPLD_NODE1_USB_PERST_L")
	)
	(segment
		(start 154.79522 -106.332782)
		(end 155.2067 -106.744262)
		(width 0.1016)
		(layer "F.Cu")
		(net "FM_CPLD_NODE1_USB_PERST_L")
	)
	(segment
		(start 157.065472 -105.58272)
		(end 156.656532 -105.17378)
		(width 0.1016)
		(layer "F.Cu")
		(net "FM_CPLD_NODE1_USB_PERST_L")
	)
	(via
		(at 172.51045 -117.865652)
		(size 0.49022)
		(drill 0.254)
		(layers "F.Cu" "B.Cu")
		(net "FM_CPLD_NODE1_USB_PERST_L")
	)
	(via
		(at 155.2067 -107.464098)
		(size 0.508)
		(drill 0.254)
		(layers "F.Cu" "B.Cu")
		(net "FM_CPLD_NODE1_USB_PERST_L")
	)
	(segment
		(start 173.952662 -115.888516)
		(end 172.51045 -117.330728)
		(width 0.1143)
		(layer "In2.Cu")
		(net "FM_CPLD_NODE1_USB_PERST_L")
	)
	(segment
		(start 155.2067 -107.464098)
		(end 157.061154 -109.318552)
		(width 0.1143)
		(layer "In2.Cu")
		(net "FM_CPLD_NODE1_USB_PERST_L")
	)
	(segment
		(start 171.052744 -109.998256)
		(end 173.952662 -112.898174)
		(width 0.1143)
		(layer "In2.Cu")
		(net "FM_CPLD_NODE1_USB_PERST_L")
	)
	(segment
		(start 161.05632 -109.318552)
		(end 161.736024 -109.998256)
		(width 0.1143)
		(layer "In2.Cu")
		(net "FM_CPLD_NODE1_USB_PERST_L")
	)
	(segment
		(start 173.952662 -112.898174)
		(end 173.952662 -115.888516)
		(width 0.1143)
		(layer "In2.Cu")
		(net "FM_CPLD_NODE1_USB_PERST_L")
	)
	(segment
		(start 157.061154 -109.318552)
		(end 161.05632 -109.318552)
		(width 0.1143)
		(layer "In2.Cu")
		(net "FM_CPLD_NODE1_USB_PERST_L")
	)
	(segment
		(start 172.51045 -117.330728)
		(end 172.51045 -117.865652)
		(width 0.1143)
		(layer "In2.Cu")
		(net "FM_CPLD_NODE1_USB_PERST_L")
	)
	(segment
		(start 161.736024 -109.998256)
		(end 171.052744 -109.998256)
		(width 0.1143)
		(layer "In2.Cu")
		(net "FM_CPLD_NODE1_USB_PERST_L")
	)
	(segment
		(start 65.64757 -78.255622)
		(end 66.034158 -78.64221)
		(width 0.3048)
		(layer "F.Cu")
		(net "P1V05_VCCPLLCPU0SIO_NODE1")
	)
	(segment
		(start 65.630044 -78.255622)
		(end 65.64757 -78.255622)
		(width 0.3048)
		(layer "F.Cu")
		(net "P1V05_VCCPLLCPU0SIO_NODE1")
	)
	(segment
		(start 66.034158 -78.64221)
		(end 66.05143 -78.64221)
		(width 0.3048)
		(layer "F.Cu")
		(net "P1V05_VCCPLLCPU0SIO_NODE1")
	)
	(via
		(at 66.05143 -78.64221)
		(size 0.508)
		(drill 0.254)
		(layers "F.Cu" "B.Cu")
		(net "P1V05_VCCPLLCPU0SIO_NODE1")
	)
	(via
		(at 86.561168 -78.005178)
		(size 0.508)
		(drill 0.254)
		(layers "F.Cu" "B.Cu")
		(net "P1V05_VCCPLLCPU0SIO_NODE1")
	)
	(segment
		(start 71.460868 -77.677518)
		(end 71.218552 -77.919834)
		(width 0.508)
		(layer "In6.Cu")
		(net "P1V05_VCCPLLCPU0SIO_NODE1")
	)
	(segment
		(start 86.561168 -78.005178)
		(end 84.427822 -78.005178)
		(width 0.508)
		(layer "In6.Cu")
		(net "P1V05_VCCPLLCPU0SIO_NODE1")
	)
	(segment
		(start 72.809862 -77.677518)
		(end 71.460868 -77.677518)
		(width 0.508)
		(layer "In6.Cu")
		(net "P1V05_VCCPLLCPU0SIO_NODE1")
	)
	(segment
		(start 71.218552 -77.919834)
		(end 66.532506 -77.919834)
		(width 0.508)
		(layer "In6.Cu")
		(net "P1V05_VCCPLLCPU0SIO_NODE1")
	)
	(segment
		(start 78.838806 -77.588364)
		(end 78.474062 -77.953108)
		(width 0.508)
		(layer "In6.Cu")
		(net "P1V05_VCCPLLCPU0SIO_NODE1")
	)
	(segment
		(start 75.05827 -79.431896)
		(end 74.56424 -79.431896)
		(width 0.508)
		(layer "In6.Cu")
		(net "P1V05_VCCPLLCPU0SIO_NODE1")
	)
	(segment
		(start 84.011008 -77.588364)
		(end 78.838806 -77.588364)
		(width 0.508)
		(layer "In6.Cu")
		(net "P1V05_VCCPLLCPU0SIO_NODE1")
	)
	(segment
		(start 78.474062 -77.953108)
		(end 76.537058 -77.953108)
		(width 0.508)
		(layer "In6.Cu")
		(net "P1V05_VCCPLLCPU0SIO_NODE1")
	)
	(segment
		(start 66.05143 -78.40091)
		(end 66.05143 -78.64221)
		(width 0.508)
		(layer "In6.Cu")
		(net "P1V05_VCCPLLCPU0SIO_NODE1")
	)
	(segment
		(start 84.427822 -78.005178)
		(end 84.011008 -77.588364)
		(width 0.508)
		(layer "In6.Cu")
		(net "P1V05_VCCPLLCPU0SIO_NODE1")
	)
	(segment
		(start 66.532506 -77.919834)
		(end 66.05143 -78.40091)
		(width 0.508)
		(layer "In6.Cu")
		(net "P1V05_VCCPLLCPU0SIO_NODE1")
	)
	(segment
		(start 74.56424 -79.431896)
		(end 72.809862 -77.677518)
		(width 0.508)
		(layer "In6.Cu")
		(net "P1V05_VCCPLLCPU0SIO_NODE1")
	)
	(segment
		(start 76.537058 -77.953108)
		(end 75.05827 -79.431896)
		(width 0.508)
		(layer "In6.Cu")
		(net "P1V05_VCCPLLCPU0SIO_NODE1")
	)
	(segment
		(start 43.06951 -63.0555)
		(end 43.06951 -61.466984)
		(width 0.1143)
		(layer "F.Cu")
		(net "TP_CPU_NODE1_RP0_PLLMON0")
	)
	(segment
		(start 43.51528 -63.50127)
		(end 43.06951 -63.0555)
		(width 0.1143)
		(layer "F.Cu")
		(net "TP_CPU_NODE1_RP0_PLLMON0")
	)
	(segment
		(start 43.06951 -61.466984)
		(end 42.540682 -60.938156)
		(width 0.1143)
		(layer "F.Cu")
		(net "TP_CPU_NODE1_RP0_PLLMON0")
	)
	(via
		(at 42.540682 -60.938156)
		(size 0.508)
		(drill 0.254)
		(layers "F.Cu" "B.Cu")
		(net "TP_CPU_NODE1_RP0_PLLMON0")
	)
	(segment
		(start 45.799248 -70.070726)
		(end 45.799248 -70.080378)
		(width 0.127)
		(layer "F.Cu")
		(net "TP_CPU_NODE1_RP0_PETP7")
	)
	(segment
		(start 45.799248 -70.080378)
		(end 45.21835 -70.661276)
		(width 0.127)
		(layer "F.Cu")
		(net "TP_CPU_NODE1_RP0_PETP7")
	)
	(segment
		(start 45.21835 -70.661276)
		(end 45.21835 -70.870572)
		(width 0.127)
		(layer "F.Cu")
		(net "TP_CPU_NODE1_RP0_PETP7")
	)
	(via
		(at 45.21835 -70.870572)
		(size 0.508)
		(drill 0.254)
		(layers "F.Cu" "B.Cu")
		(net "TP_CPU_NODE1_RP0_PETP7")
	)
	(segment
		(start 66.78676 -176.473612)
		(end 65.464182 -175.151034)
		(width 0.1016)
		(layer "F.Cu")
		(net "PSU1_DC_OK_R_BUF")
	)
	(segment
		(start 66.78676 -179.922424)
		(end 66.78676 -176.473612)
		(width 0.1016)
		(layer "F.Cu")
		(net "PSU1_DC_OK_R_BUF")
	)
	(segment
		(start 66.21272 -181.098952)
		(end 66.78676 -180.524912)
		(width 0.1016)
		(layer "F.Cu")
		(net "PSU1_DC_OK_R_BUF")
	)
	(segment
		(start 65.464182 -175.151034)
		(end 65.464182 -174.752508)
		(width 0.1016)
		(layer "F.Cu")
		(net "PSU1_DC_OK_R_BUF")
	)
	(segment
		(start 66.78676 -180.524912)
		(end 66.78676 -179.922424)
		(width 0.1016)
		(layer "F.Cu")
		(net "PSU1_DC_OK_R_BUF")
	)
	(via
		(at 66.21272 -181.098952)
		(size 0.508)
		(drill 0.254)
		(layers "F.Cu" "B.Cu")
		(net "PSU1_DC_OK_R_BUF")
	)
	(via
		(at 53.821838 -183.86298)
		(size 0.508)
		(drill 0.254)
		(layers "F.Cu" "B.Cu")
		(net "PSU1_DC_OK_R_BUF")
	)
	(segment
		(start 53.550566 -183.86298)
		(end 53.821838 -183.86298)
		(width 0.1016)
		(layer "B.Cu")
		(net "PSU1_DC_OK_R_BUF")
	)
	(segment
		(start 52.81676 -184.805574)
		(end 52.81676 -184.596786)
		(width 0.1016)
		(layer "B.Cu")
		(net "PSU1_DC_OK_R_BUF")
	)
	(segment
		(start 53.821838 -183.182514)
		(end 53.821838 -183.86298)
		(width 0.1016)
		(layer "B.Cu")
		(net "PSU1_DC_OK_R_BUF")
	)
	(segment
		(start 52.81676 -184.596786)
		(end 53.550566 -183.86298)
		(width 0.1016)
		(layer "B.Cu")
		(net "PSU1_DC_OK_R_BUF")
	)
	(segment
		(start 53.031898 -182.392574)
		(end 53.821838 -183.182514)
		(width 0.1016)
		(layer "B.Cu")
		(net "PSU1_DC_OK_R_BUF")
	)
	(segment
		(start 52.81676 -182.392574)
		(end 53.031898 -182.392574)
		(width 0.1016)
		(layer "B.Cu")
		(net "PSU1_DC_OK_R_BUF")
	)
	(segment
		(start 54.306724 -183.86298)
		(end 55.608728 -182.560976)
		(width 0.1143)
		(layer "In6.Cu")
		(net "PSU1_DC_OK_R_BUF")
	)
	(segment
		(start 55.608728 -182.560976)
		(end 55.96382 -182.560976)
		(width 0.1143)
		(layer "In6.Cu")
		(net "PSU1_DC_OK_R_BUF")
	)
	(segment
		(start 53.821838 -183.86298)
		(end 54.306724 -183.86298)
		(width 0.1143)
		(layer "In6.Cu")
		(net "PSU1_DC_OK_R_BUF")
	)
	(segment
		(start 55.96382 -182.560976)
		(end 56.196484 -182.328312)
		(width 0.1143)
		(layer "In6.Cu")
		(net "PSU1_DC_OK_R_BUF")
	)
	(segment
		(start 64.038226 -181.386226)
		(end 65.925446 -181.386226)
		(width 0.1143)
		(layer "In6.Cu")
		(net "PSU1_DC_OK_R_BUF")
	)
	(segment
		(start 63.09614 -182.328312)
		(end 64.038226 -181.386226)
		(width 0.1143)
		(layer "In6.Cu")
		(net "PSU1_DC_OK_R_BUF")
	)
	(segment
		(start 56.196484 -182.328312)
		(end 63.09614 -182.328312)
		(width 0.1143)
		(layer "In6.Cu")
		(net "PSU1_DC_OK_R_BUF")
	)
	(segment
		(start 65.925446 -181.386226)
		(end 66.21272 -181.098952)
		(width 0.1143)
		(layer "In6.Cu")
		(net "PSU1_DC_OK_R_BUF")
	)
	(segment
		(start 175.007016 -118.365524)
		(end 174.53102 -117.889528)
		(width 0.1016)
		(layer "F.Cu")
		(net "CM_STATUS_LED_N")
	)
	(segment
		(start 99.58832 -175.970184)
		(end 100.08616 -176.468024)
		(width 0.1016)
		(layer "F.Cu")
		(net "CM_STATUS_LED_N")
	)
	(segment
		(start 100.08616 -178.728878)
		(end 99.50196 -179.313078)
		(width 0.1016)
		(layer "F.Cu")
		(net "CM_STATUS_LED_N")
	)
	(segment
		(start 99.531678 -179.342796)
		(end 99.50196 -179.313078)
		(width 0.1016)
		(layer "F.Cu")
		(net "CM_STATUS_LED_N")
	)
	(segment
		(start 175.010318 -118.365524)
		(end 175.007016 -118.365524)
		(width 0.1016)
		(layer "F.Cu")
		(net "CM_STATUS_LED_N")
	)
	(segment
		(start 99.531678 -180.66512)
		(end 99.531678 -179.342796)
		(width 0.1016)
		(layer "F.Cu")
		(net "CM_STATUS_LED_N")
	)
	(segment
		(start 100.08616 -176.468024)
		(end 100.08616 -178.728878)
		(width 0.1016)
		(layer "F.Cu")
		(net "CM_STATUS_LED_N")
	)
	(via
		(at 148.31822 -165.719506)
		(size 0.508)
		(drill 0.254)
		(layers "F.Cu" "B.Cu")
		(net "CM_STATUS_LED_N")
	)
	(via
		(at 99.58832 -175.970184)
		(size 0.508)
		(drill 0.254)
		(layers "F.Cu" "B.Cu")
		(net "CM_STATUS_LED_N")
	)
	(via
		(at 174.53102 -117.889528)
		(size 0.508)
		(drill 0.254)
		(layers "F.Cu" "B.Cu")
		(net "CM_STATUS_LED_N")
	)
	(via
		(at 99.50196 -179.313078)
		(size 0.508)
		(drill 0.254)
		(layers "F.Cu" "B.Cu")
		(net "CM_STATUS_LED_N")
	)
	(via
		(at 146.558 -157.487366)
		(size 0.508)
		(drill 0.254)
		(layers "F.Cu" "B.Cu")
		(net "CM_STATUS_LED_N")
	)
	(segment
		(start 99.50196 -179.314348)
		(end 99.32162 -179.494688)
		(width 0.1016)
		(layer "B.Cu")
		(net "CM_STATUS_LED_N")
	)
	(segment
		(start 95.66656 -181.616604)
		(end 96.28886 -180.994304)
		(width 0.1016)
		(layer "B.Cu")
		(net "CM_STATUS_LED_N")
	)
	(segment
		(start 96.28886 -179.954174)
		(end 96.748346 -179.494688)
		(width 0.1016)
		(layer "B.Cu")
		(net "CM_STATUS_LED_N")
	)
	(segment
		(start 95.66529 -181.616604)
		(end 95.66656 -181.616604)
		(width 0.1016)
		(layer "B.Cu")
		(net "CM_STATUS_LED_N")
	)
	(segment
		(start 96.748346 -179.494688)
		(end 97.52076 -179.494688)
		(width 0.1016)
		(layer "B.Cu")
		(net "CM_STATUS_LED_N")
	)
	(segment
		(start 99.50196 -179.313078)
		(end 99.50196 -179.314348)
		(width 0.1016)
		(layer "B.Cu")
		(net "CM_STATUS_LED_N")
	)
	(segment
		(start 99.32162 -179.494688)
		(end 97.52076 -179.494688)
		(width 0.1016)
		(layer "B.Cu")
		(net "CM_STATUS_LED_N")
	)
	(segment
		(start 96.28886 -180.994304)
		(end 96.28886 -179.954174)
		(width 0.1016)
		(layer "B.Cu")
		(net "CM_STATUS_LED_N")
	)
	(segment
		(start 151.71166 -142.305786)
		(end 151.71166 -144.71015)
		(width 0.1143)
		(layer "In2.Cu")
		(net "CM_STATUS_LED_N")
	)
	(segment
		(start 141.559026 -168.090596)
		(end 140.7287 -168.090596)
		(width 0.1143)
		(layer "In2.Cu")
		(net "CM_STATUS_LED_N")
	)
	(segment
		(start 108.27385 -176.189386)
		(end 107.923076 -175.838612)
		(width 0.1143)
		(layer "In2.Cu")
		(net "CM_STATUS_LED_N")
	)
	(segment
		(start 140.7287 -168.090596)
		(end 138.01598 -170.803316)
		(width 0.1143)
		(layer "In2.Cu")
		(net "CM_STATUS_LED_N")
	)
	(segment
		(start 146.686524 -166.959026)
		(end 142.690596 -166.959026)
		(width 0.1143)
		(layer "In2.Cu")
		(net "CM_STATUS_LED_N")
	)
	(segment
		(start 146.975068 -166.670482)
		(end 146.686524 -166.959026)
		(width 0.1143)
		(layer "In2.Cu")
		(net "CM_STATUS_LED_N")
	)
	(segment
		(start 165.285674 -127.134874)
		(end 165.285674 -128.72593)
		(width 0.1143)
		(layer "In2.Cu")
		(net "CM_STATUS_LED_N")
	)
	(segment
		(start 148.27377 -155.156916)
		(end 146.558 -156.872686)
		(width 0.1143)
		(layer "In2.Cu")
		(net "CM_STATUS_LED_N")
	)
	(segment
		(start 164.91331 -133.65353)
		(end 164.17544 -134.3914)
		(width 0.1143)
		(layer "In2.Cu")
		(net "CM_STATUS_LED_N")
	)
	(segment
		(start 156.425392 -134.922768)
		(end 152.10155 -139.24661)
		(width 0.1143)
		(layer "In2.Cu")
		(net "CM_STATUS_LED_N")
	)
	(segment
		(start 106.703114 -175.838612)
		(end 106.012488 -176.529238)
		(width 0.1143)
		(layer "In2.Cu")
		(net "CM_STATUS_LED_N")
	)
	(segment
		(start 109.24286 -176.131474)
		(end 109.184948 -176.189386)
		(width 0.1143)
		(layer "In2.Cu")
		(net "CM_STATUS_LED_N")
	)
	(segment
		(start 152.10155 -139.24661)
		(end 152.10155 -141.915896)
		(width 0.1143)
		(layer "In2.Cu")
		(net "CM_STATUS_LED_N")
	)
	(segment
		(start 164.91331 -129.098294)
		(end 164.91331 -133.65353)
		(width 0.1143)
		(layer "In2.Cu")
		(net "CM_STATUS_LED_N")
	)
	(segment
		(start 107.923076 -175.838612)
		(end 106.703114 -175.838612)
		(width 0.1143)
		(layer "In2.Cu")
		(net "CM_STATUS_LED_N")
	)
	(segment
		(start 151.71166 -144.71015)
		(end 150.96744 -145.45437)
		(width 0.1143)
		(layer "In2.Cu")
		(net "CM_STATUS_LED_N")
	)
	(segment
		(start 134.633716 -178.178968)
		(end 112.329214 -178.178968)
		(width 0.1143)
		(layer "In2.Cu")
		(net "CM_STATUS_LED_N")
	)
	(segment
		(start 112.329214 -178.178968)
		(end 110.28172 -176.131474)
		(width 0.1143)
		(layer "In2.Cu")
		(net "CM_STATUS_LED_N")
	)
	(segment
		(start 110.28172 -176.131474)
		(end 109.24286 -176.131474)
		(width 0.1143)
		(layer "In2.Cu")
		(net "CM_STATUS_LED_N")
	)
	(segment
		(start 150.96744 -150.104094)
		(end 148.27377 -152.797764)
		(width 0.1143)
		(layer "In2.Cu")
		(net "CM_STATUS_LED_N")
	)
	(segment
		(start 158.903162 -134.3914)
		(end 158.371794 -134.922768)
		(width 0.1143)
		(layer "In2.Cu")
		(net "CM_STATUS_LED_N")
	)
	(segment
		(start 167.33266 -125.0061)
		(end 167.33266 -125.087888)
		(width 0.1143)
		(layer "In2.Cu")
		(net "CM_STATUS_LED_N")
	)
	(segment
		(start 174.53102 -118.237762)
		(end 173.08068 -119.688102)
		(width 0.1143)
		(layer "In2.Cu")
		(net "CM_STATUS_LED_N")
	)
	(segment
		(start 167.589962 -124.748798)
		(end 167.33266 -125.0061)
		(width 0.1143)
		(layer "In2.Cu")
		(net "CM_STATUS_LED_N")
	)
	(segment
		(start 150.96744 -145.45437)
		(end 150.96744 -150.104094)
		(width 0.1143)
		(layer "In2.Cu")
		(net "CM_STATUS_LED_N")
	)
	(segment
		(start 174.53102 -117.889528)
		(end 174.53102 -118.237762)
		(width 0.1143)
		(layer "In2.Cu")
		(net "CM_STATUS_LED_N")
	)
	(segment
		(start 148.31822 -165.744144)
		(end 147.391882 -166.670482)
		(width 0.1143)
		(layer "In2.Cu")
		(net "CM_STATUS_LED_N")
	)
	(segment
		(start 147.391882 -166.670482)
		(end 146.975068 -166.670482)
		(width 0.1143)
		(layer "In2.Cu")
		(net "CM_STATUS_LED_N")
	)
	(segment
		(start 101.07422 -175.970184)
		(end 99.58832 -175.970184)
		(width 0.1143)
		(layer "In2.Cu")
		(net "CM_STATUS_LED_N")
	)
	(segment
		(start 168.143174 -124.748798)
		(end 167.589962 -124.748798)
		(width 0.1143)
		(layer "In2.Cu")
		(net "CM_STATUS_LED_N")
	)
	(segment
		(start 109.184948 -176.189386)
		(end 108.27385 -176.189386)
		(width 0.1143)
		(layer "In2.Cu")
		(net "CM_STATUS_LED_N")
	)
	(segment
		(start 106.012488 -176.529238)
		(end 101.633274 -176.529238)
		(width 0.1143)
		(layer "In2.Cu")
		(net "CM_STATUS_LED_N")
	)
	(segment
		(start 152.10155 -141.915896)
		(end 151.71166 -142.305786)
		(width 0.1143)
		(layer "In2.Cu")
		(net "CM_STATUS_LED_N")
	)
	(segment
		(start 148.27377 -152.797764)
		(end 148.27377 -155.156916)
		(width 0.1143)
		(layer "In2.Cu")
		(net "CM_STATUS_LED_N")
	)
	(segment
		(start 164.17544 -134.3914)
		(end 158.903162 -134.3914)
		(width 0.1143)
		(layer "In2.Cu")
		(net "CM_STATUS_LED_N")
	)
	(segment
		(start 138.01598 -174.796704)
		(end 134.633716 -178.178968)
		(width 0.1143)
		(layer "In2.Cu")
		(net "CM_STATUS_LED_N")
	)
	(segment
		(start 173.08068 -119.688102)
		(end 173.08068 -119.811292)
		(width 0.1143)
		(layer "In2.Cu")
		(net "CM_STATUS_LED_N")
	)
	(segment
		(start 138.01598 -170.803316)
		(end 138.01598 -174.796704)
		(width 0.1143)
		(layer "In2.Cu")
		(net "CM_STATUS_LED_N")
	)
	(segment
		(start 158.371794 -134.922768)
		(end 156.425392 -134.922768)
		(width 0.1143)
		(layer "In2.Cu")
		(net "CM_STATUS_LED_N")
	)
	(segment
		(start 146.558 -156.872686)
		(end 146.558 -157.487366)
		(width 0.1143)
		(layer "In2.Cu")
		(net "CM_STATUS_LED_N")
	)
	(segment
		(start 167.33266 -125.087888)
		(end 165.285674 -127.134874)
		(width 0.1143)
		(layer "In2.Cu")
		(net "CM_STATUS_LED_N")
	)
	(segment
		(start 142.690596 -166.959026)
		(end 141.559026 -168.090596)
		(width 0.1143)
		(layer "In2.Cu")
		(net "CM_STATUS_LED_N")
	)
	(segment
		(start 165.285674 -128.72593)
		(end 164.91331 -129.098294)
		(width 0.1143)
		(layer "In2.Cu")
		(net "CM_STATUS_LED_N")
	)
	(segment
		(start 173.08068 -119.811292)
		(end 168.143174 -124.748798)
		(width 0.1143)
		(layer "In2.Cu")
		(net "CM_STATUS_LED_N")
	)
	(segment
		(start 101.633274 -176.529238)
		(end 101.07422 -175.970184)
		(width 0.1143)
		(layer "In2.Cu")
		(net "CM_STATUS_LED_N")
	)
	(segment
		(start 148.31822 -165.719506)
		(end 148.31822 -165.744144)
		(width 0.1143)
		(layer "In2.Cu")
		(net "CM_STATUS_LED_N")
	)
	(segment
		(start 148.31822 -165.02253)
		(end 146.532092 -163.236402)
		(width 0.1143)
		(layer "In6.Cu")
		(net "CM_STATUS_LED_N")
	)
	(segment
		(start 148.31822 -165.719506)
		(end 148.31822 -165.02253)
		(width 0.1143)
		(layer "In6.Cu")
		(net "CM_STATUS_LED_N")
	)
	(segment
		(start 146.558 -157.984952)
		(end 146.558 -157.487366)
		(width 0.1143)
		(layer "In6.Cu")
		(net "CM_STATUS_LED_N")
	)
	(segment
		(start 146.532092 -163.236402)
		(end 146.532092 -158.01086)
		(width 0.1143)
		(layer "In6.Cu")
		(net "CM_STATUS_LED_N")
	)
	(segment
		(start 146.532092 -158.01086)
		(end 146.558 -157.984952)
		(width 0.1143)
		(layer "In6.Cu")
		(net "CM_STATUS_LED_N")
	)
	(segment
		(start 48.62576 -180.097684)
		(end 47.63008 -181.093364)
		(width 0.1016)
		(layer "F.Cu")
		(net "PSU6_DC_OK_R_BUF")
	)
	(segment
		(start 48.62576 -178.477418)
		(end 48.62576 -179.922424)
		(width 0.1016)
		(layer "F.Cu")
		(net "PSU6_DC_OK_R_BUF")
	)
	(segment
		(start 48.192182 -174.752508)
		(end 48.192182 -175.289464)
		(width 0.1016)
		(layer "F.Cu")
		(net "PSU6_DC_OK_R_BUF")
	)
	(segment
		(start 48.957484 -178.145694)
		(end 48.62576 -178.477418)
		(width 0.1016)
		(layer "F.Cu")
		(net "PSU6_DC_OK_R_BUF")
	)
	(segment
		(start 47.63008 -181.093364)
		(end 47.63008 -183.012842)
		(width 0.1016)
		(layer "F.Cu")
		(net "PSU6_DC_OK_R_BUF")
	)
	(segment
		(start 47.285656 -183.357266)
		(end 47.285656 -183.930036)
		(width 0.1016)
		(layer "F.Cu")
		(net "PSU6_DC_OK_R_BUF")
	)
	(segment
		(start 48.62576 -179.922424)
		(end 48.62576 -180.097684)
		(width 0.1016)
		(layer "F.Cu")
		(net "PSU6_DC_OK_R_BUF")
	)
	(segment
		(start 48.651668 -175.74895)
		(end 48.62576 -175.774858)
		(width 0.1016)
		(layer "F.Cu")
		(net "PSU6_DC_OK_R_BUF")
	)
	(segment
		(start 48.62576 -176.348136)
		(end 48.957484 -176.67986)
		(width 0.1016)
		(layer "F.Cu")
		(net "PSU6_DC_OK_R_BUF")
	)
	(segment
		(start 48.62576 -175.774858)
		(end 48.62576 -176.348136)
		(width 0.1016)
		(layer "F.Cu")
		(net "PSU6_DC_OK_R_BUF")
	)
	(segment
		(start 48.957484 -176.67986)
		(end 48.957484 -178.145694)
		(width 0.1016)
		(layer "F.Cu")
		(net "PSU6_DC_OK_R_BUF")
	)
	(segment
		(start 47.63008 -183.012842)
		(end 47.285656 -183.357266)
		(width 0.1016)
		(layer "F.Cu")
		(net "PSU6_DC_OK_R_BUF")
	)
	(segment
		(start 48.192182 -175.289464)
		(end 48.651668 -175.74895)
		(width 0.1016)
		(layer "F.Cu")
		(net "PSU6_DC_OK_R_BUF")
	)
	(via
		(at 48.651668 -175.74895)
		(size 0.508)
		(drill 0.254)
		(layers "F.Cu" "B.Cu")
		(net "PSU6_DC_OK_R_BUF")
	)
	(via
		(at 47.285656 -183.930036)
		(size 0.508)
		(drill 0.254)
		(layers "F.Cu" "B.Cu")
		(net "PSU6_DC_OK_R_BUF")
	)
	(segment
		(start 47.285656 -183.209438)
		(end 47.285656 -183.930036)
		(width 0.1016)
		(layer "B.Cu")
		(net "PSU6_DC_OK_R_BUF")
	)
	(segment
		(start 47.10176 -182.392574)
		(end 47.10176 -183.025542)
		(width 0.1016)
		(layer "B.Cu")
		(net "PSU6_DC_OK_R_BUF")
	)
	(segment
		(start 47.10176 -184.805574)
		(end 47.10176 -184.113932)
		(width 0.1016)
		(layer "B.Cu")
		(net "PSU6_DC_OK_R_BUF")
	)
	(segment
		(start 47.10176 -183.025542)
		(end 47.285656 -183.209438)
		(width 0.1016)
		(layer "B.Cu")
		(net "PSU6_DC_OK_R_BUF")
	)
	(segment
		(start 47.10176 -184.113932)
		(end 47.285656 -183.930036)
		(width 0.1016)
		(layer "B.Cu")
		(net "PSU6_DC_OK_R_BUF")
	)
	(segment
		(start 51.748182 -175.338232)
		(end 51.748182 -174.752508)
		(width 0.1016)
		(layer "F.Cu")
		(net "PSU5_DC_OK_R_BUF")
	)
	(segment
		(start 50.6349 -175.951896)
		(end 50.6349 -176.469802)
		(width 0.1016)
		(layer "F.Cu")
		(net "PSU5_DC_OK_R_BUF")
	)
	(segment
		(start 50.960274 -175.626522)
		(end 51.459892 -175.626522)
		(width 0.1016)
		(layer "F.Cu")
		(net "PSU5_DC_OK_R_BUF")
	)
	(segment
		(start 52.18176 -179.922424)
		(end 52.18176 -180.97754)
		(width 0.1016)
		(layer "F.Cu")
		(net "PSU5_DC_OK_R_BUF")
	)
	(segment
		(start 50.6349 -176.469802)
		(end 51.039522 -176.874424)
		(width 0.1016)
		(layer "F.Cu")
		(net "PSU5_DC_OK_R_BUF")
	)
	(segment
		(start 50.6349 -175.951896)
		(end 50.960274 -175.626522)
		(width 0.1016)
		(layer "F.Cu")
		(net "PSU5_DC_OK_R_BUF")
	)
	(segment
		(start 51.459892 -175.626522)
		(end 51.748182 -175.338232)
		(width 0.1016)
		(layer "F.Cu")
		(net "PSU5_DC_OK_R_BUF")
	)
	(segment
		(start 52.581556 -179.522628)
		(end 52.18176 -179.922424)
		(width 0.1016)
		(layer "F.Cu")
		(net "PSU5_DC_OK_R_BUF")
	)
	(segment
		(start 51.74742 -176.874424)
		(end 52.581556 -177.70856)
		(width 0.1016)
		(layer "F.Cu")
		(net "PSU5_DC_OK_R_BUF")
	)
	(segment
		(start 52.581556 -177.70856)
		(end 52.581556 -179.522628)
		(width 0.1016)
		(layer "F.Cu")
		(net "PSU5_DC_OK_R_BUF")
	)
	(segment
		(start 51.039522 -176.874424)
		(end 51.74742 -176.874424)
		(width 0.1016)
		(layer "F.Cu")
		(net "PSU5_DC_OK_R_BUF")
	)
	(via
		(at 52.18176 -180.97754)
		(size 0.508)
		(drill 0.254)
		(layers "F.Cu" "B.Cu")
		(net "PSU5_DC_OK_R_BUF")
	)
	(via
		(at 50.6349 -175.951896)
		(size 0.508)
		(drill 0.254)
		(layers "F.Cu" "B.Cu")
		(net "PSU5_DC_OK_R_BUF")
	)
	(via
		(at 48.5521 -183.923432)
		(size 0.508)
		(drill 0.254)
		(layers "F.Cu" "B.Cu")
		(net "PSU5_DC_OK_R_BUF")
	)
	(segment
		(start 48.24476 -182.392574)
		(end 48.24476 -183.025542)
		(width 0.1016)
		(layer "B.Cu")
		(net "PSU5_DC_OK_R_BUF")
	)
	(segment
		(start 48.24476 -183.025542)
		(end 48.5521 -183.332882)
		(width 0.1016)
		(layer "B.Cu")
		(net "PSU5_DC_OK_R_BUF")
	)
	(segment
		(start 48.24476 -184.805574)
		(end 48.24476 -184.230772)
		(width 0.1016)
		(layer "B.Cu")
		(net "PSU5_DC_OK_R_BUF")
	)
	(segment
		(start 48.5521 -183.332882)
		(end 48.5521 -183.923432)
		(width 0.1016)
		(layer "B.Cu")
		(net "PSU5_DC_OK_R_BUF")
	)
	(segment
		(start 48.24476 -184.230772)
		(end 48.5521 -183.923432)
		(width 0.1016)
		(layer "B.Cu")
		(net "PSU5_DC_OK_R_BUF")
	)
	(segment
		(start 50.555906 -181.46268)
		(end 51.437286 -181.46268)
		(width 0.1143)
		(layer "In6.Cu")
		(net "PSU5_DC_OK_R_BUF")
	)
	(segment
		(start 48.5521 -183.466486)
		(end 50.555906 -181.46268)
		(width 0.1143)
		(layer "In6.Cu")
		(net "PSU5_DC_OK_R_BUF")
	)
	(segment
		(start 48.5521 -183.923432)
		(end 48.5521 -183.466486)
		(width 0.1143)
		(layer "In6.Cu")
		(net "PSU5_DC_OK_R_BUF")
	)
	(segment
		(start 51.922426 -180.97754)
		(end 52.18176 -180.97754)
		(width 0.1143)
		(layer "In6.Cu")
		(net "PSU5_DC_OK_R_BUF")
	)
	(segment
		(start 51.437286 -181.46268)
		(end 51.922426 -180.97754)
		(width 0.1143)
		(layer "In6.Cu")
		(net "PSU5_DC_OK_R_BUF")
	)
	(segment
		(start 55.14467 -174.752508)
		(end 55.14467 -176.145444)
		(width 0.1016)
		(layer "F.Cu")
		(net "PSU4_DC_OK_R_BUF")
	)
	(segment
		(start 55.73776 -179.922424)
		(end 55.73776 -180.450744)
		(width 0.1016)
		(layer "F.Cu")
		(net "PSU4_DC_OK_R_BUF")
	)
	(segment
		(start 55.73776 -176.738534)
		(end 55.73776 -179.922424)
		(width 0.1016)
		(layer "F.Cu")
		(net "PSU4_DC_OK_R_BUF")
	)
	(segment
		(start 55.73776 -180.450744)
		(end 56.56834 -181.281324)
		(width 0.1016)
		(layer "F.Cu")
		(net "PSU4_DC_OK_R_BUF")
	)
	(segment
		(start 55.14467 -176.145444)
		(end 55.73776 -176.738534)
		(width 0.1016)
		(layer "F.Cu")
		(net "PSU4_DC_OK_R_BUF")
	)
	(via
		(at 49.804066 -183.881522)
		(size 0.508)
		(drill 0.254)
		(layers "F.Cu" "B.Cu")
		(net "PSU4_DC_OK_R_BUF")
	)
	(via
		(at 56.56834 -181.281324)
		(size 0.508)
		(drill 0.254)
		(layers "F.Cu" "B.Cu")
		(net "PSU4_DC_OK_R_BUF")
	)
	(segment
		(start 49.38776 -184.805574)
		(end 49.38776 -184.543192)
		(width 0.1016)
		(layer "B.Cu")
		(net "PSU4_DC_OK_R_BUF")
	)
	(segment
		(start 49.38776 -184.543192)
		(end 49.804066 -184.126886)
		(width 0.1016)
		(layer "B.Cu")
		(net "PSU4_DC_OK_R_BUF")
	)
	(segment
		(start 49.38776 -182.384192)
		(end 49.38776 -182.558182)
		(width 0.1016)
		(layer "B.Cu")
		(net "PSU4_DC_OK_R_BUF")
	)
	(segment
		(start 49.38776 -182.558182)
		(end 49.804066 -182.974488)
		(width 0.1016)
		(layer "B.Cu")
		(net "PSU4_DC_OK_R_BUF")
	)
	(segment
		(start 49.804066 -184.126886)
		(end 49.804066 -183.881522)
		(width 0.1016)
		(layer "B.Cu")
		(net "PSU4_DC_OK_R_BUF")
	)
	(segment
		(start 49.804066 -182.974488)
		(end 49.804066 -183.881522)
		(width 0.1016)
		(layer "B.Cu")
		(net "PSU4_DC_OK_R_BUF")
	)
	(segment
		(start 56.56834 -181.281324)
		(end 56.536336 -181.24932)
		(width 0.1143)
		(layer "In2.Cu")
		(net "PSU4_DC_OK_R_BUF")
	)
	(segment
		(start 54.79542 -181.52491)
		(end 54.79542 -183.374284)
		(width 0.1143)
		(layer "In2.Cu")
		(net "PSU4_DC_OK_R_BUF")
	)
	(segment
		(start 56.536336 -181.24932)
		(end 55.07101 -181.24932)
		(width 0.1143)
		(layer "In2.Cu")
		(net "PSU4_DC_OK_R_BUF")
	)
	(segment
		(start 50.351436 -184.428892)
		(end 49.804066 -183.881522)
		(width 0.1143)
		(layer "In2.Cu")
		(net "PSU4_DC_OK_R_BUF")
	)
	(segment
		(start 53.875686 -184.428892)
		(end 50.351436 -184.428892)
		(width 0.1143)
		(layer "In2.Cu")
		(net "PSU4_DC_OK_R_BUF")
	)
	(segment
		(start 54.79542 -183.374284)
		(end 54.63286 -183.536844)
		(width 0.1143)
		(layer "In2.Cu")
		(net "PSU4_DC_OK_R_BUF")
	)
	(segment
		(start 54.63286 -183.671718)
		(end 53.875686 -184.428892)
		(width 0.1143)
		(layer "In2.Cu")
		(net "PSU4_DC_OK_R_BUF")
	)
	(segment
		(start 55.07101 -181.24932)
		(end 54.79542 -181.52491)
		(width 0.1143)
		(layer "In2.Cu")
		(net "PSU4_DC_OK_R_BUF")
	)
	(segment
		(start 54.63286 -183.536844)
		(end 54.63286 -183.671718)
		(width 0.1143)
		(layer "In2.Cu")
		(net "PSU4_DC_OK_R_BUF")
	)
	(segment
		(start 59.42076 -179.922424)
		(end 59.42076 -177.75428)
		(width 0.1016)
		(layer "F.Cu")
		(net "PSU3_DC_OK_R_BUF")
	)
	(segment
		(start 58.606182 -175.511968)
		(end 58.606182 -174.752508)
		(width 0.1016)
		(layer "F.Cu")
		(net "PSU3_DC_OK_R_BUF")
	)
	(segment
		(start 59.856116 -176.761902)
		(end 58.606182 -175.511968)
		(width 0.1016)
		(layer "F.Cu")
		(net "PSU3_DC_OK_R_BUF")
	)
	(segment
		(start 59.42076 -181.113176)
		(end 59.67984 -181.372256)
		(width 0.1016)
		(layer "F.Cu")
		(net "PSU3_DC_OK_R_BUF")
	)
	(segment
		(start 59.42076 -177.75428)
		(end 59.856116 -177.318924)
		(width 0.1016)
		(layer "F.Cu")
		(net "PSU3_DC_OK_R_BUF")
	)
	(segment
		(start 59.42076 -179.922424)
		(end 59.42076 -181.113176)
		(width 0.1016)
		(layer "F.Cu")
		(net "PSU3_DC_OK_R_BUF")
	)
	(segment
		(start 59.856116 -177.318924)
		(end 59.856116 -176.761902)
		(width 0.1016)
		(layer "F.Cu")
		(net "PSU3_DC_OK_R_BUF")
	)
	(via
		(at 51.007518 -183.94172)
		(size 0.508)
		(drill 0.254)
		(layers "F.Cu" "B.Cu")
		(net "PSU3_DC_OK_R_BUF")
	)
	(via
		(at 59.67984 -181.372256)
		(size 0.508)
		(drill 0.254)
		(layers "F.Cu" "B.Cu")
		(net "PSU3_DC_OK_R_BUF")
	)
	(segment
		(start 50.53076 -184.805574)
		(end 50.53076 -184.65927)
		(width 0.1016)
		(layer "B.Cu")
		(net "PSU3_DC_OK_R_BUF")
	)
	(segment
		(start 50.53076 -182.392574)
		(end 50.53076 -182.506874)
		(width 0.1016)
		(layer "B.Cu")
		(net "PSU3_DC_OK_R_BUF")
	)
	(segment
		(start 50.53076 -182.506874)
		(end 51.007518 -182.983632)
		(width 0.1016)
		(layer "B.Cu")
		(net "PSU3_DC_OK_R_BUF")
	)
	(segment
		(start 51.007518 -184.182512)
		(end 51.007518 -183.94172)
		(width 0.1016)
		(layer "B.Cu")
		(net "PSU3_DC_OK_R_BUF")
	)
	(segment
		(start 51.007518 -182.983632)
		(end 51.007518 -183.94172)
		(width 0.1016)
		(layer "B.Cu")
		(net "PSU3_DC_OK_R_BUF")
	)
	(segment
		(start 50.53076 -184.65927)
		(end 51.007518 -184.182512)
		(width 0.1016)
		(layer "B.Cu")
		(net "PSU3_DC_OK_R_BUF")
	)
	(segment
		(start 54.010306 -181.77256)
		(end 54.87797 -180.904896)
		(width 0.1143)
		(layer "In6.Cu")
		(net "PSU3_DC_OK_R_BUF")
	)
	(segment
		(start 54.87797 -180.904896)
		(end 55.24119 -180.904896)
		(width 0.1143)
		(layer "In6.Cu")
		(net "PSU3_DC_OK_R_BUF")
	)
	(segment
		(start 51.007518 -183.94172)
		(end 51.007518 -183.554878)
		(width 0.1143)
		(layer "In6.Cu")
		(net "PSU3_DC_OK_R_BUF")
	)
	(segment
		(start 52.789836 -181.77256)
		(end 54.010306 -181.77256)
		(width 0.1143)
		(layer "In6.Cu")
		(net "PSU3_DC_OK_R_BUF")
	)
	(segment
		(start 55.24119 -180.904896)
		(end 56.055768 -181.719474)
		(width 0.1143)
		(layer "In6.Cu")
		(net "PSU3_DC_OK_R_BUF")
	)
	(segment
		(start 58.232802 -181.372256)
		(end 59.67984 -181.372256)
		(width 0.1143)
		(layer "In6.Cu")
		(net "PSU3_DC_OK_R_BUF")
	)
	(segment
		(start 56.055768 -181.719474)
		(end 57.885584 -181.719474)
		(width 0.1143)
		(layer "In6.Cu")
		(net "PSU3_DC_OK_R_BUF")
	)
	(segment
		(start 51.007518 -183.554878)
		(end 52.789836 -181.77256)
		(width 0.1143)
		(layer "In6.Cu")
		(net "PSU3_DC_OK_R_BUF")
	)
	(segment
		(start 57.885584 -181.719474)
		(end 58.232802 -181.372256)
		(width 0.1143)
		(layer "In6.Cu")
		(net "PSU3_DC_OK_R_BUF")
	)
	(segment
		(start 62.035182 -175.997362)
		(end 63.10376 -177.06594)
		(width 0.1016)
		(layer "F.Cu")
		(net "PSU2_DC_OK_R_BUF")
	)
	(segment
		(start 63.269368 -180.088032)
		(end 62.468506 -180.088032)
		(width 0.1016)
		(layer "F.Cu")
		(net "PSU2_DC_OK_R_BUF")
	)
	(segment
		(start 63.10376 -179.922424)
		(end 63.269368 -180.088032)
		(width 0.1016)
		(layer "F.Cu")
		(net "PSU2_DC_OK_R_BUF")
	)
	(segment
		(start 61.64072 -180.915818)
		(end 61.64072 -180.933598)
		(width 0.1016)
		(layer "F.Cu")
		(net "PSU2_DC_OK_R_BUF")
	)
	(segment
		(start 62.468506 -180.088032)
		(end 61.64072 -180.915818)
		(width 0.1016)
		(layer "F.Cu")
		(net "PSU2_DC_OK_R_BUF")
	)
	(segment
		(start 62.035182 -174.752508)
		(end 62.035182 -175.997362)
		(width 0.1016)
		(layer "F.Cu")
		(net "PSU2_DC_OK_R_BUF")
	)
	(segment
		(start 63.10376 -177.06594)
		(end 63.10376 -179.922424)
		(width 0.1016)
		(layer "F.Cu")
		(net "PSU2_DC_OK_R_BUF")
	)
	(via
		(at 52.294282 -183.990742)
		(size 0.508)
		(drill 0.254)
		(layers "F.Cu" "B.Cu")
		(net "PSU2_DC_OK_R_BUF")
	)
	(via
		(at 61.64072 -180.933598)
		(size 0.508)
		(drill 0.254)
		(layers "F.Cu" "B.Cu")
		(net "PSU2_DC_OK_R_BUF")
	)
	(segment
		(start 51.67376 -184.73801)
		(end 52.294282 -184.117488)
		(width 0.1016)
		(layer "B.Cu")
		(net "PSU2_DC_OK_R_BUF")
	)
	(segment
		(start 51.67376 -184.805574)
		(end 51.67376 -184.73801)
		(width 0.1016)
		(layer "B.Cu")
		(net "PSU2_DC_OK_R_BUF")
	)
	(segment
		(start 51.67376 -182.45582)
		(end 52.294282 -183.076342)
		(width 0.1016)
		(layer "B.Cu")
		(net "PSU2_DC_OK_R_BUF")
	)
	(segment
		(start 52.294282 -184.117488)
		(end 52.294282 -183.990742)
		(width 0.1016)
		(layer "B.Cu")
		(net "PSU2_DC_OK_R_BUF")
	)
	(segment
		(start 52.294282 -183.076342)
		(end 52.294282 -183.990742)
		(width 0.1016)
		(layer "B.Cu")
		(net "PSU2_DC_OK_R_BUF")
	)
	(segment
		(start 51.67376 -182.384192)
		(end 51.67376 -182.45582)
		(width 0.1016)
		(layer "B.Cu")
		(net "PSU2_DC_OK_R_BUF")
	)
	(segment
		(start 56.10606 -182.03926)
		(end 60.535058 -182.03926)
		(width 0.1143)
		(layer "In6.Cu")
		(net "PSU2_DC_OK_R_BUF")
	)
	(segment
		(start 53.820314 -182.12562)
		(end 56.0197 -182.12562)
		(width 0.1143)
		(layer "In6.Cu")
		(net "PSU2_DC_OK_R_BUF")
	)
	(segment
		(start 60.535058 -182.03926)
		(end 61.64072 -180.933598)
		(width 0.1143)
		(layer "In6.Cu")
		(net "PSU2_DC_OK_R_BUF")
	)
	(segment
		(start 52.294282 -183.990742)
		(end 52.294282 -183.651652)
		(width 0.1143)
		(layer "In6.Cu")
		(net "PSU2_DC_OK_R_BUF")
	)
	(segment
		(start 56.0197 -182.12562)
		(end 56.10606 -182.03926)
		(width 0.1143)
		(layer "In6.Cu")
		(net "PSU2_DC_OK_R_BUF")
	)
	(segment
		(start 52.294282 -183.651652)
		(end 53.820314 -182.12562)
		(width 0.1143)
		(layer "In6.Cu")
		(net "PSU2_DC_OK_R_BUF")
	)
	(segment
		(start 102.987348 -162.781488)
		(end 102.60838 -163.160456)
		(width 0.381)
		(layer "F.Cu")
		(net "POWER_SW1_PWR_CTR_12V")
	)
	(segment
		(start 102.387654 -161.76625)
		(end 102.387654 -162.93973)
		(width 0.381)
		(layer "F.Cu")
		(net "POWER_SW1_PWR_CTR_12V")
	)
	(segment
		(start 102.387654 -162.93973)
		(end 102.60838 -163.160456)
		(width 0.381)
		(layer "F.Cu")
		(net "POWER_SW1_PWR_CTR_12V")
	)
	(segment
		(start 103.673402 -162.781488)
		(end 102.987348 -162.781488)
		(width 0.381)
		(layer "F.Cu")
		(net "POWER_SW1_PWR_CTR_12V")
	)
	(via
		(at 180.213 -187.1472)
		(size 0.508)
		(drill 0.254)
		(layers "F.Cu" "B.Cu")
		(net "POWER_SW1_PWR_CTR_12V")
	)
	(via
		(at 102.60838 -163.160456)
		(size 0.508)
		(drill 0.254)
		(layers "F.Cu" "B.Cu")
		(net "POWER_SW1_PWR_CTR_12V")
	)
	(segment
		(start 169.5196 -184.15)
		(end 169.5196 -179.2732)
		(width 0.254)
		(layer "In7.Cu")
		(net "POWER_SW1_PWR_CTR_12V")
	)
	(segment
		(start 106.4514 -163.7538)
		(end 103.201724 -163.7538)
		(width 0.254)
		(layer "In7.Cu")
		(net "POWER_SW1_PWR_CTR_12V")
	)
	(segment
		(start 126.4158 -160.401)
		(end 125.7046 -160.401)
		(width 0.254)
		(layer "In7.Cu")
		(net "POWER_SW1_PWR_CTR_12V")
	)
	(segment
		(start 150.1648 -162.4838)
		(end 144.907 -162.4838)
		(width 0.254)
		(layer "In7.Cu")
		(net "POWER_SW1_PWR_CTR_12V")
	)
	(segment
		(start 179.5018 -187.1472)
		(end 177.5968 -189.0522)
		(width 0.254)
		(layer "In7.Cu")
		(net "POWER_SW1_PWR_CTR_12V")
	)
	(segment
		(start 103.201724 -163.7538)
		(end 102.60838 -163.160456)
		(width 0.254)
		(layer "In7.Cu")
		(net "POWER_SW1_PWR_CTR_12V")
	)
	(segment
		(start 118.0338 -163.449)
		(end 117.3988 -162.814)
		(width 0.254)
		(layer "In7.Cu")
		(net "POWER_SW1_PWR_CTR_12V")
	)
	(segment
		(start 141.0208 -162.7124)
		(end 140.7922 -162.4838)
		(width 0.254)
		(layer "In7.Cu")
		(net "POWER_SW1_PWR_CTR_12V")
	)
	(segment
		(start 157.8864 -169.3164)
		(end 156.083 -167.513)
		(width 0.254)
		(layer "In7.Cu")
		(net "POWER_SW1_PWR_CTR_12V")
	)
	(segment
		(start 111.233204 -162.3568)
		(end 107.8484 -162.3568)
		(width 0.254)
		(layer "In7.Cu")
		(net "POWER_SW1_PWR_CTR_12V")
	)
	(segment
		(start 126.6952 -160.6804)
		(end 126.4158 -160.401)
		(width 0.254)
		(layer "In7.Cu")
		(net "POWER_SW1_PWR_CTR_12V")
	)
	(segment
		(start 131.422902 -162.4838)
		(end 130.584702 -161.6456)
		(width 0.254)
		(layer "In7.Cu")
		(net "POWER_SW1_PWR_CTR_12V")
	)
	(segment
		(start 117.3988 -162.814)
		(end 115.1636 -162.814)
		(width 0.254)
		(layer "In7.Cu")
		(net "POWER_SW1_PWR_CTR_12V")
	)
	(segment
		(start 164.719 -174.0662)
		(end 159.9692 -169.3164)
		(width 0.254)
		(layer "In7.Cu")
		(net "POWER_SW1_PWR_CTR_12V")
	)
	(segment
		(start 120.396 -163.449)
		(end 118.0338 -163.449)
		(width 0.254)
		(layer "In7.Cu")
		(net "POWER_SW1_PWR_CTR_12V")
	)
	(segment
		(start 125.7046 -160.401)
		(end 123.6218 -162.4838)
		(width 0.254)
		(layer "In7.Cu")
		(net "POWER_SW1_PWR_CTR_12V")
	)
	(segment
		(start 164.719 -174.4726)
		(end 164.719 -174.0662)
		(width 0.254)
		(layer "In7.Cu")
		(net "POWER_SW1_PWR_CTR_12V")
	)
	(segment
		(start 140.7922 -162.4838)
		(end 131.422902 -162.4838)
		(width 0.254)
		(layer "In7.Cu")
		(net "POWER_SW1_PWR_CTR_12V")
	)
	(segment
		(start 123.6218 -162.4838)
		(end 121.3612 -162.4838)
		(width 0.254)
		(layer "In7.Cu")
		(net "POWER_SW1_PWR_CTR_12V")
	)
	(segment
		(start 156.083 -167.513)
		(end 155.194 -167.513)
		(width 0.254)
		(layer "In7.Cu")
		(net "POWER_SW1_PWR_CTR_12V")
	)
	(segment
		(start 121.3612 -162.4838)
		(end 120.396 -163.449)
		(width 0.254)
		(layer "In7.Cu")
		(net "POWER_SW1_PWR_CTR_12V")
	)
	(segment
		(start 177.5968 -189.0522)
		(end 174.4218 -189.0522)
		(width 0.254)
		(layer "In7.Cu")
		(net "POWER_SW1_PWR_CTR_12V")
	)
	(segment
		(start 115.1636 -162.814)
		(end 114.6556 -163.322)
		(width 0.254)
		(layer "In7.Cu")
		(net "POWER_SW1_PWR_CTR_12V")
	)
	(segment
		(start 126.6952 -160.9852)
		(end 126.6952 -160.6804)
		(width 0.254)
		(layer "In7.Cu")
		(net "POWER_SW1_PWR_CTR_12V")
	)
	(segment
		(start 144.907 -162.4838)
		(end 144.6784 -162.7124)
		(width 0.254)
		(layer "In7.Cu")
		(net "POWER_SW1_PWR_CTR_12V")
	)
	(segment
		(start 107.8484 -162.3568)
		(end 106.4514 -163.7538)
		(width 0.254)
		(layer "In7.Cu")
		(net "POWER_SW1_PWR_CTR_12V")
	)
	(segment
		(start 127.3556 -161.6456)
		(end 126.6952 -160.9852)
		(width 0.254)
		(layer "In7.Cu")
		(net "POWER_SW1_PWR_CTR_12V")
	)
	(segment
		(start 155.194 -167.513)
		(end 150.1648 -162.4838)
		(width 0.254)
		(layer "In7.Cu")
		(net "POWER_SW1_PWR_CTR_12V")
	)
	(segment
		(start 130.584702 -161.6456)
		(end 127.3556 -161.6456)
		(width 0.254)
		(layer "In7.Cu")
		(net "POWER_SW1_PWR_CTR_12V")
	)
	(segment
		(start 144.6784 -162.7124)
		(end 141.0208 -162.7124)
		(width 0.254)
		(layer "In7.Cu")
		(net "POWER_SW1_PWR_CTR_12V")
	)
	(segment
		(start 159.9692 -169.3164)
		(end 157.8864 -169.3164)
		(width 0.254)
		(layer "In7.Cu")
		(net "POWER_SW1_PWR_CTR_12V")
	)
	(segment
		(start 112.198404 -163.322)
		(end 111.233204 -162.3568)
		(width 0.254)
		(layer "In7.Cu")
		(net "POWER_SW1_PWR_CTR_12V")
	)
	(segment
		(start 114.6556 -163.322)
		(end 112.198404 -163.322)
		(width 0.254)
		(layer "In7.Cu")
		(net "POWER_SW1_PWR_CTR_12V")
	)
	(segment
		(start 174.4218 -189.0522)
		(end 169.5196 -184.15)
		(width 0.254)
		(layer "In7.Cu")
		(net "POWER_SW1_PWR_CTR_12V")
	)
	(segment
		(start 180.213 -187.1472)
		(end 179.5018 -187.1472)
		(width 0.254)
		(layer "In7.Cu")
		(net "POWER_SW1_PWR_CTR_12V")
	)
	(segment
		(start 169.5196 -179.2732)
		(end 164.719 -174.4726)
		(width 0.254)
		(layer "In7.Cu")
		(net "POWER_SW1_PWR_CTR_12V")
	)
	(segment
		(start 91.528138 -164.469826)
		(end 91.4146 -164.469826)
		(width 0.1016)
		(layer "F.Cu")
		(net "POWER_SW1_PWR_CTR_N")
	)
	(segment
		(start 91.769692 -162.060128)
		(end 91.769692 -162.812222)
		(width 0.1016)
		(layer "F.Cu")
		(net "POWER_SW1_PWR_CTR_N")
	)
	(segment
		(start 92.28836 -165.230048)
		(end 91.528138 -164.469826)
		(width 0.1016)
		(layer "F.Cu")
		(net "POWER_SW1_PWR_CTR_N")
	)
	(segment
		(start 90.631518 -163.686744)
		(end 90.631518 -163.618164)
		(width 0.1016)
		(layer "F.Cu")
		(net "POWER_SW1_PWR_CTR_N")
	)
	(segment
		(start 91.769692 -162.812222)
		(end 90.96375 -163.618164)
		(width 0.1016)
		(layer "F.Cu")
		(net "POWER_SW1_PWR_CTR_N")
	)
	(segment
		(start 91.4146 -164.469826)
		(end 90.631518 -163.686744)
		(width 0.1016)
		(layer "F.Cu")
		(net "POWER_SW1_PWR_CTR_N")
	)
	(segment
		(start 90.96375 -163.618164)
		(end 90.631518 -163.618164)
		(width 0.1016)
		(layer "F.Cu")
		(net "POWER_SW1_PWR_CTR_N")
	)
	(via
		(at 92.28836 -165.230048)
		(size 0.508)
		(drill 0.254)
		(layers "F.Cu" "B.Cu")
		(net "POWER_SW1_PWR_CTR_N")
	)
	(via
		(at 99.54514 -176.972468)
		(size 0.508)
		(drill 0.254)
		(layers "F.Cu" "B.Cu")
		(net "POWER_SW1_PWR_CTR_N")
	)
	(segment
		(start 100.680774 -178.844702)
		(end 99.54514 -177.709068)
		(width 0.1016)
		(layer "B.Cu")
		(net "POWER_SW1_PWR_CTR_N")
	)
	(segment
		(start 103.36276 -178.844702)
		(end 100.680774 -178.844702)
		(width 0.1016)
		(layer "B.Cu")
		(net "POWER_SW1_PWR_CTR_N")
	)
	(segment
		(start 99.54514 -177.709068)
		(end 99.54514 -176.972468)
		(width 0.1016)
		(layer "B.Cu")
		(net "POWER_SW1_PWR_CTR_N")
	)
	(segment
		(start 93.214444 -165.64229)
		(end 94.149672 -165.64229)
		(width 0.1143)
		(layer "In7.Cu")
		(net "POWER_SW1_PWR_CTR_N")
	)
	(segment
		(start 94.84614 -167.046656)
		(end 99.154488 -171.355004)
		(width 0.1143)
		(layer "In7.Cu")
		(net "POWER_SW1_PWR_CTR_N")
	)
	(segment
		(start 92.515182 -165.45687)
		(end 93.029024 -165.45687)
		(width 0.1143)
		(layer "In7.Cu")
		(net "POWER_SW1_PWR_CTR_N")
	)
	(segment
		(start 99.154488 -171.355004)
		(end 99.154488 -171.944284)
		(width 0.1143)
		(layer "In7.Cu")
		(net "POWER_SW1_PWR_CTR_N")
	)
	(segment
		(start 99.97948 -172.769276)
		(end 99.97948 -173.298104)
		(width 0.1143)
		(layer "In7.Cu")
		(net "POWER_SW1_PWR_CTR_N")
	)
	(segment
		(start 100.14458 -173.463204)
		(end 100.14458 -176.373028)
		(width 0.1143)
		(layer "In7.Cu")
		(net "POWER_SW1_PWR_CTR_N")
	)
	(segment
		(start 99.154488 -171.944284)
		(end 99.97948 -172.769276)
		(width 0.1143)
		(layer "In7.Cu")
		(net "POWER_SW1_PWR_CTR_N")
	)
	(segment
		(start 92.28836 -165.230048)
		(end 92.515182 -165.45687)
		(width 0.1143)
		(layer "In7.Cu")
		(net "POWER_SW1_PWR_CTR_N")
	)
	(segment
		(start 93.029024 -165.45687)
		(end 93.214444 -165.64229)
		(width 0.1143)
		(layer "In7.Cu")
		(net "POWER_SW1_PWR_CTR_N")
	)
	(segment
		(start 94.149672 -165.64229)
		(end 94.84614 -166.338758)
		(width 0.1143)
		(layer "In7.Cu")
		(net "POWER_SW1_PWR_CTR_N")
	)
	(segment
		(start 100.14458 -176.373028)
		(end 99.54514 -176.972468)
		(width 0.1143)
		(layer "In7.Cu")
		(net "POWER_SW1_PWR_CTR_N")
	)
	(segment
		(start 94.84614 -166.338758)
		(end 94.84614 -167.046656)
		(width 0.1143)
		(layer "In7.Cu")
		(net "POWER_SW1_PWR_CTR_N")
	)
	(segment
		(start 99.97948 -173.298104)
		(end 100.14458 -173.463204)
		(width 0.1143)
		(layer "In7.Cu")
		(net "POWER_SW1_PWR_CTR_N")
	)
	(via
		(at 148.73732 -53.471064)
		(size 0.508)
		(drill 0.254)
		(layers "F.Cu" "B.Cu")
		(net "SATA_P7")
	)
	(segment
		(start 119.83212 -199.7202)
		(end 120.015508 -199.903588)
		(width 0.1016)
		(layer "F.Cu")
		(net "UART_T8_NODE1_RXD_R")
	)
	(segment
		(start 120.015508 -199.903588)
		(end 120.015508 -205.199488)
		(width 0.1016)
		(layer "F.Cu")
		(net "UART_T8_NODE1_RXD_R")
	)
	(segment
		(start 121.65076 -188.526674)
		(end 121.65076 -192.213738)
		(width 0.1016)
		(layer "F.Cu")
		(net "UART_T8_NODE1_RXD_R")
	)
	(segment
		(start 121.65076 -192.213738)
		(end 120.015508 -193.84899)
		(width 0.1016)
		(layer "F.Cu")
		(net "UART_T8_NODE1_RXD_R")
	)
	(segment
		(start 120.015508 -193.84899)
		(end 120.015508 -199.536812)
		(width 0.1016)
		(layer "F.Cu")
		(net "UART_T8_NODE1_RXD_R")
	)
	(segment
		(start 120.015508 -199.536812)
		(end 119.83212 -199.7202)
		(width 0.1016)
		(layer "F.Cu")
		(net "UART_T8_NODE1_RXD_R")
	)
	(via
		(at 119.83212 -199.7202)
		(size 0.508)
		(drill 0.254)
		(layers "F.Cu" "B.Cu")
		(net "UART_T8_NODE1_RXD_R")
	)
	(via
		(at 134.01548 -198.454772)
		(size 0.6604)
		(drill 0.3302)
		(layers "F.Cu" "B.Cu")
		(net "T9_NODE3_EN_R")
	)
	(segment
		(start 134.01548 -198.001382)
		(end 134.01548 -198.454772)
		(width 0.1016)
		(layer "B.Cu")
		(net "T9_NODE3_EN_R")
	)
	(segment
		(start 137.65276 -185.351674)
		(end 137.65276 -186.21375)
		(width 0.1016)
		(layer "B.Cu")
		(net "T9_NODE3_EN_R")
	)
	(segment
		(start 134.01548 -205.199488)
		(end 134.01548 -198.454772)
		(width 0.1016)
		(layer "B.Cu")
		(net "T9_NODE3_EN_R")
	)
	(segment
		(start 135.8773 -192.460626)
		(end 135.8773 -196.139562)
		(width 0.1016)
		(layer "B.Cu")
		(net "T9_NODE3_EN_R")
	)
	(segment
		(start 137.65276 -188.272674)
		(end 137.65276 -190.685166)
		(width 0.1016)
		(layer "B.Cu")
		(net "T9_NODE3_EN_R")
	)
	(segment
		(start 137.144252 -186.722258)
		(end 137.144252 -187.764166)
		(width 0.1016)
		(layer "B.Cu")
		(net "T9_NODE3_EN_R")
	)
	(segment
		(start 135.8773 -196.139562)
		(end 134.01548 -198.001382)
		(width 0.1016)
		(layer "B.Cu")
		(net "T9_NODE3_EN_R")
	)
	(segment
		(start 137.65276 -190.685166)
		(end 135.8773 -192.460626)
		(width 0.1016)
		(layer "B.Cu")
		(net "T9_NODE3_EN_R")
	)
	(segment
		(start 137.144252 -187.764166)
		(end 137.65276 -188.272674)
		(width 0.1016)
		(layer "B.Cu")
		(net "T9_NODE3_EN_R")
	)
	(segment
		(start 137.65276 -186.21375)
		(end 137.144252 -186.722258)
		(width 0.1016)
		(layer "B.Cu")
		(net "T9_NODE3_EN_R")
	)
	(segment
		(start 108.015532 -202.195684)
		(end 108.015532 -205.199488)
		(width 0.1016)
		(layer "F.Cu")
		(net "T6_NODE3_EN_R")
	)
	(segment
		(start 108.4326 -198.057008)
		(end 108.56722 -198.191628)
		(width 0.1016)
		(layer "F.Cu")
		(net "T6_NODE3_EN_R")
	)
	(segment
		(start 108.56722 -201.643996)
		(end 108.015532 -202.195684)
		(width 0.1016)
		(layer "F.Cu")
		(net "T6_NODE3_EN_R")
	)
	(segment
		(start 108.34116 -196.456808)
		(end 108.343192 -196.456808)
		(width 0.1016)
		(layer "F.Cu")
		(net "T6_NODE3_EN_R")
	)
	(segment
		(start 109.45876 -191.808608)
		(end 109.45876 -188.526674)
		(width 0.1016)
		(layer "F.Cu")
		(net "T6_NODE3_EN_R")
	)
	(segment
		(start 109.45876 -186.17946)
		(end 109.97692 -186.69762)
		(width 0.1016)
		(layer "F.Cu")
		(net "T6_NODE3_EN_R")
	)
	(segment
		(start 108.343192 -196.456808)
		(end 108.343192 -192.924176)
		(width 0.1016)
		(layer "F.Cu")
		(net "T6_NODE3_EN_R")
	)
	(segment
		(start 108.343192 -192.924176)
		(end 109.45876 -191.808608)
		(width 0.1016)
		(layer "F.Cu")
		(net "T6_NODE3_EN_R")
	)
	(segment
		(start 109.97692 -186.69762)
		(end 109.97692 -188.008514)
		(width 0.1016)
		(layer "F.Cu")
		(net "T6_NODE3_EN_R")
	)
	(segment
		(start 108.56722 -198.191628)
		(end 108.56722 -201.643996)
		(width 0.1016)
		(layer "F.Cu")
		(net "T6_NODE3_EN_R")
	)
	(segment
		(start 108.34116 -197.965568)
		(end 108.34116 -196.456808)
		(width 0.1016)
		(layer "F.Cu")
		(net "T6_NODE3_EN_R")
	)
	(segment
		(start 109.45876 -185.605674)
		(end 109.45876 -186.17946)
		(width 0.1016)
		(layer "F.Cu")
		(net "T6_NODE3_EN_R")
	)
	(segment
		(start 109.97692 -188.008514)
		(end 109.45876 -188.526674)
		(width 0.1016)
		(layer "F.Cu")
		(net "T6_NODE3_EN_R")
	)
	(segment
		(start 108.4326 -198.057008)
		(end 108.34116 -197.965568)
		(width 0.1016)
		(layer "F.Cu")
		(net "T6_NODE3_EN_R")
	)
	(via
		(at 108.4326 -198.057008)
		(size 0.508)
		(drill 0.254)
		(layers "F.Cu" "B.Cu")
		(net "T6_NODE3_EN_R")
	)
	(via
		(at 133.015482 -199.67194)
		(size 0.6604)
		(drill 0.3302)
		(layers "F.Cu" "B.Cu")
		(net "T9_NODE4_EN_R")
	)
	(segment
		(start 136.50976 -188.272674)
		(end 136.50976 -190.649352)
		(width 0.1016)
		(layer "B.Cu")
		(net "T9_NODE4_EN_R")
	)
	(segment
		(start 133.015482 -198.174356)
		(end 133.015482 -199.67194)
		(width 0.1016)
		(layer "B.Cu")
		(net "T9_NODE4_EN_R")
	)
	(segment
		(start 136.50976 -185.351674)
		(end 136.50976 -186.200796)
		(width 0.1016)
		(layer "B.Cu")
		(net "T9_NODE4_EN_R")
	)
	(segment
		(start 136.001252 -186.709304)
		(end 136.001252 -187.764166)
		(width 0.1016)
		(layer "B.Cu")
		(net "T9_NODE4_EN_R")
	)
	(segment
		(start 136.001252 -187.764166)
		(end 136.50976 -188.272674)
		(width 0.1016)
		(layer "B.Cu")
		(net "T9_NODE4_EN_R")
	)
	(segment
		(start 135.11276 -192.046352)
		(end 135.11276 -196.077078)
		(width 0.1016)
		(layer "B.Cu")
		(net "T9_NODE4_EN_R")
	)
	(segment
		(start 136.50976 -186.200796)
		(end 136.001252 -186.709304)
		(width 0.1016)
		(layer "B.Cu")
		(net "T9_NODE4_EN_R")
	)
	(segment
		(start 133.015482 -199.67194)
		(end 133.015482 -205.199488)
		(width 0.1016)
		(layer "B.Cu")
		(net "T9_NODE4_EN_R")
	)
	(segment
		(start 135.11276 -196.077078)
		(end 133.015482 -198.174356)
		(width 0.1016)
		(layer "B.Cu")
		(net "T9_NODE4_EN_R")
	)
	(segment
		(start 136.50976 -190.649352)
		(end 135.11276 -192.046352)
		(width 0.1016)
		(layer "B.Cu")
		(net "T9_NODE4_EN_R")
	)
	(segment
		(start 181.269894 -9.997694)
		(end 180.765704 -10.501884)
		(width 0.1016)
		(layer "F.Cu")
		(net "LED_PWR_GD")
	)
	(segment
		(start 181.269894 -5.259832)
		(end 181.269894 -9.997694)
		(width 0.1016)
		(layer "F.Cu")
		(net "LED_PWR_GD")
	)
	(segment
		(start 180.765704 -10.501884)
		(end 180.765704 -11.13663)
		(width 0.1016)
		(layer "F.Cu")
		(net "LED_PWR_GD")
	)
	(segment
		(start 115.04676 -192.91554)
		(end 115.04676 -188.526674)
		(width 0.1016)
		(layer "F.Cu")
		(net "UART_T8_NODE3_TXD_R")
	)
	(segment
		(start 114.48796 -187.958222)
		(end 114.815112 -188.285374)
		(width 0.1016)
		(layer "F.Cu")
		(net "UART_T8_NODE3_TXD_R")
	)
	(segment
		(start 115.0747 -184.137808)
		(end 115.0747 -186.32932)
		(width 0.1016)
		(layer "F.Cu")
		(net "UART_T8_NODE3_TXD_R")
	)
	(segment
		(start 114.832384 -188.285374)
		(end 115.04676 -188.49975)
		(width 0.1016)
		(layer "F.Cu")
		(net "UART_T8_NODE3_TXD_R")
	)
	(segment
		(start 114.01552 -205.199488)
		(end 114.01552 -193.94678)
		(width 0.1016)
		(layer "F.Cu")
		(net "UART_T8_NODE3_TXD_R")
	)
	(segment
		(start 115.30584 -183.678068)
		(end 115.30584 -183.906668)
		(width 0.1016)
		(layer "F.Cu")
		(net "UART_T8_NODE3_TXD_R")
	)
	(segment
		(start 114.815112 -188.285374)
		(end 114.832384 -188.285374)
		(width 0.1016)
		(layer "F.Cu")
		(net "UART_T8_NODE3_TXD_R")
	)
	(segment
		(start 115.30584 -183.906668)
		(end 115.0747 -184.137808)
		(width 0.1016)
		(layer "F.Cu")
		(net "UART_T8_NODE3_TXD_R")
	)
	(segment
		(start 114.48796 -186.91606)
		(end 114.48796 -187.958222)
		(width 0.1016)
		(layer "F.Cu")
		(net "UART_T8_NODE3_TXD_R")
	)
	(segment
		(start 114.01552 -193.94678)
		(end 115.04676 -192.91554)
		(width 0.1016)
		(layer "F.Cu")
		(net "UART_T8_NODE3_TXD_R")
	)
	(segment
		(start 115.04676 -188.49975)
		(end 115.04676 -188.526674)
		(width 0.1016)
		(layer "F.Cu")
		(net "UART_T8_NODE3_TXD_R")
	)
	(segment
		(start 115.0747 -186.32932)
		(end 114.48796 -186.91606)
		(width 0.1016)
		(layer "F.Cu")
		(net "UART_T8_NODE3_TXD_R")
	)
	(via
		(at 115.30584 -183.678068)
		(size 0.508)
		(drill 0.254)
		(layers "F.Cu" "B.Cu")
		(net "UART_T8_NODE3_TXD_R")
	)
	(via
		(at 131.7752 -169.107104)
		(size 0.508)
		(drill 0.254)
		(layers "F.Cu" "B.Cu")
		(net "UART_T8_NODE3_TXD_R")
	)
	(segment
		(start 129.978912 -169.264838)
		(end 131.617466 -169.264838)
		(width 0.1016)
		(layer "B.Cu")
		(net "UART_T8_NODE3_TXD_R")
	)
	(segment
		(start 131.617466 -169.264838)
		(end 131.7752 -169.107104)
		(width 0.1016)
		(layer "B.Cu")
		(net "UART_T8_NODE3_TXD_R")
	)
	(segment
		(start 128.67132 -181.363112)
		(end 132.890768 -177.143664)
		(width 0.1143)
		(layer "In7.Cu")
		(net "UART_T8_NODE3_TXD_R")
	)
	(segment
		(start 115.30584 -183.744362)
		(end 116.454682 -184.893204)
		(width 0.1143)
		(layer "In7.Cu")
		(net "UART_T8_NODE3_TXD_R")
	)
	(segment
		(start 128.67132 -182.35041)
		(end 128.67132 -181.363112)
		(width 0.1143)
		(layer "In7.Cu")
		(net "UART_T8_NODE3_TXD_R")
	)
	(segment
		(start 126.128526 -184.893204)
		(end 128.67132 -182.35041)
		(width 0.1143)
		(layer "In7.Cu")
		(net "UART_T8_NODE3_TXD_R")
	)
	(segment
		(start 132.890768 -177.143664)
		(end 132.890768 -170.222672)
		(width 0.1143)
		(layer "In7.Cu")
		(net "UART_T8_NODE3_TXD_R")
	)
	(segment
		(start 132.890768 -170.222672)
		(end 131.7752 -169.107104)
		(width 0.1143)
		(layer "In7.Cu")
		(net "UART_T8_NODE3_TXD_R")
	)
	(segment
		(start 115.30584 -183.678068)
		(end 115.30584 -183.744362)
		(width 0.1143)
		(layer "In7.Cu")
		(net "UART_T8_NODE3_TXD_R")
	)
	(segment
		(start 116.454682 -184.893204)
		(end 126.128526 -184.893204)
		(width 0.1143)
		(layer "In7.Cu")
		(net "UART_T8_NODE3_TXD_R")
	)
	(segment
		(start 109.01553 -196.341746)
		(end 108.7755 -196.101716)
		(width 0.1016)
		(layer "F.Cu")
		(net "T6_NODE2_EN_R")
	)
	(segment
		(start 111.1504 -188.305694)
		(end 110.92942 -188.526674)
		(width 0.1016)
		(layer "F.Cu")
		(net "T6_NODE2_EN_R")
	)
	(segment
		(start 110.60176 -188.526674)
		(end 110.60176 -192.117472)
		(width 0.1016)
		(layer "F.Cu")
		(net "T6_NODE2_EN_R")
	)
	(segment
		(start 111.1504 -186.154314)
		(end 111.1504 -188.305694)
		(width 0.1016)
		(layer "F.Cu")
		(net "T6_NODE2_EN_R")
	)
	(segment
		(start 108.7247 -196.050916)
		(end 108.7755 -196.101716)
		(width 0.1016)
		(layer "F.Cu")
		(net "T6_NODE2_EN_R")
	)
	(segment
		(start 108.7247 -193.994532)
		(end 108.7247 -196.050916)
		(width 0.1016)
		(layer "F.Cu")
		(net "T6_NODE2_EN_R")
	)
	(segment
		(start 110.92942 -188.526674)
		(end 110.60176 -188.526674)
		(width 0.1016)
		(layer "F.Cu")
		(net "T6_NODE2_EN_R")
	)
	(segment
		(start 109.01553 -205.199488)
		(end 109.01553 -196.341746)
		(width 0.1016)
		(layer "F.Cu")
		(net "T6_NODE2_EN_R")
	)
	(segment
		(start 110.60176 -185.605674)
		(end 111.1504 -186.154314)
		(width 0.1016)
		(layer "F.Cu")
		(net "T6_NODE2_EN_R")
	)
	(segment
		(start 110.60176 -192.117472)
		(end 108.7247 -193.994532)
		(width 0.1016)
		(layer "F.Cu")
		(net "T6_NODE2_EN_R")
	)
	(via
		(at 108.7755 -196.101716)
		(size 0.508)
		(drill 0.254)
		(layers "F.Cu" "B.Cu")
		(net "T6_NODE2_EN_R")
	)
	(segment
		(start 55.65394 -186.708288)
		(end 55.65394 -187.941712)
		(width 0.1016)
		(layer "F.Cu")
		(net "I2C_PSU1_R_SCL")
	)
	(segment
		(start 53.93944 -196.411342)
		(end 53.9369 -196.413882)
		(width 0.1016)
		(layer "F.Cu")
		(net "I2C_PSU1_R_SCL")
	)
	(segment
		(start 55.10276 -185.605674)
		(end 55.10276 -186.157108)
		(width 0.1016)
		(layer "F.Cu")
		(net "I2C_PSU1_R_SCL")
	)
	(segment
		(start 55.10276 -188.492892)
		(end 55.10276 -188.526674)
		(width 0.1016)
		(layer "F.Cu")
		(net "I2C_PSU1_R_SCL")
	)
	(segment
		(start 53.01488 -199.766936)
		(end 53.93944 -198.842376)
		(width 0.1016)
		(layer "F.Cu")
		(net "I2C_PSU1_R_SCL")
	)
	(segment
		(start 55.10276 -192.635886)
		(end 53.93944 -193.799206)
		(width 0.1016)
		(layer "F.Cu")
		(net "I2C_PSU1_R_SCL")
	)
	(segment
		(start 53.93944 -198.842376)
		(end 53.93944 -196.416422)
		(width 0.1016)
		(layer "F.Cu")
		(net "I2C_PSU1_R_SCL")
	)
	(segment
		(start 53.93944 -193.799206)
		(end 53.93944 -196.411342)
		(width 0.1016)
		(layer "F.Cu")
		(net "I2C_PSU1_R_SCL")
	)
	(segment
		(start 53.93944 -196.416422)
		(end 53.9369 -196.413882)
		(width 0.1016)
		(layer "F.Cu")
		(net "I2C_PSU1_R_SCL")
	)
	(segment
		(start 55.65394 -187.941712)
		(end 55.10276 -188.492892)
		(width 0.1016)
		(layer "F.Cu")
		(net "I2C_PSU1_R_SCL")
	)
	(segment
		(start 53.01488 -205.199488)
		(end 53.01488 -199.766936)
		(width 0.1016)
		(layer "F.Cu")
		(net "I2C_PSU1_R_SCL")
	)
	(segment
		(start 55.10276 -186.157108)
		(end 55.65394 -186.708288)
		(width 0.1016)
		(layer "F.Cu")
		(net "I2C_PSU1_R_SCL")
	)
	(segment
		(start 55.10276 -188.526674)
		(end 55.10276 -192.635886)
		(width 0.1016)
		(layer "F.Cu")
		(net "I2C_PSU1_R_SCL")
	)
	(via
		(at 53.9369 -196.413882)
		(size 0.508)
		(drill 0.254)
		(layers "F.Cu" "B.Cu")
		(net "I2C_PSU1_R_SCL")
	)
	(segment
		(start 130.79476 -185.605674)
		(end 130.79476 -185.68289)
		(width 0.1016)
		(layer "F.Cu")
		(net "UART_T9_NODE3_TXD_R")
	)
	(segment
		(start 130.79476 -185.68289)
		(end 131.09448 -185.98261)
		(width 0.1016)
		(layer "F.Cu")
		(net "UART_T9_NODE3_TXD_R")
	)
	(segment
		(start 131.09448 -185.98261)
		(end 131.09448 -186.459622)
		(width 0.1016)
		(layer "F.Cu")
		(net "UART_T9_NODE3_TXD_R")
	)
	(segment
		(start 129.45618 -185.580782)
		(end 130.769868 -185.580782)
		(width 0.1016)
		(layer "F.Cu")
		(net "UART_T9_NODE3_TXD_R")
	)
	(segment
		(start 130.87096 -186.683142)
		(end 130.87096 -189.09919)
		(width 0.1016)
		(layer "F.Cu")
		(net "UART_T9_NODE3_TXD_R")
	)
	(segment
		(start 131.09448 -186.459622)
		(end 130.87096 -186.683142)
		(width 0.1016)
		(layer "F.Cu")
		(net "UART_T9_NODE3_TXD_R")
	)
	(segment
		(start 130.769868 -185.580782)
		(end 130.79476 -185.605674)
		(width 0.1016)
		(layer "F.Cu")
		(net "UART_T9_NODE3_TXD_R")
	)
	(segment
		(start 130.87096 -189.09919)
		(end 130.20294 -189.76721)
		(width 0.1016)
		(layer "F.Cu")
		(net "UART_T9_NODE3_TXD_R")
	)
	(via
		(at 130.20294 -189.76721)
		(size 0.508)
		(drill 0.254)
		(layers "F.Cu" "B.Cu")
		(net "UART_T9_NODE3_TXD_R")
	)
	(segment
		(start 125.015498 -205.199488)
		(end 125.015498 -198.948294)
		(width 0.1016)
		(layer "B.Cu")
		(net "UART_T9_NODE3_TXD_R")
	)
	(segment
		(start 129.565146 -193.06286)
		(end 129.565146 -190.405004)
		(width 0.1016)
		(layer "B.Cu")
		(net "UART_T9_NODE3_TXD_R")
	)
	(segment
		(start 129.565146 -190.405004)
		(end 130.20294 -189.76721)
		(width 0.1016)
		(layer "B.Cu")
		(net "UART_T9_NODE3_TXD_R")
	)
	(segment
		(start 125.015498 -198.948294)
		(end 125.606556 -198.357236)
		(width 0.1016)
		(layer "B.Cu")
		(net "UART_T9_NODE3_TXD_R")
	)
	(segment
		(start 125.606556 -198.357236)
		(end 125.606556 -197.02145)
		(width 0.1016)
		(layer "B.Cu")
		(net "UART_T9_NODE3_TXD_R")
	)
	(segment
		(start 125.606556 -197.02145)
		(end 129.565146 -193.06286)
		(width 0.1016)
		(layer "B.Cu")
		(net "UART_T9_NODE3_TXD_R")
	)
	(segment
		(start 53.95976 -192.385696)
		(end 53.95976 -188.526674)
		(width 0.1016)
		(layer "F.Cu")
		(net "I2C_PSU1_R_SDA")
	)
	(segment
		(start 53.975762 -188.526674)
		(end 53.95976 -188.526674)
		(width 0.1016)
		(layer "F.Cu")
		(net "I2C_PSU1_R_SDA")
	)
	(segment
		(start 52.37734 -195.980558)
		(end 52.37734 -193.968116)
		(width 0.1016)
		(layer "F.Cu")
		(net "I2C_PSU1_R_SDA")
	)
	(segment
		(start 52.37734 -193.968116)
		(end 53.95976 -192.385696)
		(width 0.1016)
		(layer "F.Cu")
		(net "I2C_PSU1_R_SDA")
	)
	(segment
		(start 52.37734 -196.42963)
		(end 52.014882 -196.792088)
		(width 0.1016)
		(layer "F.Cu")
		(net "I2C_PSU1_R_SDA")
	)
	(segment
		(start 54.5211 -187.981336)
		(end 53.975762 -188.526674)
		(width 0.1016)
		(layer "F.Cu")
		(net "I2C_PSU1_R_SDA")
	)
	(segment
		(start 53.95976 -186.0931)
		(end 54.5211 -186.65444)
		(width 0.1016)
		(layer "F.Cu")
		(net "I2C_PSU1_R_SDA")
	)
	(segment
		(start 53.95976 -185.605674)
		(end 53.95976 -186.0931)
		(width 0.1016)
		(layer "F.Cu")
		(net "I2C_PSU1_R_SDA")
	)
	(segment
		(start 52.37734 -195.980558)
		(end 52.37734 -196.42963)
		(width 0.1016)
		(layer "F.Cu")
		(net "I2C_PSU1_R_SDA")
	)
	(segment
		(start 52.014882 -196.792088)
		(end 52.014882 -205.199488)
		(width 0.1016)
		(layer "F.Cu")
		(net "I2C_PSU1_R_SDA")
	)
	(segment
		(start 54.5211 -186.65444)
		(end 54.5211 -187.981336)
		(width 0.1016)
		(layer "F.Cu")
		(net "I2C_PSU1_R_SDA")
	)
	(via
		(at 52.37734 -195.980558)
		(size 0.508)
		(drill 0.254)
		(layers "F.Cu" "B.Cu")
		(net "I2C_PSU1_R_SDA")
	)
	(via
		(at 92.015056 -199.751696)
		(size 0.6604)
		(drill 0.3302)
		(layers "F.Cu" "B.Cu")
		(net "UART_T5_NODE1_RXD_R")
	)
	(segment
		(start 92.015056 -199.751696)
		(end 91.97848 -199.71512)
		(width 0.1016)
		(layer "B.Cu")
		(net "UART_T5_NODE1_RXD_R")
	)
	(segment
		(start 91.98864 -197.193408)
		(end 91.98864 -196.772276)
		(width 0.1016)
		(layer "B.Cu")
		(net "UART_T5_NODE1_RXD_R")
	)
	(segment
		(start 91.7702 -197.873366)
		(end 91.88704 -197.756526)
		(width 0.1016)
		(layer "B.Cu")
		(net "UART_T5_NODE1_RXD_R")
	)
	(segment
		(start 91.98864 -196.772276)
		(end 91.88704 -196.670676)
		(width 0.1016)
		(layer "B.Cu")
		(net "UART_T5_NODE1_RXD_R")
	)
	(segment
		(start 91.88704 -197.756526)
		(end 91.88704 -197.295008)
		(width 0.1016)
		(layer "B.Cu")
		(net "UART_T5_NODE1_RXD_R")
	)
	(segment
		(start 91.7702 -198.661528)
		(end 91.7702 -197.873366)
		(width 0.1016)
		(layer "B.Cu")
		(net "UART_T5_NODE1_RXD_R")
	)
	(segment
		(start 92.015056 -205.199488)
		(end 92.015056 -199.751696)
		(width 0.1016)
		(layer "B.Cu")
		(net "UART_T5_NODE1_RXD_R")
	)
	(segment
		(start 91.97848 -198.869808)
		(end 91.7702 -198.661528)
		(width 0.1016)
		(layer "B.Cu")
		(net "UART_T5_NODE1_RXD_R")
	)
	(segment
		(start 91.88704 -197.295008)
		(end 91.98864 -197.193408)
		(width 0.1016)
		(layer "B.Cu")
		(net "UART_T5_NODE1_RXD_R")
	)
	(segment
		(start 91.502484 -189.391036)
		(end 91.502484 -188.858398)
		(width 0.1016)
		(layer "B.Cu")
		(net "UART_T5_NODE1_RXD_R")
	)
	(segment
		(start 91.88704 -189.775592)
		(end 91.502484 -189.391036)
		(width 0.1016)
		(layer "B.Cu")
		(net "UART_T5_NODE1_RXD_R")
	)
	(segment
		(start 91.88704 -196.670676)
		(end 91.88704 -189.775592)
		(width 0.1016)
		(layer "B.Cu")
		(net "UART_T5_NODE1_RXD_R")
	)
	(segment
		(start 91.97848 -199.71512)
		(end 91.97848 -198.869808)
		(width 0.1016)
		(layer "B.Cu")
		(net "UART_T5_NODE1_RXD_R")
	)
	(via
		(at 75.50912 -197.849744)
		(size 0.6604)
		(drill 0.3302)
		(layers "F.Cu" "B.Cu")
		(net "UART_T3_NODE1_RXD_R")
	)
	(segment
		(start 75.67676 -190.789306)
		(end 75.501246 -190.96482)
		(width 0.1016)
		(layer "B.Cu")
		(net "UART_T3_NODE1_RXD_R")
	)
	(segment
		(start 75.50912 -197.849744)
		(end 75.50912 -200.090278)
		(width 0.1016)
		(layer "B.Cu")
		(net "UART_T3_NODE1_RXD_R")
	)
	(segment
		(start 75.50912 -196.463412)
		(end 75.50912 -197.849744)
		(width 0.1016)
		(layer "B.Cu")
		(net "UART_T3_NODE1_RXD_R")
	)
	(segment
		(start 75.501246 -190.96482)
		(end 75.501246 -196.455538)
		(width 0.1016)
		(layer "B.Cu")
		(net "UART_T3_NODE1_RXD_R")
	)
	(segment
		(start 75.501246 -196.455538)
		(end 75.50912 -196.463412)
		(width 0.1016)
		(layer "B.Cu")
		(net "UART_T3_NODE1_RXD_R")
	)
	(segment
		(start 75.67676 -190.085726)
		(end 75.67676 -190.789306)
		(width 0.1016)
		(layer "B.Cu")
		(net "UART_T3_NODE1_RXD_R")
	)
	(segment
		(start 75.04176 -189.450726)
		(end 75.67676 -190.085726)
		(width 0.1016)
		(layer "B.Cu")
		(net "UART_T3_NODE1_RXD_R")
	)
	(segment
		(start 75.50912 -200.090278)
		(end 75.01509 -200.584308)
		(width 0.1016)
		(layer "B.Cu")
		(net "UART_T3_NODE1_RXD_R")
	)
	(segment
		(start 75.04176 -188.526674)
		(end 75.04176 -189.450726)
		(width 0.1016)
		(layer "B.Cu")
		(net "UART_T3_NODE1_RXD_R")
	)
	(segment
		(start 75.01509 -200.584308)
		(end 75.01509 -205.199488)
		(width 0.1016)
		(layer "B.Cu")
		(net "UART_T3_NODE1_RXD_R")
	)
	(via
		(at 90.5764 -198.649844)
		(size 0.6604)
		(drill 0.3302)
		(layers "F.Cu" "B.Cu")
		(net "UART_T5_NODE1_TXD_R")
	)
	(via
		(at 92.70492 -166.437564)
		(size 0.508)
		(drill 0.254)
		(layers "F.Cu" "B.Cu")
		(net "UART_T5_NODE1_TXD_R")
	)
	(via
		(at 90.02268 -190.296292)
		(size 0.508)
		(drill 0.254)
		(layers "F.Cu" "B.Cu")
		(net "UART_T5_NODE1_TXD_R")
	)
	(segment
		(start 91.965526 -161.830512)
		(end 91.21267 -161.830512)
		(width 0.1016)
		(layer "B.Cu")
		(net "UART_T5_NODE1_TXD_R")
	)
	(segment
		(start 90.97264 -205.158848)
		(end 90.97264 -199.046084)
		(width 0.1016)
		(layer "B.Cu")
		(net "UART_T5_NODE1_TXD_R")
	)
	(segment
		(start 93.5863 -164.154358)
		(end 93.5863 -162.4584)
		(width 0.1016)
		(layer "B.Cu")
		(net "UART_T5_NODE1_TXD_R")
	)
	(segment
		(start 90.02268 -190.296292)
		(end 90.270584 -190.048388)
		(width 0.1016)
		(layer "B.Cu")
		(net "UART_T5_NODE1_TXD_R")
	)
	(segment
		(start 90.64498 -190.918592)
		(end 90.02268 -190.296292)
		(width 0.1016)
		(layer "B.Cu")
		(net "UART_T5_NODE1_TXD_R")
	)
	(segment
		(start 92.84462 -164.896038)
		(end 93.5863 -164.154358)
		(width 0.1016)
		(layer "B.Cu")
		(net "UART_T5_NODE1_TXD_R")
	)
	(segment
		(start 92.70492 -166.437564)
		(end 92.84462 -166.297864)
		(width 0.1016)
		(layer "B.Cu")
		(net "UART_T5_NODE1_TXD_R")
	)
	(segment
		(start 92.84462 -166.297864)
		(end 92.84462 -164.896038)
		(width 0.1016)
		(layer "B.Cu")
		(net "UART_T5_NODE1_TXD_R")
	)
	(segment
		(start 90.5764 -196.211698)
		(end 90.64498 -196.143118)
		(width 0.1016)
		(layer "B.Cu")
		(net "UART_T5_NODE1_TXD_R")
	)
	(segment
		(start 90.270584 -187.98667)
		(end 90.414856 -187.842398)
		(width 0.1016)
		(layer "B.Cu")
		(net "UART_T5_NODE1_TXD_R")
	)
	(segment
		(start 90.270584 -190.048388)
		(end 90.270584 -187.98667)
		(width 0.1016)
		(layer "B.Cu")
		(net "UART_T5_NODE1_TXD_R")
	)
	(segment
		(start 90.64498 -196.143118)
		(end 90.64498 -190.918592)
		(width 0.1016)
		(layer "B.Cu")
		(net "UART_T5_NODE1_TXD_R")
	)
	(segment
		(start 93.5863 -162.4584)
		(end 92.95003 -161.82213)
		(width 0.1016)
		(layer "B.Cu")
		(net "UART_T5_NODE1_TXD_R")
	)
	(segment
		(start 91.015058 -205.199488)
		(end 91.01328 -205.199488)
		(width 0.1016)
		(layer "B.Cu")
		(net "UART_T5_NODE1_TXD_R")
	)
	(segment
		(start 90.414856 -187.842398)
		(end 90.702384 -187.842398)
		(width 0.1016)
		(layer "B.Cu")
		(net "UART_T5_NODE1_TXD_R")
	)
	(segment
		(start 91.01328 -205.199488)
		(end 90.97264 -205.158848)
		(width 0.1016)
		(layer "B.Cu")
		(net "UART_T5_NODE1_TXD_R")
	)
	(segment
		(start 92.95003 -161.82213)
		(end 91.973908 -161.82213)
		(width 0.1016)
		(layer "B.Cu")
		(net "UART_T5_NODE1_TXD_R")
	)
	(segment
		(start 90.97264 -199.046084)
		(end 90.5764 -198.649844)
		(width 0.1016)
		(layer "B.Cu")
		(net "UART_T5_NODE1_TXD_R")
	)
	(segment
		(start 90.5764 -198.649844)
		(end 90.5764 -196.211698)
		(width 0.1016)
		(layer "B.Cu")
		(net "UART_T5_NODE1_TXD_R")
	)
	(segment
		(start 91.973908 -161.82213)
		(end 91.965526 -161.830512)
		(width 0.1016)
		(layer "B.Cu")
		(net "UART_T5_NODE1_TXD_R")
	)
	(segment
		(start 90.42654 -172.729652)
		(end 90.96502 -172.191172)
		(width 0.1143)
		(layer "In7.Cu")
		(net "UART_T5_NODE1_TXD_R")
	)
	(segment
		(start 92.852748 -166.585392)
		(end 92.70492 -166.437564)
		(width 0.1143)
		(layer "In7.Cu")
		(net "UART_T5_NODE1_TXD_R")
	)
	(segment
		(start 87.34552 -185.89117)
		(end 88.60917 -184.627266)
		(width 0.1143)
		(layer "In7.Cu")
		(net "UART_T5_NODE1_TXD_R")
	)
	(segment
		(start 89.027 -182.788052)
		(end 89.87028 -181.944772)
		(width 0.1143)
		(layer "In7.Cu")
		(net "UART_T5_NODE1_TXD_R")
	)
	(segment
		(start 93.87586 -166.841932)
		(end 93.61932 -166.585392)
		(width 0.1143)
		(layer "In7.Cu")
		(net "UART_T5_NODE1_TXD_R")
	)
	(segment
		(start 89.87028 -176.732946)
		(end 90.42654 -176.176686)
		(width 0.1143)
		(layer "In7.Cu")
		(net "UART_T5_NODE1_TXD_R")
	)
	(segment
		(start 89.87028 -181.944772)
		(end 89.87028 -176.732946)
		(width 0.1143)
		(layer "In7.Cu")
		(net "UART_T5_NODE1_TXD_R")
	)
	(segment
		(start 88.60917 -183.822848)
		(end 89.027 -183.405018)
		(width 0.1143)
		(layer "In7.Cu")
		(net "UART_T5_NODE1_TXD_R")
	)
	(segment
		(start 93.05036 -168.857676)
		(end 93.36532 -168.542716)
		(width 0.1143)
		(layer "In7.Cu")
		(net "UART_T5_NODE1_TXD_R")
	)
	(segment
		(start 93.61932 -166.585392)
		(end 92.852748 -166.585392)
		(width 0.1143)
		(layer "In7.Cu")
		(net "UART_T5_NODE1_TXD_R")
	)
	(segment
		(start 87.34552 -186.944)
		(end 87.34552 -185.89117)
		(width 0.1143)
		(layer "In7.Cu")
		(net "UART_T5_NODE1_TXD_R")
	)
	(segment
		(start 88.60917 -184.627266)
		(end 88.60917 -183.822848)
		(width 0.1143)
		(layer "In7.Cu")
		(net "UART_T5_NODE1_TXD_R")
	)
	(segment
		(start 91.740228 -169.380662)
		(end 92.173552 -169.380662)
		(width 0.1143)
		(layer "In7.Cu")
		(net "UART_T5_NODE1_TXD_R")
	)
	(segment
		(start 89.786714 -190.060326)
		(end 89.786714 -189.385194)
		(width 0.1143)
		(layer "In7.Cu")
		(net "UART_T5_NODE1_TXD_R")
	)
	(segment
		(start 90.96502 -172.191172)
		(end 90.96502 -170.15587)
		(width 0.1143)
		(layer "In7.Cu")
		(net "UART_T5_NODE1_TXD_R")
	)
	(segment
		(start 90.02268 -190.296292)
		(end 89.786714 -190.060326)
		(width 0.1143)
		(layer "In7.Cu")
		(net "UART_T5_NODE1_TXD_R")
	)
	(segment
		(start 93.87586 -167.203374)
		(end 93.87586 -166.841932)
		(width 0.1143)
		(layer "In7.Cu")
		(net "UART_T5_NODE1_TXD_R")
	)
	(segment
		(start 92.696538 -168.857676)
		(end 93.05036 -168.857676)
		(width 0.1143)
		(layer "In7.Cu")
		(net "UART_T5_NODE1_TXD_R")
	)
	(segment
		(start 90.96502 -170.15587)
		(end 91.740228 -169.380662)
		(width 0.1143)
		(layer "In7.Cu")
		(net "UART_T5_NODE1_TXD_R")
	)
	(segment
		(start 89.027 -183.405018)
		(end 89.027 -182.788052)
		(width 0.1143)
		(layer "In7.Cu")
		(net "UART_T5_NODE1_TXD_R")
	)
	(segment
		(start 92.173552 -169.380662)
		(end 92.696538 -168.857676)
		(width 0.1143)
		(layer "In7.Cu")
		(net "UART_T5_NODE1_TXD_R")
	)
	(segment
		(start 90.42654 -176.176686)
		(end 90.42654 -172.729652)
		(width 0.1143)
		(layer "In7.Cu")
		(net "UART_T5_NODE1_TXD_R")
	)
	(segment
		(start 93.36532 -167.713914)
		(end 93.87586 -167.203374)
		(width 0.1143)
		(layer "In7.Cu")
		(net "UART_T5_NODE1_TXD_R")
	)
	(segment
		(start 93.36532 -168.542716)
		(end 93.36532 -167.713914)
		(width 0.1143)
		(layer "In7.Cu")
		(net "UART_T5_NODE1_TXD_R")
	)
	(segment
		(start 89.786714 -189.385194)
		(end 87.34552 -186.944)
		(width 0.1143)
		(layer "In7.Cu")
		(net "UART_T5_NODE1_TXD_R")
	)
	(via
		(at 74.53376 -190.08852)
		(size 0.508)
		(drill 0.254)
		(layers "F.Cu" "B.Cu")
		(net "UART_T3_NODE1_TXD_R")
	)
	(via
		(at 74.3839 -166.715186)
		(size 0.508)
		(drill 0.254)
		(layers "F.Cu" "B.Cu")
		(net "UART_T3_NODE1_TXD_R")
	)
	(segment
		(start 74.02576 -189.58052)
		(end 74.53376 -190.08852)
		(width 0.1016)
		(layer "B.Cu")
		(net "UART_T3_NODE1_TXD_R")
	)
	(segment
		(start 74.015092 -205.199488)
		(end 74.015092 -201.838306)
		(width 0.1016)
		(layer "B.Cu")
		(net "UART_T3_NODE1_TXD_R")
	)
	(segment
		(start 74.4474 -199.506586)
		(end 74.50836 -199.445626)
		(width 0.1016)
		(layer "B.Cu")
		(net "UART_T3_NODE1_TXD_R")
	)
	(segment
		(start 74.50836 -190.11392)
		(end 74.53376 -190.08852)
		(width 0.1016)
		(layer "B.Cu")
		(net "UART_T3_NODE1_TXD_R")
	)
	(segment
		(start 74.27468 -165.707568)
		(end 74.27468 -166.605966)
		(width 0.1016)
		(layer "B.Cu")
		(net "UART_T3_NODE1_TXD_R")
	)
	(segment
		(start 74.015092 -201.838306)
		(end 74.4474 -201.405998)
		(width 0.1016)
		(layer "B.Cu")
		(net "UART_T3_NODE1_TXD_R")
	)
	(segment
		(start 74.50836 -199.445626)
		(end 74.50836 -190.11392)
		(width 0.1016)
		(layer "B.Cu")
		(net "UART_T3_NODE1_TXD_R")
	)
	(segment
		(start 74.27468 -166.605966)
		(end 74.3839 -166.715186)
		(width 0.1016)
		(layer "B.Cu")
		(net "UART_T3_NODE1_TXD_R")
	)
	(segment
		(start 74.4474 -201.405998)
		(end 74.4474 -199.506586)
		(width 0.1016)
		(layer "B.Cu")
		(net "UART_T3_NODE1_TXD_R")
	)
	(segment
		(start 74.02576 -188.526674)
		(end 74.02576 -189.58052)
		(width 0.1016)
		(layer "B.Cu")
		(net "UART_T3_NODE1_TXD_R")
	)
	(segment
		(start 76.073 -174.065184)
		(end 76.073 -171.19727)
		(width 0.1143)
		(layer "In7.Cu")
		(net "UART_T3_NODE1_TXD_R")
	)
	(segment
		(start 72.068182 -187.622942)
		(end 70.990714 -187.622942)
		(width 0.1143)
		(layer "In7.Cu")
		(net "UART_T3_NODE1_TXD_R")
	)
	(segment
		(start 69.86016 -181.955948)
		(end 70.385432 -181.430676)
		(width 0.1143)
		(layer "In7.Cu")
		(net "UART_T3_NODE1_TXD_R")
	)
	(segment
		(start 73.533508 -177.889154)
		(end 75.60945 -175.813212)
		(width 0.1143)
		(layer "In7.Cu")
		(net "UART_T3_NODE1_TXD_R")
	)
	(segment
		(start 75.34148 -170.46575)
		(end 75.34148 -169.508932)
		(width 0.1143)
		(layer "In7.Cu")
		(net "UART_T3_NODE1_TXD_R")
	)
	(segment
		(start 73.533508 -179.054252)
		(end 73.533508 -177.889154)
		(width 0.1143)
		(layer "In7.Cu")
		(net "UART_T3_NODE1_TXD_R")
	)
	(segment
		(start 70.385432 -181.430676)
		(end 71.157084 -181.430676)
		(width 0.1143)
		(layer "In7.Cu")
		(net "UART_T3_NODE1_TXD_R")
	)
	(segment
		(start 76.073 -171.19727)
		(end 75.34148 -170.46575)
		(width 0.1143)
		(layer "In7.Cu")
		(net "UART_T3_NODE1_TXD_R")
	)
	(segment
		(start 74.53376 -190.08852)
		(end 72.068182 -187.622942)
		(width 0.1143)
		(layer "In7.Cu")
		(net "UART_T3_NODE1_TXD_R")
	)
	(segment
		(start 70.39991 -185.54827)
		(end 69.25818 -184.40654)
		(width 0.1143)
		(layer "In7.Cu")
		(net "UART_T3_NODE1_TXD_R")
	)
	(segment
		(start 74.69886 -167.77843)
		(end 74.3839 -167.46347)
		(width 0.1143)
		(layer "In7.Cu")
		(net "UART_T3_NODE1_TXD_R")
	)
	(segment
		(start 71.157084 -181.430676)
		(end 73.533508 -179.054252)
		(width 0.1143)
		(layer "In7.Cu")
		(net "UART_T3_NODE1_TXD_R")
	)
	(segment
		(start 74.69886 -168.866312)
		(end 74.69886 -167.77843)
		(width 0.1143)
		(layer "In7.Cu")
		(net "UART_T3_NODE1_TXD_R")
	)
	(segment
		(start 69.25818 -183.07177)
		(end 69.86016 -182.46979)
		(width 0.1143)
		(layer "In7.Cu")
		(net "UART_T3_NODE1_TXD_R")
	)
	(segment
		(start 69.25818 -184.40654)
		(end 69.25818 -183.07177)
		(width 0.1143)
		(layer "In7.Cu")
		(net "UART_T3_NODE1_TXD_R")
	)
	(segment
		(start 75.34148 -169.508932)
		(end 74.69886 -168.866312)
		(width 0.1143)
		(layer "In7.Cu")
		(net "UART_T3_NODE1_TXD_R")
	)
	(segment
		(start 70.39991 -187.032138)
		(end 70.39991 -185.54827)
		(width 0.1143)
		(layer "In7.Cu")
		(net "UART_T3_NODE1_TXD_R")
	)
	(segment
		(start 75.60945 -174.528734)
		(end 76.073 -174.065184)
		(width 0.1143)
		(layer "In7.Cu")
		(net "UART_T3_NODE1_TXD_R")
	)
	(segment
		(start 75.60945 -175.813212)
		(end 75.60945 -174.528734)
		(width 0.1143)
		(layer "In7.Cu")
		(net "UART_T3_NODE1_TXD_R")
	)
	(segment
		(start 69.86016 -182.46979)
		(end 69.86016 -181.955948)
		(width 0.1143)
		(layer "In7.Cu")
		(net "UART_T3_NODE1_TXD_R")
	)
	(segment
		(start 70.990714 -187.622942)
		(end 70.39991 -187.032138)
		(width 0.1143)
		(layer "In7.Cu")
		(net "UART_T3_NODE1_TXD_R")
	)
	(segment
		(start 74.3839 -167.46347)
		(end 74.3839 -166.715186)
		(width 0.1143)
		(layer "In7.Cu")
		(net "UART_T3_NODE1_TXD_R")
	)
	(segment
		(start 113.015522 -205.199488)
		(end 113.015522 -195.76415)
		(width 0.1016)
		(layer "F.Cu")
		(net "UART_T8_NODE4_RXD_R")
	)
	(segment
		(start 113.015522 -195.76415)
		(end 112.86998 -195.618608)
		(width 0.1016)
		(layer "F.Cu")
		(net "UART_T8_NODE4_RXD_R")
	)
	(segment
		(start 112.86998 -195.618608)
		(end 112.84458 -195.593208)
		(width 0.1016)
		(layer "F.Cu")
		(net "UART_T8_NODE4_RXD_R")
	)
	(segment
		(start 113.90376 -192.914524)
		(end 113.90376 -188.526674)
		(width 0.1016)
		(layer "F.Cu")
		(net "UART_T8_NODE4_RXD_R")
	)
	(segment
		(start 112.84458 -195.593208)
		(end 112.84458 -193.973704)
		(width 0.1016)
		(layer "F.Cu")
		(net "UART_T8_NODE4_RXD_R")
	)
	(segment
		(start 112.84458 -193.973704)
		(end 113.90376 -192.914524)
		(width 0.1016)
		(layer "F.Cu")
		(net "UART_T8_NODE4_RXD_R")
	)
	(via
		(at 112.86998 -195.618608)
		(size 0.508)
		(drill 0.254)
		(layers "F.Cu" "B.Cu")
		(net "UART_T8_NODE4_RXD_R")
	)
	(segment
		(start 135.36676 -192.974722)
		(end 135.36676 -197.64248)
		(width 0.1016)
		(layer "F.Cu")
		(net "UART_T10_NODE1_RXD_R")
	)
	(segment
		(start 135.36676 -197.64248)
		(end 135.5344 -197.81012)
		(width 0.1016)
		(layer "F.Cu")
		(net "UART_T10_NODE1_RXD_R")
	)
	(segment
		(start 135.74776 -188.526674)
		(end 135.74776 -192.593722)
		(width 0.1016)
		(layer "F.Cu")
		(net "UART_T10_NODE1_RXD_R")
	)
	(segment
		(start 135.74776 -192.593722)
		(end 135.36676 -192.974722)
		(width 0.1016)
		(layer "F.Cu")
		(net "UART_T10_NODE1_RXD_R")
	)
	(segment
		(start 135.015478 -198.329042)
		(end 135.015478 -205.199488)
		(width 0.1016)
		(layer "F.Cu")
		(net "UART_T10_NODE1_RXD_R")
	)
	(segment
		(start 135.5344 -197.81012)
		(end 135.015478 -198.329042)
		(width 0.1016)
		(layer "F.Cu")
		(net "UART_T10_NODE1_RXD_R")
	)
	(via
		(at 135.5344 -197.81012)
		(size 0.508)
		(drill 0.254)
		(layers "F.Cu" "B.Cu")
		(net "UART_T10_NODE1_RXD_R")
	)
	(via
		(at 73.413112 -197.70852)
		(size 0.6604)
		(drill 0.3302)
		(layers "F.Cu" "B.Cu")
		(net "UART_T3_NODE2_RXD_R")
	)
	(segment
		(start 73.41108 -197.706488)
		(end 73.413112 -197.70852)
		(width 0.1016)
		(layer "B.Cu")
		(net "UART_T3_NODE2_RXD_R")
	)
	(segment
		(start 73.41108 -193.496438)
		(end 73.41108 -197.706488)
		(width 0.1016)
		(layer "B.Cu")
		(net "UART_T3_NODE2_RXD_R")
	)
	(segment
		(start 73.015094 -200.333864)
		(end 73.015094 -205.199488)
		(width 0.1016)
		(layer "B.Cu")
		(net "UART_T3_NODE2_RXD_R")
	)
	(segment
		(start 73.39076 -189.308994)
		(end 73.39076 -193.476118)
		(width 0.1016)
		(layer "B.Cu")
		(net "UART_T3_NODE2_RXD_R")
	)
	(segment
		(start 73.413112 -199.935846)
		(end 73.015094 -200.333864)
		(width 0.1016)
		(layer "B.Cu")
		(net "UART_T3_NODE2_RXD_R")
	)
	(segment
		(start 73.39076 -193.476118)
		(end 73.41108 -193.496438)
		(width 0.1016)
		(layer "B.Cu")
		(net "UART_T3_NODE2_RXD_R")
	)
	(segment
		(start 73.00976 -188.526674)
		(end 73.00976 -188.927994)
		(width 0.1016)
		(layer "B.Cu")
		(net "UART_T3_NODE2_RXD_R")
	)
	(segment
		(start 73.00976 -188.927994)
		(end 73.39076 -189.308994)
		(width 0.1016)
		(layer "B.Cu")
		(net "UART_T3_NODE2_RXD_R")
	)
	(segment
		(start 73.413112 -197.70852)
		(end 73.413112 -199.935846)
		(width 0.1016)
		(layer "B.Cu")
		(net "UART_T3_NODE2_RXD_R")
	)
	(via
		(at 89.06002 -197.405498)
		(size 0.6604)
		(drill 0.3302)
		(layers "F.Cu" "B.Cu")
		(net "UART_T5_NODE2_RXD_R")
	)
	(segment
		(start 89.06002 -197.405498)
		(end 89.5477 -197.893178)
		(width 0.1016)
		(layer "B.Cu")
		(net "UART_T5_NODE2_RXD_R")
	)
	(segment
		(start 90.529156 -187.281566)
		(end 93.336364 -187.281566)
		(width 0.1016)
		(layer "B.Cu")
		(net "UART_T5_NODE2_RXD_R")
	)
	(segment
		(start 89.51468 -188.296042)
		(end 90.529156 -187.281566)
		(width 0.1016)
		(layer "B.Cu")
		(net "UART_T5_NODE2_RXD_R")
	)
	(segment
		(start 89.5477 -200.244202)
		(end 89.015062 -200.77684)
		(width 0.1016)
		(layer "B.Cu")
		(net "UART_T5_NODE2_RXD_R")
	)
	(segment
		(start 89.015062 -200.77684)
		(end 89.015062 -205.199488)
		(width 0.1016)
		(layer "B.Cu")
		(net "UART_T5_NODE2_RXD_R")
	)
	(segment
		(start 93.336364 -187.281566)
		(end 93.811344 -186.806586)
		(width 0.1016)
		(layer "B.Cu")
		(net "UART_T5_NODE2_RXD_R")
	)
	(segment
		(start 89.51468 -196.950838)
		(end 89.51468 -188.296042)
		(width 0.1016)
		(layer "B.Cu")
		(net "UART_T5_NODE2_RXD_R")
	)
	(segment
		(start 89.5477 -197.893178)
		(end 89.5477 -200.244202)
		(width 0.1016)
		(layer "B.Cu")
		(net "UART_T5_NODE2_RXD_R")
	)
	(segment
		(start 89.06002 -197.405498)
		(end 89.51468 -196.950838)
		(width 0.1016)
		(layer "B.Cu")
		(net "UART_T5_NODE2_RXD_R")
	)
	(segment
		(start 131.93776 -189.719204)
		(end 132.31876 -189.338204)
		(width 0.1016)
		(layer "F.Cu")
		(net "UART_T10_NODE2_TXD_R")
	)
	(segment
		(start 132.015484 -202.384406)
		(end 132.015484 -205.199488)
		(width 0.1016)
		(layer "F.Cu")
		(net "UART_T10_NODE2_TXD_R")
	)
	(segment
		(start 132.31876 -189.338204)
		(end 132.31876 -188.526674)
		(width 0.1016)
		(layer "F.Cu")
		(net "UART_T10_NODE2_TXD_R")
	)
	(segment
		(start 132.84454 -188.000894)
		(end 132.31876 -188.526674)
		(width 0.1016)
		(layer "F.Cu")
		(net "UART_T10_NODE2_TXD_R")
	)
	(segment
		(start 131.93776 -196.306694)
		(end 131.93776 -189.719204)
		(width 0.1016)
		(layer "F.Cu")
		(net "UART_T10_NODE2_TXD_R")
	)
	(segment
		(start 131.93776 -196.306694)
		(end 131.93776 -197.248526)
		(width 0.1016)
		(layer "F.Cu")
		(net "UART_T10_NODE2_TXD_R")
	)
	(segment
		(start 132.36956 -183.538368)
		(end 132.36956 -185.652918)
		(width 0.1016)
		(layer "F.Cu")
		(net "UART_T10_NODE2_TXD_R")
	)
	(segment
		(start 131.93776 -197.248526)
		(end 132.59054 -197.901306)
		(width 0.1016)
		(layer "F.Cu")
		(net "UART_T10_NODE2_TXD_R")
	)
	(segment
		(start 131.774692 -182.9435)
		(end 132.36956 -183.538368)
		(width 0.1016)
		(layer "F.Cu")
		(net "UART_T10_NODE2_TXD_R")
	)
	(segment
		(start 130.074162 -182.231792)
		(end 130.78587 -182.9435)
		(width 0.1016)
		(layer "F.Cu")
		(net "UART_T10_NODE2_TXD_R")
	)
	(segment
		(start 130.78587 -182.9435)
		(end 131.774692 -182.9435)
		(width 0.1016)
		(layer "F.Cu")
		(net "UART_T10_NODE2_TXD_R")
	)
	(segment
		(start 132.1054 -186.294522)
		(end 132.84454 -187.033662)
		(width 0.1016)
		(layer "F.Cu")
		(net "UART_T10_NODE2_TXD_R")
	)
	(segment
		(start 132.59054 -201.80935)
		(end 132.015484 -202.384406)
		(width 0.1016)
		(layer "F.Cu")
		(net "UART_T10_NODE2_TXD_R")
	)
	(segment
		(start 132.36956 -185.652918)
		(end 132.1054 -185.917078)
		(width 0.1016)
		(layer "F.Cu")
		(net "UART_T10_NODE2_TXD_R")
	)
	(segment
		(start 132.1054 -185.917078)
		(end 132.1054 -186.294522)
		(width 0.1016)
		(layer "F.Cu")
		(net "UART_T10_NODE2_TXD_R")
	)
	(segment
		(start 132.84454 -187.033662)
		(end 132.84454 -188.000894)
		(width 0.1016)
		(layer "F.Cu")
		(net "UART_T10_NODE2_TXD_R")
	)
	(segment
		(start 129.694432 -182.231792)
		(end 130.074162 -182.231792)
		(width 0.1016)
		(layer "F.Cu")
		(net "UART_T10_NODE2_TXD_R")
	)
	(segment
		(start 132.59054 -197.901306)
		(end 132.59054 -201.80935)
		(width 0.1016)
		(layer "F.Cu")
		(net "UART_T10_NODE2_TXD_R")
	)
	(via
		(at 131.93776 -196.306694)
		(size 0.508)
		(drill 0.254)
		(layers "F.Cu" "B.Cu")
		(net "UART_T10_NODE2_TXD_R")
	)
	(via
		(at 129.694432 -182.231792)
		(size 0.508)
		(drill 0.254)
		(layers "F.Cu" "B.Cu")
		(net "UART_T10_NODE2_TXD_R")
	)
	(segment
		(start 129.694432 -179.175918)
		(end 129.694432 -182.231792)
		(width 0.1016)
		(layer "B.Cu")
		(net "UART_T10_NODE2_TXD_R")
	)
	(segment
		(start 140.141452 -164.677344)
		(end 137.814304 -167.004492)
		(width 0.1016)
		(layer "B.Cu")
		(net "UART_T10_NODE2_TXD_R")
	)
	(segment
		(start 132.30352 -168.489376)
		(end 132.30352 -176.56683)
		(width 0.1016)
		(layer "B.Cu")
		(net "UART_T10_NODE2_TXD_R")
	)
	(segment
		(start 134.333488 -167.004492)
		(end 133.61416 -167.72382)
		(width 0.1016)
		(layer "B.Cu")
		(net "UART_T10_NODE2_TXD_R")
	)
	(segment
		(start 140.141452 -164.187632)
		(end 140.141452 -164.677344)
		(width 0.1016)
		(layer "B.Cu")
		(net "UART_T10_NODE2_TXD_R")
	)
	(segment
		(start 132.30352 -176.56683)
		(end 129.694432 -179.175918)
		(width 0.1016)
		(layer "B.Cu")
		(net "UART_T10_NODE2_TXD_R")
	)
	(segment
		(start 133.069076 -167.72382)
		(end 132.30352 -168.489376)
		(width 0.1016)
		(layer "B.Cu")
		(net "UART_T10_NODE2_TXD_R")
	)
	(segment
		(start 137.814304 -167.004492)
		(end 134.333488 -167.004492)
		(width 0.1016)
		(layer "B.Cu")
		(net "UART_T10_NODE2_TXD_R")
	)
	(segment
		(start 139.317222 -163.363402)
		(end 140.141452 -164.187632)
		(width 0.1016)
		(layer "B.Cu")
		(net "UART_T10_NODE2_TXD_R")
	)
	(segment
		(start 133.61416 -167.72382)
		(end 133.069076 -167.72382)
		(width 0.1016)
		(layer "B.Cu")
		(net "UART_T10_NODE2_TXD_R")
	)
	(via
		(at 50.009044 -197.905624)
		(size 0.6604)
		(drill 0.3302)
		(layers "F.Cu" "B.Cu")
		(net "PSU2_DC_OK_R")
	)
	(segment
		(start 51.02606 -187.878974)
		(end 51.67376 -188.526674)
		(width 0.1016)
		(layer "B.Cu")
		(net "PSU2_DC_OK_R")
	)
	(segment
		(start 51.67376 -185.605674)
		(end 51.67376 -186.21375)
		(width 0.1016)
		(layer "B.Cu")
		(net "PSU2_DC_OK_R")
	)
	(segment
		(start 51.02606 -186.86145)
		(end 51.02606 -187.878974)
		(width 0.1016)
		(layer "B.Cu")
		(net "PSU2_DC_OK_R")
	)
	(segment
		(start 51.67376 -186.21375)
		(end 51.02606 -186.86145)
		(width 0.1016)
		(layer "B.Cu")
		(net "PSU2_DC_OK_R")
	)
	(segment
		(start 51.67376 -190.448184)
		(end 50.009044 -192.1129)
		(width 0.1016)
		(layer "B.Cu")
		(net "PSU2_DC_OK_R")
	)
	(segment
		(start 50.009044 -199.462898)
		(end 50.009044 -197.905624)
		(width 0.1016)
		(layer "B.Cu")
		(net "PSU2_DC_OK_R")
	)
	(segment
		(start 50.009044 -192.1129)
		(end 50.009044 -197.905624)
		(width 0.1016)
		(layer "B.Cu")
		(net "PSU2_DC_OK_R")
	)
	(segment
		(start 51.67376 -188.526674)
		(end 51.67376 -190.448184)
		(width 0.1016)
		(layer "B.Cu")
		(net "PSU2_DC_OK_R")
	)
	(segment
		(start 49.014888 -205.199488)
		(end 49.014888 -200.457054)
		(width 0.1016)
		(layer "B.Cu")
		(net "PSU2_DC_OK_R")
	)
	(segment
		(start 49.014888 -200.457054)
		(end 50.009044 -199.462898)
		(width 0.1016)
		(layer "B.Cu")
		(net "PSU2_DC_OK_R")
	)
	(segment
		(start 128.015492 -196.33946)
		(end 128.12776 -196.227192)
		(width 0.1016)
		(layer "F.Cu")
		(net "UART_T10_NODE4_RXD_R")
	)
	(segment
		(start 128.015492 -205.199488)
		(end 128.015492 -196.33946)
		(width 0.1016)
		(layer "F.Cu")
		(net "UART_T10_NODE4_RXD_R")
	)
	(segment
		(start 129.06756 -195.287392)
		(end 128.12776 -196.227192)
		(width 0.1016)
		(layer "F.Cu")
		(net "UART_T10_NODE4_RXD_R")
	)
	(segment
		(start 129.06756 -188.526674)
		(end 129.06756 -195.287392)
		(width 0.1016)
		(layer "F.Cu")
		(net "UART_T10_NODE4_RXD_R")
	)
	(via
		(at 128.12776 -196.227192)
		(size 0.508)
		(drill 0.254)
		(layers "F.Cu" "B.Cu")
		(net "UART_T10_NODE4_RXD_R")
	)
	(via
		(at 72.271128 -189.863222)
		(size 0.508)
		(drill 0.254)
		(layers "F.Cu" "B.Cu")
		(net "UART_T3_NODE2_TXD_R")
	)
	(via
		(at 76.47178 -166.60368)
		(size 0.508)
		(drill 0.254)
		(layers "F.Cu" "B.Cu")
		(net "UART_T3_NODE2_TXD_R")
	)
	(segment
		(start 72.015096 -205.199488)
		(end 72.015096 -198.747888)
		(width 0.1016)
		(layer "B.Cu")
		(net "UART_T3_NODE2_TXD_R")
	)
	(segment
		(start 75.599036 -164.896546)
		(end 76.06538 -165.36289)
		(width 0.1016)
		(layer "B.Cu")
		(net "UART_T3_NODE2_TXD_R")
	)
	(segment
		(start 72.24776 -189.839854)
		(end 72.271128 -189.863222)
		(width 0.1016)
		(layer "B.Cu")
		(net "UART_T3_NODE2_TXD_R")
	)
	(segment
		(start 71.99376 -188.526674)
		(end 71.99376 -189.134496)
		(width 0.1016)
		(layer "B.Cu")
		(net "UART_T3_NODE2_TXD_R")
	)
	(segment
		(start 72.24776 -189.88659)
		(end 72.271128 -189.863222)
		(width 0.1016)
		(layer "B.Cu")
		(net "UART_T3_NODE2_TXD_R")
	)
	(segment
		(start 71.99376 -189.134496)
		(end 72.24776 -189.388496)
		(width 0.1016)
		(layer "B.Cu")
		(net "UART_T3_NODE2_TXD_R")
	)
	(segment
		(start 76.06538 -165.36289)
		(end 76.06538 -166.19728)
		(width 0.1016)
		(layer "B.Cu")
		(net "UART_T3_NODE2_TXD_R")
	)
	(segment
		(start 75.299062 -164.896546)
		(end 75.599036 -164.896546)
		(width 0.1016)
		(layer "B.Cu")
		(net "UART_T3_NODE2_TXD_R")
	)
	(segment
		(start 72.24776 -189.388496)
		(end 72.24776 -189.839854)
		(width 0.1016)
		(layer "B.Cu")
		(net "UART_T3_NODE2_TXD_R")
	)
	(segment
		(start 76.06538 -166.19728)
		(end 76.47178 -166.60368)
		(width 0.1016)
		(layer "B.Cu")
		(net "UART_T3_NODE2_TXD_R")
	)
	(segment
		(start 72.24776 -198.515224)
		(end 72.24776 -189.88659)
		(width 0.1016)
		(layer "B.Cu")
		(net "UART_T3_NODE2_TXD_R")
	)
	(segment
		(start 72.015096 -198.747888)
		(end 72.24776 -198.515224)
		(width 0.1016)
		(layer "B.Cu")
		(net "UART_T3_NODE2_TXD_R")
	)
	(segment
		(start 69.32676 -182.038244)
		(end 69.32676 -182.55234)
		(width 0.1143)
		(layer "In7.Cu")
		(net "UART_T3_NODE2_TXD_R")
	)
	(segment
		(start 73.94575 -167.5511)
		(end 74.25436 -167.85971)
		(width 0.1143)
		(layer "In7.Cu")
		(net "UART_T3_NODE2_TXD_R")
	)
	(segment
		(start 69.32676 -182.55234)
		(end 69.06895 -182.81015)
		(width 0.1143)
		(layer "In7.Cu")
		(net "UART_T3_NODE2_TXD_R")
	)
	(segment
		(start 68.38061 -187.034678)
		(end 71.209154 -189.863222)
		(width 0.1143)
		(layer "In7.Cu")
		(net "UART_T3_NODE2_TXD_R")
	)
	(segment
		(start 76.134468 -166.266368)
		(end 74.212958 -166.266368)
		(width 0.1143)
		(layer "In7.Cu")
		(net "UART_T3_NODE2_TXD_R")
	)
	(segment
		(start 74.212958 -166.266368)
		(end 73.94575 -166.533576)
		(width 0.1143)
		(layer "In7.Cu")
		(net "UART_T3_NODE2_TXD_R")
	)
	(segment
		(start 75.194922 -170.881294)
		(end 75.194922 -174.493428)
		(width 0.1143)
		(layer "In7.Cu")
		(net "UART_T3_NODE2_TXD_R")
	)
	(segment
		(start 74.73188 -174.95647)
		(end 74.73188 -175.42764)
		(width 0.1143)
		(layer "In7.Cu")
		(net "UART_T3_NODE2_TXD_R")
	)
	(segment
		(start 69.06895 -182.81015)
		(end 68.79717 -182.81015)
		(width 0.1143)
		(layer "In7.Cu")
		(net "UART_T3_NODE2_TXD_R")
	)
	(segment
		(start 74.25436 -169.940732)
		(end 75.194922 -170.881294)
		(width 0.1143)
		(layer "In7.Cu")
		(net "UART_T3_NODE2_TXD_R")
	)
	(segment
		(start 76.47178 -166.60368)
		(end 76.134468 -166.266368)
		(width 0.1143)
		(layer "In7.Cu")
		(net "UART_T3_NODE2_TXD_R")
	)
	(segment
		(start 71.209154 -189.863222)
		(end 72.271128 -189.863222)
		(width 0.1143)
		(layer "In7.Cu")
		(net "UART_T3_NODE2_TXD_R")
	)
	(segment
		(start 75.194922 -174.493428)
		(end 74.73188 -174.95647)
		(width 0.1143)
		(layer "In7.Cu")
		(net "UART_T3_NODE2_TXD_R")
	)
	(segment
		(start 71.80326 -179.561744)
		(end 69.32676 -182.038244)
		(width 0.1143)
		(layer "In7.Cu")
		(net "UART_T3_NODE2_TXD_R")
	)
	(segment
		(start 68.79717 -182.81015)
		(end 68.38061 -183.22671)
		(width 0.1143)
		(layer "In7.Cu")
		(net "UART_T3_NODE2_TXD_R")
	)
	(segment
		(start 73.94575 -166.533576)
		(end 73.94575 -167.5511)
		(width 0.1143)
		(layer "In7.Cu")
		(net "UART_T3_NODE2_TXD_R")
	)
	(segment
		(start 74.73188 -175.42764)
		(end 71.80326 -178.35626)
		(width 0.1143)
		(layer "In7.Cu")
		(net "UART_T3_NODE2_TXD_R")
	)
	(segment
		(start 68.38061 -183.22671)
		(end 68.38061 -187.034678)
		(width 0.1143)
		(layer "In7.Cu")
		(net "UART_T3_NODE2_TXD_R")
	)
	(segment
		(start 74.25436 -167.85971)
		(end 74.25436 -169.940732)
		(width 0.1143)
		(layer "In7.Cu")
		(net "UART_T3_NODE2_TXD_R")
	)
	(segment
		(start 71.80326 -178.35626)
		(end 71.80326 -179.561744)
		(width 0.1143)
		(layer "In7.Cu")
		(net "UART_T3_NODE2_TXD_R")
	)
	(segment
		(start 49.38776 -186.08675)
		(end 49.895252 -186.594242)
		(width 0.1016)
		(layer "F.Cu")
		(net "PSU4_AC_OK_R")
	)
	(segment
		(start 49.38776 -185.605674)
		(end 49.38776 -186.08675)
		(width 0.1016)
		(layer "F.Cu")
		(net "PSU4_AC_OK_R")
	)
	(segment
		(start 47.014892 -199.593454)
		(end 48.20158 -198.406766)
		(width 0.1016)
		(layer "F.Cu")
		(net "PSU4_AC_OK_R")
	)
	(segment
		(start 48.253142 -195.287646)
		(end 48.253142 -197.581266)
		(width 0.1016)
		(layer "F.Cu")
		(net "PSU4_AC_OK_R")
	)
	(segment
		(start 49.38776 -188.498734)
		(end 49.38776 -188.526674)
		(width 0.1016)
		(layer "F.Cu")
		(net "PSU4_AC_OK_R")
	)
	(segment
		(start 47.014892 -204.699616)
		(end 47.014892 -199.593454)
		(width 0.1016)
		(layer "F.Cu")
		(net "PSU4_AC_OK_R")
	)
	(segment
		(start 49.38776 -194.153028)
		(end 48.253142 -195.287646)
		(width 0.1016)
		(layer "F.Cu")
		(net "PSU4_AC_OK_R")
	)
	(segment
		(start 49.895252 -187.991242)
		(end 49.38776 -188.498734)
		(width 0.1016)
		(layer "F.Cu")
		(net "PSU4_AC_OK_R")
	)
	(segment
		(start 48.253142 -197.581266)
		(end 48.20158 -197.632828)
		(width 0.1016)
		(layer "F.Cu")
		(net "PSU4_AC_OK_R")
	)
	(segment
		(start 48.20158 -198.406766)
		(end 48.20158 -197.632828)
		(width 0.1016)
		(layer "F.Cu")
		(net "PSU4_AC_OK_R")
	)
	(segment
		(start 49.38776 -188.526674)
		(end 49.38776 -194.153028)
		(width 0.1016)
		(layer "F.Cu")
		(net "PSU4_AC_OK_R")
	)
	(segment
		(start 49.895252 -186.594242)
		(end 49.895252 -187.991242)
		(width 0.1016)
		(layer "F.Cu")
		(net "PSU4_AC_OK_R")
	)
	(via
		(at 48.20158 -197.632828)
		(size 0.508)
		(drill 0.254)
		(layers "F.Cu" "B.Cu")
		(net "PSU4_AC_OK_R")
	)
	(segment
		(start 90.702384 -187.842398)
		(end 90.672666 -187.842398)
		(width 0.1016)
		(layer "F.Cu")
		(net "UART_T5_NODE2_TXD_R")
	)
	(segment
		(start 89.101676 -189.413388)
		(end 89.08288 -189.413388)
		(width 0.1016)
		(layer "F.Cu")
		(net "UART_T5_NODE2_TXD_R")
	)
	(segment
		(start 92.852494 -168.434512)
		(end 92.86748 -168.419526)
		(width 0.1016)
		(layer "F.Cu")
		(net "UART_T5_NODE2_TXD_R")
	)
	(segment
		(start 91.21267 -168.434512)
		(end 92.852494 -168.434512)
		(width 0.1016)
		(layer "F.Cu")
		(net "UART_T5_NODE2_TXD_R")
	)
	(segment
		(start 90.672666 -187.842398)
		(end 89.101676 -189.413388)
		(width 0.1016)
		(layer "F.Cu")
		(net "UART_T5_NODE2_TXD_R")
	)
	(via
		(at 89.08288 -189.413388)
		(size 0.508)
		(drill 0.254)
		(layers "F.Cu" "B.Cu")
		(net "UART_T5_NODE2_TXD_R")
	)
	(via
		(at 92.86748 -168.419526)
		(size 0.508)
		(drill 0.254)
		(layers "F.Cu" "B.Cu")
		(net "UART_T5_NODE2_TXD_R")
	)
	(via
		(at 87.6554 -196.064124)
		(size 0.6604)
		(drill 0.3302)
		(layers "F.Cu" "B.Cu")
		(net "UART_T5_NODE2_TXD_R")
	)
	(segment
		(start 87.6554 -197.769734)
		(end 87.6554 -196.064124)
		(width 0.1016)
		(layer "B.Cu")
		(net "UART_T5_NODE2_TXD_R")
	)
	(segment
		(start 88.446864 -200.913746)
		(end 88.446864 -198.561198)
		(width 0.1016)
		(layer "B.Cu")
		(net "UART_T5_NODE2_TXD_R")
	)
	(segment
		(start 88.446864 -198.561198)
		(end 87.6554 -197.769734)
		(width 0.1016)
		(layer "B.Cu")
		(net "UART_T5_NODE2_TXD_R")
	)
	(segment
		(start 87.6554 -196.064124)
		(end 87.6554 -190.840868)
		(width 0.1016)
		(layer "B.Cu")
		(net "UART_T5_NODE2_TXD_R")
	)
	(segment
		(start 88.015064 -201.345546)
		(end 88.446864 -200.913746)
		(width 0.1016)
		(layer "B.Cu")
		(net "UART_T5_NODE2_TXD_R")
	)
	(segment
		(start 87.6554 -190.840868)
		(end 89.08288 -189.413388)
		(width 0.1016)
		(layer "B.Cu")
		(net "UART_T5_NODE2_TXD_R")
	)
	(segment
		(start 88.015064 -205.199488)
		(end 88.015064 -201.345546)
		(width 0.1016)
		(layer "B.Cu")
		(net "UART_T5_NODE2_TXD_R")
	)
	(segment
		(start 90.64752 -171.85386)
		(end 88.92159 -173.57979)
		(width 0.1143)
		(layer "In7.Cu")
		(net "UART_T5_NODE2_TXD_R")
	)
	(segment
		(start 87.02802 -187.358528)
		(end 89.08288 -189.413388)
		(width 0.1143)
		(layer "In7.Cu")
		(net "UART_T5_NODE2_TXD_R")
	)
	(segment
		(start 88.2904 -184.131458)
		(end 87.02802 -185.393838)
		(width 0.1143)
		(layer "In7.Cu")
		(net "UART_T5_NODE2_TXD_R")
	)
	(segment
		(start 88.2904 -183.690514)
		(end 88.2904 -184.131458)
		(width 0.1143)
		(layer "In7.Cu")
		(net "UART_T5_NODE2_TXD_R")
	)
	(segment
		(start 91.895168 -168.419526)
		(end 90.64752 -169.667174)
		(width 0.1143)
		(layer "In7.Cu")
		(net "UART_T5_NODE2_TXD_R")
	)
	(segment
		(start 88.92159 -173.57979)
		(end 88.92159 -180.56987)
		(width 0.1143)
		(layer "In7.Cu")
		(net "UART_T5_NODE2_TXD_R")
	)
	(segment
		(start 88.96604 -181.766972)
		(end 88.7095 -182.023512)
		(width 0.1143)
		(layer "In7.Cu")
		(net "UART_T5_NODE2_TXD_R")
	)
	(segment
		(start 87.02802 -185.393838)
		(end 87.02802 -187.358528)
		(width 0.1143)
		(layer "In7.Cu")
		(net "UART_T5_NODE2_TXD_R")
	)
	(segment
		(start 88.7095 -183.271414)
		(end 88.2904 -183.690514)
		(width 0.1143)
		(layer "In7.Cu")
		(net "UART_T5_NODE2_TXD_R")
	)
	(segment
		(start 88.92159 -180.56987)
		(end 88.96604 -180.61432)
		(width 0.1143)
		(layer "In7.Cu")
		(net "UART_T5_NODE2_TXD_R")
	)
	(segment
		(start 88.7095 -182.023512)
		(end 88.7095 -183.271414)
		(width 0.1143)
		(layer "In7.Cu")
		(net "UART_T5_NODE2_TXD_R")
	)
	(segment
		(start 88.96604 -180.61432)
		(end 88.96604 -181.766972)
		(width 0.1143)
		(layer "In7.Cu")
		(net "UART_T5_NODE2_TXD_R")
	)
	(segment
		(start 92.86748 -168.419526)
		(end 91.895168 -168.419526)
		(width 0.1143)
		(layer "In7.Cu")
		(net "UART_T5_NODE2_TXD_R")
	)
	(segment
		(start 90.64752 -169.667174)
		(end 90.64752 -171.85386)
		(width 0.1143)
		(layer "In7.Cu")
		(net "UART_T5_NODE2_TXD_R")
	)
	(segment
		(start 48.24476 -188.498734)
		(end 48.24476 -188.526674)
		(width 0.1016)
		(layer "F.Cu")
		(net "PSU5_AC_OK_R")
	)
	(segment
		(start 48.752252 -187.991242)
		(end 48.24476 -188.498734)
		(width 0.1016)
		(layer "F.Cu")
		(net "PSU5_AC_OK_R")
	)
	(segment
		(start 46.355 -198.319644)
		(end 46.014894 -198.65975)
		(width 0.1016)
		(layer "F.Cu")
		(net "PSU5_AC_OK_R")
	)
	(segment
		(start 46.355 -195.684902)
		(end 48.24476 -193.795142)
		(width 0.1016)
		(layer "F.Cu")
		(net "PSU5_AC_OK_R")
	)
	(segment
		(start 48.752252 -186.594242)
		(end 48.752252 -187.991242)
		(width 0.1016)
		(layer "F.Cu")
		(net "PSU5_AC_OK_R")
	)
	(segment
		(start 48.24476 -185.605674)
		(end 48.24476 -186.08675)
		(width 0.1016)
		(layer "F.Cu")
		(net "PSU5_AC_OK_R")
	)
	(segment
		(start 48.24476 -186.08675)
		(end 48.752252 -186.594242)
		(width 0.1016)
		(layer "F.Cu")
		(net "PSU5_AC_OK_R")
	)
	(segment
		(start 48.24476 -193.795142)
		(end 48.24476 -188.526674)
		(width 0.1016)
		(layer "F.Cu")
		(net "PSU5_AC_OK_R")
	)
	(segment
		(start 46.355 -198.319644)
		(end 46.355 -195.684902)
		(width 0.1016)
		(layer "F.Cu")
		(net "PSU5_AC_OK_R")
	)
	(segment
		(start 46.014894 -198.65975)
		(end 46.014894 -205.199488)
		(width 0.1016)
		(layer "F.Cu")
		(net "PSU5_AC_OK_R")
	)
	(via
		(at 46.355 -198.319644)
		(size 0.508)
		(drill 0.254)
		(layers "F.Cu" "B.Cu")
		(net "PSU5_AC_OK_R")
	)
	(segment
		(start 133.08076 -196.39915)
		(end 133.37794 -196.69633)
		(width 0.1016)
		(layer "F.Cu")
		(net "UART_T10_NODE2_RXD_R")
	)
	(segment
		(start 133.015482 -198.67626)
		(end 133.08076 -198.610982)
		(width 0.1016)
		(layer "F.Cu")
		(net "UART_T10_NODE2_RXD_R")
	)
	(segment
		(start 133.08076 -189.288928)
		(end 133.08076 -196.39915)
		(width 0.1016)
		(layer "F.Cu")
		(net "UART_T10_NODE2_RXD_R")
	)
	(segment
		(start 133.46176 -188.907928)
		(end 133.08076 -189.288928)
		(width 0.1016)
		(layer "F.Cu")
		(net "UART_T10_NODE2_RXD_R")
	)
	(segment
		(start 133.08076 -196.99351)
		(end 133.37794 -196.69633)
		(width 0.1016)
		(layer "F.Cu")
		(net "UART_T10_NODE2_RXD_R")
	)
	(segment
		(start 133.015482 -205.199488)
		(end 133.015482 -198.67626)
		(width 0.1016)
		(layer "F.Cu")
		(net "UART_T10_NODE2_RXD_R")
	)
	(segment
		(start 133.08076 -198.610982)
		(end 133.08076 -196.99351)
		(width 0.1016)
		(layer "F.Cu")
		(net "UART_T10_NODE2_RXD_R")
	)
	(segment
		(start 133.46176 -188.526674)
		(end 133.46176 -188.907928)
		(width 0.1016)
		(layer "F.Cu")
		(net "UART_T10_NODE2_RXD_R")
	)
	(via
		(at 133.37794 -196.69633)
		(size 0.508)
		(drill 0.254)
		(layers "F.Cu" "B.Cu")
		(net "UART_T10_NODE2_RXD_R")
	)
	(segment
		(start 46.466252 -186.594242)
		(end 47.10176 -185.958734)
		(width 0.1016)
		(layer "F.Cu")
		(net "PSU6_AC_OK_R")
	)
	(segment
		(start 47.10176 -185.958734)
		(end 47.10176 -185.605674)
		(width 0.1016)
		(layer "F.Cu")
		(net "PSU6_AC_OK_R")
	)
	(segment
		(start 46.466252 -187.864242)
		(end 46.466252 -186.594242)
		(width 0.1016)
		(layer "F.Cu")
		(net "PSU6_AC_OK_R")
	)
	(segment
		(start 47.10176 -188.526674)
		(end 47.10176 -192.844674)
		(width 0.1016)
		(layer "F.Cu")
		(net "PSU6_AC_OK_R")
	)
	(segment
		(start 45.014896 -194.931538)
		(end 45.014896 -197.55231)
		(width 0.1016)
		(layer "F.Cu")
		(net "PSU6_AC_OK_R")
	)
	(segment
		(start 47.10176 -192.844674)
		(end 45.014896 -194.931538)
		(width 0.1016)
		(layer "F.Cu")
		(net "PSU6_AC_OK_R")
	)
	(segment
		(start 45.014896 -205.199488)
		(end 45.014896 -197.55231)
		(width 0.1016)
		(layer "F.Cu")
		(net "PSU6_AC_OK_R")
	)
	(segment
		(start 47.10176 -188.49975)
		(end 46.466252 -187.864242)
		(width 0.1016)
		(layer "F.Cu")
		(net "PSU6_AC_OK_R")
	)
	(segment
		(start 47.10176 -188.526674)
		(end 47.10176 -188.49975)
		(width 0.1016)
		(layer "F.Cu")
		(net "PSU6_AC_OK_R")
	)
	(via
		(at 45.014896 -197.55231)
		(size 0.508)
		(drill 0.254)
		(layers "F.Cu" "B.Cu")
		(net "PSU6_AC_OK_R")
	)
	(segment
		(start 126.81458 -197.213474)
		(end 126.574296 -197.453758)
		(width 0.1016)
		(layer "F.Cu")
		(net "UART_T10_NODE4_TXD_R")
	)
	(segment
		(start 126.47676 -187.192666)
		(end 126.47676 -188.126116)
		(width 0.1016)
		(layer "F.Cu")
		(net "UART_T10_NODE4_TXD_R")
	)
	(segment
		(start 126.574296 -201.204576)
		(end 127.015494 -201.645774)
		(width 0.1016)
		(layer "F.Cu")
		(net "UART_T10_NODE4_TXD_R")
	)
	(segment
		(start 130.71348 -181.151022)
		(end 130.154172 -181.151022)
		(width 0.1016)
		(layer "F.Cu")
		(net "UART_T10_NODE4_TXD_R")
	)
	(segment
		(start 126.94412 -185.978038)
		(end 126.94412 -186.725306)
		(width 0.1016)
		(layer "F.Cu")
		(net "UART_T10_NODE4_TXD_R")
	)
	(segment
		(start 130.154172 -181.151022)
		(end 127.64262 -183.662574)
		(width 0.1016)
		(layer "F.Cu")
		(net "UART_T10_NODE4_TXD_R")
	)
	(segment
		(start 126.877318 -188.526674)
		(end 127.03556 -188.526674)
		(width 0.1016)
		(layer "F.Cu")
		(net "UART_T10_NODE4_TXD_R")
	)
	(segment
		(start 127.03556 -188.526674)
		(end 127.03556 -196.992494)
		(width 0.1016)
		(layer "F.Cu")
		(net "UART_T10_NODE4_TXD_R")
	)
	(segment
		(start 127.64262 -185.279538)
		(end 126.94412 -185.978038)
		(width 0.1016)
		(layer "F.Cu")
		(net "UART_T10_NODE4_TXD_R")
	)
	(segment
		(start 126.574296 -197.453758)
		(end 126.574296 -201.204576)
		(width 0.1016)
		(layer "F.Cu")
		(net "UART_T10_NODE4_TXD_R")
	)
	(segment
		(start 127.03556 -196.992494)
		(end 126.81458 -197.213474)
		(width 0.1016)
		(layer "F.Cu")
		(net "UART_T10_NODE4_TXD_R")
	)
	(segment
		(start 127.64262 -183.662574)
		(end 127.64262 -185.279538)
		(width 0.1016)
		(layer "F.Cu")
		(net "UART_T10_NODE4_TXD_R")
	)
	(segment
		(start 126.47676 -188.126116)
		(end 126.877318 -188.526674)
		(width 0.1016)
		(layer "F.Cu")
		(net "UART_T10_NODE4_TXD_R")
	)
	(segment
		(start 127.015494 -201.645774)
		(end 127.015494 -205.199488)
		(width 0.1016)
		(layer "F.Cu")
		(net "UART_T10_NODE4_TXD_R")
	)
	(segment
		(start 126.94412 -186.725306)
		(end 126.47676 -187.192666)
		(width 0.1016)
		(layer "F.Cu")
		(net "UART_T10_NODE4_TXD_R")
	)
	(via
		(at 126.81458 -197.213474)
		(size 0.508)
		(drill 0.254)
		(layers "F.Cu" "B.Cu")
		(net "UART_T10_NODE4_TXD_R")
	)
	(via
		(at 130.71348 -181.151022)
		(size 0.508)
		(drill 0.254)
		(layers "F.Cu" "B.Cu")
		(net "UART_T10_NODE4_TXD_R")
	)
	(segment
		(start 132.91312 -177.040794)
		(end 130.71348 -179.240434)
		(width 0.1016)
		(layer "B.Cu")
		(net "UART_T10_NODE4_TXD_R")
	)
	(segment
		(start 138.418316 -168.40708)
		(end 134.19836 -168.40708)
		(width 0.1016)
		(layer "B.Cu")
		(net "UART_T10_NODE4_TXD_R")
	)
	(segment
		(start 130.71348 -179.240434)
		(end 130.71348 -181.151022)
		(width 0.1016)
		(layer "B.Cu")
		(net "UART_T10_NODE4_TXD_R")
	)
	(segment
		(start 140.66139 -166.881048)
		(end 139.944348 -166.881048)
		(width 0.1016)
		(layer "B.Cu")
		(net "UART_T10_NODE4_TXD_R")
	)
	(segment
		(start 142.070582 -163.888166)
		(end 141.55928 -164.399468)
		(width 0.1016)
		(layer "B.Cu")
		(net "UART_T10_NODE4_TXD_R")
	)
	(segment
		(start 142.070582 -163.353242)
		(end 142.070582 -163.888166)
		(width 0.1016)
		(layer "B.Cu")
		(net "UART_T10_NODE4_TXD_R")
	)
	(segment
		(start 141.55928 -165.983158)
		(end 140.66139 -166.881048)
		(width 0.1016)
		(layer "B.Cu")
		(net "UART_T10_NODE4_TXD_R")
	)
	(segment
		(start 134.19836 -168.40708)
		(end 134.1247 -168.33342)
		(width 0.1016)
		(layer "B.Cu")
		(net "UART_T10_NODE4_TXD_R")
	)
	(segment
		(start 132.91312 -168.922954)
		(end 132.91312 -177.040794)
		(width 0.1016)
		(layer "B.Cu")
		(net "UART_T10_NODE4_TXD_R")
	)
	(segment
		(start 141.55928 -164.399468)
		(end 141.55928 -165.983158)
		(width 0.1016)
		(layer "B.Cu")
		(net "UART_T10_NODE4_TXD_R")
	)
	(segment
		(start 133.502654 -168.33342)
		(end 132.91312 -168.922954)
		(width 0.1016)
		(layer "B.Cu")
		(net "UART_T10_NODE4_TXD_R")
	)
	(segment
		(start 139.944348 -166.881048)
		(end 138.418316 -168.40708)
		(width 0.1016)
		(layer "B.Cu")
		(net "UART_T10_NODE4_TXD_R")
	)
	(segment
		(start 134.1247 -168.33342)
		(end 133.502654 -168.33342)
		(width 0.1016)
		(layer "B.Cu")
		(net "UART_T10_NODE4_TXD_R")
	)
	(via
		(at 70.751446 -199.739758)
		(size 0.6604)
		(drill 0.3302)
		(layers "F.Cu" "B.Cu")
		(net "UART_T3_NODE3_RXD_R")
	)
	(segment
		(start 70.97776 -188.526674)
		(end 70.97776 -189.231524)
		(width 0.1016)
		(layer "B.Cu")
		(net "UART_T3_NODE3_RXD_R")
	)
	(segment
		(start 71.10476 -189.358524)
		(end 71.10476 -192.116456)
		(width 0.1016)
		(layer "B.Cu")
		(net "UART_T3_NODE3_RXD_R")
	)
	(segment
		(start 70.0151 -200.476104)
		(end 70.751446 -199.739758)
		(width 0.1016)
		(layer "B.Cu")
		(net "UART_T3_NODE3_RXD_R")
	)
	(segment
		(start 71.10476 -192.116456)
		(end 70.98538 -192.235836)
		(width 0.1016)
		(layer "B.Cu")
		(net "UART_T3_NODE3_RXD_R")
	)
	(segment
		(start 70.98538 -192.235836)
		(end 70.98538 -199.505824)
		(width 0.1016)
		(layer "B.Cu")
		(net "UART_T3_NODE3_RXD_R")
	)
	(segment
		(start 70.0151 -205.199488)
		(end 70.0151 -200.476104)
		(width 0.1016)
		(layer "B.Cu")
		(net "UART_T3_NODE3_RXD_R")
	)
	(segment
		(start 70.98538 -199.505824)
		(end 70.751446 -199.739758)
		(width 0.1016)
		(layer "B.Cu")
		(net "UART_T3_NODE3_RXD_R")
	)
	(segment
		(start 70.97776 -189.231524)
		(end 71.10476 -189.358524)
		(width 0.1016)
		(layer "B.Cu")
		(net "UART_T3_NODE3_RXD_R")
	)
	(via
		(at 87.21598 -198.04888)
		(size 0.6604)
		(drill 0.3302)
		(layers "F.Cu" "B.Cu")
		(net "UART_T5_NODE3_RXD_R")
	)
	(segment
		(start 87.015066 -197.84822)
		(end 87.215726 -198.04888)
		(width 0.1016)
		(layer "B.Cu")
		(net "UART_T5_NODE3_RXD_R")
	)
	(segment
		(start 87.215726 -198.04888)
		(end 87.21598 -198.04888)
		(width 0.1016)
		(layer "B.Cu")
		(net "UART_T5_NODE3_RXD_R")
	)
	(segment
		(start 90.518488 -186.826398)
		(end 87.015066 -190.32982)
		(width 0.1016)
		(layer "B.Cu")
		(net "UART_T5_NODE3_RXD_R")
	)
	(segment
		(start 87.015066 -190.32982)
		(end 87.015066 -197.84822)
		(width 0.1016)
		(layer "B.Cu")
		(net "UART_T5_NODE3_RXD_R")
	)
	(segment
		(start 87.015066 -205.199488)
		(end 87.015066 -198.24954)
		(width 0.1016)
		(layer "B.Cu")
		(net "UART_T5_NODE3_RXD_R")
	)
	(segment
		(start 90.702384 -186.826398)
		(end 90.518488 -186.826398)
		(width 0.1016)
		(layer "B.Cu")
		(net "UART_T5_NODE3_RXD_R")
	)
	(segment
		(start 87.015066 -198.24954)
		(end 87.215726 -198.04888)
		(width 0.1016)
		(layer "B.Cu")
		(net "UART_T5_NODE3_RXD_R")
	)
	(segment
		(start 113.31956 -186.774582)
		(end 113.31956 -187.939934)
		(width 0.1016)
		(layer "F.Cu")
		(net "UART_T8_NODE4_TXD_R")
	)
	(segment
		(start 112.91062 -183.874918)
		(end 112.91062 -186.365642)
		(width 0.1016)
		(layer "F.Cu")
		(net "UART_T8_NODE4_TXD_R")
	)
	(segment
		(start 112.014 -199.465438)
		(end 112.015524 -199.465438)
		(width 0.1016)
		(layer "F.Cu")
		(net "UART_T8_NODE4_TXD_R")
	)
	(segment
		(start 112.015524 -205.199488)
		(end 112.015524 -202.22337)
		(width 0.1016)
		(layer "F.Cu")
		(net "UART_T8_NODE4_TXD_R")
	)
	(segment
		(start 112.76076 -188.498734)
		(end 112.76076 -188.526674)
		(width 0.1016)
		(layer "F.Cu")
		(net "UART_T8_NODE4_TXD_R")
	)
	(segment
		(start 112.91062 -186.365642)
		(end 113.31956 -186.774582)
		(width 0.1016)
		(layer "F.Cu")
		(net "UART_T8_NODE4_TXD_R")
	)
	(segment
		(start 112.48136 -200.27392)
		(end 112.015524 -199.808084)
		(width 0.1016)
		(layer "F.Cu")
		(net "UART_T8_NODE4_TXD_R")
	)
	(segment
		(start 112.76076 -188.526674)
		(end 112.76076 -192.886838)
		(width 0.1016)
		(layer "F.Cu")
		(net "UART_T8_NODE4_TXD_R")
	)
	(segment
		(start 113.31956 -187.939934)
		(end 112.76076 -188.498734)
		(width 0.1016)
		(layer "F.Cu")
		(net "UART_T8_NODE4_TXD_R")
	)
	(segment
		(start 112.76076 -192.886838)
		(end 112.014 -193.633598)
		(width 0.1016)
		(layer "F.Cu")
		(net "UART_T8_NODE4_TXD_R")
	)
	(segment
		(start 112.015524 -199.808084)
		(end 112.015524 -199.465438)
		(width 0.1016)
		(layer "F.Cu")
		(net "UART_T8_NODE4_TXD_R")
	)
	(segment
		(start 112.48136 -201.757534)
		(end 112.48136 -200.27392)
		(width 0.1016)
		(layer "F.Cu")
		(net "UART_T8_NODE4_TXD_R")
	)
	(segment
		(start 112.015524 -202.22337)
		(end 112.48136 -201.757534)
		(width 0.1016)
		(layer "F.Cu")
		(net "UART_T8_NODE4_TXD_R")
	)
	(segment
		(start 112.014 -193.633598)
		(end 112.014 -199.465438)
		(width 0.1016)
		(layer "F.Cu")
		(net "UART_T8_NODE4_TXD_R")
	)
	(via
		(at 112.015524 -199.465438)
		(size 0.508)
		(drill 0.254)
		(layers "F.Cu" "B.Cu")
		(net "UART_T8_NODE4_TXD_R")
	)
	(via
		(at 130.921252 -165.098984)
		(size 0.508)
		(drill 0.254)
		(layers "F.Cu" "B.Cu")
		(net "UART_T8_NODE4_TXD_R")
	)
	(via
		(at 112.91062 -183.874918)
		(size 0.508)
		(drill 0.254)
		(layers "F.Cu" "B.Cu")
		(net "UART_T8_NODE4_TXD_R")
	)
	(segment
		(start 130.319018 -166.371778)
		(end 130.319018 -165.701218)
		(width 0.1016)
		(layer "B.Cu")
		(net "UART_T8_NODE4_TXD_R")
	)
	(segment
		(start 130.319018 -165.701218)
		(end 130.921252 -165.098984)
		(width 0.1016)
		(layer "B.Cu")
		(net "UART_T8_NODE4_TXD_R")
	)
	(segment
		(start 122.175524 -179.759356)
		(end 123.438412 -178.496468)
		(width 0.1143)
		(layer "In7.Cu")
		(net "UART_T8_NODE4_TXD_R")
	)
	(segment
		(start 112.91062 -183.192674)
		(end 114.32286 -181.780434)
		(width 0.1143)
		(layer "In7.Cu")
		(net "UART_T8_NODE4_TXD_R")
	)
	(segment
		(start 127.08382 -178.054)
		(end 127.78232 -177.3555)
		(width 0.1143)
		(layer "In7.Cu")
		(net "UART_T8_NODE4_TXD_R")
	)
	(segment
		(start 131.839462 -166.017194)
		(end 130.921252 -165.098984)
		(width 0.1143)
		(layer "In7.Cu")
		(net "UART_T8_NODE4_TXD_R")
	)
	(segment
		(start 123.438412 -178.496468)
		(end 126.64186 -178.496468)
		(width 0.1143)
		(layer "In7.Cu")
		(net "UART_T8_NODE4_TXD_R")
	)
	(segment
		(start 127.083312 -178.055016)
		(end 127.08382 -178.055016)
		(width 0.1143)
		(layer "In7.Cu")
		(net "UART_T8_NODE4_TXD_R")
	)
	(segment
		(start 131.839462 -167.875204)
		(end 131.839462 -166.017194)
		(width 0.1143)
		(layer "In7.Cu")
		(net "UART_T8_NODE4_TXD_R")
	)
	(segment
		(start 127.82931 -173.40326)
		(end 127.82931 -171.885356)
		(width 0.1143)
		(layer "In7.Cu")
		(net "UART_T8_NODE4_TXD_R")
	)
	(segment
		(start 127.78232 -173.45025)
		(end 127.82931 -173.40326)
		(width 0.1143)
		(layer "In7.Cu")
		(net "UART_T8_NODE4_TXD_R")
	)
	(segment
		(start 114.32286 -181.780434)
		(end 114.32286 -180.721)
		(width 0.1143)
		(layer "In7.Cu")
		(net "UART_T8_NODE4_TXD_R")
	)
	(segment
		(start 112.91062 -183.874918)
		(end 112.91062 -183.192674)
		(width 0.1143)
		(layer "In7.Cu")
		(net "UART_T8_NODE4_TXD_R")
	)
	(segment
		(start 127.82931 -171.885356)
		(end 131.839462 -167.875204)
		(width 0.1143)
		(layer "In7.Cu")
		(net "UART_T8_NODE4_TXD_R")
	)
	(segment
		(start 126.64186 -178.496468)
		(end 127.083312 -178.055016)
		(width 0.1143)
		(layer "In7.Cu")
		(net "UART_T8_NODE4_TXD_R")
	)
	(segment
		(start 127.78232 -177.3555)
		(end 127.78232 -173.45025)
		(width 0.1143)
		(layer "In7.Cu")
		(net "UART_T8_NODE4_TXD_R")
	)
	(segment
		(start 114.32286 -180.721)
		(end 115.284504 -179.759356)
		(width 0.1143)
		(layer "In7.Cu")
		(net "UART_T8_NODE4_TXD_R")
	)
	(segment
		(start 115.284504 -179.759356)
		(end 122.175524 -179.759356)
		(width 0.1143)
		(layer "In7.Cu")
		(net "UART_T8_NODE4_TXD_R")
	)
	(segment
		(start 127.08382 -178.055016)
		(end 127.08382 -178.054)
		(width 0.1143)
		(layer "In7.Cu")
		(net "UART_T8_NODE4_TXD_R")
	)
	(segment
		(start 150.48992 -188.536834)
		(end 150.48992 -195.964556)
		(width 0.1016)
		(layer "F.Cu")
		(net "UART_T12_NODE1_TXD_R")
	)
	(segment
		(start 150.48992 -195.964556)
		(end 150.48992 -197.874128)
		(width 0.1016)
		(layer "F.Cu")
		(net "UART_T12_NODE1_TXD_R")
	)
	(segment
		(start 150.47976 -186.178952)
		(end 149.850094 -186.808618)
		(width 0.1016)
		(layer "F.Cu")
		(net "UART_T12_NODE1_TXD_R")
	)
	(segment
		(start 150.47976 -185.605674)
		(end 150.47976 -186.178952)
		(width 0.1016)
		(layer "F.Cu")
		(net "UART_T12_NODE1_TXD_R")
	)
	(segment
		(start 149.015704 -199.348344)
		(end 149.015704 -205.199488)
		(width 0.1016)
		(layer "F.Cu")
		(net "UART_T12_NODE1_TXD_R")
	)
	(segment
		(start 150.47976 -188.526674)
		(end 150.48992 -188.536834)
		(width 0.1016)
		(layer "F.Cu")
		(net "UART_T12_NODE1_TXD_R")
	)
	(segment
		(start 149.850094 -186.808618)
		(end 149.850094 -187.897008)
		(width 0.1016)
		(layer "F.Cu")
		(net "UART_T12_NODE1_TXD_R")
	)
	(segment
		(start 149.850094 -187.897008)
		(end 150.47976 -188.526674)
		(width 0.1016)
		(layer "F.Cu")
		(net "UART_T12_NODE1_TXD_R")
	)
	(segment
		(start 150.48992 -197.874128)
		(end 149.015704 -199.348344)
		(width 0.1016)
		(layer "F.Cu")
		(net "UART_T12_NODE1_TXD_R")
	)
	(via
		(at 150.48992 -195.964556)
		(size 0.508)
		(drill 0.254)
		(layers "F.Cu" "B.Cu")
		(net "UART_T12_NODE1_TXD_R")
	)
	(segment
		(start 130.4671 -191.844422)
		(end 131.30276 -191.008762)
		(width 0.1016)
		(layer "F.Cu")
		(net "UART_T10_NODE3_RXD_R")
	)
	(segment
		(start 129.98958 -198.10476)
		(end 130.015488 -198.130668)
		(width 0.1016)
		(layer "F.Cu")
		(net "UART_T10_NODE3_RXD_R")
	)
	(segment
		(start 130.015488 -198.130668)
		(end 130.015488 -205.199488)
		(width 0.1016)
		(layer "F.Cu")
		(net "UART_T10_NODE3_RXD_R")
	)
	(segment
		(start 129.98958 -198.10476)
		(end 130.4671 -197.62724)
		(width 0.1016)
		(layer "F.Cu")
		(net "UART_T10_NODE3_RXD_R")
	)
	(segment
		(start 130.4671 -197.62724)
		(end 130.4671 -191.844422)
		(width 0.1016)
		(layer "F.Cu")
		(net "UART_T10_NODE3_RXD_R")
	)
	(segment
		(start 131.30276 -191.008762)
		(end 131.30276 -188.526674)
		(width 0.1016)
		(layer "F.Cu")
		(net "UART_T10_NODE3_RXD_R")
	)
	(via
		(at 129.98958 -198.10476)
		(size 0.508)
		(drill 0.254)
		(layers "F.Cu" "B.Cu")
		(net "UART_T10_NODE3_RXD_R")
	)
	(segment
		(start 119.81434 -184.482486)
		(end 119.48922 -184.807606)
		(width 0.1016)
		(layer "F.Cu")
		(net "T7_NODE1_EN_R")
	)
	(segment
		(start 119.941086 -184.482486)
		(end 119.81434 -184.482486)
		(width 0.1016)
		(layer "F.Cu")
		(net "T7_NODE1_EN_R")
	)
	(segment
		(start 120.28424 -184.139332)
		(end 119.941086 -184.482486)
		(width 0.1016)
		(layer "F.Cu")
		(net "T7_NODE1_EN_R")
	)
	(segment
		(start 120.28424 -184.137554)
		(end 120.28424 -184.139332)
		(width 0.1016)
		(layer "F.Cu")
		(net "T7_NODE1_EN_R")
	)
	(segment
		(start 119.48922 -184.807606)
		(end 119.48922 -184.809892)
		(width 0.1016)
		(layer "F.Cu")
		(net "T7_NODE1_EN_R")
	)
	(via
		(at 120.28424 -184.137554)
		(size 0.508)
		(drill 0.254)
		(layers "F.Cu" "B.Cu")
		(net "T7_NODE1_EN_R")
	)
	(via
		(at 121.48566 -199.743822)
		(size 0.6604)
		(drill 0.3302)
		(layers "F.Cu" "B.Cu")
		(net "T7_NODE1_EN_R")
	)
	(segment
		(start 121.48566 -199.743822)
		(end 121.48566 -188.888878)
		(width 0.1016)
		(layer "B.Cu")
		(net "T7_NODE1_EN_R")
	)
	(segment
		(start 121.015506 -202.106276)
		(end 121.015506 -205.199488)
		(width 0.1016)
		(layer "B.Cu")
		(net "T7_NODE1_EN_R")
	)
	(segment
		(start 120.28424 -184.137554)
		(end 119.95404 -184.467754)
		(width 0.1016)
		(layer "B.Cu")
		(net "T7_NODE1_EN_R")
	)
	(segment
		(start 121.48566 -201.636122)
		(end 121.015506 -202.106276)
		(width 0.1016)
		(layer "B.Cu")
		(net "T7_NODE1_EN_R")
	)
	(segment
		(start 121.48566 -199.743822)
		(end 121.48566 -201.636122)
		(width 0.1016)
		(layer "B.Cu")
		(net "T7_NODE1_EN_R")
	)
	(segment
		(start 119.95404 -184.467754)
		(end 119.95404 -185.143394)
		(width 0.1016)
		(layer "B.Cu")
		(net "T7_NODE1_EN_R")
	)
	(segment
		(start 120.214136 -186.01309)
		(end 119.80672 -185.605674)
		(width 0.1016)
		(layer "B.Cu")
		(net "T7_NODE1_EN_R")
	)
	(segment
		(start 121.48566 -188.888878)
		(end 120.214136 -187.617354)
		(width 0.1016)
		(layer "B.Cu")
		(net "T7_NODE1_EN_R")
	)
	(segment
		(start 120.214136 -187.617354)
		(end 120.214136 -186.01309)
		(width 0.1016)
		(layer "B.Cu")
		(net "T7_NODE1_EN_R")
	)
	(segment
		(start 119.80672 -185.605674)
		(end 119.49176 -185.605674)
		(width 0.1016)
		(layer "B.Cu")
		(net "T7_NODE1_EN_R")
	)
	(segment
		(start 119.95404 -185.143394)
		(end 119.49176 -185.605674)
		(width 0.1016)
		(layer "B.Cu")
		(net "T7_NODE1_EN_R")
	)
	(segment
		(start 90.702384 -184.794398)
		(end 90.343736 -184.794398)
		(width 0.1016)
		(layer "F.Cu")
		(net "UART_T5_NODE3_TXD_R")
	)
	(segment
		(start 90.343736 -184.794398)
		(end 90.04808 -185.090054)
		(width 0.1016)
		(layer "F.Cu")
		(net "UART_T5_NODE3_TXD_R")
	)
	(via
		(at 90.04808 -185.090054)
		(size 0.508)
		(drill 0.254)
		(layers "F.Cu" "B.Cu")
		(net "UART_T5_NODE3_TXD_R")
	)
	(via
		(at 86.015068 -199.571864)
		(size 0.6604)
		(drill 0.3302)
		(layers "F.Cu" "B.Cu")
		(net "UART_T5_NODE3_TXD_R")
	)
	(segment
		(start 84.38896 -186.73826)
		(end 84.38896 -192.133982)
		(width 0.1016)
		(layer "B.Cu")
		(net "UART_T5_NODE3_TXD_R")
	)
	(segment
		(start 84.38896 -192.133982)
		(end 85.24494 -192.989962)
		(width 0.1016)
		(layer "B.Cu")
		(net "UART_T5_NODE3_TXD_R")
	)
	(segment
		(start 85.24494 -192.989962)
		(end 85.24494 -198.772272)
		(width 0.1016)
		(layer "B.Cu")
		(net "UART_T5_NODE3_TXD_R")
	)
	(segment
		(start 86.015068 -205.199488)
		(end 86.015068 -199.571864)
		(width 0.1016)
		(layer "B.Cu")
		(net "UART_T5_NODE3_TXD_R")
	)
	(segment
		(start 90.702384 -184.794398)
		(end 90.343736 -184.794398)
		(width 0.1016)
		(layer "B.Cu")
		(net "UART_T5_NODE3_TXD_R")
	)
	(segment
		(start 90.04808 -185.090054)
		(end 89.778078 -185.360056)
		(width 0.1016)
		(layer "B.Cu")
		(net "UART_T5_NODE3_TXD_R")
	)
	(segment
		(start 85.767164 -185.360056)
		(end 84.38896 -186.73826)
		(width 0.1016)
		(layer "B.Cu")
		(net "UART_T5_NODE3_TXD_R")
	)
	(segment
		(start 89.778078 -185.360056)
		(end 85.767164 -185.360056)
		(width 0.1016)
		(layer "B.Cu")
		(net "UART_T5_NODE3_TXD_R")
	)
	(segment
		(start 90.343736 -184.794398)
		(end 90.04808 -185.090054)
		(width 0.1016)
		(layer "B.Cu")
		(net "UART_T5_NODE3_TXD_R")
	)
	(segment
		(start 86.015068 -199.5424)
		(end 86.015068 -199.571864)
		(width 0.1016)
		(layer "B.Cu")
		(net "UART_T5_NODE3_TXD_R")
	)
	(segment
		(start 85.24494 -198.772272)
		(end 86.015068 -199.5424)
		(width 0.1016)
		(layer "B.Cu")
		(net "UART_T5_NODE3_TXD_R")
	)
	(segment
		(start 150.015702 -199.924416)
		(end 150.015702 -205.199488)
		(width 0.1016)
		(layer "F.Cu")
		(net "UART_T12_NODE1_RXD_R")
	)
	(segment
		(start 151.77262 -190.4492)
		(end 151.62276 -190.29934)
		(width 0.1016)
		(layer "F.Cu")
		(net "UART_T12_NODE1_RXD_R")
	)
	(segment
		(start 151.62276 -190.29934)
		(end 151.62276 -188.526674)
		(width 0.1016)
		(layer "F.Cu")
		(net "UART_T12_NODE1_RXD_R")
	)
	(segment
		(start 151.77262 -198.168514)
		(end 151.77262 -190.4492)
		(width 0.1016)
		(layer "F.Cu")
		(net "UART_T12_NODE1_RXD_R")
	)
	(segment
		(start 151.77262 -198.168514)
		(end 150.125938 -199.815196)
		(width 0.1016)
		(layer "F.Cu")
		(net "UART_T12_NODE1_RXD_R")
	)
	(segment
		(start 150.125938 -199.815196)
		(end 150.124922 -199.815196)
		(width 0.1016)
		(layer "F.Cu")
		(net "UART_T12_NODE1_RXD_R")
	)
	(segment
		(start 150.124922 -199.815196)
		(end 150.015702 -199.924416)
		(width 0.1016)
		(layer "F.Cu")
		(net "UART_T12_NODE1_RXD_R")
	)
	(via
		(at 151.77262 -198.168514)
		(size 0.508)
		(drill 0.254)
		(layers "F.Cu" "B.Cu")
		(net "UART_T12_NODE1_RXD_R")
	)
	(via
		(at 69.96176 -195.781422)
		(size 0.6604)
		(drill 0.3302)
		(layers "F.Cu" "B.Cu")
		(net "UART_T3_NODE3_TXD_R")
	)
	(segment
		(start 69.96176 -195.781422)
		(end 69.96176 -188.526674)
		(width 0.1016)
		(layer "B.Cu")
		(net "UART_T3_NODE3_TXD_R")
	)
	(segment
		(start 69.015102 -205.199488)
		(end 69.015102 -202.094338)
		(width 0.1016)
		(layer "B.Cu")
		(net "UART_T3_NODE3_TXD_R")
	)
	(segment
		(start 69.66204 -201.4474)
		(end 69.66204 -198.152512)
		(width 0.1016)
		(layer "B.Cu")
		(net "UART_T3_NODE3_TXD_R")
	)
	(segment
		(start 69.96176 -185.967878)
		(end 69.38264 -186.546998)
		(width 0.1016)
		(layer "B.Cu")
		(net "UART_T3_NODE3_TXD_R")
	)
	(segment
		(start 69.66204 -198.152512)
		(end 69.31152 -197.801992)
		(width 0.1016)
		(layer "B.Cu")
		(net "UART_T3_NODE3_TXD_R")
	)
	(segment
		(start 69.38264 -186.546998)
		(end 69.38264 -187.947554)
		(width 0.1016)
		(layer "B.Cu")
		(net "UART_T3_NODE3_TXD_R")
	)
	(segment
		(start 69.31152 -196.718682)
		(end 69.96176 -196.068442)
		(width 0.1016)
		(layer "B.Cu")
		(net "UART_T3_NODE3_TXD_R")
	)
	(segment
		(start 69.31152 -197.801992)
		(end 69.31152 -196.718682)
		(width 0.1016)
		(layer "B.Cu")
		(net "UART_T3_NODE3_TXD_R")
	)
	(segment
		(start 69.96176 -185.605674)
		(end 69.96176 -185.967878)
		(width 0.1016)
		(layer "B.Cu")
		(net "UART_T3_NODE3_TXD_R")
	)
	(segment
		(start 69.96176 -196.068442)
		(end 69.96176 -195.781422)
		(width 0.1016)
		(layer "B.Cu")
		(net "UART_T3_NODE3_TXD_R")
	)
	(segment
		(start 69.38264 -187.947554)
		(end 69.96176 -188.526674)
		(width 0.1016)
		(layer "B.Cu")
		(net "UART_T3_NODE3_TXD_R")
	)
	(segment
		(start 69.015102 -202.094338)
		(end 69.66204 -201.4474)
		(width 0.1016)
		(layer "B.Cu")
		(net "UART_T3_NODE3_TXD_R")
	)
	(via
		(at 120.80748 -197.89013)
		(size 0.6604)
		(drill 0.3302)
		(layers "F.Cu" "B.Cu")
		(net "T7_NODE2_EN_R")
	)
	(segment
		(start 119.115586 -188.526674)
		(end 119.49176 -188.526674)
		(width 0.1016)
		(layer "B.Cu")
		(net "T7_NODE2_EN_R")
	)
	(segment
		(start 119.49176 -195.741798)
		(end 120.80748 -197.057518)
		(width 0.1016)
		(layer "B.Cu")
		(net "T7_NODE2_EN_R")
	)
	(segment
		(start 119.02186 -188.432948)
		(end 119.115586 -188.526674)
		(width 0.1016)
		(layer "B.Cu")
		(net "T7_NODE2_EN_R")
	)
	(segment
		(start 120.015508 -200.5076)
		(end 120.015508 -205.199488)
		(width 0.1016)
		(layer "B.Cu")
		(net "T7_NODE2_EN_R")
	)
	(segment
		(start 120.80748 -199.715628)
		(end 120.015508 -200.5076)
		(width 0.1016)
		(layer "B.Cu")
		(net "T7_NODE2_EN_R")
	)
	(segment
		(start 119.02186 -186.151774)
		(end 119.02186 -188.432948)
		(width 0.1016)
		(layer "B.Cu")
		(net "T7_NODE2_EN_R")
	)
	(segment
		(start 120.80748 -197.89013)
		(end 120.80748 -199.715628)
		(width 0.1016)
		(layer "B.Cu")
		(net "T7_NODE2_EN_R")
	)
	(segment
		(start 118.47576 -185.605674)
		(end 119.02186 -186.151774)
		(width 0.1016)
		(layer "B.Cu")
		(net "T7_NODE2_EN_R")
	)
	(segment
		(start 120.80748 -197.057518)
		(end 120.80748 -197.89013)
		(width 0.1016)
		(layer "B.Cu")
		(net "T7_NODE2_EN_R")
	)
	(segment
		(start 119.49176 -188.526674)
		(end 119.49176 -195.741798)
		(width 0.1016)
		(layer "B.Cu")
		(net "T7_NODE2_EN_R")
	)
	(via
		(at 83.38312 -195.594478)
		(size 0.6604)
		(drill 0.3302)
		(layers "F.Cu" "B.Cu")
		(net "UART_T5_NODE4_RXD_R")
	)
	(segment
		(start 92.857066 -184.358534)
		(end 93.27388 -184.775348)
		(width 0.1016)
		(layer "B.Cu")
		(net "UART_T5_NODE4_RXD_R")
	)
	(segment
		(start 83.015074 -199.774302)
		(end 83.015074 -205.199488)
		(width 0.1016)
		(layer "B.Cu")
		(net "UART_T5_NODE4_RXD_R")
	)
	(segment
		(start 89.310718 -184.358534)
		(end 92.857066 -184.358534)
		(width 0.1016)
		(layer "B.Cu")
		(net "UART_T5_NODE4_RXD_R")
	)
	(segment
		(start 83.221322 -186.742324)
		(end 84.90839 -185.055256)
		(width 0.1016)
		(layer "B.Cu")
		(net "UART_T5_NODE4_RXD_R")
	)
	(segment
		(start 84.90839 -185.055256)
		(end 88.613996 -185.055256)
		(width 0.1016)
		(layer "B.Cu")
		(net "UART_T5_NODE4_RXD_R")
	)
	(segment
		(start 93.811344 -185.5851)
		(end 93.811344 -185.790586)
		(width 0.1016)
		(layer "B.Cu")
		(net "UART_T5_NODE4_RXD_R")
	)
	(segment
		(start 93.27388 -184.775348)
		(end 93.27388 -185.047636)
		(width 0.1016)
		(layer "B.Cu")
		(net "UART_T5_NODE4_RXD_R")
	)
	(segment
		(start 83.38312 -195.594478)
		(end 83.221322 -195.43268)
		(width 0.1016)
		(layer "B.Cu")
		(net "UART_T5_NODE4_RXD_R")
	)
	(segment
		(start 88.613996 -185.055256)
		(end 89.310718 -184.358534)
		(width 0.1016)
		(layer "B.Cu")
		(net "UART_T5_NODE4_RXD_R")
	)
	(segment
		(start 83.38312 -195.594478)
		(end 83.38312 -199.406256)
		(width 0.1016)
		(layer "B.Cu")
		(net "UART_T5_NODE4_RXD_R")
	)
	(segment
		(start 83.221322 -195.43268)
		(end 83.221322 -186.742324)
		(width 0.1016)
		(layer "B.Cu")
		(net "UART_T5_NODE4_RXD_R")
	)
	(segment
		(start 93.27388 -185.047636)
		(end 93.811344 -185.5851)
		(width 0.1016)
		(layer "B.Cu")
		(net "UART_T5_NODE4_RXD_R")
	)
	(segment
		(start 83.38312 -199.406256)
		(end 83.015074 -199.774302)
		(width 0.1016)
		(layer "B.Cu")
		(net "UART_T5_NODE4_RXD_R")
	)
	(via
		(at 68.55206 -196.410072)
		(size 0.6604)
		(drill 0.3302)
		(layers "F.Cu" "B.Cu")
		(net "UART_T3_NODE4_RXD_R")
	)
	(segment
		(start 68.015104 -200.462388)
		(end 68.015104 -205.199488)
		(width 0.1016)
		(layer "B.Cu")
		(net "UART_T3_NODE4_RXD_R")
	)
	(segment
		(start 68.55206 -196.410072)
		(end 68.55206 -189.46876)
		(width 0.1016)
		(layer "B.Cu")
		(net "UART_T3_NODE4_RXD_R")
	)
	(segment
		(start 68.81876 -189.20206)
		(end 68.81876 -188.526674)
		(width 0.1016)
		(layer "B.Cu")
		(net "UART_T3_NODE4_RXD_R")
	)
	(segment
		(start 68.55206 -199.925432)
		(end 68.015104 -200.462388)
		(width 0.1016)
		(layer "B.Cu")
		(net "UART_T3_NODE4_RXD_R")
	)
	(segment
		(start 68.55206 -196.410072)
		(end 68.55206 -199.925432)
		(width 0.1016)
		(layer "B.Cu")
		(net "UART_T3_NODE4_RXD_R")
	)
	(segment
		(start 68.55206 -189.46876)
		(end 68.81876 -189.20206)
		(width 0.1016)
		(layer "B.Cu")
		(net "UART_T3_NODE4_RXD_R")
	)
	(segment
		(start 90.702384 -183.778398)
		(end 89.86647 -183.778398)
		(width 0.1016)
		(layer "F.Cu")
		(net "UART_T5_NODE4_TXD_R")
	)
	(segment
		(start 89.86647 -183.778398)
		(end 89.5096 -183.421528)
		(width 0.1016)
		(layer "F.Cu")
		(net "UART_T5_NODE4_TXD_R")
	)
	(via
		(at 82.009234 -199.41286)
		(size 0.6604)
		(drill 0.3302)
		(layers "F.Cu" "B.Cu")
		(net "UART_T5_NODE4_TXD_R")
	)
	(via
		(at 89.5096 -183.421528)
		(size 0.508)
		(drill 0.254)
		(layers "F.Cu" "B.Cu")
		(net "UART_T5_NODE4_TXD_R")
	)
	(segment
		(start 82.009234 -186.191906)
		(end 82.009234 -199.41286)
		(width 0.1016)
		(layer "B.Cu")
		(net "UART_T5_NODE4_TXD_R")
	)
	(segment
		(start 89.5096 -183.421528)
		(end 88.809576 -183.421528)
		(width 0.1016)
		(layer "B.Cu")
		(net "UART_T5_NODE4_TXD_R")
	)
	(segment
		(start 87.604092 -184.627012)
		(end 83.574636 -184.627012)
		(width 0.1016)
		(layer "B.Cu")
		(net "UART_T5_NODE4_TXD_R")
	)
	(segment
		(start 82.015076 -199.418702)
		(end 82.009234 -199.41286)
		(width 0.1016)
		(layer "B.Cu")
		(net "UART_T5_NODE4_TXD_R")
	)
	(segment
		(start 83.574636 -184.627012)
		(end 82.009234 -186.191906)
		(width 0.1016)
		(layer "B.Cu")
		(net "UART_T5_NODE4_TXD_R")
	)
	(segment
		(start 82.015076 -205.199488)
		(end 82.015076 -199.418702)
		(width 0.1016)
		(layer "B.Cu")
		(net "UART_T5_NODE4_TXD_R")
	)
	(segment
		(start 89.86647 -183.778398)
		(end 89.5096 -183.421528)
		(width 0.1016)
		(layer "B.Cu")
		(net "UART_T5_NODE4_TXD_R")
	)
	(segment
		(start 90.702384 -183.778398)
		(end 89.86647 -183.778398)
		(width 0.1016)
		(layer "B.Cu")
		(net "UART_T5_NODE4_TXD_R")
	)
	(segment
		(start 88.809576 -183.421528)
		(end 87.604092 -184.627012)
		(width 0.1016)
		(layer "B.Cu")
		(net "UART_T5_NODE4_TXD_R")
	)
	(segment
		(start 147.015708 -202.29322)
		(end 147.57654 -201.732388)
		(width 0.1016)
		(layer "F.Cu")
		(net "UART_T12_NODE2_TXD_R")
	)
	(segment
		(start 147.015708 -205.199488)
		(end 147.015708 -202.29322)
		(width 0.1016)
		(layer "F.Cu")
		(net "UART_T12_NODE2_TXD_R")
	)
	(segment
		(start 147.605496 -187.93841)
		(end 148.19376 -188.526674)
		(width 0.1016)
		(layer "F.Cu")
		(net "UART_T12_NODE2_TXD_R")
	)
	(segment
		(start 147.57654 -197.336918)
		(end 147.12696 -196.887338)
		(width 0.1016)
		(layer "F.Cu")
		(net "UART_T12_NODE2_TXD_R")
	)
	(segment
		(start 147.12696 -190.760096)
		(end 148.19376 -189.693296)
		(width 0.1016)
		(layer "F.Cu")
		(net "UART_T12_NODE2_TXD_R")
	)
	(segment
		(start 147.605496 -186.63412)
		(end 147.605496 -187.93841)
		(width 0.1016)
		(layer "F.Cu")
		(net "UART_T12_NODE2_TXD_R")
	)
	(segment
		(start 148.19376 -189.693296)
		(end 148.19376 -188.526674)
		(width 0.1016)
		(layer "F.Cu")
		(net "UART_T12_NODE2_TXD_R")
	)
	(segment
		(start 147.12696 -196.887338)
		(end 147.12696 -190.760096)
		(width 0.1016)
		(layer "F.Cu")
		(net "UART_T12_NODE2_TXD_R")
	)
	(segment
		(start 148.19376 -185.605674)
		(end 148.19376 -186.045856)
		(width 0.1016)
		(layer "F.Cu")
		(net "UART_T12_NODE2_TXD_R")
	)
	(segment
		(start 147.57654 -201.732388)
		(end 147.57654 -197.336918)
		(width 0.1016)
		(layer "F.Cu")
		(net "UART_T12_NODE2_TXD_R")
	)
	(segment
		(start 148.19376 -186.045856)
		(end 147.605496 -186.63412)
		(width 0.1016)
		(layer "F.Cu")
		(net "UART_T12_NODE2_TXD_R")
	)
	(via
		(at 147.12696 -196.887338)
		(size 0.508)
		(drill 0.254)
		(layers "F.Cu" "B.Cu")
		(net "UART_T12_NODE2_TXD_R")
	)
	(via
		(at 67.7799 -199.636634)
		(size 0.6604)
		(drill 0.3302)
		(layers "F.Cu" "B.Cu")
		(net "UART_T3_NODE4_TXD_R")
	)
	(segment
		(start 67.7799 -199.636634)
		(end 67.015106 -200.401428)
		(width 0.1016)
		(layer "B.Cu")
		(net "UART_T3_NODE4_TXD_R")
	)
	(segment
		(start 67.11188 -187.962794)
		(end 67.11188 -186.686444)
		(width 0.1016)
		(layer "B.Cu")
		(net "UART_T3_NODE4_TXD_R")
	)
	(segment
		(start 67.67576 -188.526674)
		(end 67.11188 -187.962794)
		(width 0.1016)
		(layer "B.Cu")
		(net "UART_T3_NODE4_TXD_R")
	)
	(segment
		(start 67.11188 -186.686444)
		(end 67.67576 -186.122564)
		(width 0.1016)
		(layer "B.Cu")
		(net "UART_T3_NODE4_TXD_R")
	)
	(segment
		(start 67.015106 -200.401428)
		(end 67.015106 -205.199488)
		(width 0.1016)
		(layer "B.Cu")
		(net "UART_T3_NODE4_TXD_R")
	)
	(segment
		(start 67.67576 -188.526674)
		(end 67.67576 -199.532494)
		(width 0.1016)
		(layer "B.Cu")
		(net "UART_T3_NODE4_TXD_R")
	)
	(segment
		(start 67.67576 -199.532494)
		(end 67.7799 -199.636634)
		(width 0.1016)
		(layer "B.Cu")
		(net "UART_T3_NODE4_TXD_R")
	)
	(segment
		(start 67.67576 -186.122564)
		(end 67.67576 -185.605674)
		(width 0.1016)
		(layer "B.Cu")
		(net "UART_T3_NODE4_TXD_R")
	)
	(via
		(at 60.98032 -198.096632)
		(size 0.6604)
		(drill 0.3302)
		(layers "F.Cu" "B.Cu")
		(net "UART_T1_NODE2_RXD_R")
	)
	(segment
		(start 61.96076 -188.526674)
		(end 61.96076 -192.296034)
		(width 0.1016)
		(layer "B.Cu")
		(net "UART_T1_NODE2_RXD_R")
	)
	(segment
		(start 60.01512 -200.506584)
		(end 60.01512 -205.199488)
		(width 0.1016)
		(layer "B.Cu")
		(net "UART_T1_NODE2_RXD_R")
	)
	(segment
		(start 61.37402 -195.703698)
		(end 60.98032 -196.097398)
		(width 0.1016)
		(layer "B.Cu")
		(net "UART_T1_NODE2_RXD_R")
	)
	(segment
		(start 60.98032 -196.097398)
		(end 60.98032 -198.096632)
		(width 0.1016)
		(layer "B.Cu")
		(net "UART_T1_NODE2_RXD_R")
	)
	(segment
		(start 60.98032 -198.096632)
		(end 60.98032 -199.541384)
		(width 0.1016)
		(layer "B.Cu")
		(net "UART_T1_NODE2_RXD_R")
	)
	(segment
		(start 61.96076 -192.296034)
		(end 61.37402 -192.882774)
		(width 0.1016)
		(layer "B.Cu")
		(net "UART_T1_NODE2_RXD_R")
	)
	(segment
		(start 60.98032 -199.541384)
		(end 60.01512 -200.506584)
		(width 0.1016)
		(layer "B.Cu")
		(net "UART_T1_NODE2_RXD_R")
	)
	(segment
		(start 61.37402 -192.882774)
		(end 61.37402 -195.703698)
		(width 0.1016)
		(layer "B.Cu")
		(net "UART_T1_NODE2_RXD_R")
	)
	(via
		(at 109.54766 -199.512936)
		(size 0.6604)
		(drill 0.3302)
		(layers "F.Cu" "B.Cu")
		(net "UART_T7_NODE4_RXD_R")
	)
	(segment
		(start 109.54766 -199.799448)
		(end 109.54766 -199.512936)
		(width 0.1016)
		(layer "B.Cu")
		(net "UART_T7_NODE4_RXD_R")
	)
	(segment
		(start 109.58576 -188.526674)
		(end 109.58576 -188.912754)
		(width 0.1016)
		(layer "B.Cu")
		(net "UART_T7_NODE4_RXD_R")
	)
	(segment
		(start 109.54766 -188.950854)
		(end 109.54766 -199.512936)
		(width 0.1016)
		(layer "B.Cu")
		(net "UART_T7_NODE4_RXD_R")
	)
	(segment
		(start 109.01553 -205.199488)
		(end 109.01553 -200.331578)
		(width 0.1016)
		(layer "B.Cu")
		(net "UART_T7_NODE4_RXD_R")
	)
	(segment
		(start 109.58576 -188.912754)
		(end 109.54766 -188.950854)
		(width 0.1016)
		(layer "B.Cu")
		(net "UART_T7_NODE4_RXD_R")
	)
	(segment
		(start 109.01553 -200.331578)
		(end 109.54766 -199.799448)
		(width 0.1016)
		(layer "B.Cu")
		(net "UART_T7_NODE4_RXD_R")
	)
	(segment
		(start 127.48006 -189.652402)
		(end 128.05156 -189.080902)
		(width 0.1016)
		(layer "F.Cu")
		(net "UART_T9_NODE4_TXD_R")
	)
	(segment
		(start 128.05156 -189.080902)
		(end 128.05156 -188.526674)
		(width 0.1016)
		(layer "F.Cu")
		(net "UART_T9_NODE4_TXD_R")
	)
	(via
		(at 127.48006 -189.652402)
		(size 0.508)
		(drill 0.254)
		(layers "F.Cu" "B.Cu")
		(net "UART_T9_NODE4_TXD_R")
	)
	(segment
		(start 127.48006 -189.652402)
		(end 127.48006 -189.089538)
		(width 0.1016)
		(layer "B.Cu")
		(net "UART_T9_NODE4_TXD_R")
	)
	(segment
		(start 127.3556 -171.020486)
		(end 127.3556 -169.118534)
		(width 0.1016)
		(layer "B.Cu")
		(net "UART_T9_NODE4_TXD_R")
	)
	(segment
		(start 128.00076 -173.838108)
		(end 128.00076 -172.958252)
		(width 0.1016)
		(layer "B.Cu")
		(net "UART_T9_NODE4_TXD_R")
	)
	(segment
		(start 127.3556 -169.118534)
		(end 127.866648 -168.607486)
		(width 0.1016)
		(layer "B.Cu")
		(net "UART_T9_NODE4_TXD_R")
	)
	(segment
		(start 127.48006 -191.7827)
		(end 127.48006 -189.652402)
		(width 0.1016)
		(layer "B.Cu")
		(net "UART_T9_NODE4_TXD_R")
	)
	(segment
		(start 123.015502 -198.179182)
		(end 122.90298 -198.06666)
		(width 0.1016)
		(layer "B.Cu")
		(net "UART_T9_NODE4_TXD_R")
	)
	(segment
		(start 134.850632 -165.988492)
		(end 136.397492 -165.988492)
		(width 0.1016)
		(layer "B.Cu")
		(net "UART_T9_NODE4_TXD_R")
	)
	(segment
		(start 122.90298 -196.35978)
		(end 127.48006 -191.7827)
		(width 0.1016)
		(layer "B.Cu")
		(net "UART_T9_NODE4_TXD_R")
	)
	(segment
		(start 125.37186 -186.69889)
		(end 125.2601 -186.58713)
		(width 0.1016)
		(layer "B.Cu")
		(net "UART_T9_NODE4_TXD_R")
	)
	(segment
		(start 128.339596 -174.176944)
		(end 128.00076 -173.838108)
		(width 0.1016)
		(layer "B.Cu")
		(net "UART_T9_NODE4_TXD_R")
	)
	(segment
		(start 130.727196 -168.607486)
		(end 130.73634 -168.61663)
		(width 0.1016)
		(layer "B.Cu")
		(net "UART_T9_NODE4_TXD_R")
	)
	(segment
		(start 125.37186 -186.981338)
		(end 125.37186 -186.69889)
		(width 0.1016)
		(layer "B.Cu")
		(net "UART_T9_NODE4_TXD_R")
	)
	(segment
		(start 130.73634 -168.61663)
		(end 131.15798 -168.61663)
		(width 0.1016)
		(layer "B.Cu")
		(net "UART_T9_NODE4_TXD_R")
	)
	(segment
		(start 126.97714 -171.398946)
		(end 127.3556 -171.020486)
		(width 0.1016)
		(layer "B.Cu")
		(net "UART_T9_NODE4_TXD_R")
	)
	(segment
		(start 128.00076 -172.958252)
		(end 126.97714 -171.933362)
		(width 0.1016)
		(layer "B.Cu")
		(net "UART_T9_NODE4_TXD_R")
	)
	(segment
		(start 131.15798 -168.61663)
		(end 132.874004 -166.900606)
		(width 0.1016)
		(layer "B.Cu")
		(net "UART_T9_NODE4_TXD_R")
	)
	(segment
		(start 127.866648 -168.607486)
		(end 130.727196 -168.607486)
		(width 0.1016)
		(layer "B.Cu")
		(net "UART_T9_NODE4_TXD_R")
	)
	(segment
		(start 125.2601 -185.057796)
		(end 126.688342 -183.629554)
		(width 0.1016)
		(layer "B.Cu")
		(net "UART_T9_NODE4_TXD_R")
	)
	(segment
		(start 125.2601 -186.58713)
		(end 125.2601 -185.057796)
		(width 0.1016)
		(layer "B.Cu")
		(net "UART_T9_NODE4_TXD_R")
	)
	(segment
		(start 136.397492 -165.988492)
		(end 137.215626 -165.170358)
		(width 0.1016)
		(layer "B.Cu")
		(net "UART_T9_NODE4_TXD_R")
	)
	(segment
		(start 122.90298 -198.06666)
		(end 122.90298 -196.35978)
		(width 0.1016)
		(layer "B.Cu")
		(net "UART_T9_NODE4_TXD_R")
	)
	(segment
		(start 129.262632 -179.174394)
		(end 129.456434 -178.980592)
		(width 0.1016)
		(layer "B.Cu")
		(net "UART_T9_NODE4_TXD_R")
	)
	(segment
		(start 123.015502 -205.199488)
		(end 123.015502 -198.179182)
		(width 0.1016)
		(layer "B.Cu")
		(net "UART_T9_NODE4_TXD_R")
	)
	(segment
		(start 133.938518 -166.900606)
		(end 134.850632 -165.988492)
		(width 0.1016)
		(layer "B.Cu")
		(net "UART_T9_NODE4_TXD_R")
	)
	(segment
		(start 129.456434 -174.834804)
		(end 128.798574 -174.176944)
		(width 0.1016)
		(layer "B.Cu")
		(net "UART_T9_NODE4_TXD_R")
	)
	(segment
		(start 129.262632 -182.453534)
		(end 129.262632 -179.174394)
		(width 0.1016)
		(layer "B.Cu")
		(net "UART_T9_NODE4_TXD_R")
	)
	(segment
		(start 126.97714 -171.933362)
		(end 126.97714 -171.398946)
		(width 0.1016)
		(layer "B.Cu")
		(net "UART_T9_NODE4_TXD_R")
	)
	(segment
		(start 137.215626 -165.170358)
		(end 137.638028 -165.170358)
		(width 0.1016)
		(layer "B.Cu")
		(net "UART_T9_NODE4_TXD_R")
	)
	(segment
		(start 129.456434 -178.980592)
		(end 129.456434 -174.834804)
		(width 0.1016)
		(layer "B.Cu")
		(net "UART_T9_NODE4_TXD_R")
	)
	(segment
		(start 132.874004 -166.900606)
		(end 133.938518 -166.900606)
		(width 0.1016)
		(layer "B.Cu")
		(net "UART_T9_NODE4_TXD_R")
	)
	(segment
		(start 128.798574 -174.176944)
		(end 128.339596 -174.176944)
		(width 0.1016)
		(layer "B.Cu")
		(net "UART_T9_NODE4_TXD_R")
	)
	(segment
		(start 128.086612 -183.629554)
		(end 129.262632 -182.453534)
		(width 0.1016)
		(layer "B.Cu")
		(net "UART_T9_NODE4_TXD_R")
	)
	(segment
		(start 126.688342 -183.629554)
		(end 128.086612 -183.629554)
		(width 0.1016)
		(layer "B.Cu")
		(net "UART_T9_NODE4_TXD_R")
	)
	(segment
		(start 127.48006 -189.089538)
		(end 125.37186 -186.981338)
		(width 0.1016)
		(layer "B.Cu")
		(net "UART_T9_NODE4_TXD_R")
	)
	(via
		(at 60.57138 -195.598796)
		(size 0.6604)
		(drill 0.3302)
		(layers "F.Cu" "B.Cu")
		(net "UART_T1_NODE2_TXD_R")
	)
	(segment
		(start 60.24626 -198.357236)
		(end 60.24626 -195.923916)
		(width 0.1016)
		(layer "B.Cu")
		(net "UART_T1_NODE2_TXD_R")
	)
	(segment
		(start 60.81776 -185.605674)
		(end 60.24118 -186.182254)
		(width 0.1016)
		(layer "B.Cu")
		(net "UART_T1_NODE2_TXD_R")
	)
	(segment
		(start 59.45124 -199.152256)
		(end 60.24626 -198.357236)
		(width 0.1016)
		(layer "B.Cu")
		(net "UART_T1_NODE2_TXD_R")
	)
	(segment
		(start 59.45124 -201.44486)
		(end 59.45124 -199.152256)
		(width 0.1016)
		(layer "B.Cu")
		(net "UART_T1_NODE2_TXD_R")
	)
	(segment
		(start 59.015122 -205.199488)
		(end 59.015122 -201.880978)
		(width 0.1016)
		(layer "B.Cu")
		(net "UART_T1_NODE2_TXD_R")
	)
	(segment
		(start 60.57138 -194.588384)
		(end 60.81776 -194.342004)
		(width 0.1016)
		(layer "B.Cu")
		(net "UART_T1_NODE2_TXD_R")
	)
	(segment
		(start 59.015122 -201.880978)
		(end 59.45124 -201.44486)
		(width 0.1016)
		(layer "B.Cu")
		(net "UART_T1_NODE2_TXD_R")
	)
	(segment
		(start 60.57138 -195.598796)
		(end 60.57138 -194.588384)
		(width 0.1016)
		(layer "B.Cu")
		(net "UART_T1_NODE2_TXD_R")
	)
	(segment
		(start 60.24626 -195.923916)
		(end 60.57138 -195.598796)
		(width 0.1016)
		(layer "B.Cu")
		(net "UART_T1_NODE2_TXD_R")
	)
	(segment
		(start 60.24118 -187.950094)
		(end 60.81776 -188.526674)
		(width 0.1016)
		(layer "B.Cu")
		(net "UART_T1_NODE2_TXD_R")
	)
	(segment
		(start 60.81776 -194.342004)
		(end 60.81776 -188.526674)
		(width 0.1016)
		(layer "B.Cu")
		(net "UART_T1_NODE2_TXD_R")
	)
	(segment
		(start 60.24118 -186.182254)
		(end 60.24118 -187.950094)
		(width 0.1016)
		(layer "B.Cu")
		(net "UART_T1_NODE2_TXD_R")
	)
	(via
		(at 110.88624 -195.809616)
		(size 0.6604)
		(drill 0.3302)
		(layers "F.Cu" "B.Cu")
		(net "UART_T7_NODE3_TXD_R")
	)
	(segment
		(start 110.015528 -199.763634)
		(end 110.015528 -205.199488)
		(width 0.1016)
		(layer "B.Cu")
		(net "UART_T7_NODE3_TXD_R")
	)
	(segment
		(start 110.345474 -188.526674)
		(end 110.10138 -188.28258)
		(width 0.1016)
		(layer "B.Cu")
		(net "UART_T7_NODE3_TXD_R")
	)
	(segment
		(start 110.88624 -194.580256)
		(end 110.88624 -195.809616)
		(width 0.1016)
		(layer "B.Cu")
		(net "UART_T7_NODE3_TXD_R")
	)
	(segment
		(start 110.88624 -195.809616)
		(end 110.88624 -198.892922)
		(width 0.1016)
		(layer "B.Cu")
		(net "UART_T7_NODE3_TXD_R")
	)
	(segment
		(start 110.72876 -194.422776)
		(end 110.88624 -194.580256)
		(width 0.1016)
		(layer "B.Cu")
		(net "UART_T7_NODE3_TXD_R")
	)
	(segment
		(start 110.30712 -183.81345)
		(end 110.30712 -182.658512)
		(width 0.1016)
		(layer "B.Cu")
		(net "UART_T7_NODE3_TXD_R")
	)
	(segment
		(start 110.10138 -188.28258)
		(end 110.04296 -188.225176)
		(width 0.1016)
		(layer "B.Cu")
		(net "UART_T7_NODE3_TXD_R")
	)
	(segment
		(start 110.04296 -188.225176)
		(end 110.04296 -184.07761)
		(width 0.1016)
		(layer "B.Cu")
		(net "UART_T7_NODE3_TXD_R")
	)
	(segment
		(start 110.72876 -188.526674)
		(end 110.345474 -188.526674)
		(width 0.1016)
		(layer "B.Cu")
		(net "UART_T7_NODE3_TXD_R")
	)
	(segment
		(start 110.88624 -198.892922)
		(end 110.015528 -199.763634)
		(width 0.1016)
		(layer "B.Cu")
		(net "UART_T7_NODE3_TXD_R")
	)
	(segment
		(start 110.72876 -188.526674)
		(end 110.72876 -194.422776)
		(width 0.1016)
		(layer "B.Cu")
		(net "UART_T7_NODE3_TXD_R")
	)
	(segment
		(start 110.04296 -184.07761)
		(end 110.30712 -183.81345)
		(width 0.1016)
		(layer "B.Cu")
		(net "UART_T7_NODE3_TXD_R")
	)
	(via
		(at 108.08716 -199.772524)
		(size 0.6604)
		(drill 0.3302)
		(layers "F.Cu" "B.Cu")
		(net "UART_T7_NODE4_TXD_R")
	)
	(via
		(at 113.35004 -183.391556)
		(size 0.508)
		(drill 0.254)
		(layers "F.Cu" "B.Cu")
		(net "UART_T7_NODE4_TXD_R")
	)
	(via
		(at 131.669028 -172.274738)
		(size 0.508)
		(drill 0.254)
		(layers "F.Cu" "B.Cu")
		(net "UART_T7_NODE4_TXD_R")
	)
	(via
		(at 107.6706 -186.95797)
		(size 0.508)
		(drill 0.254)
		(layers "F.Cu" "B.Cu")
		(net "UART_T7_NODE4_TXD_R")
	)
	(segment
		(start 108.04398 -199.815704)
		(end 108.04398 -205.171548)
		(width 0.1016)
		(layer "B.Cu")
		(net "UART_T7_NODE4_TXD_R")
	)
	(segment
		(start 108.44276 -189.324742)
		(end 108.44276 -188.526674)
		(width 0.1016)
		(layer "B.Cu")
		(net "UART_T7_NODE4_TXD_R")
	)
	(segment
		(start 131.477258 -172.466508)
		(end 131.669028 -172.274738)
		(width 0.1016)
		(layer "B.Cu")
		(net "UART_T7_NODE4_TXD_R")
	)
	(segment
		(start 108.08716 -199.772524)
		(end 107.9246 -199.609964)
		(width 0.1016)
		(layer "B.Cu")
		(net "UART_T7_NODE4_TXD_R")
	)
	(segment
		(start 108.44276 -188.526674)
		(end 108.053378 -188.526674)
		(width 0.1016)
		(layer "B.Cu")
		(net "UART_T7_NODE4_TXD_R")
	)
	(segment
		(start 108.01604 -205.199488)
		(end 108.015532 -205.199488)
		(width 0.1016)
		(layer "B.Cu")
		(net "UART_T7_NODE4_TXD_R")
	)
	(segment
		(start 107.9246 -199.609964)
		(end 107.9246 -189.842902)
		(width 0.1016)
		(layer "B.Cu")
		(net "UART_T7_NODE4_TXD_R")
	)
	(segment
		(start 130.295142 -172.466508)
		(end 131.477258 -172.466508)
		(width 0.1016)
		(layer "B.Cu")
		(net "UART_T7_NODE4_TXD_R")
	)
	(segment
		(start 108.053378 -188.526674)
		(end 107.88396 -188.357256)
		(width 0.1016)
		(layer "B.Cu")
		(net "UART_T7_NODE4_TXD_R")
	)
	(segment
		(start 108.08716 -199.772524)
		(end 108.04398 -199.815704)
		(width 0.1016)
		(layer "B.Cu")
		(net "UART_T7_NODE4_TXD_R")
	)
	(segment
		(start 107.88396 -187.17133)
		(end 107.6706 -186.95797)
		(width 0.1016)
		(layer "B.Cu")
		(net "UART_T7_NODE4_TXD_R")
	)
	(segment
		(start 108.04398 -205.171548)
		(end 108.01604 -205.199488)
		(width 0.1016)
		(layer "B.Cu")
		(net "UART_T7_NODE4_TXD_R")
	)
	(segment
		(start 107.9246 -189.842902)
		(end 108.44276 -189.324742)
		(width 0.1016)
		(layer "B.Cu")
		(net "UART_T7_NODE4_TXD_R")
	)
	(segment
		(start 107.88396 -188.357256)
		(end 107.88396 -187.17133)
		(width 0.1016)
		(layer "B.Cu")
		(net "UART_T7_NODE4_TXD_R")
	)
	(segment
		(start 112.264698 -183.391556)
		(end 108.4961 -187.160154)
		(width 0.1143)
		(layer "In2.Cu")
		(net "UART_T7_NODE4_TXD_R")
	)
	(segment
		(start 107.872784 -187.160154)
		(end 107.6706 -186.95797)
		(width 0.1143)
		(layer "In2.Cu")
		(net "UART_T7_NODE4_TXD_R")
	)
	(segment
		(start 108.4961 -187.160154)
		(end 107.872784 -187.160154)
		(width 0.1143)
		(layer "In2.Cu")
		(net "UART_T7_NODE4_TXD_R")
	)
	(segment
		(start 113.35004 -183.391556)
		(end 112.264698 -183.391556)
		(width 0.1143)
		(layer "In2.Cu")
		(net "UART_T7_NODE4_TXD_R")
	)
	(segment
		(start 128.09982 -174.393098)
		(end 128.20396 -174.288958)
		(width 0.1143)
		(layer "In7.Cu")
		(net "UART_T7_NODE4_TXD_R")
	)
	(segment
		(start 124.87148 -179.79898)
		(end 125.856492 -178.813968)
		(width 0.1143)
		(layer "In7.Cu")
		(net "UART_T7_NODE4_TXD_R")
	)
	(segment
		(start 128.20396 -173.375828)
		(end 129.30505 -172.274738)
		(width 0.1143)
		(layer "In7.Cu")
		(net "UART_T7_NODE4_TXD_R")
	)
	(segment
		(start 128.09982 -177.488088)
		(end 128.09982 -174.393098)
		(width 0.1143)
		(layer "In7.Cu")
		(net "UART_T7_NODE4_TXD_R")
	)
	(segment
		(start 125.856492 -178.813968)
		(end 126.77394 -178.813968)
		(width 0.1143)
		(layer "In7.Cu")
		(net "UART_T7_NODE4_TXD_R")
	)
	(segment
		(start 114.890042 -181.851554)
		(end 115.51666 -181.851554)
		(width 0.1143)
		(layer "In7.Cu")
		(net "UART_T7_NODE4_TXD_R")
	)
	(segment
		(start 122.767344 -179.79898)
		(end 124.87148 -179.79898)
		(width 0.1143)
		(layer "In7.Cu")
		(net "UART_T7_NODE4_TXD_R")
	)
	(segment
		(start 115.51666 -181.851554)
		(end 115.77193 -181.596284)
		(width 0.1143)
		(layer "In7.Cu")
		(net "UART_T7_NODE4_TXD_R")
	)
	(segment
		(start 115.77193 -181.230524)
		(end 116.892578 -180.109876)
		(width 0.1143)
		(layer "In7.Cu")
		(net "UART_T7_NODE4_TXD_R")
	)
	(segment
		(start 116.892578 -180.109876)
		(end 122.456448 -180.109876)
		(width 0.1143)
		(layer "In7.Cu")
		(net "UART_T7_NODE4_TXD_R")
	)
	(segment
		(start 113.35004 -183.391556)
		(end 114.890042 -181.851554)
		(width 0.1143)
		(layer "In7.Cu")
		(net "UART_T7_NODE4_TXD_R")
	)
	(segment
		(start 128.20396 -174.288958)
		(end 128.20396 -173.375828)
		(width 0.1143)
		(layer "In7.Cu")
		(net "UART_T7_NODE4_TXD_R")
	)
	(segment
		(start 122.456448 -180.109876)
		(end 122.767344 -179.79898)
		(width 0.1143)
		(layer "In7.Cu")
		(net "UART_T7_NODE4_TXD_R")
	)
	(segment
		(start 115.77193 -181.596284)
		(end 115.77193 -181.230524)
		(width 0.1143)
		(layer "In7.Cu")
		(net "UART_T7_NODE4_TXD_R")
	)
	(segment
		(start 129.30505 -172.274738)
		(end 131.669028 -172.274738)
		(width 0.1143)
		(layer "In7.Cu")
		(net "UART_T7_NODE4_TXD_R")
	)
	(segment
		(start 126.77394 -178.813968)
		(end 128.09982 -177.488088)
		(width 0.1143)
		(layer "In7.Cu")
		(net "UART_T7_NODE4_TXD_R")
	)
	(via
		(at 143.015462 -199.591168)
		(size 0.6604)
		(drill 0.3302)
		(layers "F.Cu" "B.Cu")
		(net "UART_T11_NODE2_TXD_R")
	)
	(segment
		(start 143.73479 -196.80047)
		(end 143.73479 -195.451984)
		(width 0.1016)
		(layer "B.Cu")
		(net "UART_T11_NODE2_TXD_R")
	)
	(segment
		(start 143.015462 -199.591168)
		(end 143.0909 -199.51573)
		(width 0.1016)
		(layer "B.Cu")
		(net "UART_T11_NODE2_TXD_R")
	)
	(segment
		(start 145.65376 -193.533014)
		(end 145.65376 -188.399674)
		(width 0.1016)
		(layer "B.Cu")
		(net "UART_T11_NODE2_TXD_R")
	)
	(segment
		(start 143.0909 -199.51573)
		(end 143.0909 -197.44436)
		(width 0.1016)
		(layer "B.Cu")
		(net "UART_T11_NODE2_TXD_R")
	)
	(segment
		(start 146.21256 -186.62904)
		(end 146.21256 -187.840874)
		(width 0.1016)
		(layer "B.Cu")
		(net "UART_T11_NODE2_TXD_R")
	)
	(segment
		(start 143.015462 -205.199488)
		(end 143.015462 -199.591168)
		(width 0.1016)
		(layer "B.Cu")
		(net "UART_T11_NODE2_TXD_R")
	)
	(segment
		(start 143.73479 -195.451984)
		(end 145.65376 -193.533014)
		(width 0.1016)
		(layer "B.Cu")
		(net "UART_T11_NODE2_TXD_R")
	)
	(segment
		(start 145.65376 -186.07024)
		(end 146.21256 -186.62904)
		(width 0.1016)
		(layer "B.Cu")
		(net "UART_T11_NODE2_TXD_R")
	)
	(segment
		(start 146.21256 -187.840874)
		(end 145.65376 -188.399674)
		(width 0.1016)
		(layer "B.Cu")
		(net "UART_T11_NODE2_TXD_R")
	)
	(segment
		(start 145.65376 -185.351674)
		(end 145.65376 -186.07024)
		(width 0.1016)
		(layer "B.Cu")
		(net "UART_T11_NODE2_TXD_R")
	)
	(segment
		(start 143.0909 -197.44436)
		(end 143.73479 -196.80047)
		(width 0.1016)
		(layer "B.Cu")
		(net "UART_T11_NODE2_TXD_R")
	)
	(segment
		(start 149.14118 -196.537072)
		(end 149.14118 -198.321422)
		(width 0.1016)
		(layer "F.Cu")
		(net "UART_T12_NODE2_RXD_R")
	)
	(segment
		(start 149.14118 -196.537072)
		(end 149.33676 -196.341492)
		(width 0.1016)
		(layer "F.Cu")
		(net "UART_T12_NODE2_RXD_R")
	)
	(segment
		(start 149.33676 -196.341492)
		(end 149.33676 -188.526674)
		(width 0.1016)
		(layer "F.Cu")
		(net "UART_T12_NODE2_RXD_R")
	)
	(segment
		(start 148.015706 -199.446896)
		(end 148.015706 -205.199488)
		(width 0.1016)
		(layer "F.Cu")
		(net "UART_T12_NODE2_RXD_R")
	)
	(segment
		(start 149.14118 -198.321422)
		(end 148.015706 -199.446896)
		(width 0.1016)
		(layer "F.Cu")
		(net "UART_T12_NODE2_RXD_R")
	)
	(via
		(at 149.14118 -196.537072)
		(size 0.508)
		(drill 0.254)
		(layers "F.Cu" "B.Cu")
		(net "UART_T12_NODE2_RXD_R")
	)
	(segment
		(start 14.014958 -200.91146)
		(end 14.351 -200.575418)
		(width 0.1016)
		(layer "F.Cu")
		(net "MATE_R_N")
	)
	(segment
		(start 14.014958 -204.699616)
		(end 14.014958 -200.91146)
		(width 0.1016)
		(layer "F.Cu")
		(net "MATE_R_N")
	)
	(via
		(at 26.4922 -196.3674)
		(size 0.508)
		(drill 0.254)
		(layers "F.Cu" "B.Cu")
		(net "MATE_R_N")
	)
	(via
		(at 14.351 -200.575418)
		(size 0.508)
		(drill 0.254)
		(layers "F.Cu" "B.Cu")
		(net "MATE_R_N")
	)
	(via
		(at 44.438316 -185.014616)
		(size 0.508)
		(drill 0.254)
		(layers "F.Cu" "B.Cu")
		(net "MATE_R_N")
	)
	(segment
		(start 26.4922 -196.38899)
		(end 26.4922 -196.3674)
		(width 0.1016)
		(layer "B.Cu")
		(net "MATE_R_N")
	)
	(segment
		(start 44.484544 -192.802256)
		(end 42.1894 -195.0974)
		(width 0.1016)
		(layer "B.Cu")
		(net "MATE_R_N")
	)
	(segment
		(start 44.746418 -185.322718)
		(end 44.438316 -185.014616)
		(width 0.1016)
		(layer "B.Cu")
		(net "MATE_R_N")
	)
	(segment
		(start 45.642022 -185.322718)
		(end 44.746418 -185.322718)
		(width 0.1016)
		(layer "B.Cu")
		(net "MATE_R_N")
	)
	(segment
		(start 45.642022 -191.661542)
		(end 44.501308 -192.802256)
		(width 0.1016)
		(layer "B.Cu")
		(net "MATE_R_N")
	)
	(segment
		(start 27.78379 -195.0974)
		(end 26.4922 -196.38899)
		(width 0.1016)
		(layer "B.Cu")
		(net "MATE_R_N")
	)
	(segment
		(start 42.1894 -195.0974)
		(end 27.78379 -195.0974)
		(width 0.1016)
		(layer "B.Cu")
		(net "MATE_R_N")
	)
	(segment
		(start 45.642022 -185.322718)
		(end 45.642022 -191.661542)
		(width 0.1016)
		(layer "B.Cu")
		(net "MATE_R_N")
	)
	(segment
		(start 44.501308 -192.802256)
		(end 44.484544 -192.802256)
		(width 0.1016)
		(layer "B.Cu")
		(net "MATE_R_N")
	)
	(segment
		(start 26.4922 -196.38899)
		(end 23.28545 -199.59574)
		(width 0.1143)
		(layer "In2.Cu")
		(net "MATE_R_N")
	)
	(segment
		(start 23.28545 -199.59574)
		(end 15.330678 -199.59574)
		(width 0.1143)
		(layer "In2.Cu")
		(net "MATE_R_N")
	)
	(segment
		(start 15.330678 -199.59574)
		(end 14.351 -200.575418)
		(width 0.1143)
		(layer "In2.Cu")
		(net "MATE_R_N")
	)
	(segment
		(start 26.4922 -196.3674)
		(end 26.4922 -196.38899)
		(width 0.1143)
		(layer "In2.Cu")
		(net "MATE_R_N")
	)
	(via
		(at 52.36972 -197.524116)
		(size 0.6604)
		(drill 0.3302)
		(layers "F.Cu" "B.Cu")
		(net "UART_T1_NODE1_TXD_R")
	)
	(segment
		(start 53.39842 -187.965334)
		(end 53.95976 -188.526674)
		(width 0.1016)
		(layer "B.Cu")
		(net "UART_T1_NODE1_TXD_R")
	)
	(segment
		(start 52.01412 -197.879716)
		(end 52.01412 -198.667116)
		(width 0.1016)
		(layer "B.Cu")
		(net "UART_T1_NODE1_TXD_R")
	)
	(segment
		(start 53.95976 -190.97752)
		(end 53.95976 -188.526674)
		(width 0.1016)
		(layer "B.Cu")
		(net "UART_T1_NODE1_TXD_R")
	)
	(segment
		(start 52.01412 -198.667116)
		(end 52.014882 -198.667116)
		(width 0.1016)
		(layer "B.Cu")
		(net "UART_T1_NODE1_TXD_R")
	)
	(segment
		(start 53.39842 -186.312556)
		(end 53.39842 -187.965334)
		(width 0.1016)
		(layer "B.Cu")
		(net "UART_T1_NODE1_TXD_R")
	)
	(segment
		(start 52.36972 -197.524116)
		(end 52.36972 -196.895212)
		(width 0.1016)
		(layer "B.Cu")
		(net "UART_T1_NODE1_TXD_R")
	)
	(segment
		(start 53.009038 -196.255894)
		(end 53.009038 -191.928242)
		(width 0.1016)
		(layer "B.Cu")
		(net "UART_T1_NODE1_TXD_R")
	)
	(segment
		(start 53.95976 -185.605674)
		(end 53.95976 -185.751216)
		(width 0.1016)
		(layer "B.Cu")
		(net "UART_T1_NODE1_TXD_R")
	)
	(segment
		(start 52.014882 -198.667116)
		(end 52.014882 -205.199488)
		(width 0.1016)
		(layer "B.Cu")
		(net "UART_T1_NODE1_TXD_R")
	)
	(segment
		(start 52.36972 -197.524116)
		(end 52.01412 -197.879716)
		(width 0.1016)
		(layer "B.Cu")
		(net "UART_T1_NODE1_TXD_R")
	)
	(segment
		(start 52.36972 -196.895212)
		(end 53.009038 -196.255894)
		(width 0.1016)
		(layer "B.Cu")
		(net "UART_T1_NODE1_TXD_R")
	)
	(segment
		(start 53.009038 -191.928242)
		(end 53.95976 -190.97752)
		(width 0.1016)
		(layer "B.Cu")
		(net "UART_T1_NODE1_TXD_R")
	)
	(segment
		(start 53.95976 -185.751216)
		(end 53.39842 -186.312556)
		(width 0.1016)
		(layer "B.Cu")
		(net "UART_T1_NODE1_TXD_R")
	)
	(via
		(at 144.07134 -197.74662)
		(size 0.6604)
		(drill 0.3302)
		(layers "F.Cu" "B.Cu")
		(net "UART_T11_NODE2_RXD_R")
	)
	(segment
		(start 146.79676 -188.399674)
		(end 146.79676 -194.695826)
		(width 0.1016)
		(layer "B.Cu")
		(net "UART_T11_NODE2_RXD_R")
	)
	(segment
		(start 144.441672 -197.050914)
		(end 144.441672 -197.376288)
		(width 0.1016)
		(layer "B.Cu")
		(net "UART_T11_NODE2_RXD_R")
	)
	(segment
		(start 146.79676 -194.695826)
		(end 144.441672 -197.050914)
		(width 0.1016)
		(layer "B.Cu")
		(net "UART_T11_NODE2_RXD_R")
	)
	(segment
		(start 144.441672 -197.376288)
		(end 144.07134 -197.74662)
		(width 0.1016)
		(layer "B.Cu")
		(net "UART_T11_NODE2_RXD_R")
	)
	(segment
		(start 144.01546 -205.199488)
		(end 144.01546 -197.8025)
		(width 0.1016)
		(layer "B.Cu")
		(net "UART_T11_NODE2_RXD_R")
	)
	(segment
		(start 144.01546 -197.8025)
		(end 144.07134 -197.74662)
		(width 0.1016)
		(layer "B.Cu")
		(net "UART_T11_NODE2_RXD_R")
	)
	(segment
		(start 145.47088 -197.404736)
		(end 145.47088 -190.89878)
		(width 0.1016)
		(layer "F.Cu")
		(net "UART_T12_NODE3_RXD_R")
	)
	(segment
		(start 145.47088 -190.89878)
		(end 145.65376 -190.7159)
		(width 0.1016)
		(layer "F.Cu")
		(net "UART_T12_NODE3_RXD_R")
	)
	(segment
		(start 145.015712 -197.859904)
		(end 145.015712 -205.199488)
		(width 0.1016)
		(layer "F.Cu")
		(net "UART_T12_NODE3_RXD_R")
	)
	(segment
		(start 145.65376 -190.7159)
		(end 145.65376 -188.526674)
		(width 0.1016)
		(layer "F.Cu")
		(net "UART_T12_NODE3_RXD_R")
	)
	(segment
		(start 145.47088 -197.404736)
		(end 145.015712 -197.859904)
		(width 0.1016)
		(layer "F.Cu")
		(net "UART_T12_NODE3_RXD_R")
	)
	(via
		(at 145.47088 -197.404736)
		(size 0.508)
		(drill 0.254)
		(layers "F.Cu" "B.Cu")
		(net "UART_T12_NODE3_RXD_R")
	)
	(via
		(at 141.82344 -197.042278)
		(size 0.6604)
		(drill 0.3302)
		(layers "F.Cu" "B.Cu")
		(net "UART_T11_NODE3_RXD_R")
	)
	(segment
		(start 141.82344 -195.66128)
		(end 141.82344 -197.042278)
		(width 0.1016)
		(layer "B.Cu")
		(net "UART_T11_NODE3_RXD_R")
	)
	(segment
		(start 141.447266 -201.213974)
		(end 141.015466 -201.645774)
		(width 0.1016)
		(layer "B.Cu")
		(net "UART_T11_NODE3_RXD_R")
	)
	(segment
		(start 141.447266 -198.550784)
		(end 141.447266 -201.213974)
		(width 0.1016)
		(layer "B.Cu")
		(net "UART_T11_NODE3_RXD_R")
	)
	(segment
		(start 141.015466 -201.645774)
		(end 141.015466 -205.199488)
		(width 0.1016)
		(layer "B.Cu")
		(net "UART_T11_NODE3_RXD_R")
	)
	(segment
		(start 141.82344 -198.17461)
		(end 141.447266 -198.550784)
		(width 0.1016)
		(layer "B.Cu")
		(net "UART_T11_NODE3_RXD_R")
	)
	(segment
		(start 141.82344 -197.042278)
		(end 141.82344 -198.17461)
		(width 0.1016)
		(layer "B.Cu")
		(net "UART_T11_NODE3_RXD_R")
	)
	(segment
		(start 144.51076 -188.399674)
		(end 144.51076 -192.97396)
		(width 0.1016)
		(layer "B.Cu")
		(net "UART_T11_NODE3_RXD_R")
	)
	(segment
		(start 144.51076 -192.97396)
		(end 141.82344 -195.66128)
		(width 0.1016)
		(layer "B.Cu")
		(net "UART_T11_NODE3_RXD_R")
	)
	(via
		(at 119.21744 -198.224394)
		(size 0.6604)
		(drill 0.3302)
		(layers "F.Cu" "B.Cu")
		(net "T7_NODE3_EN_R")
	)
	(segment
		(start 119.01678 -198.550276)
		(end 119.21744 -198.349616)
		(width 0.1016)
		(layer "B.Cu")
		(net "T7_NODE3_EN_R")
	)
	(segment
		(start 118.04396 -188.028834)
		(end 118.04396 -186.691524)
		(width 0.1016)
		(layer "B.Cu")
		(net "T7_NODE3_EN_R")
	)
	(segment
		(start 119.01551 -205.199488)
		(end 119.01551 -198.550276)
		(width 0.1016)
		(layer "B.Cu")
		(net "T7_NODE3_EN_R")
	)
	(segment
		(start 119.21744 -198.224394)
		(end 118.93804 -197.944994)
		(width 0.1016)
		(layer "B.Cu")
		(net "T7_NODE3_EN_R")
	)
	(segment
		(start 118.04396 -186.691524)
		(end 117.45976 -186.107324)
		(width 0.1016)
		(layer "B.Cu")
		(net "T7_NODE3_EN_R")
	)
	(segment
		(start 118.47576 -188.526674)
		(end 118.47576 -188.458856)
		(width 0.1016)
		(layer "B.Cu")
		(net "T7_NODE3_EN_R")
	)
	(segment
		(start 118.93804 -188.988954)
		(end 118.47576 -188.526674)
		(width 0.1016)
		(layer "B.Cu")
		(net "T7_NODE3_EN_R")
	)
	(segment
		(start 117.45976 -186.107324)
		(end 117.45976 -185.605674)
		(width 0.1016)
		(layer "B.Cu")
		(net "T7_NODE3_EN_R")
	)
	(segment
		(start 119.01551 -198.550276)
		(end 119.01678 -198.550276)
		(width 0.1016)
		(layer "B.Cu")
		(net "T7_NODE3_EN_R")
	)
	(segment
		(start 119.21744 -198.349616)
		(end 119.21744 -198.224394)
		(width 0.1016)
		(layer "B.Cu")
		(net "T7_NODE3_EN_R")
	)
	(segment
		(start 118.387622 -188.372496)
		(end 118.04396 -188.028834)
		(width 0.1016)
		(layer "B.Cu")
		(net "T7_NODE3_EN_R")
	)
	(segment
		(start 118.93804 -197.944994)
		(end 118.93804 -188.988954)
		(width 0.1016)
		(layer "B.Cu")
		(net "T7_NODE3_EN_R")
	)
	(segment
		(start 118.3894 -188.372496)
		(end 118.387622 -188.372496)
		(width 0.1016)
		(layer "B.Cu")
		(net "T7_NODE3_EN_R")
	)
	(segment
		(start 118.47576 -188.458856)
		(end 118.3894 -188.372496)
		(width 0.1016)
		(layer "B.Cu")
		(net "T7_NODE3_EN_R")
	)
	(via
		(at 50.9397 -196.099684)
		(size 0.6604)
		(drill 0.3302)
		(layers "F.Cu" "B.Cu")
		(net "PSU1_DC_OK_R")
	)
	(segment
		(start 52.81676 -185.605674)
		(end 52.81676 -186.20359)
		(width 0.1016)
		(layer "B.Cu")
		(net "PSU1_DC_OK_R")
	)
	(segment
		(start 51.55692 -195.482464)
		(end 50.9397 -196.099684)
		(width 0.1016)
		(layer "B.Cu")
		(net "PSU1_DC_OK_R")
	)
	(segment
		(start 52.15128 -187.861194)
		(end 52.81676 -188.526674)
		(width 0.1016)
		(layer "B.Cu")
		(net "PSU1_DC_OK_R")
	)
	(segment
		(start 52.81676 -188.526674)
		(end 52.81676 -190.250064)
		(width 0.1016)
		(layer "B.Cu")
		(net "PSU1_DC_OK_R")
	)
	(segment
		(start 50.014886 -200.221088)
		(end 50.557684 -199.67829)
		(width 0.1016)
		(layer "B.Cu")
		(net "PSU1_DC_OK_R")
	)
	(segment
		(start 52.81676 -190.250064)
		(end 51.55692 -191.509904)
		(width 0.1016)
		(layer "B.Cu")
		(net "PSU1_DC_OK_R")
	)
	(segment
		(start 52.15128 -186.86907)
		(end 52.15128 -187.861194)
		(width 0.1016)
		(layer "B.Cu")
		(net "PSU1_DC_OK_R")
	)
	(segment
		(start 50.557684 -199.67829)
		(end 50.557684 -196.4817)
		(width 0.1016)
		(layer "B.Cu")
		(net "PSU1_DC_OK_R")
	)
	(segment
		(start 50.014886 -205.199488)
		(end 50.014886 -200.221088)
		(width 0.1016)
		(layer "B.Cu")
		(net "PSU1_DC_OK_R")
	)
	(segment
		(start 50.557684 -196.4817)
		(end 50.9397 -196.099684)
		(width 0.1016)
		(layer "B.Cu")
		(net "PSU1_DC_OK_R")
	)
	(segment
		(start 51.55692 -191.509904)
		(end 51.55692 -195.482464)
		(width 0.1016)
		(layer "B.Cu")
		(net "PSU1_DC_OK_R")
	)
	(segment
		(start 52.81676 -186.20359)
		(end 52.15128 -186.86907)
		(width 0.1016)
		(layer "B.Cu")
		(net "PSU1_DC_OK_R")
	)
	(via
		(at 118.38178 -196.849238)
		(size 0.6604)
		(drill 0.3302)
		(layers "F.Cu" "B.Cu")
		(net "T7_NODE4_EN_R")
	)
	(segment
		(start 118.38178 -200.473564)
		(end 118.38178 -196.849238)
		(width 0.1016)
		(layer "B.Cu")
		(net "T7_NODE4_EN_R")
	)
	(segment
		(start 116.44376 -186.05246)
		(end 116.44376 -185.605674)
		(width 0.1016)
		(layer "B.Cu")
		(net "T7_NODE4_EN_R")
	)
	(segment
		(start 117.45976 -194.186556)
		(end 117.45976 -188.526674)
		(width 0.1016)
		(layer "B.Cu")
		(net "T7_NODE4_EN_R")
	)
	(segment
		(start 118.38178 -196.849238)
		(end 118.38178 -195.108576)
		(width 0.1016)
		(layer "B.Cu")
		(net "T7_NODE4_EN_R")
	)
	(segment
		(start 118.015512 -205.199488)
		(end 118.015512 -200.839832)
		(width 0.1016)
		(layer "B.Cu")
		(net "T7_NODE4_EN_R")
	)
	(segment
		(start 118.38178 -195.108576)
		(end 117.45976 -194.186556)
		(width 0.1016)
		(layer "B.Cu")
		(net "T7_NODE4_EN_R")
	)
	(segment
		(start 116.8908 -186.4995)
		(end 116.44376 -186.05246)
		(width 0.1016)
		(layer "B.Cu")
		(net "T7_NODE4_EN_R")
	)
	(segment
		(start 117.45976 -188.526674)
		(end 116.8908 -187.957714)
		(width 0.1016)
		(layer "B.Cu")
		(net "T7_NODE4_EN_R")
	)
	(segment
		(start 118.015512 -200.839832)
		(end 118.38178 -200.473564)
		(width 0.1016)
		(layer "B.Cu")
		(net "T7_NODE4_EN_R")
	)
	(segment
		(start 116.8908 -187.957714)
		(end 116.8908 -186.4995)
		(width 0.1016)
		(layer "B.Cu")
		(net "T7_NODE4_EN_R")
	)
	(via
		(at 140.41882 -199.39381)
		(size 0.6604)
		(drill 0.3302)
		(layers "F.Cu" "B.Cu")
		(net "UART_T11_NODE3_TXD_R")
	)
	(segment
		(start 143.31696 -186.124342)
		(end 143.315944 -186.124342)
		(width 0.1016)
		(layer "B.Cu")
		(net "UART_T11_NODE3_TXD_R")
	)
	(segment
		(start 143.36776 -192.702688)
		(end 140.589762 -195.480686)
		(width 0.1016)
		(layer "B.Cu")
		(net "UART_T11_NODE3_TXD_R")
	)
	(segment
		(start 140.589762 -195.480686)
		(end 140.589762 -196.672454)
		(width 0.1016)
		(layer "B.Cu")
		(net "UART_T11_NODE3_TXD_R")
	)
	(segment
		(start 140.015468 -199.797162)
		(end 140.41882 -199.39381)
		(width 0.1016)
		(layer "B.Cu")
		(net "UART_T11_NODE3_TXD_R")
	)
	(segment
		(start 143.315944 -186.124342)
		(end 142.780512 -186.659774)
		(width 0.1016)
		(layer "B.Cu")
		(net "UART_T11_NODE3_TXD_R")
	)
	(segment
		(start 143.36776 -185.351674)
		(end 143.36776 -186.073542)
		(width 0.1016)
		(layer "B.Cu")
		(net "UART_T11_NODE3_TXD_R")
	)
	(segment
		(start 143.36776 -188.399674)
		(end 143.36776 -192.702688)
		(width 0.1016)
		(layer "B.Cu")
		(net "UART_T11_NODE3_TXD_R")
	)
	(segment
		(start 140.015468 -205.199488)
		(end 140.015468 -199.797162)
		(width 0.1016)
		(layer "B.Cu")
		(net "UART_T11_NODE3_TXD_R")
	)
	(segment
		(start 142.780512 -187.812426)
		(end 143.36776 -188.399674)
		(width 0.1016)
		(layer "B.Cu")
		(net "UART_T11_NODE3_TXD_R")
	)
	(segment
		(start 143.36776 -186.073542)
		(end 143.31696 -186.124342)
		(width 0.1016)
		(layer "B.Cu")
		(net "UART_T11_NODE3_TXD_R")
	)
	(segment
		(start 142.780512 -186.659774)
		(end 142.780512 -187.812426)
		(width 0.1016)
		(layer "B.Cu")
		(net "UART_T11_NODE3_TXD_R")
	)
	(segment
		(start 140.41882 -196.843396)
		(end 140.41882 -199.39381)
		(width 0.1016)
		(layer "B.Cu")
		(net "UART_T11_NODE3_TXD_R")
	)
	(segment
		(start 140.589762 -196.672454)
		(end 140.41882 -196.843396)
		(width 0.1016)
		(layer "B.Cu")
		(net "UART_T11_NODE3_TXD_R")
	)
	(segment
		(start 58.015124 -197.740778)
		(end 59.438794 -196.317108)
		(width 0.1016)
		(layer "F.Cu")
		(net "UART_T2_NODE3_RXD_R")
	)
	(segment
		(start 59.67476 -196.081142)
		(end 59.67476 -188.526674)
		(width 0.1016)
		(layer "F.Cu")
		(net "UART_T2_NODE3_RXD_R")
	)
	(segment
		(start 59.438794 -196.317108)
		(end 59.67476 -196.081142)
		(width 0.1016)
		(layer "F.Cu")
		(net "UART_T2_NODE3_RXD_R")
	)
	(segment
		(start 58.015124 -205.199488)
		(end 58.015124 -197.740778)
		(width 0.1016)
		(layer "F.Cu")
		(net "UART_T2_NODE3_RXD_R")
	)
	(via
		(at 59.438794 -196.317108)
		(size 0.508)
		(drill 0.254)
		(layers "F.Cu" "B.Cu")
		(net "UART_T2_NODE3_RXD_R")
	)
	(via
		(at 139.5349 -197.463664)
		(size 0.6604)
		(drill 0.3302)
		(layers "F.Cu" "B.Cu")
		(net "UART_T11_NODE4_RXD_R")
	)
	(segment
		(start 139.01547 -205.199488)
		(end 139.01547 -197.983094)
		(width 0.1016)
		(layer "B.Cu")
		(net "UART_T11_NODE4_RXD_R")
	)
	(segment
		(start 142.22476 -191.702182)
		(end 139.41552 -194.511422)
		(width 0.1016)
		(layer "B.Cu")
		(net "UART_T11_NODE4_RXD_R")
	)
	(segment
		(start 142.22476 -188.399674)
		(end 142.22476 -191.702182)
		(width 0.1016)
		(layer "B.Cu")
		(net "UART_T11_NODE4_RXD_R")
	)
	(segment
		(start 139.01547 -197.983094)
		(end 139.5349 -197.463664)
		(width 0.1016)
		(layer "B.Cu")
		(net "UART_T11_NODE4_RXD_R")
	)
	(segment
		(start 139.41552 -194.511422)
		(end 139.41552 -197.344284)
		(width 0.1016)
		(layer "B.Cu")
		(net "UART_T11_NODE4_RXD_R")
	)
	(segment
		(start 139.41552 -197.344284)
		(end 139.5349 -197.463664)
		(width 0.1016)
		(layer "B.Cu")
		(net "UART_T11_NODE4_RXD_R")
	)
	(segment
		(start 57.97296 -188.177678)
		(end 58.321956 -188.526674)
		(width 0.1016)
		(layer "F.Cu")
		(net "UART_T2_NODE3_TXD_R")
	)
	(segment
		(start 57.015126 -197.125336)
		(end 57.57418 -196.566282)
		(width 0.1016)
		(layer "F.Cu")
		(net "UART_T2_NODE3_TXD_R")
	)
	(segment
		(start 57.97296 -186.817)
		(end 57.97296 -188.177678)
		(width 0.1016)
		(layer "F.Cu")
		(net "UART_T2_NODE3_TXD_R")
	)
	(segment
		(start 58.53176 -186.2582)
		(end 57.97296 -186.817)
		(width 0.1016)
		(layer "F.Cu")
		(net "UART_T2_NODE3_TXD_R")
	)
	(segment
		(start 58.53176 -185.605674)
		(end 58.53176 -186.2582)
		(width 0.1016)
		(layer "F.Cu")
		(net "UART_T2_NODE3_TXD_R")
	)
	(segment
		(start 57.015126 -205.199488)
		(end 57.015126 -197.125336)
		(width 0.1016)
		(layer "F.Cu")
		(net "UART_T2_NODE3_TXD_R")
	)
	(segment
		(start 58.53176 -195.096384)
		(end 58.53176 -188.526674)
		(width 0.1016)
		(layer "F.Cu")
		(net "UART_T2_NODE3_TXD_R")
	)
	(segment
		(start 57.57418 -196.566282)
		(end 57.57418 -196.417946)
		(width 0.1016)
		(layer "F.Cu")
		(net "UART_T2_NODE3_TXD_R")
	)
	(segment
		(start 58.321956 -188.526674)
		(end 58.53176 -188.526674)
		(width 0.1016)
		(layer "F.Cu")
		(net "UART_T2_NODE3_TXD_R")
	)
	(segment
		(start 57.57418 -196.417946)
		(end 57.57418 -196.053964)
		(width 0.1016)
		(layer "F.Cu")
		(net "UART_T2_NODE3_TXD_R")
	)
	(segment
		(start 57.57418 -196.053964)
		(end 58.53176 -195.096384)
		(width 0.1016)
		(layer "F.Cu")
		(net "UART_T2_NODE3_TXD_R")
	)
	(via
		(at 57.57418 -196.417946)
		(size 0.508)
		(drill 0.254)
		(layers "F.Cu" "B.Cu")
		(net "UART_T2_NODE3_TXD_R")
	)
	(via
		(at 137.94105 -196.996558)
		(size 0.6604)
		(drill 0.3302)
		(layers "F.Cu" "B.Cu")
		(net "UART_T11_NODE4_TXD_R")
	)
	(segment
		(start 137.72134 -197.216268)
		(end 137.72134 -199.680068)
		(width 0.1016)
		(layer "B.Cu")
		(net "UART_T11_NODE4_TXD_R")
	)
	(segment
		(start 140.512292 -187.779406)
		(end 140.512292 -186.345322)
		(width 0.1016)
		(layer "B.Cu")
		(net "UART_T11_NODE4_TXD_R")
	)
	(segment
		(start 141.08176 -185.775854)
		(end 141.08176 -185.351674)
		(width 0.1016)
		(layer "B.Cu")
		(net "UART_T11_NODE4_TXD_R")
	)
	(segment
		(start 138.015472 -199.9742)
		(end 138.015472 -205.199488)
		(width 0.1016)
		(layer "B.Cu")
		(net "UART_T11_NODE4_TXD_R")
	)
	(segment
		(start 141.08176 -188.755782)
		(end 141.08176 -188.348874)
		(width 0.1016)
		(layer "B.Cu")
		(net "UART_T11_NODE4_TXD_R")
	)
	(segment
		(start 138.589766 -193.743834)
		(end 141.04112 -191.29248)
		(width 0.1016)
		(layer "B.Cu")
		(net "UART_T11_NODE4_TXD_R")
	)
	(segment
		(start 140.512292 -186.345322)
		(end 141.08176 -185.775854)
		(width 0.1016)
		(layer "B.Cu")
		(net "UART_T11_NODE4_TXD_R")
	)
	(segment
		(start 138.589766 -196.347842)
		(end 138.589766 -193.743834)
		(width 0.1016)
		(layer "B.Cu")
		(net "UART_T11_NODE4_TXD_R")
	)
	(segment
		(start 141.08176 -188.348874)
		(end 140.512292 -187.779406)
		(width 0.1016)
		(layer "B.Cu")
		(net "UART_T11_NODE4_TXD_R")
	)
	(segment
		(start 137.94105 -196.996558)
		(end 138.589766 -196.347842)
		(width 0.1016)
		(layer "B.Cu")
		(net "UART_T11_NODE4_TXD_R")
	)
	(segment
		(start 137.94105 -196.996558)
		(end 137.72134 -197.216268)
		(width 0.1016)
		(layer "B.Cu")
		(net "UART_T11_NODE4_TXD_R")
	)
	(segment
		(start 141.04112 -191.29248)
		(end 141.04112 -188.796422)
		(width 0.1016)
		(layer "B.Cu")
		(net "UART_T11_NODE4_TXD_R")
	)
	(segment
		(start 137.72134 -199.680068)
		(end 138.015472 -199.9742)
		(width 0.1016)
		(layer "B.Cu")
		(net "UART_T11_NODE4_TXD_R")
	)
	(segment
		(start 141.04112 -188.796422)
		(end 141.08176 -188.755782)
		(width 0.1016)
		(layer "B.Cu")
		(net "UART_T11_NODE4_TXD_R")
	)
	(segment
		(start 105.70972 -199.303894)
		(end 106.14152 -199.735694)
		(width 0.1016)
		(layer "F.Cu")
		(net "UART_T6_NODE1_RXD_R")
	)
	(segment
		(start 107.29976 -192.098168)
		(end 105.70972 -193.688208)
		(width 0.1016)
		(layer "F.Cu")
		(net "UART_T6_NODE1_RXD_R")
	)
	(segment
		(start 105.015538 -200.861676)
		(end 105.015538 -204.699616)
		(width 0.1016)
		(layer "F.Cu")
		(net "UART_T6_NODE1_RXD_R")
	)
	(segment
		(start 107.29976 -188.526674)
		(end 107.29976 -192.098168)
		(width 0.1016)
		(layer "F.Cu")
		(net "UART_T6_NODE1_RXD_R")
	)
	(segment
		(start 105.70972 -193.688208)
		(end 105.70972 -199.303894)
		(width 0.1016)
		(layer "F.Cu")
		(net "UART_T6_NODE1_RXD_R")
	)
	(segment
		(start 106.14152 -199.735694)
		(end 105.015538 -200.861676)
		(width 0.1016)
		(layer "F.Cu")
		(net "UART_T6_NODE1_RXD_R")
	)
	(via
		(at 106.14152 -199.735694)
		(size 0.508)
		(drill 0.254)
		(layers "F.Cu" "B.Cu")
		(net "UART_T6_NODE1_RXD_R")
	)
	(via
		(at 107.19054 -194.73926)
		(size 0.6604)
		(drill 0.3302)
		(layers "F.Cu" "B.Cu")
		(net "PSU_ALERT_R_N")
	)
	(segment
		(start 106.50982 -201.636376)
		(end 106.015536 -202.13066)
		(width 0.1016)
		(layer "B.Cu")
		(net "PSU_ALERT_R_N")
	)
	(segment
		(start 106.64952 -200.506838)
		(end 106.50982 -200.646538)
		(width 0.1016)
		(layer "B.Cu")
		(net "PSU_ALERT_R_N")
	)
	(segment
		(start 106.015536 -202.13066)
		(end 106.015536 -205.199488)
		(width 0.1016)
		(layer "B.Cu")
		(net "PSU_ALERT_R_N")
	)
	(segment
		(start 107.42676 -194.50304)
		(end 107.19054 -194.73926)
		(width 0.1016)
		(layer "B.Cu")
		(net "PSU_ALERT_R_N")
	)
	(segment
		(start 106.60126 -198.215758)
		(end 106.64952 -198.264018)
		(width 0.1016)
		(layer "B.Cu")
		(net "PSU_ALERT_R_N")
	)
	(segment
		(start 106.50982 -200.646538)
		(end 106.50982 -201.636376)
		(width 0.1016)
		(layer "B.Cu")
		(net "PSU_ALERT_R_N")
	)
	(segment
		(start 106.60126 -195.32854)
		(end 106.60126 -198.215758)
		(width 0.1016)
		(layer "B.Cu")
		(net "PSU_ALERT_R_N")
	)
	(segment
		(start 107.42676 -188.526674)
		(end 107.42676 -194.50304)
		(width 0.1016)
		(layer "B.Cu")
		(net "PSU_ALERT_R_N")
	)
	(segment
		(start 106.64952 -198.264018)
		(end 106.64952 -200.506838)
		(width 0.1016)
		(layer "B.Cu")
		(net "PSU_ALERT_R_N")
	)
	(segment
		(start 107.19054 -194.73926)
		(end 106.60126 -195.32854)
		(width 0.1016)
		(layer "B.Cu")
		(net "PSU_ALERT_R_N")
	)
	(segment
		(start 56.015128 -202.22337)
		(end 56.5531 -201.685398)
		(width 0.1016)
		(layer "F.Cu")
		(net "UART_T2_NODE4_RXD_R")
	)
	(segment
		(start 56.5531 -201.685398)
		(end 56.5531 -198.183754)
		(width 0.1016)
		(layer "F.Cu")
		(net "UART_T2_NODE4_RXD_R")
	)
	(segment
		(start 56.015128 -205.199488)
		(end 56.015128 -202.22337)
		(width 0.1016)
		(layer "F.Cu")
		(net "UART_T2_NODE4_RXD_R")
	)
	(segment
		(start 56.12384 -195.084192)
		(end 57.38876 -193.819272)
		(width 0.1016)
		(layer "F.Cu")
		(net "UART_T2_NODE4_RXD_R")
	)
	(segment
		(start 56.12384 -197.754494)
		(end 56.12384 -195.084192)
		(width 0.1016)
		(layer "F.Cu")
		(net "UART_T2_NODE4_RXD_R")
	)
	(segment
		(start 57.38876 -193.819272)
		(end 57.38876 -188.526674)
		(width 0.1016)
		(layer "F.Cu")
		(net "UART_T2_NODE4_RXD_R")
	)
	(segment
		(start 56.5531 -198.183754)
		(end 56.12384 -197.754494)
		(width 0.1016)
		(layer "F.Cu")
		(net "UART_T2_NODE4_RXD_R")
	)
	(via
		(at 56.12384 -197.754494)
		(size 0.508)
		(drill 0.254)
		(layers "F.Cu" "B.Cu")
		(net "UART_T2_NODE4_RXD_R")
	)
	(via
		(at 114.20094 -197.594982)
		(size 0.6604)
		(drill 0.3302)
		(layers "F.Cu" "B.Cu")
		(net "UART_T7_NODE2_RXD_R")
	)
	(segment
		(start 114.20094 -197.594982)
		(end 114.20094 -194.891914)
		(width 0.1016)
		(layer "B.Cu")
		(net "UART_T7_NODE2_RXD_R")
	)
	(segment
		(start 114.20094 -197.594982)
		(end 114.20094 -197.972934)
		(width 0.1016)
		(layer "B.Cu")
		(net "UART_T7_NODE2_RXD_R")
	)
	(segment
		(start 114.01552 -198.158354)
		(end 114.01552 -205.199488)
		(width 0.1016)
		(layer "B.Cu")
		(net "UART_T7_NODE2_RXD_R")
	)
	(segment
		(start 114.20094 -197.972934)
		(end 114.01552 -198.158354)
		(width 0.1016)
		(layer "B.Cu")
		(net "UART_T7_NODE2_RXD_R")
	)
	(segment
		(start 114.20094 -194.891914)
		(end 114.15776 -194.848734)
		(width 0.1016)
		(layer "B.Cu")
		(net "UART_T7_NODE2_RXD_R")
	)
	(segment
		(start 114.15776 -194.848734)
		(end 114.15776 -188.526674)
		(width 0.1016)
		(layer "B.Cu")
		(net "UART_T7_NODE2_RXD_R")
	)
	(segment
		(start 104.01554 -200.752202)
		(end 104.01554 -205.199488)
		(width 0.1016)
		(layer "F.Cu")
		(net "UART_T6_NODE1_TXD_R")
	)
	(segment
		(start 91.520772 -171.48302)
		(end 91.212162 -171.48302)
		(width 0.1016)
		(layer "F.Cu")
		(net "UART_T6_NODE1_TXD_R")
	)
	(segment
		(start 105.60812 -189.757812)
		(end 105.60812 -193.05143)
		(width 0.1016)
		(layer "F.Cu")
		(net "UART_T6_NODE1_TXD_R")
	)
	(segment
		(start 104.894888 -199.872854)
		(end 104.01554 -200.752202)
		(width 0.1016)
		(layer "F.Cu")
		(net "UART_T6_NODE1_TXD_R")
	)
	(segment
		(start 91.89974 -171.452794)
		(end 91.874848 -171.477686)
		(width 0.1016)
		(layer "F.Cu")
		(net "UART_T6_NODE1_TXD_R")
	)
	(segment
		(start 106.28376 -188.526674)
		(end 106.28376 -188.777626)
		(width 0.1016)
		(layer "F.Cu")
		(net "UART_T6_NODE1_TXD_R")
	)
	(segment
		(start 106.28376 -188.777626)
		(end 105.60812 -189.453266)
		(width 0.1016)
		(layer "F.Cu")
		(net "UART_T6_NODE1_TXD_R")
	)
	(segment
		(start 91.874848 -171.477686)
		(end 91.526106 -171.477686)
		(width 0.1016)
		(layer "F.Cu")
		(net "UART_T6_NODE1_TXD_R")
	)
	(segment
		(start 105.60812 -193.05143)
		(end 104.894888 -193.764662)
		(width 0.1016)
		(layer "F.Cu")
		(net "UART_T6_NODE1_TXD_R")
	)
	(segment
		(start 91.526106 -171.477686)
		(end 91.520772 -171.48302)
		(width 0.1016)
		(layer "F.Cu")
		(net "UART_T6_NODE1_TXD_R")
	)
	(segment
		(start 104.894888 -193.764662)
		(end 104.894888 -199.872854)
		(width 0.1016)
		(layer "F.Cu")
		(net "UART_T6_NODE1_TXD_R")
	)
	(segment
		(start 105.60812 -189.453266)
		(end 105.60812 -189.757812)
		(width 0.1016)
		(layer "F.Cu")
		(net "UART_T6_NODE1_TXD_R")
	)
	(via
		(at 105.60812 -189.757812)
		(size 0.508)
		(drill 0.254)
		(layers "F.Cu" "B.Cu")
		(net "UART_T6_NODE1_TXD_R")
	)
	(via
		(at 91.89974 -171.452794)
		(size 0.508)
		(drill 0.254)
		(layers "F.Cu" "B.Cu")
		(net "UART_T6_NODE1_TXD_R")
	)
	(segment
		(start 95.30588 -179.082192)
		(end 94.98711 -179.400962)
		(width 0.1143)
		(layer "In7.Cu")
		(net "UART_T6_NODE1_TXD_R")
	)
	(segment
		(start 92.31122 -171.041314)
		(end 92.31122 -170.740578)
		(width 0.1143)
		(layer "In7.Cu")
		(net "UART_T6_NODE1_TXD_R")
	)
	(segment
		(start 93.68028 -169.267632)
		(end 93.93555 -169.522902)
		(width 0.1143)
		(layer "In7.Cu")
		(net "UART_T6_NODE1_TXD_R")
	)
	(segment
		(start 95.30588 -171.434506)
		(end 95.30588 -179.082192)
		(width 0.1143)
		(layer "In7.Cu")
		(net "UART_T6_NODE1_TXD_R")
	)
	(segment
		(start 94.98711 -180.893974)
		(end 97.29089 -183.197754)
		(width 0.1143)
		(layer "In7.Cu")
		(net "UART_T6_NODE1_TXD_R")
	)
	(segment
		(start 92.3544 -170.697398)
		(end 92.3544 -169.751248)
		(width 0.1143)
		(layer "In7.Cu")
		(net "UART_T6_NODE1_TXD_R")
	)
	(segment
		(start 101.60381 -183.814466)
		(end 102.272084 -183.814466)
		(width 0.1143)
		(layer "In7.Cu")
		(net "UART_T6_NODE1_TXD_R")
	)
	(segment
		(start 92.3544 -169.751248)
		(end 92.838016 -169.267632)
		(width 0.1143)
		(layer "In7.Cu")
		(net "UART_T6_NODE1_TXD_R")
	)
	(segment
		(start 97.29089 -183.197754)
		(end 100.987098 -183.197754)
		(width 0.1143)
		(layer "In7.Cu")
		(net "UART_T6_NODE1_TXD_R")
	)
	(segment
		(start 94.98711 -179.400962)
		(end 94.98711 -180.893974)
		(width 0.1143)
		(layer "In7.Cu")
		(net "UART_T6_NODE1_TXD_R")
	)
	(segment
		(start 92.31122 -170.740578)
		(end 92.3544 -170.697398)
		(width 0.1143)
		(layer "In7.Cu")
		(net "UART_T6_NODE1_TXD_R")
	)
	(segment
		(start 100.987098 -183.197754)
		(end 101.60381 -183.814466)
		(width 0.1143)
		(layer "In7.Cu")
		(net "UART_T6_NODE1_TXD_R")
	)
	(segment
		(start 92.838016 -169.267632)
		(end 93.68028 -169.267632)
		(width 0.1143)
		(layer "In7.Cu")
		(net "UART_T6_NODE1_TXD_R")
	)
	(segment
		(start 91.89974 -171.452794)
		(end 92.31122 -171.041314)
		(width 0.1143)
		(layer "In7.Cu")
		(net "UART_T6_NODE1_TXD_R")
	)
	(segment
		(start 93.93555 -169.522902)
		(end 93.93555 -170.064176)
		(width 0.1143)
		(layer "In7.Cu")
		(net "UART_T6_NODE1_TXD_R")
	)
	(segment
		(start 104.70261 -186.244992)
		(end 104.70261 -188.38926)
		(width 0.1143)
		(layer "In7.Cu")
		(net "UART_T6_NODE1_TXD_R")
	)
	(segment
		(start 104.70261 -188.38926)
		(end 105.60812 -189.29477)
		(width 0.1143)
		(layer "In7.Cu")
		(net "UART_T6_NODE1_TXD_R")
	)
	(segment
		(start 93.93555 -170.064176)
		(end 95.30588 -171.434506)
		(width 0.1143)
		(layer "In7.Cu")
		(net "UART_T6_NODE1_TXD_R")
	)
	(segment
		(start 105.60812 -189.29477)
		(end 105.60812 -189.757812)
		(width 0.1143)
		(layer "In7.Cu")
		(net "UART_T6_NODE1_TXD_R")
	)
	(segment
		(start 102.272084 -183.814466)
		(end 104.70261 -186.244992)
		(width 0.1143)
		(layer "In7.Cu")
		(net "UART_T6_NODE1_TXD_R")
	)
	(segment
		(start 56.24576 -186.049412)
		(end 56.81726 -186.620912)
		(width 0.1016)
		(layer "F.Cu")
		(net "UART_T2_NODE4_TXD_R")
	)
	(segment
		(start 56.24576 -193.302636)
		(end 56.24576 -188.526674)
		(width 0.1016)
		(layer "F.Cu")
		(net "UART_T2_NODE4_TXD_R")
	)
	(segment
		(start 55.014876 -205.199488)
		(end 55.014876 -199.982582)
		(width 0.1016)
		(layer "F.Cu")
		(net "UART_T2_NODE4_TXD_R")
	)
	(segment
		(start 56.81726 -188.154818)
		(end 56.445404 -188.526674)
		(width 0.1016)
		(layer "F.Cu")
		(net "UART_T2_NODE4_TXD_R")
	)
	(segment
		(start 56.24576 -185.605674)
		(end 56.24576 -186.049412)
		(width 0.1016)
		(layer "F.Cu")
		(net "UART_T2_NODE4_TXD_R")
	)
	(segment
		(start 55.44058 -194.107816)
		(end 56.24576 -193.302636)
		(width 0.1016)
		(layer "F.Cu")
		(net "UART_T2_NODE4_TXD_R")
	)
	(segment
		(start 56.445404 -188.526674)
		(end 56.24576 -188.526674)
		(width 0.1016)
		(layer "F.Cu")
		(net "UART_T2_NODE4_TXD_R")
	)
	(segment
		(start 55.014876 -199.982582)
		(end 55.44058 -199.556878)
		(width 0.1016)
		(layer "F.Cu")
		(net "UART_T2_NODE4_TXD_R")
	)
	(segment
		(start 55.44058 -199.556878)
		(end 55.44058 -194.107816)
		(width 0.1016)
		(layer "F.Cu")
		(net "UART_T2_NODE4_TXD_R")
	)
	(segment
		(start 56.81726 -186.620912)
		(end 56.81726 -188.154818)
		(width 0.1016)
		(layer "F.Cu")
		(net "UART_T2_NODE4_TXD_R")
	)
	(via
		(at 55.44058 -199.556878)
		(size 0.508)
		(drill 0.254)
		(layers "F.Cu" "B.Cu")
		(net "UART_T2_NODE4_TXD_R")
	)
	(via
		(at 113.41354 -199.36206)
		(size 0.6604)
		(drill 0.3302)
		(layers "F.Cu" "B.Cu")
		(net "UART_T7_NODE2_TXD_R")
	)
	(segment
		(start 112.30356 -187.424314)
		(end 112.17656 -187.297314)
		(width 0.1016)
		(layer "B.Cu")
		(net "UART_T7_NODE2_TXD_R")
	)
	(segment
		(start 112.17656 -187.297314)
		(end 112.17656 -186.43346)
		(width 0.1016)
		(layer "B.Cu")
		(net "UART_T7_NODE2_TXD_R")
	)
	(segment
		(start 112.30356 -188.183266)
		(end 112.30356 -187.424314)
		(width 0.1016)
		(layer "B.Cu")
		(net "UART_T7_NODE2_TXD_R")
	)
	(segment
		(start 113.01476 -194.564254)
		(end 113.01476 -188.526674)
		(width 0.1016)
		(layer "B.Cu")
		(net "UART_T7_NODE2_TXD_R")
	)
	(segment
		(start 113.015522 -205.199488)
		(end 113.015522 -199.760078)
		(width 0.1016)
		(layer "B.Cu")
		(net "UART_T7_NODE2_TXD_R")
	)
	(segment
		(start 112.646968 -188.526674)
		(end 112.30356 -188.183266)
		(width 0.1016)
		(layer "B.Cu")
		(net "UART_T7_NODE2_TXD_R")
	)
	(segment
		(start 111.99876 -186.25566)
		(end 111.99876 -185.605674)
		(width 0.1016)
		(layer "B.Cu")
		(net "UART_T7_NODE2_TXD_R")
	)
	(segment
		(start 113.41354 -194.963034)
		(end 113.01476 -194.564254)
		(width 0.1016)
		(layer "B.Cu")
		(net "UART_T7_NODE2_TXD_R")
	)
	(segment
		(start 113.015522 -199.760078)
		(end 113.41354 -199.36206)
		(width 0.1016)
		(layer "B.Cu")
		(net "UART_T7_NODE2_TXD_R")
	)
	(segment
		(start 113.01476 -188.526674)
		(end 112.646968 -188.526674)
		(width 0.1016)
		(layer "B.Cu")
		(net "UART_T7_NODE2_TXD_R")
	)
	(segment
		(start 113.41354 -199.36206)
		(end 113.41354 -194.963034)
		(width 0.1016)
		(layer "B.Cu")
		(net "UART_T7_NODE2_TXD_R")
	)
	(segment
		(start 112.17656 -186.43346)
		(end 111.99876 -186.25566)
		(width 0.1016)
		(layer "B.Cu")
		(net "UART_T7_NODE2_TXD_R")
	)
	(segment
		(start 78.015084 -195.431664)
		(end 78.015084 -194.789044)
		(width 0.1016)
		(layer "F.Cu")
		(net "UART_T4_NODE1_RXD_R")
	)
	(segment
		(start 78.015084 -194.789044)
		(end 77.96276 -194.73672)
		(width 0.1016)
		(layer "F.Cu")
		(net "UART_T4_NODE1_RXD_R")
	)
	(segment
		(start 77.96276 -194.73672)
		(end 77.96276 -188.526674)
		(width 0.1016)
		(layer "F.Cu")
		(net "UART_T4_NODE1_RXD_R")
	)
	(segment
		(start 78.015084 -204.699616)
		(end 78.015084 -195.431664)
		(width 0.1016)
		(layer "F.Cu")
		(net "UART_T4_NODE1_RXD_R")
	)
	(via
		(at 78.015084 -195.431664)
		(size 0.508)
		(drill 0.254)
		(layers "F.Cu" "B.Cu")
		(net "UART_T4_NODE1_RXD_R")
	)
	(via
		(at 112.2934 -197.516242)
		(size 0.6604)
		(drill 0.3302)
		(layers "F.Cu" "B.Cu")
		(net "UART_T7_NODE3_RXD_R")
	)
	(segment
		(start 111.87176 -194.226942)
		(end 112.2934 -194.648582)
		(width 0.1016)
		(layer "B.Cu")
		(net "UART_T7_NODE3_RXD_R")
	)
	(segment
		(start 111.44758 -198.362062)
		(end 111.44758 -201.692764)
		(width 0.1016)
		(layer "B.Cu")
		(net "UART_T7_NODE3_RXD_R")
	)
	(segment
		(start 112.2934 -197.516242)
		(end 111.44758 -198.362062)
		(width 0.1016)
		(layer "B.Cu")
		(net "UART_T7_NODE3_RXD_R")
	)
	(segment
		(start 111.015526 -202.124818)
		(end 111.015526 -205.199488)
		(width 0.1016)
		(layer "B.Cu")
		(net "UART_T7_NODE3_RXD_R")
	)
	(segment
		(start 111.87176 -188.526674)
		(end 111.87176 -194.226942)
		(width 0.1016)
		(layer "B.Cu")
		(net "UART_T7_NODE3_RXD_R")
	)
	(segment
		(start 111.44758 -201.692764)
		(end 111.015526 -202.124818)
		(width 0.1016)
		(layer "B.Cu")
		(net "UART_T7_NODE3_RXD_R")
	)
	(segment
		(start 112.2934 -194.648582)
		(end 112.2934 -197.516242)
		(width 0.1016)
		(layer "B.Cu")
		(net "UART_T7_NODE3_RXD_R")
	)
	(segment
		(start 93.447616 -197.695058)
		(end 93.447616 -198.743316)
		(width 0.1016)
		(layer "F.Cu")
		(net "UART_T6_NODE2_RXD_R")
	)
	(segment
		(start 93.811344 -189.575694)
		(end 93.447616 -189.939422)
		(width 0.1016)
		(layer "F.Cu")
		(net "UART_T6_NODE2_RXD_R")
	)
	(segment
		(start 93.447616 -198.743316)
		(end 95.01505 -200.31075)
		(width 0.1016)
		(layer "F.Cu")
		(net "UART_T6_NODE2_RXD_R")
	)
	(segment
		(start 93.811344 -188.838586)
		(end 93.811344 -189.575694)
		(width 0.1016)
		(layer "F.Cu")
		(net "UART_T6_NODE2_RXD_R")
	)
	(segment
		(start 95.01505 -200.31075)
		(end 95.01505 -205.199488)
		(width 0.1016)
		(layer "F.Cu")
		(net "UART_T6_NODE2_RXD_R")
	)
	(segment
		(start 93.447616 -189.939422)
		(end 93.447616 -197.695058)
		(width 0.1016)
		(layer "F.Cu")
		(net "UART_T6_NODE2_RXD_R")
	)
	(via
		(at 93.447616 -197.695058)
		(size 0.508)
		(drill 0.254)
		(layers "F.Cu" "B.Cu")
		(net "UART_T6_NODE2_RXD_R")
	)
	(via
		(at 58.79084 -198.164196)
		(size 0.6604)
		(drill 0.3302)
		(layers "F.Cu" "B.Cu")
		(net "UART_T1_NODE3_RXD_R")
	)
	(segment
		(start 58.79084 -198.164196)
		(end 58.79084 -198.917306)
		(width 0.1016)
		(layer "B.Cu")
		(net "UART_T1_NODE3_RXD_R")
	)
	(segment
		(start 59.67476 -188.526674)
		(end 59.67476 -190.376048)
		(width 0.1016)
		(layer "B.Cu")
		(net "UART_T1_NODE3_RXD_R")
	)
	(segment
		(start 58.015124 -199.693022)
		(end 58.015124 -205.199488)
		(width 0.1016)
		(layer "B.Cu")
		(net "UART_T1_NODE3_RXD_R")
	)
	(segment
		(start 58.79084 -191.259968)
		(end 58.79084 -198.164196)
		(width 0.1016)
		(layer "B.Cu")
		(net "UART_T1_NODE3_RXD_R")
	)
	(segment
		(start 58.79084 -198.917306)
		(end 58.015124 -199.693022)
		(width 0.1016)
		(layer "B.Cu")
		(net "UART_T1_NODE3_RXD_R")
	)
	(segment
		(start 59.67476 -190.376048)
		(end 58.79084 -191.259968)
		(width 0.1016)
		(layer "B.Cu")
		(net "UART_T1_NODE3_RXD_R")
	)
	(segment
		(start 92.114878 -172.407834)
		(end 91.568524 -172.407834)
		(width 0.1016)
		(layer "F.Cu")
		(net "UART_T6_NODE2_TXD_R")
	)
	(segment
		(start 93.811344 -187.957714)
		(end 93.811344 -187.822586)
		(width 0.1016)
		(layer "F.Cu")
		(net "UART_T6_NODE2_TXD_R")
	)
	(segment
		(start 91.568524 -172.407834)
		(end 91.476576 -172.499782)
		(width 0.1016)
		(layer "F.Cu")
		(net "UART_T6_NODE2_TXD_R")
	)
	(segment
		(start 92.7481 -190.40475)
		(end 92.47886 -190.13551)
		(width 0.1016)
		(layer "F.Cu")
		(net "UART_T6_NODE2_TXD_R")
	)
	(segment
		(start 92.7481 -198.616062)
		(end 92.7481 -190.40475)
		(width 0.1016)
		(layer "F.Cu")
		(net "UART_T6_NODE2_TXD_R")
	)
	(segment
		(start 92.47886 -190.13551)
		(end 92.7481 -189.86627)
		(width 0.1016)
		(layer "F.Cu")
		(net "UART_T6_NODE2_TXD_R")
	)
	(segment
		(start 94.015052 -199.883014)
		(end 92.7481 -198.616062)
		(width 0.1016)
		(layer "F.Cu")
		(net "UART_T6_NODE2_TXD_R")
	)
	(segment
		(start 91.476576 -172.499782)
		(end 91.212162 -172.499782)
		(width 0.1016)
		(layer "F.Cu")
		(net "UART_T6_NODE2_TXD_R")
	)
	(segment
		(start 92.7481 -189.86627)
		(end 92.7481 -189.020958)
		(width 0.1016)
		(layer "F.Cu")
		(net "UART_T6_NODE2_TXD_R")
	)
	(segment
		(start 92.7481 -189.020958)
		(end 93.811344 -187.957714)
		(width 0.1016)
		(layer "F.Cu")
		(net "UART_T6_NODE2_TXD_R")
	)
	(segment
		(start 92.53728 -172.830236)
		(end 92.114878 -172.407834)
		(width 0.1016)
		(layer "F.Cu")
		(net "UART_T6_NODE2_TXD_R")
	)
	(segment
		(start 94.015052 -205.199488)
		(end 94.015052 -199.883014)
		(width 0.1016)
		(layer "F.Cu")
		(net "UART_T6_NODE2_TXD_R")
	)
	(via
		(at 92.53728 -172.830236)
		(size 0.508)
		(drill 0.254)
		(layers "F.Cu" "B.Cu")
		(net "UART_T6_NODE2_TXD_R")
	)
	(via
		(at 92.47886 -190.13551)
		(size 0.508)
		(drill 0.254)
		(layers "F.Cu" "B.Cu")
		(net "UART_T6_NODE2_TXD_R")
	)
	(segment
		(start 92.86875 -182.023512)
		(end 94.39148 -183.546242)
		(width 0.1143)
		(layer "In7.Cu")
		(net "UART_T6_NODE2_TXD_R")
	)
	(segment
		(start 95.4786 -190.255652)
		(end 94.941136 -190.793116)
		(width 0.1143)
		(layer "In7.Cu")
		(net "UART_T6_NODE2_TXD_R")
	)
	(segment
		(start 93.136466 -190.793116)
		(end 92.47886 -190.13551)
		(width 0.1143)
		(layer "In7.Cu")
		(net "UART_T6_NODE2_TXD_R")
	)
	(segment
		(start 92.86875 -180.205126)
		(end 92.86875 -182.023512)
		(width 0.1143)
		(layer "In7.Cu")
		(net "UART_T6_NODE2_TXD_R")
	)
	(segment
		(start 92.53728 -172.920152)
		(end 93.055186 -173.438058)
		(width 0.1143)
		(layer "In7.Cu")
		(net "UART_T6_NODE2_TXD_R")
	)
	(segment
		(start 93.055186 -173.438058)
		(end 93.47708 -173.438058)
		(width 0.1143)
		(layer "In7.Cu")
		(net "UART_T6_NODE2_TXD_R")
	)
	(segment
		(start 92.53728 -172.830236)
		(end 92.53728 -172.920152)
		(width 0.1143)
		(layer "In7.Cu")
		(net "UART_T6_NODE2_TXD_R")
	)
	(segment
		(start 93.47708 -173.438058)
		(end 94.67088 -174.631858)
		(width 0.1143)
		(layer "In7.Cu")
		(net "UART_T6_NODE2_TXD_R")
	)
	(segment
		(start 94.67088 -178.402996)
		(end 92.86875 -180.205126)
		(width 0.1143)
		(layer "In7.Cu")
		(net "UART_T6_NODE2_TXD_R")
	)
	(segment
		(start 94.67088 -174.631858)
		(end 94.67088 -178.402996)
		(width 0.1143)
		(layer "In7.Cu")
		(net "UART_T6_NODE2_TXD_R")
	)
	(segment
		(start 95.4786 -189.109604)
		(end 95.4786 -190.255652)
		(width 0.1143)
		(layer "In7.Cu")
		(net "UART_T6_NODE2_TXD_R")
	)
	(segment
		(start 94.941136 -190.793116)
		(end 93.136466 -190.793116)
		(width 0.1143)
		(layer "In7.Cu")
		(net "UART_T6_NODE2_TXD_R")
	)
	(segment
		(start 94.39148 -188.022484)
		(end 95.4786 -189.109604)
		(width 0.1143)
		(layer "In7.Cu")
		(net "UART_T6_NODE2_TXD_R")
	)
	(segment
		(start 94.39148 -183.546242)
		(end 94.39148 -188.022484)
		(width 0.1143)
		(layer "In7.Cu")
		(net "UART_T6_NODE2_TXD_R")
	)
	(segment
		(start 77.107034 -186.476132)
		(end 77.002894 -186.476132)
		(width 0.1016)
		(layer "F.Cu")
		(net "UART_T4_NODE1_TXD_R")
	)
	(segment
		(start 77.40396 -190.36538)
		(end 76.81976 -189.78118)
		(width 0.1016)
		(layer "F.Cu")
		(net "UART_T4_NODE1_TXD_R")
	)
	(segment
		(start 77.015086 -200.660508)
		(end 77.40396 -200.271634)
		(width 0.1016)
		(layer "F.Cu")
		(net "UART_T4_NODE1_TXD_R")
	)
	(segment
		(start 76.81976 -189.78118)
		(end 76.81976 -188.526674)
		(width 0.1016)
		(layer "F.Cu")
		(net "UART_T4_NODE1_TXD_R")
	)
	(segment
		(start 77.43444 -187.911994)
		(end 77.43444 -186.803538)
		(width 0.1016)
		(layer "F.Cu")
		(net "UART_T4_NODE1_TXD_R")
	)
	(segment
		(start 77.40396 -197.428358)
		(end 77.40396 -190.36538)
		(width 0.1016)
		(layer "F.Cu")
		(net "UART_T4_NODE1_TXD_R")
	)
	(segment
		(start 82.190082 -161.655506)
		(end 83.133692 -161.655506)
		(width 0.1016)
		(layer "F.Cu")
		(net "UART_T4_NODE1_TXD_R")
	)
	(segment
		(start 77.40396 -200.271634)
		(end 77.40396 -197.428358)
		(width 0.1016)
		(layer "F.Cu")
		(net "UART_T4_NODE1_TXD_R")
	)
	(segment
		(start 77.43444 -186.803538)
		(end 77.107034 -186.476132)
		(width 0.1016)
		(layer "F.Cu")
		(net "UART_T4_NODE1_TXD_R")
	)
	(segment
		(start 83.133692 -161.655506)
		(end 83.912202 -162.434016)
		(width 0.1016)
		(layer "F.Cu")
		(net "UART_T4_NODE1_TXD_R")
	)
	(segment
		(start 77.015086 -205.199488)
		(end 77.015086 -200.660508)
		(width 0.1016)
		(layer "F.Cu")
		(net "UART_T4_NODE1_TXD_R")
	)
	(segment
		(start 76.81976 -188.526674)
		(end 77.43444 -187.911994)
		(width 0.1016)
		(layer "F.Cu")
		(net "UART_T4_NODE1_TXD_R")
	)
	(segment
		(start 83.912202 -162.434016)
		(end 83.93176 -162.434016)
		(width 0.1016)
		(layer "F.Cu")
		(net "UART_T4_NODE1_TXD_R")
	)
	(segment
		(start 77.002894 -186.476132)
		(end 76.91374 -186.386978)
		(width 0.1016)
		(layer "F.Cu")
		(net "UART_T4_NODE1_TXD_R")
	)
	(via
		(at 76.91374 -186.386978)
		(size 0.508)
		(drill 0.254)
		(layers "F.Cu" "B.Cu")
		(net "UART_T4_NODE1_TXD_R")
	)
	(via
		(at 83.93176 -162.434016)
		(size 0.508)
		(drill 0.254)
		(layers "F.Cu" "B.Cu")
		(net "UART_T4_NODE1_TXD_R")
	)
	(via
		(at 77.40396 -197.428358)
		(size 0.508)
		(drill 0.254)
		(layers "F.Cu" "B.Cu")
		(net "UART_T4_NODE1_TXD_R")
	)
	(segment
		(start 82.0166 -167.771318)
		(end 83.63331 -166.154608)
		(width 0.1143)
		(layer "In7.Cu")
		(net "UART_T4_NODE1_TXD_R")
	)
	(segment
		(start 79.0321 -183.621172)
		(end 80.04048 -182.612792)
		(width 0.1143)
		(layer "In7.Cu")
		(net "UART_T4_NODE1_TXD_R")
	)
	(segment
		(start 85.26399 -164.010848)
		(end 85.26399 -162.93084)
		(width 0.1143)
		(layer "In7.Cu")
		(net "UART_T4_NODE1_TXD_R")
	)
	(segment
		(start 81.46161 -177.50917)
		(end 82.0166 -176.95418)
		(width 0.1143)
		(layer "In7.Cu")
		(net "UART_T4_NODE1_TXD_R")
	)
	(segment
		(start 85.26399 -162.93084)
		(end 84.776564 -162.443414)
		(width 0.1143)
		(layer "In7.Cu")
		(net "UART_T4_NODE1_TXD_R")
	)
	(segment
		(start 76.91374 -186.386978)
		(end 79.0321 -184.268618)
		(width 0.1143)
		(layer "In7.Cu")
		(net "UART_T4_NODE1_TXD_R")
	)
	(segment
		(start 81.23428 -181.246272)
		(end 81.23428 -179.279042)
		(width 0.1143)
		(layer "In7.Cu")
		(net "UART_T4_NODE1_TXD_R")
	)
	(segment
		(start 83.63331 -166.154608)
		(end 83.63331 -165.641528)
		(width 0.1143)
		(layer "In7.Cu")
		(net "UART_T4_NODE1_TXD_R")
	)
	(segment
		(start 84.776564 -162.443414)
		(end 83.941158 -162.443414)
		(width 0.1143)
		(layer "In7.Cu")
		(net "UART_T4_NODE1_TXD_R")
	)
	(segment
		(start 83.63331 -165.641528)
		(end 85.26399 -164.010848)
		(width 0.1143)
		(layer "In7.Cu")
		(net "UART_T4_NODE1_TXD_R")
	)
	(segment
		(start 81.74609 -178.767232)
		(end 81.74609 -178.404012)
		(width 0.1143)
		(layer "In7.Cu")
		(net "UART_T4_NODE1_TXD_R")
	)
	(segment
		(start 80.04048 -182.440072)
		(end 81.23428 -181.246272)
		(width 0.1143)
		(layer "In7.Cu")
		(net "UART_T4_NODE1_TXD_R")
	)
	(segment
		(start 79.0321 -184.268618)
		(end 79.0321 -183.621172)
		(width 0.1143)
		(layer "In7.Cu")
		(net "UART_T4_NODE1_TXD_R")
	)
	(segment
		(start 83.941158 -162.443414)
		(end 83.93176 -162.434016)
		(width 0.1143)
		(layer "In7.Cu")
		(net "UART_T4_NODE1_TXD_R")
	)
	(segment
		(start 81.74609 -178.404012)
		(end 81.46161 -178.119532)
		(width 0.1143)
		(layer "In7.Cu")
		(net "UART_T4_NODE1_TXD_R")
	)
	(segment
		(start 81.46161 -178.119532)
		(end 81.46161 -177.50917)
		(width 0.1143)
		(layer "In7.Cu")
		(net "UART_T4_NODE1_TXD_R")
	)
	(segment
		(start 80.04048 -182.612792)
		(end 80.04048 -182.440072)
		(width 0.1143)
		(layer "In7.Cu")
		(net "UART_T4_NODE1_TXD_R")
	)
	(segment
		(start 81.23428 -179.279042)
		(end 81.74609 -178.767232)
		(width 0.1143)
		(layer "In7.Cu")
		(net "UART_T4_NODE1_TXD_R")
	)
	(segment
		(start 82.0166 -176.95418)
		(end 82.0166 -167.771318)
		(width 0.1143)
		(layer "In7.Cu")
		(net "UART_T4_NODE1_TXD_R")
	)
	(via
		(at 116.21262 -197.870064)
		(size 0.6604)
		(drill 0.3302)
		(layers "F.Cu" "B.Cu")
		(net "UART_T7_NODE1_RXD_R")
	)
	(segment
		(start 116.015516 -201.645774)
		(end 116.015516 -205.199488)
		(width 0.1016)
		(layer "B.Cu")
		(net "UART_T7_NODE1_RXD_R")
	)
	(segment
		(start 116.21262 -197.136766)
		(end 116.21262 -197.870064)
		(width 0.1016)
		(layer "B.Cu")
		(net "UART_T7_NODE1_RXD_R")
	)
	(segment
		(start 116.44376 -196.905626)
		(end 116.21262 -197.136766)
		(width 0.1016)
		(layer "B.Cu")
		(net "UART_T7_NODE1_RXD_R")
	)
	(segment
		(start 116.447316 -201.213974)
		(end 116.015516 -201.645774)
		(width 0.1016)
		(layer "B.Cu")
		(net "UART_T7_NODE1_RXD_R")
	)
	(segment
		(start 116.21262 -197.870064)
		(end 116.447316 -198.10476)
		(width 0.1016)
		(layer "B.Cu")
		(net "UART_T7_NODE1_RXD_R")
	)
	(segment
		(start 116.447316 -198.10476)
		(end 116.447316 -201.213974)
		(width 0.1016)
		(layer "B.Cu")
		(net "UART_T7_NODE1_RXD_R")
	)
	(segment
		(start 116.44376 -188.526674)
		(end 116.44376 -196.905626)
		(width 0.1016)
		(layer "B.Cu")
		(net "UART_T7_NODE1_RXD_R")
	)
	(via
		(at 57.4675 -199.624442)
		(size 0.6604)
		(drill 0.3302)
		(layers "F.Cu" "B.Cu")
		(net "UART_T1_NODE3_TXD_R")
	)
	(segment
		(start 58.53176 -185.938668)
		(end 57.95518 -186.515248)
		(width 0.1016)
		(layer "B.Cu")
		(net "UART_T1_NODE3_TXD_R")
	)
	(segment
		(start 57.95518 -186.515248)
		(end 57.95518 -187.950094)
		(width 0.1016)
		(layer "B.Cu")
		(net "UART_T1_NODE3_TXD_R")
	)
	(segment
		(start 57.4675 -197.906894)
		(end 57.06618 -197.505574)
		(width 0.1016)
		(layer "B.Cu")
		(net "UART_T1_NODE3_TXD_R")
	)
	(segment
		(start 57.015126 -205.199488)
		(end 57.015126 -200.076816)
		(width 0.1016)
		(layer "B.Cu")
		(net "UART_T1_NODE3_TXD_R")
	)
	(segment
		(start 57.06618 -197.505574)
		(end 57.06618 -191.987932)
		(width 0.1016)
		(layer "B.Cu")
		(net "UART_T1_NODE3_TXD_R")
	)
	(segment
		(start 58.53176 -190.522352)
		(end 58.53176 -188.526674)
		(width 0.1016)
		(layer "B.Cu")
		(net "UART_T1_NODE3_TXD_R")
	)
	(segment
		(start 57.06618 -191.987932)
		(end 58.53176 -190.522352)
		(width 0.1016)
		(layer "B.Cu")
		(net "UART_T1_NODE3_TXD_R")
	)
	(segment
		(start 58.53176 -185.605674)
		(end 58.53176 -185.938668)
		(width 0.1016)
		(layer "B.Cu")
		(net "UART_T1_NODE3_TXD_R")
	)
	(segment
		(start 57.95518 -187.950094)
		(end 58.53176 -188.526674)
		(width 0.1016)
		(layer "B.Cu")
		(net "UART_T1_NODE3_TXD_R")
	)
	(segment
		(start 57.015126 -200.076816)
		(end 57.4675 -199.624442)
		(width 0.1016)
		(layer "B.Cu")
		(net "UART_T1_NODE3_TXD_R")
	)
	(segment
		(start 57.4675 -199.624442)
		(end 57.4675 -197.906894)
		(width 0.1016)
		(layer "B.Cu")
		(net "UART_T1_NODE3_TXD_R")
	)
	(segment
		(start 92.01404 -193.952114)
		(end 92.01404 -198.186802)
		(width 0.1016)
		(layer "F.Cu")
		(net "UART_T6_NODE3_RXD_R")
	)
	(segment
		(start 89.13876 -188.526674)
		(end 88.5698 -189.095634)
		(width 0.1016)
		(layer "F.Cu")
		(net "UART_T6_NODE3_RXD_R")
	)
	(segment
		(start 88.5698 -189.095634)
		(end 88.5698 -190.507874)
		(width 0.1016)
		(layer "F.Cu")
		(net "UART_T6_NODE3_RXD_R")
	)
	(segment
		(start 88.5698 -190.507874)
		(end 92.01404 -193.952114)
		(width 0.1016)
		(layer "F.Cu")
		(net "UART_T6_NODE3_RXD_R")
	)
	(segment
		(start 92.015056 -205.199488)
		(end 92.015056 -198.714106)
		(width 0.1016)
		(layer "F.Cu")
		(net "UART_T6_NODE3_RXD_R")
	)
	(segment
		(start 92.01404 -198.186802)
		(end 92.2782 -198.450962)
		(width 0.1016)
		(layer "F.Cu")
		(net "UART_T6_NODE3_RXD_R")
	)
	(segment
		(start 92.015056 -198.714106)
		(end 92.2782 -198.450962)
		(width 0.1016)
		(layer "F.Cu")
		(net "UART_T6_NODE3_RXD_R")
	)
	(via
		(at 92.2782 -198.450962)
		(size 0.508)
		(drill 0.254)
		(layers "F.Cu" "B.Cu")
		(net "UART_T6_NODE3_RXD_R")
	)
	(segment
		(start 76.009246 -191.252602)
		(end 76.009246 -195.936362)
		(width 0.1016)
		(layer "F.Cu")
		(net "UART_T4_NODE2_RXD_R")
	)
	(segment
		(start 76.015088 -202.365356)
		(end 76.015088 -205.199488)
		(width 0.1016)
		(layer "F.Cu")
		(net "UART_T4_NODE2_RXD_R")
	)
	(segment
		(start 76.009246 -199.284082)
		(end 76.4667 -199.741536)
		(width 0.1016)
		(layer "F.Cu")
		(net "UART_T4_NODE2_RXD_R")
	)
	(segment
		(start 76.4667 -199.741536)
		(end 76.4667 -201.913744)
		(width 0.1016)
		(layer "F.Cu")
		(net "UART_T4_NODE2_RXD_R")
	)
	(segment
		(start 76.009246 -195.936362)
		(end 76.009246 -199.284082)
		(width 0.1016)
		(layer "F.Cu")
		(net "UART_T4_NODE2_RXD_R")
	)
	(segment
		(start 75.67676 -188.526674)
		(end 75.67676 -190.920116)
		(width 0.1016)
		(layer "F.Cu")
		(net "UART_T4_NODE2_RXD_R")
	)
	(segment
		(start 76.4667 -201.913744)
		(end 76.015088 -202.365356)
		(width 0.1016)
		(layer "F.Cu")
		(net "UART_T4_NODE2_RXD_R")
	)
	(segment
		(start 75.67676 -190.920116)
		(end 76.009246 -191.252602)
		(width 0.1016)
		(layer "F.Cu")
		(net "UART_T4_NODE2_RXD_R")
	)
	(via
		(at 76.009246 -195.936362)
		(size 0.508)
		(drill 0.254)
		(layers "F.Cu" "B.Cu")
		(net "UART_T4_NODE2_RXD_R")
	)
	(via
		(at 115.417346 -196.055742)
		(size 0.6604)
		(drill 0.3302)
		(layers "F.Cu" "B.Cu")
		(net "UART_T7_NODE1_TXD_R")
	)
	(segment
		(start 115.44554 -196.812662)
		(end 114.83848 -197.419722)
		(width 0.1016)
		(layer "B.Cu")
		(net "UART_T7_NODE1_TXD_R")
	)
	(segment
		(start 115.30076 -195.939156)
		(end 115.30076 -188.526674)
		(width 0.1016)
		(layer "B.Cu")
		(net "UART_T7_NODE1_TXD_R")
	)
	(segment
		(start 114.63782 -187.863734)
		(end 114.63782 -186.732418)
		(width 0.1016)
		(layer "B.Cu")
		(net "UART_T7_NODE1_TXD_R")
	)
	(segment
		(start 114.83594 -186.534298)
		(end 114.83594 -186.176158)
		(width 0.1016)
		(layer "B.Cu")
		(net "UART_T7_NODE1_TXD_R")
	)
	(segment
		(start 115.417346 -196.055742)
		(end 115.30076 -195.939156)
		(width 0.1016)
		(layer "B.Cu")
		(net "UART_T7_NODE1_TXD_R")
	)
	(segment
		(start 115.417346 -196.055742)
		(end 115.44554 -196.083936)
		(width 0.1016)
		(layer "B.Cu")
		(net "UART_T7_NODE1_TXD_R")
	)
	(segment
		(start 114.63782 -186.732418)
		(end 114.83594 -186.534298)
		(width 0.1016)
		(layer "B.Cu")
		(net "UART_T7_NODE1_TXD_R")
	)
	(segment
		(start 114.83848 -201.824336)
		(end 115.015518 -202.001374)
		(width 0.1016)
		(layer "B.Cu")
		(net "UART_T7_NODE1_TXD_R")
	)
	(segment
		(start 114.292888 -185.633106)
		(end 114.28476 -185.633106)
		(width 0.1016)
		(layer "B.Cu")
		(net "UART_T7_NODE1_TXD_R")
	)
	(segment
		(start 115.44554 -196.083936)
		(end 115.44554 -196.812662)
		(width 0.1016)
		(layer "B.Cu")
		(net "UART_T7_NODE1_TXD_R")
	)
	(segment
		(start 115.30076 -188.526674)
		(end 114.63782 -187.863734)
		(width 0.1016)
		(layer "B.Cu")
		(net "UART_T7_NODE1_TXD_R")
	)
	(segment
		(start 114.83848 -197.419722)
		(end 114.83848 -201.824336)
		(width 0.1016)
		(layer "B.Cu")
		(net "UART_T7_NODE1_TXD_R")
	)
	(segment
		(start 115.015518 -202.001374)
		(end 115.015518 -205.199488)
		(width 0.1016)
		(layer "B.Cu")
		(net "UART_T7_NODE1_TXD_R")
	)
	(segment
		(start 114.83594 -186.176158)
		(end 114.292888 -185.633106)
		(width 0.1016)
		(layer "B.Cu")
		(net "UART_T7_NODE1_TXD_R")
	)
	(segment
		(start 114.28476 -185.633106)
		(end 114.28476 -185.605674)
		(width 0.1016)
		(layer "B.Cu")
		(net "UART_T7_NODE1_TXD_R")
	)
	(segment
		(start 91.48064 -196.982842)
		(end 91.48064 -194.30746)
		(width 0.1016)
		(layer "F.Cu")
		(net "UART_T6_NODE3_TXD_R")
	)
	(segment
		(start 87.56396 -187.958222)
		(end 87.80018 -188.194442)
		(width 0.1016)
		(layer "F.Cu")
		(net "UART_T6_NODE3_TXD_R")
	)
	(segment
		(start 91.015058 -205.199488)
		(end 91.015058 -199.516746)
		(width 0.1016)
		(layer "F.Cu")
		(net "UART_T6_NODE3_TXD_R")
	)
	(segment
		(start 88.02624 -190.85306)
		(end 88.02624 -188.623194)
		(width 0.1016)
		(layer "F.Cu")
		(net "UART_T6_NODE3_TXD_R")
	)
	(segment
		(start 88.24976 -185.605674)
		(end 88.24976 -186.6265)
		(width 0.1016)
		(layer "F.Cu")
		(net "UART_T6_NODE3_TXD_R")
	)
	(segment
		(start 87.80018 -188.194442)
		(end 87.80018 -188.204094)
		(width 0.1016)
		(layer "F.Cu")
		(net "UART_T6_NODE3_TXD_R")
	)
	(segment
		(start 88.02624 -188.623194)
		(end 88.12276 -188.526674)
		(width 0.1016)
		(layer "F.Cu")
		(net "UART_T6_NODE3_TXD_R")
	)
	(segment
		(start 87.80018 -188.204094)
		(end 88.12276 -188.526674)
		(width 0.1016)
		(layer "F.Cu")
		(net "UART_T6_NODE3_TXD_R")
	)
	(segment
		(start 91.015058 -199.516746)
		(end 91.48064 -199.051164)
		(width 0.1016)
		(layer "F.Cu")
		(net "UART_T6_NODE3_TXD_R")
	)
	(segment
		(start 87.56396 -187.3123)
		(end 87.56396 -187.958222)
		(width 0.1016)
		(layer "F.Cu")
		(net "UART_T6_NODE3_TXD_R")
	)
	(segment
		(start 91.48064 -199.051164)
		(end 91.48064 -196.982842)
		(width 0.1016)
		(layer "F.Cu")
		(net "UART_T6_NODE3_TXD_R")
	)
	(segment
		(start 91.48064 -194.30746)
		(end 88.02624 -190.85306)
		(width 0.1016)
		(layer "F.Cu")
		(net "UART_T6_NODE3_TXD_R")
	)
	(segment
		(start 88.24976 -186.6265)
		(end 87.56396 -187.3123)
		(width 0.1016)
		(layer "F.Cu")
		(net "UART_T6_NODE3_TXD_R")
	)
	(via
		(at 91.48064 -196.982842)
		(size 0.508)
		(drill 0.254)
		(layers "F.Cu" "B.Cu")
		(net "UART_T6_NODE3_TXD_R")
	)
	(segment
		(start 74.53376 -189.093348)
		(end 75.009248 -189.568836)
		(width 0.1016)
		(layer "F.Cu")
		(net "UART_T4_NODE2_TXD_R")
	)
	(segment
		(start 75.09256 -187.127134)
		(end 75.09256 -187.967874)
		(width 0.1016)
		(layer "F.Cu")
		(net "UART_T4_NODE2_TXD_R")
	)
	(segment
		(start 75.01509 -205.199488)
		(end 75.01509 -199.772016)
		(width 0.1016)
		(layer "F.Cu")
		(net "UART_T4_NODE2_TXD_R")
	)
	(segment
		(start 74.53376 -188.526674)
		(end 74.53376 -189.093348)
		(width 0.1016)
		(layer "F.Cu")
		(net "UART_T4_NODE2_TXD_R")
	)
	(segment
		(start 74.53376 -185.605674)
		(end 74.53376 -186.566556)
		(width 0.1016)
		(layer "F.Cu")
		(net "UART_T4_NODE2_TXD_R")
	)
	(segment
		(start 75.01509 -199.772016)
		(end 74.9554 -199.712326)
		(width 0.1016)
		(layer "F.Cu")
		(net "UART_T4_NODE2_TXD_R")
	)
	(segment
		(start 75.009248 -189.568836)
		(end 75.009248 -199.658478)
		(width 0.1016)
		(layer "F.Cu")
		(net "UART_T4_NODE2_TXD_R")
	)
	(segment
		(start 74.53376 -186.566556)
		(end 74.67346 -186.706256)
		(width 0.1016)
		(layer "F.Cu")
		(net "UART_T4_NODE2_TXD_R")
	)
	(segment
		(start 75.09256 -187.967874)
		(end 74.53376 -188.526674)
		(width 0.1016)
		(layer "F.Cu")
		(net "UART_T4_NODE2_TXD_R")
	)
	(segment
		(start 74.67346 -186.708034)
		(end 75.09256 -187.127134)
		(width 0.1016)
		(layer "F.Cu")
		(net "UART_T4_NODE2_TXD_R")
	)
	(segment
		(start 75.009248 -199.658478)
		(end 74.9554 -199.712326)
		(width 0.1016)
		(layer "F.Cu")
		(net "UART_T4_NODE2_TXD_R")
	)
	(segment
		(start 74.67346 -186.706256)
		(end 74.67346 -186.708034)
		(width 0.1016)
		(layer "F.Cu")
		(net "UART_T4_NODE2_TXD_R")
	)
	(via
		(at 74.9554 -199.712326)
		(size 0.508)
		(drill 0.254)
		(layers "F.Cu" "B.Cu")
		(net "UART_T4_NODE2_TXD_R")
	)
	(segment
		(start 101.431598 -180.66512)
		(end 101.220016 -180.66512)
		(width 0.1016)
		(layer "F.Cu")
		(net "CM_STATUS_LED_R")
	)
	(segment
		(start 101.220016 -180.66512)
		(end 100.6221 -180.067204)
		(width 0.1016)
		(layer "F.Cu")
		(net "CM_STATUS_LED_R")
	)
	(via
		(at 100.6221 -180.067204)
		(size 0.508)
		(drill 0.254)
		(layers "F.Cu" "B.Cu")
		(net "CM_STATUS_LED_R")
	)
	(via
		(at 194.3735 -90.878406)
		(size 0.508)
		(drill 0.254)
		(layers "F.Cu" "B.Cu")
		(net "CM_STATUS_LED_R")
	)
	(segment
		(start 109.1819 -181.806088)
		(end 108.672884 -181.297072)
		(width 0.1143)
		(layer "In2.Cu")
		(net "CM_STATUS_LED_R")
	)
	(segment
		(start 193.929 -140.589)
		(end 193.929 -154.584146)
		(width 0.1143)
		(layer "In2.Cu")
		(net "CM_STATUS_LED_R")
	)
	(segment
		(start 193.929 -91.313)
		(end 193.929 -116.586)
		(width 0.1143)
		(layer "In2.Cu")
		(net "CM_STATUS_LED_R")
	)
	(segment
		(start 151.067262 -188.038232)
		(end 121.476516 -188.038232)
		(width 0.1143)
		(layer "In2.Cu")
		(net "CM_STATUS_LED_R")
	)
	(segment
		(start 120.49506 -187.056776)
		(end 120.49506 -186.550554)
		(width 0.1143)
		(layer "In2.Cu")
		(net "CM_STATUS_LED_R")
	)
	(segment
		(start 193.929 -116.586)
		(end 194.31 -116.967)
		(width 0.1143)
		(layer "In2.Cu")
		(net "CM_STATUS_LED_R")
	)
	(segment
		(start 118.03761 -183.78424)
		(end 116.580412 -182.327042)
		(width 0.1143)
		(layer "In2.Cu")
		(net "CM_STATUS_LED_R")
	)
	(segment
		(start 168.5544 -168.3258)
		(end 168.5544 -169.0878)
		(width 0.1143)
		(layer "In2.Cu")
		(net "CM_STATUS_LED_R")
	)
	(segment
		(start 101.851968 -181.297072)
		(end 100.6221 -180.067204)
		(width 0.1143)
		(layer "In2.Cu")
		(net "CM_STATUS_LED_R")
	)
	(segment
		(start 166.243 -176.7586)
		(end 167.3606 -177.8762)
		(width 0.1143)
		(layer "In2.Cu")
		(net "CM_STATUS_LED_R")
	)
	(segment
		(start 112.653826 -181.806088)
		(end 109.1819 -181.806088)
		(width 0.1143)
		(layer "In2.Cu")
		(net "CM_STATUS_LED_R")
	)
	(segment
		(start 193.929 -154.584146)
		(end 183.065674 -165.447472)
		(width 0.1143)
		(layer "In2.Cu")
		(net "CM_STATUS_LED_R")
	)
	(segment
		(start 172.194728 -165.447472)
		(end 170.5102 -167.132)
		(width 0.1143)
		(layer "In2.Cu")
		(net "CM_STATUS_LED_R")
	)
	(segment
		(start 167.3606 -177.8762)
		(end 167.3606 -181.164738)
		(width 0.1143)
		(layer "In2.Cu")
		(net "CM_STATUS_LED_R")
	)
	(segment
		(start 161.4043 -185.68924)
		(end 161.381186 -185.666126)
		(width 0.1143)
		(layer "In2.Cu")
		(net "CM_STATUS_LED_R")
	)
	(segment
		(start 116.580412 -182.327042)
		(end 113.17478 -182.327042)
		(width 0.1143)
		(layer "In2.Cu")
		(net "CM_STATUS_LED_R")
	)
	(segment
		(start 153.342848 -185.666126)
		(end 152.32634 -186.682634)
		(width 0.1143)
		(layer "In2.Cu")
		(net "CM_STATUS_LED_R")
	)
	(segment
		(start 161.76879 -185.68924)
		(end 161.4043 -185.68924)
		(width 0.1143)
		(layer "In2.Cu")
		(net "CM_STATUS_LED_R")
	)
	(segment
		(start 121.476516 -188.038232)
		(end 120.49506 -187.056776)
		(width 0.1143)
		(layer "In2.Cu")
		(net "CM_STATUS_LED_R")
	)
	(segment
		(start 194.31 -90.932)
		(end 193.929 -91.313)
		(width 0.1143)
		(layer "In2.Cu")
		(net "CM_STATUS_LED_R")
	)
	(segment
		(start 183.065674 -165.447472)
		(end 172.194728 -165.447472)
		(width 0.1143)
		(layer "In2.Cu")
		(net "CM_STATUS_LED_R")
	)
	(segment
		(start 194.3735 -90.878406)
		(end 194.31 -90.941906)
		(width 0.1143)
		(layer "In2.Cu")
		(net "CM_STATUS_LED_R")
	)
	(segment
		(start 170.5102 -167.132)
		(end 169.7482 -167.132)
		(width 0.1143)
		(layer "In2.Cu")
		(net "CM_STATUS_LED_R")
	)
	(segment
		(start 118.396766 -184.45226)
		(end 118.29415 -184.45226)
		(width 0.1143)
		(layer "In2.Cu")
		(net "CM_STATUS_LED_R")
	)
	(segment
		(start 152.32634 -186.779154)
		(end 151.067262 -188.038232)
		(width 0.1143)
		(layer "In2.Cu")
		(net "CM_STATUS_LED_R")
	)
	(segment
		(start 168.5544 -169.0878)
		(end 167.3606 -170.2816)
		(width 0.1143)
		(layer "In2.Cu")
		(net "CM_STATUS_LED_R")
	)
	(segment
		(start 108.672884 -181.297072)
		(end 101.851968 -181.297072)
		(width 0.1143)
		(layer "In2.Cu")
		(net "CM_STATUS_LED_R")
	)
	(segment
		(start 167.3606 -181.164738)
		(end 166.784782 -181.740556)
		(width 0.1143)
		(layer "In2.Cu")
		(net "CM_STATUS_LED_R")
	)
	(segment
		(start 194.31 -116.967)
		(end 194.31 -140.208)
		(width 0.1143)
		(layer "In2.Cu")
		(net "CM_STATUS_LED_R")
	)
	(segment
		(start 120.49506 -186.550554)
		(end 118.396766 -184.45226)
		(width 0.1143)
		(layer "In2.Cu")
		(net "CM_STATUS_LED_R")
	)
	(segment
		(start 165.717474 -181.740556)
		(end 161.76879 -185.68924)
		(width 0.1143)
		(layer "In2.Cu")
		(net "CM_STATUS_LED_R")
	)
	(segment
		(start 194.31 -90.941906)
		(end 194.31 -90.932)
		(width 0.1143)
		(layer "In2.Cu")
		(net "CM_STATUS_LED_R")
	)
	(segment
		(start 169.7482 -167.132)
		(end 168.5544 -168.3258)
		(width 0.1143)
		(layer "In2.Cu")
		(net "CM_STATUS_LED_R")
	)
	(segment
		(start 166.784782 -181.740556)
		(end 165.717474 -181.740556)
		(width 0.1143)
		(layer "In2.Cu")
		(net "CM_STATUS_LED_R")
	)
	(segment
		(start 152.32634 -186.682634)
		(end 152.32634 -186.779154)
		(width 0.1143)
		(layer "In2.Cu")
		(net "CM_STATUS_LED_R")
	)
	(segment
		(start 167.3606 -170.2816)
		(end 167.3606 -173.736)
		(width 0.1143)
		(layer "In2.Cu")
		(net "CM_STATUS_LED_R")
	)
	(segment
		(start 167.3606 -173.736)
		(end 166.243 -174.8536)
		(width 0.1143)
		(layer "In2.Cu")
		(net "CM_STATUS_LED_R")
	)
	(segment
		(start 113.17478 -182.327042)
		(end 112.653826 -181.806088)
		(width 0.1143)
		(layer "In2.Cu")
		(net "CM_STATUS_LED_R")
	)
	(segment
		(start 118.29415 -184.45226)
		(end 118.03761 -184.19572)
		(width 0.1143)
		(layer "In2.Cu")
		(net "CM_STATUS_LED_R")
	)
	(segment
		(start 161.381186 -185.666126)
		(end 153.342848 -185.666126)
		(width 0.1143)
		(layer "In2.Cu")
		(net "CM_STATUS_LED_R")
	)
	(segment
		(start 166.243 -174.8536)
		(end 166.243 -176.7586)
		(width 0.1143)
		(layer "In2.Cu")
		(net "CM_STATUS_LED_R")
	)
	(segment
		(start 118.03761 -184.19572)
		(end 118.03761 -183.78424)
		(width 0.1143)
		(layer "In2.Cu")
		(net "CM_STATUS_LED_R")
	)
	(segment
		(start 194.31 -140.208)
		(end 193.929 -140.589)
		(width 0.1143)
		(layer "In2.Cu")
		(net "CM_STATUS_LED_R")
	)
	(segment
		(start 180.060854 -13.250926)
		(end 180.30317 -13.493242)
		(width 0.1143)
		(layer "In6.Cu")
		(net "CM_STATUS_LED_R")
	)
	(segment
		(start 176.4411 -48.246284)
		(end 176.4411 -51.915314)
		(width 0.1143)
		(layer "In6.Cu")
		(net "CM_STATUS_LED_R")
	)
	(segment
		(start 180.30317 -29.332682)
		(end 176.06772 -33.567878)
		(width 0.1143)
		(layer "In6.Cu")
		(net "CM_STATUS_LED_R")
	)
	(segment
		(start 176.4411 -51.915314)
		(end 176.59731 -52.071524)
		(width 0.1143)
		(layer "In6.Cu")
		(net "CM_STATUS_LED_R")
	)
	(segment
		(start 176.06772 -33.567878)
		(end 176.06772 -46.806104)
		(width 0.1143)
		(layer "In6.Cu")
		(net "CM_STATUS_LED_R")
	)
	(segment
		(start 180.060854 -12.061444)
		(end 180.060854 -13.250926)
		(width 0.1143)
		(layer "In6.Cu")
		(net "CM_STATUS_LED_R")
	)
	(segment
		(start 180.30317 -13.493242)
		(end 180.30317 -29.332682)
		(width 0.1143)
		(layer "In6.Cu")
		(net "CM_STATUS_LED_R")
	)
	(segment
		(start 191.962024 -81.331054)
		(end 194.3735 -83.74253)
		(width 0.1143)
		(layer "In6.Cu")
		(net "CM_STATUS_LED_R")
	)
	(segment
		(start 188.90488 -81.331054)
		(end 191.962024 -81.331054)
		(width 0.1143)
		(layer "In6.Cu")
		(net "CM_STATUS_LED_R")
	)
	(segment
		(start 176.06772 -46.806104)
		(end 175.71593 -47.157894)
		(width 0.1143)
		(layer "In6.Cu")
		(net "CM_STATUS_LED_R")
	)
	(segment
		(start 178.93538 -5.465318)
		(end 178.93538 -10.93597)
		(width 0.1143)
		(layer "In6.Cu")
		(net "CM_STATUS_LED_R")
	)
	(segment
		(start 194.3735 -83.74253)
		(end 194.3735 -90.878406)
		(width 0.1143)
		(layer "In6.Cu")
		(net "CM_STATUS_LED_R")
	)
	(segment
		(start 175.71593 -47.157894)
		(end 175.71593 -47.521114)
		(width 0.1143)
		(layer "In6.Cu")
		(net "CM_STATUS_LED_R")
	)
	(segment
		(start 178.93538 -10.93597)
		(end 180.060854 -12.061444)
		(width 0.1143)
		(layer "In6.Cu")
		(net "CM_STATUS_LED_R")
	)
	(segment
		(start 176.59731 -52.071524)
		(end 176.59731 -69.023484)
		(width 0.1143)
		(layer "In6.Cu")
		(net "CM_STATUS_LED_R")
	)
	(segment
		(start 178.729894 -5.259832)
		(end 178.93538 -5.465318)
		(width 0.1143)
		(layer "In6.Cu")
		(net "CM_STATUS_LED_R")
	)
	(segment
		(start 176.59731 -69.023484)
		(end 188.90488 -81.331054)
		(width 0.1143)
		(layer "In6.Cu")
		(net "CM_STATUS_LED_R")
	)
	(segment
		(start 175.71593 -47.521114)
		(end 176.4411 -48.246284)
		(width 0.1143)
		(layer "In6.Cu")
		(net "CM_STATUS_LED_R")
	)
	(segment
		(start 90.01506 -201.655172)
		(end 90.01506 -205.199488)
		(width 0.1016)
		(layer "F.Cu")
		(net "UART_T6_NODE4_RXD_R")
	)
	(segment
		(start 90.13698 -200.085198)
		(end 90.44686 -200.395078)
		(width 0.1016)
		(layer "F.Cu")
		(net "UART_T6_NODE4_RXD_R")
	)
	(segment
		(start 90.44686 -200.395078)
		(end 90.44686 -201.223372)
		(width 0.1016)
		(layer "F.Cu")
		(net "UART_T6_NODE4_RXD_R")
	)
	(segment
		(start 90.13698 -195.932552)
		(end 90.13698 -200.085198)
		(width 0.1016)
		(layer "F.Cu")
		(net "UART_T6_NODE4_RXD_R")
	)
	(segment
		(start 89.90584 -193.437256)
		(end 87.10676 -190.638176)
		(width 0.1016)
		(layer "F.Cu")
		(net "UART_T6_NODE4_RXD_R")
	)
	(segment
		(start 89.90584 -195.701412)
		(end 89.90584 -193.437256)
		(width 0.1016)
		(layer "F.Cu")
		(net "UART_T6_NODE4_RXD_R")
	)
	(segment
		(start 90.13698 -195.932552)
		(end 89.90584 -195.701412)
		(width 0.1016)
		(layer "F.Cu")
		(net "UART_T6_NODE4_RXD_R")
	)
	(segment
		(start 90.44686 -201.223372)
		(end 90.01506 -201.655172)
		(width 0.1016)
		(layer "F.Cu")
		(net "UART_T6_NODE4_RXD_R")
	)
	(segment
		(start 87.10676 -190.638176)
		(end 87.10676 -188.526674)
		(width 0.1016)
		(layer "F.Cu")
		(net "UART_T6_NODE4_RXD_R")
	)
	(via
		(at 90.13698 -195.932552)
		(size 0.508)
		(drill 0.254)
		(layers "F.Cu" "B.Cu")
		(net "UART_T6_NODE4_RXD_R")
	)
	(via
		(at 55.75808 -195.789296)
		(size 0.6604)
		(drill 0.3302)
		(layers "F.Cu" "B.Cu")
		(net "UART_T1_NODE4_RXD_R")
	)
	(segment
		(start 57.38876 -190.44412)
		(end 55.75808 -192.0748)
		(width 0.1016)
		(layer "B.Cu")
		(net "UART_T1_NODE4_RXD_R")
	)
	(segment
		(start 55.014876 -199.863964)
		(end 55.014876 -205.199488)
		(width 0.1016)
		(layer "B.Cu")
		(net "UART_T1_NODE4_RXD_R")
	)
	(segment
		(start 54.99481 -198.955152)
		(end 54.80304 -199.146922)
		(width 0.1016)
		(layer "B.Cu")
		(net "UART_T1_NODE4_RXD_R")
	)
	(segment
		(start 54.80304 -199.146922)
		(end 54.80304 -199.652128)
		(width 0.1016)
		(layer "B.Cu")
		(net "UART_T1_NODE4_RXD_R")
	)
	(segment
		(start 57.38876 -188.526674)
		(end 57.38876 -190.44412)
		(width 0.1016)
		(layer "B.Cu")
		(net "UART_T1_NODE4_RXD_R")
	)
	(segment
		(start 54.99481 -196.552566)
		(end 54.99481 -198.955152)
		(width 0.1016)
		(layer "B.Cu")
		(net "UART_T1_NODE4_RXD_R")
	)
	(segment
		(start 54.80304 -199.652128)
		(end 55.014876 -199.863964)
		(width 0.1016)
		(layer "B.Cu")
		(net "UART_T1_NODE4_RXD_R")
	)
	(segment
		(start 55.75808 -192.0748)
		(end 55.75808 -195.789296)
		(width 0.1016)
		(layer "B.Cu")
		(net "UART_T1_NODE4_RXD_R")
	)
	(segment
		(start 55.75808 -195.789296)
		(end 54.99481 -196.552566)
		(width 0.1016)
		(layer "B.Cu")
		(net "UART_T1_NODE4_RXD_R")
	)
	(segment
		(start 86.45144 -186.586876)
		(end 86.45144 -186.131708)
		(width 0.1016)
		(layer "F.Cu")
		(net "UART_T6_NODE4_TXD_R")
	)
	(segment
		(start 86.45144 -188.038994)
		(end 86.45144 -188.031374)
		(width 0.1016)
		(layer "F.Cu")
		(net "UART_T6_NODE4_TXD_R")
	)
	(segment
		(start 85.96376 -188.526674)
		(end 85.96376 -190.792354)
		(width 0.1016)
		(layer "F.Cu")
		(net "UART_T6_NODE4_TXD_R")
	)
	(segment
		(start 85.96376 -190.792354)
		(end 88.60028 -193.428874)
		(width 0.1016)
		(layer "F.Cu")
		(net "UART_T6_NODE4_TXD_R")
	)
	(segment
		(start 86.45144 -186.131708)
		(end 85.96376 -185.644028)
		(width 0.1016)
		(layer "F.Cu")
		(net "UART_T6_NODE4_TXD_R")
	)
	(segment
		(start 89.0143 -199.90816)
		(end 89.015062 -199.90816)
		(width 0.1016)
		(layer "F.Cu")
		(net "UART_T6_NODE4_TXD_R")
	)
	(segment
		(start 86.52256 -187.960254)
		(end 86.52256 -186.657996)
		(width 0.1016)
		(layer "F.Cu")
		(net "UART_T6_NODE4_TXD_R")
	)
	(segment
		(start 88.60028 -198.971408)
		(end 89.0143 -199.385428)
		(width 0.1016)
		(layer "F.Cu")
		(net "UART_T6_NODE4_TXD_R")
	)
	(segment
		(start 89.0143 -199.385428)
		(end 89.0143 -199.90816)
		(width 0.1016)
		(layer "F.Cu")
		(net "UART_T6_NODE4_TXD_R")
	)
	(segment
		(start 86.52256 -186.657996)
		(end 86.45144 -186.586876)
		(width 0.1016)
		(layer "F.Cu")
		(net "UART_T6_NODE4_TXD_R")
	)
	(segment
		(start 86.45144 -188.031374)
		(end 86.52256 -187.960254)
		(width 0.1016)
		(layer "F.Cu")
		(net "UART_T6_NODE4_TXD_R")
	)
	(segment
		(start 88.60028 -193.428874)
		(end 88.60028 -198.971408)
		(width 0.1016)
		(layer "F.Cu")
		(net "UART_T6_NODE4_TXD_R")
	)
	(segment
		(start 85.96376 -185.644028)
		(end 85.96376 -185.605674)
		(width 0.1016)
		(layer "F.Cu")
		(net "UART_T6_NODE4_TXD_R")
	)
	(segment
		(start 89.015062 -199.90816)
		(end 89.015062 -205.199488)
		(width 0.1016)
		(layer "F.Cu")
		(net "UART_T6_NODE4_TXD_R")
	)
	(segment
		(start 85.96376 -188.526674)
		(end 86.45144 -188.038994)
		(width 0.1016)
		(layer "F.Cu")
		(net "UART_T6_NODE4_TXD_R")
	)
	(via
		(at 89.0143 -199.385428)
		(size 0.508)
		(drill 0.254)
		(layers "F.Cu" "B.Cu")
		(net "UART_T6_NODE4_TXD_R")
	)
	(via
		(at 54.39664 -198.025258)
		(size 0.6604)
		(drill 0.3302)
		(layers "F.Cu" "B.Cu")
		(net "UART_T1_NODE4_TXD_R")
	)
	(segment
		(start 54.446932 -198.073518)
		(end 54.446932 -201.666348)
		(width 0.1016)
		(layer "B.Cu")
		(net "UART_T1_NODE4_TXD_R")
	)
	(segment
		(start 55.66918 -186.228736)
		(end 55.66918 -187.950094)
		(width 0.1016)
		(layer "B.Cu")
		(net "UART_T1_NODE4_TXD_R")
	)
	(segment
		(start 54.446932 -201.666348)
		(end 54.015132 -202.098148)
		(width 0.1016)
		(layer "B.Cu")
		(net "UART_T1_NODE4_TXD_R")
	)
	(segment
		(start 56.24576 -188.526674)
		(end 56.24576 -190.638176)
		(width 0.1016)
		(layer "B.Cu")
		(net "UART_T1_NODE4_TXD_R")
	)
	(segment
		(start 55.66918 -187.950094)
		(end 56.24576 -188.526674)
		(width 0.1016)
		(layer "B.Cu")
		(net "UART_T1_NODE4_TXD_R")
	)
	(segment
		(start 56.24576 -185.652156)
		(end 55.66918 -186.228736)
		(width 0.1016)
		(layer "B.Cu")
		(net "UART_T1_NODE4_TXD_R")
	)
	(segment
		(start 54.398672 -198.025258)
		(end 54.446932 -198.073518)
		(width 0.1016)
		(layer "B.Cu")
		(net "UART_T1_NODE4_TXD_R")
	)
	(segment
		(start 56.24576 -190.638176)
		(end 54.4449 -192.439036)
		(width 0.1016)
		(layer "B.Cu")
		(net "UART_T1_NODE4_TXD_R")
	)
	(segment
		(start 56.24576 -185.605674)
		(end 56.24576 -185.652156)
		(width 0.1016)
		(layer "B.Cu")
		(net "UART_T1_NODE4_TXD_R")
	)
	(segment
		(start 54.4449 -192.439036)
		(end 54.4449 -197.976998)
		(width 0.1016)
		(layer "B.Cu")
		(net "UART_T1_NODE4_TXD_R")
	)
	(segment
		(start 54.39664 -198.025258)
		(end 54.398672 -198.025258)
		(width 0.1016)
		(layer "B.Cu")
		(net "UART_T1_NODE4_TXD_R")
	)
	(segment
		(start 54.015132 -202.098148)
		(end 54.015132 -205.199488)
		(width 0.1016)
		(layer "B.Cu")
		(net "UART_T1_NODE4_TXD_R")
	)
	(segment
		(start 54.4449 -197.976998)
		(end 54.39664 -198.025258)
		(width 0.1016)
		(layer "B.Cu")
		(net "UART_T1_NODE4_TXD_R")
	)
	(segment
		(start 134.01548 -197.859396)
		(end 134.22376 -197.651116)
		(width 0.1016)
		(layer "F.Cu")
		(net "UART_T10_NODE1_TXD_R")
	)
	(segment
		(start 134.22376 -186.086242)
		(end 134.44728 -186.309762)
		(width 0.1016)
		(layer "F.Cu")
		(net "UART_T10_NODE1_TXD_R")
	)
	(segment
		(start 134.01548 -205.199488)
		(end 134.01548 -197.859396)
		(width 0.1016)
		(layer "F.Cu")
		(net "UART_T10_NODE1_TXD_R")
	)
	(segment
		(start 134.60476 -189.809374)
		(end 134.60476 -188.526674)
		(width 0.1016)
		(layer "F.Cu")
		(net "UART_T10_NODE1_TXD_R")
	)
	(segment
		(start 134.44728 -186.397138)
		(end 135.17372 -187.123578)
		(width 0.1016)
		(layer "F.Cu")
		(net "UART_T10_NODE1_TXD_R")
	)
	(segment
		(start 135.17372 -187.123578)
		(end 135.17372 -187.957714)
		(width 0.1016)
		(layer "F.Cu")
		(net "UART_T10_NODE1_TXD_R")
	)
	(segment
		(start 134.44728 -186.309762)
		(end 134.44728 -186.397138)
		(width 0.1016)
		(layer "F.Cu")
		(net "UART_T10_NODE1_TXD_R")
	)
	(segment
		(start 134.4422 -189.971934)
		(end 134.60476 -189.809374)
		(width 0.1016)
		(layer "F.Cu")
		(net "UART_T10_NODE1_TXD_R")
	)
	(segment
		(start 135.17372 -187.957714)
		(end 134.60476 -188.526674)
		(width 0.1016)
		(layer "F.Cu")
		(net "UART_T10_NODE1_TXD_R")
	)
	(segment
		(start 134.22376 -196.139054)
		(end 134.4422 -195.920614)
		(width 0.1016)
		(layer "F.Cu")
		(net "UART_T10_NODE1_TXD_R")
	)
	(segment
		(start 134.22376 -185.605674)
		(end 134.22376 -186.086242)
		(width 0.1016)
		(layer "F.Cu")
		(net "UART_T10_NODE1_TXD_R")
	)
	(segment
		(start 134.4422 -195.920614)
		(end 134.4422 -189.971934)
		(width 0.1016)
		(layer "F.Cu")
		(net "UART_T10_NODE1_TXD_R")
	)
	(segment
		(start 134.22376 -197.651116)
		(end 134.22376 -196.139054)
		(width 0.1016)
		(layer "F.Cu")
		(net "UART_T10_NODE1_TXD_R")
	)
	(via
		(at 134.4422 -195.920614)
		(size 0.508)
		(drill 0.254)
		(layers "F.Cu" "B.Cu")
		(net "UART_T10_NODE1_TXD_R")
	)
	(segment
		(start 73.39076 -188.526674)
		(end 73.39076 -189.28969)
		(width 0.1016)
		(layer "F.Cu")
		(net "UART_T4_NODE3_RXD_R")
	)
	(segment
		(start 73.39076 -189.28969)
		(end 74.00798 -189.90691)
		(width 0.1016)
		(layer "F.Cu")
		(net "UART_T4_NODE3_RXD_R")
	)
	(segment
		(start 74.00798 -195.889118)
		(end 74.00798 -199.150986)
		(width 0.1016)
		(layer "F.Cu")
		(net "UART_T4_NODE3_RXD_R")
	)
	(segment
		(start 74.00798 -195.889118)
		(end 74.00036 -195.889118)
		(width 0.1016)
		(layer "F.Cu")
		(net "UART_T4_NODE3_RXD_R")
	)
	(segment
		(start 73.015094 -200.143872)
		(end 73.015094 -205.199488)
		(width 0.1016)
		(layer "F.Cu")
		(net "UART_T4_NODE3_RXD_R")
	)
	(segment
		(start 74.00798 -189.90691)
		(end 74.00798 -195.889118)
		(width 0.1016)
		(layer "F.Cu")
		(net "UART_T4_NODE3_RXD_R")
	)
	(segment
		(start 74.00798 -199.150986)
		(end 73.015094 -200.143872)
		(width 0.1016)
		(layer "F.Cu")
		(net "UART_T4_NODE3_RXD_R")
	)
	(via
		(at 74.00036 -195.889118)
		(size 0.508)
		(drill 0.254)
		(layers "F.Cu" "B.Cu")
		(net "UART_T4_NODE3_RXD_R")
	)
	(segment
		(start 140.015468 -199.9234)
		(end 140.015468 -205.199488)
		(width 0.1016)
		(layer "F.Cu")
		(net "T10_NODE1_EN_R")
	)
	(segment
		(start 140.504672 -186.352942)
		(end 140.504672 -187.949586)
		(width 0.1016)
		(layer "F.Cu")
		(net "T10_NODE1_EN_R")
	)
	(segment
		(start 141.08176 -197.832472)
		(end 140.93698 -197.977252)
		(width 0.1016)
		(layer "F.Cu")
		(net "T10_NODE1_EN_R")
	)
	(segment
		(start 141.08176 -185.605674)
		(end 141.08176 -185.775854)
		(width 0.1016)
		(layer "F.Cu")
		(net "T10_NODE1_EN_R")
	)
	(segment
		(start 140.504672 -187.949586)
		(end 141.08176 -188.526674)
		(width 0.1016)
		(layer "F.Cu")
		(net "T10_NODE1_EN_R")
	)
	(segment
		(start 141.08176 -188.526674)
		(end 141.08176 -197.832472)
		(width 0.1016)
		(layer "F.Cu")
		(net "T10_NODE1_EN_R")
	)
	(segment
		(start 140.61694 -198.297292)
		(end 140.61694 -199.321928)
		(width 0.1016)
		(layer "F.Cu")
		(net "T10_NODE1_EN_R")
	)
	(segment
		(start 140.93698 -197.977252)
		(end 140.61694 -198.297292)
		(width 0.1016)
		(layer "F.Cu")
		(net "T10_NODE1_EN_R")
	)
	(segment
		(start 140.61694 -199.321928)
		(end 140.015468 -199.9234)
		(width 0.1016)
		(layer "F.Cu")
		(net "T10_NODE1_EN_R")
	)
	(segment
		(start 141.08176 -185.775854)
		(end 140.504672 -186.352942)
		(width 0.1016)
		(layer "F.Cu")
		(net "T10_NODE1_EN_R")
	)
	(via
		(at 140.93698 -197.977252)
		(size 0.508)
		(drill 0.254)
		(layers "F.Cu" "B.Cu")
		(net "T10_NODE1_EN_R")
	)
	(segment
		(start 72.119744 -188.538358)
		(end 72.236076 -188.538358)
		(width 0.1016)
		(layer "F.Cu")
		(net "UART_T4_NODE3_TXD_R")
	)
	(segment
		(start 71.66356 -186.027822)
		(end 71.66356 -188.082174)
		(width 0.1016)
		(layer "F.Cu")
		(net "UART_T4_NODE3_TXD_R")
	)
	(segment
		(start 72.015096 -205.199488)
		(end 72.015096 -202.716638)
		(width 0.1016)
		(layer "F.Cu")
		(net "UART_T4_NODE3_TXD_R")
	)
	(segment
		(start 72.4027 -202.329034)
		(end 72.4027 -200.050654)
		(width 0.1016)
		(layer "F.Cu")
		(net "UART_T4_NODE3_TXD_R")
	)
	(segment
		(start 72.236076 -188.538358)
		(end 72.24776 -188.526674)
		(width 0.1016)
		(layer "F.Cu")
		(net "UART_T4_NODE3_TXD_R")
	)
	(segment
		(start 72.236076 -189.215268)
		(end 72.236076 -188.538358)
		(width 0.1016)
		(layer "F.Cu")
		(net "UART_T4_NODE3_TXD_R")
	)
	(segment
		(start 72.015096 -202.716638)
		(end 72.4027 -202.329034)
		(width 0.1016)
		(layer "F.Cu")
		(net "UART_T4_NODE3_TXD_R")
	)
	(segment
		(start 72.24776 -185.605674)
		(end 72.085708 -185.605674)
		(width 0.1016)
		(layer "F.Cu")
		(net "UART_T4_NODE3_TXD_R")
	)
	(segment
		(start 72.4027 -200.050654)
		(end 72.827388 -199.625966)
		(width 0.1016)
		(layer "F.Cu")
		(net "UART_T4_NODE3_TXD_R")
	)
	(segment
		(start 72.085708 -185.605674)
		(end 71.66356 -186.027822)
		(width 0.1016)
		(layer "F.Cu")
		(net "UART_T4_NODE3_TXD_R")
	)
	(segment
		(start 72.827388 -199.625966)
		(end 72.827388 -189.80658)
		(width 0.1016)
		(layer "F.Cu")
		(net "UART_T4_NODE3_TXD_R")
	)
	(segment
		(start 71.66356 -188.082174)
		(end 72.119744 -188.538358)
		(width 0.1016)
		(layer "F.Cu")
		(net "UART_T4_NODE3_TXD_R")
	)
	(segment
		(start 72.827388 -189.80658)
		(end 72.236076 -189.215268)
		(width 0.1016)
		(layer "F.Cu")
		(net "UART_T4_NODE3_TXD_R")
	)
	(via
		(at 72.827388 -199.625966)
		(size 0.508)
		(drill 0.254)
		(layers "F.Cu" "B.Cu")
		(net "UART_T4_NODE3_TXD_R")
	)
	(segment
		(start 139.93876 -198.644764)
		(end 139.01547 -199.568054)
		(width 0.1016)
		(layer "F.Cu")
		(net "T10_NODE2_EN_R")
	)
	(segment
		(start 139.93876 -185.605674)
		(end 139.93876 -186.08675)
		(width 0.1016)
		(layer "F.Cu")
		(net "T10_NODE2_EN_R")
	)
	(segment
		(start 139.93876 -196.051932)
		(end 139.93876 -198.644764)
		(width 0.1016)
		(layer "F.Cu")
		(net "T10_NODE2_EN_R")
	)
	(segment
		(start 139.01547 -199.568054)
		(end 139.01547 -205.199488)
		(width 0.1016)
		(layer "F.Cu")
		(net "T10_NODE2_EN_R")
	)
	(segment
		(start 139.93876 -186.08675)
		(end 139.430252 -186.595258)
		(width 0.1016)
		(layer "F.Cu")
		(net "T10_NODE2_EN_R")
	)
	(segment
		(start 139.93876 -188.526674)
		(end 139.93876 -196.051932)
		(width 0.1016)
		(layer "F.Cu")
		(net "T10_NODE2_EN_R")
	)
	(segment
		(start 139.430252 -188.018166)
		(end 139.93876 -188.526674)
		(width 0.1016)
		(layer "F.Cu")
		(net "T10_NODE2_EN_R")
	)
	(segment
		(start 139.430252 -186.595258)
		(end 139.430252 -188.018166)
		(width 0.1016)
		(layer "F.Cu")
		(net "T10_NODE2_EN_R")
	)
	(via
		(at 139.93876 -196.051932)
		(size 0.508)
		(drill 0.254)
		(layers "F.Cu" "B.Cu")
		(net "T10_NODE2_EN_R")
	)
	(segment
		(start 129.55016 -186.544712)
		(end 129.55016 -187.993274)
		(width 0.1016)
		(layer "F.Cu")
		(net "UART_T10_NODE3_TXD_R")
	)
	(segment
		(start 129.01549 -199.568816)
		(end 129.01549 -205.199488)
		(width 0.1016)
		(layer "F.Cu")
		(net "UART_T10_NODE3_TXD_R")
	)
	(segment
		(start 129.0701 -183.745378)
		(end 129.0701 -184.200546)
		(width 0.1016)
		(layer "F.Cu")
		(net "UART_T10_NODE3_TXD_R")
	)
	(segment
		(start 130.107436 -183.491378)
		(end 129.3241 -183.491378)
		(width 0.1016)
		(layer "F.Cu")
		(net "UART_T10_NODE3_TXD_R")
	)
	(segment
		(start 129.65176 -196.062092)
		(end 129.01549 -196.698362)
		(width 0.1016)
		(layer "F.Cu")
		(net "UART_T10_NODE3_TXD_R")
	)
	(segment
		(start 129.02438 -186.018932)
		(end 129.55016 -186.544712)
		(width 0.1016)
		(layer "F.Cu")
		(net "UART_T10_NODE3_TXD_R")
	)
	(segment
		(start 130.08356 -188.526674)
		(end 130.08356 -188.784992)
		(width 0.1016)
		(layer "F.Cu")
		(net "UART_T10_NODE3_TXD_R")
	)
	(segment
		(start 130.187192 -183.411622)
		(end 130.107436 -183.491378)
		(width 0.1016)
		(layer "F.Cu")
		(net "UART_T10_NODE3_TXD_R")
	)
	(segment
		(start 129.02438 -184.246266)
		(end 129.02438 -186.018932)
		(width 0.1016)
		(layer "F.Cu")
		(net "UART_T10_NODE3_TXD_R")
	)
	(segment
		(start 129.55016 -187.993274)
		(end 130.08356 -188.526674)
		(width 0.1016)
		(layer "F.Cu")
		(net "UART_T10_NODE3_TXD_R")
	)
	(segment
		(start 129.01549 -196.698362)
		(end 129.01549 -199.568816)
		(width 0.1016)
		(layer "F.Cu")
		(net "UART_T10_NODE3_TXD_R")
	)
	(segment
		(start 130.08356 -188.784992)
		(end 129.65176 -189.216792)
		(width 0.1016)
		(layer "F.Cu")
		(net "UART_T10_NODE3_TXD_R")
	)
	(segment
		(start 129.3241 -183.491378)
		(end 129.0701 -183.745378)
		(width 0.1016)
		(layer "F.Cu")
		(net "UART_T10_NODE3_TXD_R")
	)
	(segment
		(start 129.0701 -184.200546)
		(end 129.02438 -184.246266)
		(width 0.1016)
		(layer "F.Cu")
		(net "UART_T10_NODE3_TXD_R")
	)
	(segment
		(start 129.65176 -189.216792)
		(end 129.65176 -196.062092)
		(width 0.1016)
		(layer "F.Cu")
		(net "UART_T10_NODE3_TXD_R")
	)
	(via
		(at 129.01549 -199.568816)
		(size 0.508)
		(drill 0.254)
		(layers "F.Cu" "B.Cu")
		(net "UART_T10_NODE3_TXD_R")
	)
	(via
		(at 130.187192 -183.411622)
		(size 0.508)
		(drill 0.254)
		(layers "F.Cu" "B.Cu")
		(net "UART_T10_NODE3_TXD_R")
	)
	(segment
		(start 133.19633 -168.02862)
		(end 132.60832 -168.61663)
		(width 0.1016)
		(layer "B.Cu")
		(net "UART_T10_NODE3_TXD_R")
	)
	(segment
		(start 132.60832 -168.61663)
		(end 132.60832 -176.693322)
		(width 0.1016)
		(layer "B.Cu")
		(net "UART_T10_NODE3_TXD_R")
	)
	(segment
		(start 141.099032 -166.012114)
		(end 140.534898 -166.576248)
		(width 0.1016)
		(layer "B.Cu")
		(net "UART_T10_NODE3_TXD_R")
	)
	(segment
		(start 134.38378 -167.39108)
		(end 133.74624 -168.02862)
		(width 0.1016)
		(layer "B.Cu")
		(net "UART_T10_NODE3_TXD_R")
	)
	(segment
		(start 139.625324 -166.576248)
		(end 138.810492 -167.39108)
		(width 0.1016)
		(layer "B.Cu")
		(net "UART_T10_NODE3_TXD_R")
	)
	(segment
		(start 132.60832 -176.693322)
		(end 130.2258 -179.075842)
		(width 0.1016)
		(layer "B.Cu")
		(net "UART_T10_NODE3_TXD_R")
	)
	(segment
		(start 141.099032 -163.898072)
		(end 141.099032 -166.012114)
		(width 0.1016)
		(layer "B.Cu")
		(net "UART_T10_NODE3_TXD_R")
	)
	(segment
		(start 138.810492 -167.39108)
		(end 134.38378 -167.39108)
		(width 0.1016)
		(layer "B.Cu")
		(net "UART_T10_NODE3_TXD_R")
	)
	(segment
		(start 140.534898 -166.576248)
		(end 139.625324 -166.576248)
		(width 0.1016)
		(layer "B.Cu")
		(net "UART_T10_NODE3_TXD_R")
	)
	(segment
		(start 133.74624 -168.02862)
		(end 133.19633 -168.02862)
		(width 0.1016)
		(layer "B.Cu")
		(net "UART_T10_NODE3_TXD_R")
	)
	(segment
		(start 130.2258 -183.373014)
		(end 130.187192 -183.411622)
		(width 0.1016)
		(layer "B.Cu")
		(net "UART_T10_NODE3_TXD_R")
	)
	(segment
		(start 130.2258 -179.075842)
		(end 130.2258 -183.373014)
		(width 0.1016)
		(layer "B.Cu")
		(net "UART_T10_NODE3_TXD_R")
	)
	(segment
		(start 138.79576 -186.08675)
		(end 138.287252 -186.595258)
		(width 0.1016)
		(layer "F.Cu")
		(net "T10_NODE3_EN_R")
	)
	(segment
		(start 138.5062 -198.920608)
		(end 138.015472 -199.411336)
		(width 0.1016)
		(layer "F.Cu")
		(net "T10_NODE3_EN_R")
	)
	(segment
		(start 138.287252 -187.991242)
		(end 138.795252 -188.499242)
		(width 0.1016)
		(layer "F.Cu")
		(net "T10_NODE3_EN_R")
	)
	(segment
		(start 138.79576 -198.631048)
		(end 138.79576 -188.526674)
		(width 0.1016)
		(layer "F.Cu")
		(net "T10_NODE3_EN_R")
	)
	(segment
		(start 138.015472 -199.411336)
		(end 138.015472 -204.699616)
		(width 0.1016)
		(layer "F.Cu")
		(net "T10_NODE3_EN_R")
	)
	(segment
		(start 138.5062 -198.920608)
		(end 138.79576 -198.631048)
		(width 0.1016)
		(layer "F.Cu")
		(net "T10_NODE3_EN_R")
	)
	(segment
		(start 138.287252 -186.595258)
		(end 138.287252 -187.991242)
		(width 0.1016)
		(layer "F.Cu")
		(net "T10_NODE3_EN_R")
	)
	(segment
		(start 138.795252 -188.499242)
		(end 138.795252 -188.526166)
		(width 0.1016)
		(layer "F.Cu")
		(net "T10_NODE3_EN_R")
	)
	(segment
		(start 138.795252 -188.526166)
		(end 138.79576 -188.526674)
		(width 0.1016)
		(layer "F.Cu")
		(net "T10_NODE3_EN_R")
	)
	(segment
		(start 138.79576 -185.605674)
		(end 138.79576 -186.08675)
		(width 0.1016)
		(layer "F.Cu")
		(net "T10_NODE3_EN_R")
	)
	(via
		(at 138.5062 -198.920608)
		(size 0.508)
		(drill 0.254)
		(layers "F.Cu" "B.Cu")
		(net "T10_NODE3_EN_R")
	)
	(segment
		(start 51.67376 -186.213242)
		(end 52.181252 -186.720734)
		(width 0.1016)
		(layer "F.Cu")
		(net "PSU2_AC_OK_R")
	)
	(segment
		(start 51.67376 -188.498734)
		(end 51.67376 -188.526674)
		(width 0.1016)
		(layer "F.Cu")
		(net "PSU2_AC_OK_R")
	)
	(segment
		(start 51.67376 -188.526674)
		(end 51.67376 -190.469012)
		(width 0.1016)
		(layer "F.Cu")
		(net "PSU2_AC_OK_R")
	)
	(segment
		(start 51.67376 -190.469012)
		(end 50.73904 -191.403732)
		(width 0.1016)
		(layer "F.Cu")
		(net "PSU2_AC_OK_R")
	)
	(segment
		(start 52.181252 -187.991242)
		(end 51.67376 -188.498734)
		(width 0.1016)
		(layer "F.Cu")
		(net "PSU2_AC_OK_R")
	)
	(segment
		(start 51.67376 -185.605674)
		(end 51.67376 -186.213242)
		(width 0.1016)
		(layer "F.Cu")
		(net "PSU2_AC_OK_R")
	)
	(segment
		(start 50.2285 -194.548506)
		(end 50.2285 -198.54037)
		(width 0.1016)
		(layer "F.Cu")
		(net "PSU2_AC_OK_R")
	)
	(segment
		(start 49.014888 -199.753982)
		(end 49.014888 -205.199488)
		(width 0.1016)
		(layer "F.Cu")
		(net "PSU2_AC_OK_R")
	)
	(segment
		(start 52.181252 -186.720734)
		(end 52.181252 -187.991242)
		(width 0.1016)
		(layer "F.Cu")
		(net "PSU2_AC_OK_R")
	)
	(segment
		(start 50.73904 -194.037966)
		(end 50.2285 -194.548506)
		(width 0.1016)
		(layer "F.Cu")
		(net "PSU2_AC_OK_R")
	)
	(segment
		(start 50.2285 -198.54037)
		(end 49.014888 -199.753982)
		(width 0.1016)
		(layer "F.Cu")
		(net "PSU2_AC_OK_R")
	)
	(segment
		(start 50.73904 -191.403732)
		(end 50.73904 -194.037966)
		(width 0.1016)
		(layer "F.Cu")
		(net "PSU2_AC_OK_R")
	)
	(via
		(at 50.73904 -194.037966)
		(size 0.508)
		(drill 0.254)
		(layers "F.Cu" "B.Cu")
		(net "PSU2_AC_OK_R")
	)
	(via
		(at 130.66522 -199.573134)
		(size 0.6604)
		(drill 0.3302)
		(layers "F.Cu" "B.Cu")
		(net "UART_T9_NODE1_TXD_R")
	)
	(segment
		(start 133.638036 -187.68695)
		(end 134.22376 -188.272674)
		(width 0.1016)
		(layer "B.Cu")
		(net "UART_T9_NODE1_TXD_R")
	)
	(segment
		(start 130.66522 -199.573134)
		(end 130.015488 -200.222866)
		(width 0.1016)
		(layer "B.Cu")
		(net "UART_T9_NODE1_TXD_R")
	)
	(segment
		(start 134.22376 -193.127122)
		(end 130.66522 -196.685662)
		(width 0.1016)
		(layer "B.Cu")
		(net "UART_T9_NODE1_TXD_R")
	)
	(segment
		(start 134.22376 -185.351674)
		(end 134.22376 -186.085734)
		(width 0.1016)
		(layer "B.Cu")
		(net "UART_T9_NODE1_TXD_R")
	)
	(segment
		(start 130.66522 -196.685662)
		(end 130.66522 -199.573134)
		(width 0.1016)
		(layer "B.Cu")
		(net "UART_T9_NODE1_TXD_R")
	)
	(segment
		(start 133.638036 -186.671458)
		(end 133.638036 -187.68695)
		(width 0.1016)
		(layer "B.Cu")
		(net "UART_T9_NODE1_TXD_R")
	)
	(segment
		(start 130.015488 -200.222866)
		(end 130.015488 -205.199488)
		(width 0.1016)
		(layer "B.Cu")
		(net "UART_T9_NODE1_TXD_R")
	)
	(segment
		(start 134.22376 -188.272674)
		(end 134.22376 -193.127122)
		(width 0.1016)
		(layer "B.Cu")
		(net "UART_T9_NODE1_TXD_R")
	)
	(segment
		(start 134.22376 -186.085734)
		(end 133.638036 -186.671458)
		(width 0.1016)
		(layer "B.Cu")
		(net "UART_T9_NODE1_TXD_R")
	)
	(segment
		(start 137.65276 -186.21375)
		(end 137.144252 -186.722258)
		(width 0.1016)
		(layer "F.Cu")
		(net "T10_NODE4_EN_R")
	)
	(segment
		(start 137.015474 -205.199488)
		(end 137.015474 -202.265534)
		(width 0.1016)
		(layer "F.Cu")
		(net "T10_NODE4_EN_R")
	)
	(segment
		(start 137.65276 -196.718936)
		(end 137.65276 -188.526674)
		(width 0.1016)
		(layer "F.Cu")
		(net "T10_NODE4_EN_R")
	)
	(segment
		(start 137.144252 -188.018166)
		(end 137.65276 -188.526674)
		(width 0.1016)
		(layer "F.Cu")
		(net "T10_NODE4_EN_R")
	)
	(segment
		(start 137.65276 -198.940928)
		(end 137.0711 -198.359268)
		(width 0.1016)
		(layer "F.Cu")
		(net "T10_NODE4_EN_R")
	)
	(segment
		(start 137.65276 -185.605674)
		(end 137.65276 -186.21375)
		(width 0.1016)
		(layer "F.Cu")
		(net "T10_NODE4_EN_R")
	)
	(segment
		(start 137.0711 -198.359268)
		(end 137.0711 -197.300596)
		(width 0.1016)
		(layer "F.Cu")
		(net "T10_NODE4_EN_R")
	)
	(segment
		(start 137.144252 -186.722258)
		(end 137.144252 -188.018166)
		(width 0.1016)
		(layer "F.Cu")
		(net "T10_NODE4_EN_R")
	)
	(segment
		(start 137.015474 -202.265534)
		(end 137.65276 -201.628248)
		(width 0.1016)
		(layer "F.Cu")
		(net "T10_NODE4_EN_R")
	)
	(segment
		(start 137.65276 -201.628248)
		(end 137.65276 -198.940928)
		(width 0.1016)
		(layer "F.Cu")
		(net "T10_NODE4_EN_R")
	)
	(segment
		(start 137.0711 -197.300596)
		(end 137.65276 -196.718936)
		(width 0.1016)
		(layer "F.Cu")
		(net "T10_NODE4_EN_R")
	)
	(via
		(at 137.0711 -198.359268)
		(size 0.508)
		(drill 0.254)
		(layers "F.Cu" "B.Cu")
		(net "T10_NODE4_EN_R")
	)
	(segment
		(start 51.038252 -186.721242)
		(end 51.038252 -187.991242)
		(width 0.1016)
		(layer "F.Cu")
		(net "PSU3_AC_OK_R")
	)
	(segment
		(start 49.777142 -190.289434)
		(end 50.53076 -189.535816)
		(width 0.1016)
		(layer "F.Cu")
		(net "PSU3_AC_OK_R")
	)
	(segment
		(start 48.01489 -205.199488)
		(end 48.01489 -199.323198)
		(width 0.1016)
		(layer "F.Cu")
		(net "PSU3_AC_OK_R")
	)
	(segment
		(start 49.777142 -194.845432)
		(end 49.777142 -190.289434)
		(width 0.1016)
		(layer "F.Cu")
		(net "PSU3_AC_OK_R")
	)
	(segment
		(start 51.038252 -187.991242)
		(end 50.53076 -188.498734)
		(width 0.1016)
		(layer "F.Cu")
		(net "PSU3_AC_OK_R")
	)
	(segment
		(start 50.53076 -186.21375)
		(end 51.038252 -186.721242)
		(width 0.1016)
		(layer "F.Cu")
		(net "PSU3_AC_OK_R")
	)
	(segment
		(start 48.01489 -199.323198)
		(end 49.009046 -198.329042)
		(width 0.1016)
		(layer "F.Cu")
		(net "PSU3_AC_OK_R")
	)
	(segment
		(start 49.009046 -198.329042)
		(end 49.009046 -195.83908)
		(width 0.1016)
		(layer "F.Cu")
		(net "PSU3_AC_OK_R")
	)
	(segment
		(start 50.53076 -185.605674)
		(end 50.53076 -186.21375)
		(width 0.1016)
		(layer "F.Cu")
		(net "PSU3_AC_OK_R")
	)
	(segment
		(start 49.009046 -195.83908)
		(end 49.009046 -195.613528)
		(width 0.1016)
		(layer "F.Cu")
		(net "PSU3_AC_OK_R")
	)
	(segment
		(start 50.53076 -188.498734)
		(end 50.53076 -188.526674)
		(width 0.1016)
		(layer "F.Cu")
		(net "PSU3_AC_OK_R")
	)
	(segment
		(start 49.009046 -195.613528)
		(end 49.777142 -194.845432)
		(width 0.1016)
		(layer "F.Cu")
		(net "PSU3_AC_OK_R")
	)
	(segment
		(start 50.53076 -189.535816)
		(end 50.53076 -188.526674)
		(width 0.1016)
		(layer "F.Cu")
		(net "PSU3_AC_OK_R")
	)
	(via
		(at 49.009046 -195.83908)
		(size 0.508)
		(drill 0.254)
		(layers "F.Cu" "B.Cu")
		(net "PSU3_AC_OK_R")
	)
	(segment
		(start 87.55634 -193.890392)
		(end 84.82076 -191.154812)
		(width 0.1016)
		(layer "F.Cu")
		(net "I2C_PSU2_R_SCL")
	)
	(segment
		(start 87.55634 -199.588628)
		(end 87.55634 -193.890392)
		(width 0.1016)
		(layer "F.Cu")
		(net "I2C_PSU2_R_SCL")
	)
	(segment
		(start 84.28736 -186.139074)
		(end 84.28736 -188.318394)
		(width 0.1016)
		(layer "F.Cu")
		(net "I2C_PSU2_R_SCL")
	)
	(segment
		(start 87.015066 -205.199488)
		(end 87.015066 -200.129902)
		(width 0.1016)
		(layer "F.Cu")
		(net "I2C_PSU2_R_SCL")
	)
	(segment
		(start 84.28736 -188.318394)
		(end 84.49564 -188.526674)
		(width 0.1016)
		(layer "F.Cu")
		(net "I2C_PSU2_R_SCL")
	)
	(segment
		(start 84.49564 -188.526674)
		(end 84.82076 -188.526674)
		(width 0.1016)
		(layer "F.Cu")
		(net "I2C_PSU2_R_SCL")
	)
	(segment
		(start 87.015066 -200.129902)
		(end 87.55634 -199.588628)
		(width 0.1016)
		(layer "F.Cu")
		(net "I2C_PSU2_R_SCL")
	)
	(segment
		(start 84.82076 -191.154812)
		(end 84.82076 -188.526674)
		(width 0.1016)
		(layer "F.Cu")
		(net "I2C_PSU2_R_SCL")
	)
	(segment
		(start 84.82076 -185.605674)
		(end 84.28736 -186.139074)
		(width 0.1016)
		(layer "F.Cu")
		(net "I2C_PSU2_R_SCL")
	)
	(via
		(at 87.55634 -199.588628)
		(size 0.508)
		(drill 0.254)
		(layers "F.Cu" "B.Cu")
		(net "I2C_PSU2_R_SCL")
	)
	(segment
		(start 83.1596 -188.318394)
		(end 83.36788 -188.526674)
		(width 0.1016)
		(layer "F.Cu")
		(net "I2C_PSU2_R_SDA")
	)
	(segment
		(start 83.36788 -188.526674)
		(end 83.67776 -188.526674)
		(width 0.1016)
		(layer "F.Cu")
		(net "I2C_PSU2_R_SDA")
	)
	(segment
		(start 83.67776 -188.526674)
		(end 83.67776 -192.590166)
		(width 0.1016)
		(layer "F.Cu")
		(net "I2C_PSU2_R_SDA")
	)
	(segment
		(start 86.015068 -202.988164)
		(end 86.015068 -205.199488)
		(width 0.1016)
		(layer "F.Cu")
		(net "I2C_PSU2_R_SDA")
	)
	(segment
		(start 83.67776 -192.590166)
		(end 85.8012 -194.713606)
		(width 0.1016)
		(layer "F.Cu")
		(net "I2C_PSU2_R_SDA")
	)
	(segment
		(start 85.8012 -194.713606)
		(end 85.8012 -196.767958)
		(width 0.1016)
		(layer "F.Cu")
		(net "I2C_PSU2_R_SDA")
	)
	(segment
		(start 86.3346 -202.668632)
		(end 86.015068 -202.988164)
		(width 0.1016)
		(layer "F.Cu")
		(net "I2C_PSU2_R_SDA")
	)
	(segment
		(start 83.67776 -185.605674)
		(end 83.1596 -186.123834)
		(width 0.1016)
		(layer "F.Cu")
		(net "I2C_PSU2_R_SDA")
	)
	(segment
		(start 86.3346 -197.301358)
		(end 86.3346 -202.668632)
		(width 0.1016)
		(layer "F.Cu")
		(net "I2C_PSU2_R_SDA")
	)
	(segment
		(start 85.8012 -196.767958)
		(end 86.3346 -197.301358)
		(width 0.1016)
		(layer "F.Cu")
		(net "I2C_PSU2_R_SDA")
	)
	(segment
		(start 83.1596 -186.123834)
		(end 83.1596 -188.318394)
		(width 0.1016)
		(layer "F.Cu")
		(net "I2C_PSU2_R_SDA")
	)
	(via
		(at 85.8012 -196.767958)
		(size 0.508)
		(drill 0.254)
		(layers "F.Cu" "B.Cu")
		(net "I2C_PSU2_R_SDA")
	)
	(segment
		(start 123.93676 -185.605674)
		(end 124.30125 -185.970164)
		(width 0.1016)
		(layer "F.Cu")
		(net "T8_NODE1_EN_R")
	)
	(segment
		(start 125.45314 -186.78017)
		(end 125.45314 -188.272674)
		(width 0.1016)
		(layer "F.Cu")
		(net "T8_NODE1_EN_R")
	)
	(segment
		(start 125.94336 -195.834762)
		(end 125.75794 -196.020182)
		(width 0.1016)
		(layer "F.Cu")
		(net "T8_NODE1_EN_R")
	)
	(segment
		(start 125.94336 -188.526674)
		(end 125.94336 -195.834762)
		(width 0.1016)
		(layer "F.Cu")
		(net "T8_NODE1_EN_R")
	)
	(segment
		(start 124.30125 -185.970164)
		(end 124.643134 -185.970164)
		(width 0.1016)
		(layer "F.Cu")
		(net "T8_NODE1_EN_R")
	)
	(segment
		(start 125.684788 -196.093334)
		(end 125.684788 -199.027034)
		(width 0.1016)
		(layer "F.Cu")
		(net "T8_NODE1_EN_R")
	)
	(segment
		(start 125.015498 -199.696324)
		(end 125.015498 -205.199488)
		(width 0.1016)
		(layer "F.Cu")
		(net "T8_NODE1_EN_R")
	)
	(segment
		(start 125.684788 -199.027034)
		(end 125.015498 -199.696324)
		(width 0.1016)
		(layer "F.Cu")
		(net "T8_NODE1_EN_R")
	)
	(segment
		(start 124.643134 -185.970164)
		(end 125.45314 -186.78017)
		(width 0.1016)
		(layer "F.Cu")
		(net "T8_NODE1_EN_R")
	)
	(segment
		(start 125.70714 -188.526674)
		(end 125.94336 -188.526674)
		(width 0.1016)
		(layer "F.Cu")
		(net "T8_NODE1_EN_R")
	)
	(segment
		(start 125.75794 -196.020182)
		(end 125.684788 -196.093334)
		(width 0.1016)
		(layer "F.Cu")
		(net "T8_NODE1_EN_R")
	)
	(segment
		(start 125.45314 -188.272674)
		(end 125.70714 -188.526674)
		(width 0.1016)
		(layer "F.Cu")
		(net "T8_NODE1_EN_R")
	)
	(via
		(at 125.75794 -196.020182)
		(size 0.508)
		(drill 0.254)
		(layers "F.Cu" "B.Cu")
		(net "T8_NODE1_EN_R")
	)
	(segment
		(start 52.81676 -186.213242)
		(end 53.324252 -186.720734)
		(width 0.1016)
		(layer "F.Cu")
		(net "PSU1_AC_OK_R")
	)
	(segment
		(start 50.939446 -199.369426)
		(end 51.3207 -199.369426)
		(width 0.1016)
		(layer "F.Cu")
		(net "PSU1_AC_OK_R")
	)
	(segment
		(start 51.3207 -191.808862)
		(end 52.81676 -190.312802)
		(width 0.1016)
		(layer "F.Cu")
		(net "PSU1_AC_OK_R")
	)
	(segment
		(start 53.324252 -187.991242)
		(end 52.81676 -188.498734)
		(width 0.1016)
		(layer "F.Cu")
		(net "PSU1_AC_OK_R")
	)
	(segment
		(start 53.324252 -186.720734)
		(end 53.324252 -187.991242)
		(width 0.1016)
		(layer "F.Cu")
		(net "PSU1_AC_OK_R")
	)
	(segment
		(start 50.014886 -205.199488)
		(end 50.014886 -200.293986)
		(width 0.1016)
		(layer "F.Cu")
		(net "PSU1_AC_OK_R")
	)
	(segment
		(start 52.81676 -190.312802)
		(end 52.81676 -188.526674)
		(width 0.1016)
		(layer "F.Cu")
		(net "PSU1_AC_OK_R")
	)
	(segment
		(start 52.81676 -188.498734)
		(end 52.81676 -188.526674)
		(width 0.1016)
		(layer "F.Cu")
		(net "PSU1_AC_OK_R")
	)
	(segment
		(start 51.3207 -199.369426)
		(end 51.3207 -191.808862)
		(width 0.1016)
		(layer "F.Cu")
		(net "PSU1_AC_OK_R")
	)
	(segment
		(start 52.81676 -185.605674)
		(end 52.81676 -186.213242)
		(width 0.1016)
		(layer "F.Cu")
		(net "PSU1_AC_OK_R")
	)
	(segment
		(start 50.014886 -200.293986)
		(end 50.939446 -199.369426)
		(width 0.1016)
		(layer "F.Cu")
		(net "PSU1_AC_OK_R")
	)
	(via
		(at 51.3207 -199.369426)
		(size 0.508)
		(drill 0.254)
		(layers "F.Cu" "B.Cu")
		(net "PSU1_AC_OK_R")
	)
	(segment
		(start 154.015694 -200.163684)
		(end 154.774138 -199.40524)
		(width 0.1016)
		(layer "F.Cu")
		(net "T12_NODE2_EN_R")
	)
	(segment
		(start 153.90876 -189.16777)
		(end 153.90876 -188.526674)
		(width 0.1016)
		(layer "F.Cu")
		(net "T12_NODE2_EN_R")
	)
	(segment
		(start 153.400252 -188.018166)
		(end 153.90876 -188.526674)
		(width 0.1016)
		(layer "F.Cu")
		(net "T12_NODE2_EN_R")
	)
	(segment
		(start 154.015694 -205.199488)
		(end 154.015694 -200.163684)
		(width 0.1016)
		(layer "F.Cu")
		(net "T12_NODE2_EN_R")
	)
	(segment
		(start 153.400252 -186.594242)
		(end 153.400252 -188.018166)
		(width 0.1016)
		(layer "F.Cu")
		(net "T12_NODE2_EN_R")
	)
	(segment
		(start 154.774138 -197.770496)
		(end 154.774138 -190.033148)
		(width 0.1016)
		(layer "F.Cu")
		(net "T12_NODE2_EN_R")
	)
	(segment
		(start 154.774138 -199.40524)
		(end 154.774138 -197.770496)
		(width 0.1016)
		(layer "F.Cu")
		(net "T12_NODE2_EN_R")
	)
	(segment
		(start 154.774138 -190.033148)
		(end 153.90876 -189.16777)
		(width 0.1016)
		(layer "F.Cu")
		(net "T12_NODE2_EN_R")
	)
	(segment
		(start 153.90876 -186.085734)
		(end 153.400252 -186.594242)
		(width 0.1016)
		(layer "F.Cu")
		(net "T12_NODE2_EN_R")
	)
	(segment
		(start 153.90876 -185.605674)
		(end 153.90876 -186.085734)
		(width 0.1016)
		(layer "F.Cu")
		(net "T12_NODE2_EN_R")
	)
	(via
		(at 154.774138 -197.770496)
		(size 0.508)
		(drill 0.254)
		(layers "F.Cu" "B.Cu")
		(net "T12_NODE2_EN_R")
	)
	(segment
		(start 152.257252 -186.594242)
		(end 152.257252 -188.018166)
		(width 0.1016)
		(layer "F.Cu")
		(net "T12_NODE3_EN_R")
	)
	(segment
		(start 153.99258 -191.053974)
		(end 153.294334 -190.355728)
		(width 0.1016)
		(layer "F.Cu")
		(net "T12_NODE3_EN_R")
	)
	(segment
		(start 152.76576 -186.085734)
		(end 152.257252 -186.594242)
		(width 0.1016)
		(layer "F.Cu")
		(net "T12_NODE3_EN_R")
	)
	(segment
		(start 153.832052 -196.912738)
		(end 153.832052 -197.822058)
		(width 0.1016)
		(layer "F.Cu")
		(net "T12_NODE3_EN_R")
	)
	(segment
		(start 153.294334 -189.055248)
		(end 152.76576 -188.526674)
		(width 0.1016)
		(layer "F.Cu")
		(net "T12_NODE3_EN_R")
	)
	(segment
		(start 153.99258 -196.75221)
		(end 153.832052 -196.912738)
		(width 0.1016)
		(layer "F.Cu")
		(net "T12_NODE3_EN_R")
	)
	(segment
		(start 152.257252 -188.018166)
		(end 152.76576 -188.526674)
		(width 0.1016)
		(layer "F.Cu")
		(net "T12_NODE3_EN_R")
	)
	(segment
		(start 153.015696 -198.638414)
		(end 153.015696 -205.199488)
		(width 0.1016)
		(layer "F.Cu")
		(net "T12_NODE3_EN_R")
	)
	(segment
		(start 153.99258 -196.75221)
		(end 153.99258 -191.053974)
		(width 0.1016)
		(layer "F.Cu")
		(net "T12_NODE3_EN_R")
	)
	(segment
		(start 153.294334 -190.355728)
		(end 153.294334 -189.055248)
		(width 0.1016)
		(layer "F.Cu")
		(net "T12_NODE3_EN_R")
	)
	(segment
		(start 153.832052 -197.822058)
		(end 153.015696 -198.638414)
		(width 0.1016)
		(layer "F.Cu")
		(net "T12_NODE3_EN_R")
	)
	(segment
		(start 152.76576 -185.605674)
		(end 152.76576 -186.085734)
		(width 0.1016)
		(layer "F.Cu")
		(net "T12_NODE3_EN_R")
	)
	(via
		(at 153.99258 -196.75221)
		(size 0.508)
		(drill 0.254)
		(layers "F.Cu" "B.Cu")
		(net "T12_NODE3_EN_R")
	)
	(segment
		(start 124.126244 -186.405774)
		(end 123.357132 -186.405774)
		(width 0.1016)
		(layer "F.Cu")
		(net "T8_NODE2_EN_R")
	)
	(segment
		(start 124.49048 -188.526674)
		(end 124.39396 -188.430154)
		(width 0.1016)
		(layer "F.Cu")
		(net "T8_NODE2_EN_R")
	)
	(segment
		(start 124.39396 -188.430154)
		(end 124.39396 -186.67349)
		(width 0.1016)
		(layer "F.Cu")
		(net "T8_NODE2_EN_R")
	)
	(segment
		(start 125.07976 -188.755274)
		(end 124.85116 -188.526674)
		(width 0.1016)
		(layer "F.Cu")
		(net "T8_NODE2_EN_R")
	)
	(segment
		(start 123.357132 -186.405774)
		(end 122.79376 -185.842402)
		(width 0.1016)
		(layer "F.Cu")
		(net "T8_NODE2_EN_R")
	)
	(segment
		(start 122.79376 -185.842402)
		(end 122.79376 -185.605674)
		(width 0.1016)
		(layer "F.Cu")
		(net "T8_NODE2_EN_R")
	)
	(segment
		(start 124.89688 -188.938154)
		(end 125.07976 -188.755274)
		(width 0.1016)
		(layer "F.Cu")
		(net "T8_NODE2_EN_R")
	)
	(segment
		(start 124.0155 -198.166482)
		(end 124.0155 -205.199488)
		(width 0.1016)
		(layer "F.Cu")
		(net "T8_NODE2_EN_R")
	)
	(segment
		(start 124.89688 -197.285102)
		(end 124.0155 -198.166482)
		(width 0.1016)
		(layer "F.Cu")
		(net "T8_NODE2_EN_R")
	)
	(segment
		(start 124.85116 -188.526674)
		(end 124.49048 -188.526674)
		(width 0.1016)
		(layer "F.Cu")
		(net "T8_NODE2_EN_R")
	)
	(segment
		(start 124.89688 -197.285102)
		(end 124.89688 -188.938154)
		(width 0.1016)
		(layer "F.Cu")
		(net "T8_NODE2_EN_R")
	)
	(segment
		(start 124.39396 -186.67349)
		(end 124.126244 -186.405774)
		(width 0.1016)
		(layer "F.Cu")
		(net "T8_NODE2_EN_R")
	)
	(via
		(at 124.89688 -197.285102)
		(size 0.508)
		(drill 0.254)
		(layers "F.Cu" "B.Cu")
		(net "T8_NODE2_EN_R")
	)
	(segment
		(start 123.75896 -188.526674)
		(end 123.23572 -188.003434)
		(width 0.1016)
		(layer "F.Cu")
		(net "T8_NODE3_EN_R")
	)
	(segment
		(start 123.93676 -188.704474)
		(end 123.75896 -188.526674)
		(width 0.1016)
		(layer "F.Cu")
		(net "T8_NODE3_EN_R")
	)
	(segment
		(start 123.23572 -186.924442)
		(end 121.92127 -185.609992)
		(width 0.1016)
		(layer "F.Cu")
		(net "T8_NODE3_EN_R")
	)
	(segment
		(start 123.41098 -197.126098)
		(end 123.015502 -197.521576)
		(width 0.1016)
		(layer "F.Cu")
		(net "T8_NODE3_EN_R")
	)
	(segment
		(start 123.41098 -189.230254)
		(end 123.93676 -188.704474)
		(width 0.1016)
		(layer "F.Cu")
		(net "T8_NODE3_EN_R")
	)
	(segment
		(start 121.92127 -185.609992)
		(end 121.77522 -185.609992)
		(width 0.1016)
		(layer "F.Cu")
		(net "T8_NODE3_EN_R")
	)
	(segment
		(start 123.41098 -197.126098)
		(end 123.41098 -189.230254)
		(width 0.1016)
		(layer "F.Cu")
		(net "T8_NODE3_EN_R")
	)
	(segment
		(start 123.23572 -188.003434)
		(end 123.23572 -186.924442)
		(width 0.1016)
		(layer "F.Cu")
		(net "T8_NODE3_EN_R")
	)
	(segment
		(start 123.015502 -197.521576)
		(end 123.015502 -205.199488)
		(width 0.1016)
		(layer "F.Cu")
		(net "T8_NODE3_EN_R")
	)
	(via
		(at 123.41098 -197.126098)
		(size 0.508)
		(drill 0.254)
		(layers "F.Cu" "B.Cu")
		(net "T8_NODE3_EN_R")
	)
	(segment
		(start 122.14352 -188.003434)
		(end 122.66676 -188.526674)
		(width 0.1016)
		(layer "F.Cu")
		(net "T8_NODE4_EN_R")
	)
	(segment
		(start 122.79376 -194.150488)
		(end 122.79376 -188.653674)
		(width 0.1016)
		(layer "F.Cu")
		(net "T8_NODE4_EN_R")
	)
	(segment
		(start 122.79376 -188.653674)
		(end 122.66676 -188.526674)
		(width 0.1016)
		(layer "F.Cu")
		(net "T8_NODE4_EN_R")
	)
	(segment
		(start 122.14352 -187.341002)
		(end 122.14352 -188.003434)
		(width 0.1016)
		(layer "F.Cu")
		(net "T8_NODE4_EN_R")
	)
	(segment
		(start 122.015504 -202.150472)
		(end 122.015504 -205.199488)
		(width 0.1016)
		(layer "F.Cu")
		(net "T8_NODE4_EN_R")
	)
	(segment
		(start 121.64568 -186.46902)
		(end 121.64568 -186.843162)
		(width 0.1016)
		(layer "F.Cu")
		(net "T8_NODE4_EN_R")
	)
	(segment
		(start 122.447304 -197.975474)
		(end 122.447304 -201.718672)
		(width 0.1016)
		(layer "F.Cu")
		(net "T8_NODE4_EN_R")
	)
	(segment
		(start 122.11558 -194.828668)
		(end 122.79376 -194.150488)
		(width 0.1016)
		(layer "F.Cu")
		(net "T8_NODE4_EN_R")
	)
	(segment
		(start 121.64568 -186.843162)
		(end 122.14352 -187.341002)
		(width 0.1016)
		(layer "F.Cu")
		(net "T8_NODE4_EN_R")
	)
	(segment
		(start 120.63222 -185.609992)
		(end 120.786652 -185.609992)
		(width 0.1016)
		(layer "F.Cu")
		(net "T8_NODE4_EN_R")
	)
	(segment
		(start 120.786652 -185.609992)
		(end 121.64568 -186.46902)
		(width 0.1016)
		(layer "F.Cu")
		(net "T8_NODE4_EN_R")
	)
	(segment
		(start 122.447304 -201.718672)
		(end 122.015504 -202.150472)
		(width 0.1016)
		(layer "F.Cu")
		(net "T8_NODE4_EN_R")
	)
	(segment
		(start 122.11558 -197.64375)
		(end 122.447304 -197.975474)
		(width 0.1016)
		(layer "F.Cu")
		(net "T8_NODE4_EN_R")
	)
	(segment
		(start 122.11558 -197.64375)
		(end 122.11558 -194.828668)
		(width 0.1016)
		(layer "F.Cu")
		(net "T8_NODE4_EN_R")
	)
	(via
		(at 122.11558 -197.64375)
		(size 0.508)
		(drill 0.254)
		(layers "F.Cu" "B.Cu")
		(net "T8_NODE4_EN_R")
	)
	(segment
		(start 155.559252 -188.019182)
		(end 155.05176 -188.526674)
		(width 0.1016)
		(layer "F.Cu")
		(net "T12_NODE1_EN_R")
	)
	(segment
		(start 155.51404 -199.44334)
		(end 154.583892 -200.373488)
		(width 0.1016)
		(layer "F.Cu")
		(net "T12_NODE1_EN_R")
	)
	(segment
		(start 155.559252 -187.160408)
		(end 155.559252 -188.019182)
		(width 0.1016)
		(layer "F.Cu")
		(net "T12_NODE1_EN_R")
	)
	(segment
		(start 155.51404 -189.458092)
		(end 155.51404 -198.908924)
		(width 0.1016)
		(layer "F.Cu")
		(net "T12_NODE1_EN_R")
	)
	(segment
		(start 155.05176 -186.652916)
		(end 155.559252 -187.160408)
		(width 0.1016)
		(layer "F.Cu")
		(net "T12_NODE1_EN_R")
	)
	(segment
		(start 154.583892 -200.373488)
		(end 154.583892 -201.868786)
		(width 0.1016)
		(layer "F.Cu")
		(net "T12_NODE1_EN_R")
	)
	(segment
		(start 155.05176 -188.526674)
		(end 155.05176 -188.995812)
		(width 0.1016)
		(layer "F.Cu")
		(net "T12_NODE1_EN_R")
	)
	(segment
		(start 155.05176 -185.605674)
		(end 155.05176 -186.652916)
		(width 0.1016)
		(layer "F.Cu")
		(net "T12_NODE1_EN_R")
	)
	(segment
		(start 155.015692 -202.300586)
		(end 155.015692 -204.699616)
		(width 0.1016)
		(layer "F.Cu")
		(net "T12_NODE1_EN_R")
	)
	(segment
		(start 155.51404 -198.908924)
		(end 155.51404 -199.44334)
		(width 0.1016)
		(layer "F.Cu")
		(net "T12_NODE1_EN_R")
	)
	(segment
		(start 155.05176 -188.995812)
		(end 155.51404 -189.458092)
		(width 0.1016)
		(layer "F.Cu")
		(net "T12_NODE1_EN_R")
	)
	(segment
		(start 154.583892 -201.868786)
		(end 155.015692 -202.300586)
		(width 0.1016)
		(layer "F.Cu")
		(net "T12_NODE1_EN_R")
	)
	(via
		(at 155.51404 -198.908924)
		(size 0.508)
		(drill 0.254)
		(layers "F.Cu" "B.Cu")
		(net "T12_NODE1_EN_R")
	)
	(via
		(at 146.89582 -199.393556)
		(size 0.6604)
		(drill 0.3302)
		(layers "F.Cu" "B.Cu")
		(net "UART_T11_NODE1_RXD_R")
	)
	(segment
		(start 146.44878 -199.840596)
		(end 146.89582 -199.393556)
		(width 0.1016)
		(layer "B.Cu")
		(net "UART_T11_NODE1_RXD_R")
	)
	(segment
		(start 146.01698 -201.64425)
		(end 146.44878 -201.21245)
		(width 0.1016)
		(layer "B.Cu")
		(net "UART_T11_NODE1_RXD_R")
	)
	(segment
		(start 150.47976 -192.950084)
		(end 147.78736 -195.642484)
		(width 0.1016)
		(layer "B.Cu")
		(net "UART_T11_NODE1_RXD_R")
	)
	(segment
		(start 147.78736 -197.4215)
		(end 146.89582 -198.31304)
		(width 0.1016)
		(layer "B.Cu")
		(net "UART_T11_NODE1_RXD_R")
	)
	(segment
		(start 146.89582 -198.31304)
		(end 146.89582 -199.393556)
		(width 0.1016)
		(layer "B.Cu")
		(net "UART_T11_NODE1_RXD_R")
	)
	(segment
		(start 146.015456 -201.64425)
		(end 146.01698 -201.64425)
		(width 0.1016)
		(layer "B.Cu")
		(net "UART_T11_NODE1_RXD_R")
	)
	(segment
		(start 150.47976 -188.272674)
		(end 150.47976 -192.950084)
		(width 0.1016)
		(layer "B.Cu")
		(net "UART_T11_NODE1_RXD_R")
	)
	(segment
		(start 147.78736 -195.642484)
		(end 147.78736 -197.4215)
		(width 0.1016)
		(layer "B.Cu")
		(net "UART_T11_NODE1_RXD_R")
	)
	(segment
		(start 146.44878 -201.21245)
		(end 146.44878 -199.840596)
		(width 0.1016)
		(layer "B.Cu")
		(net "UART_T11_NODE1_RXD_R")
	)
	(segment
		(start 146.015456 -205.199488)
		(end 146.015456 -201.64425)
		(width 0.1016)
		(layer "B.Cu")
		(net "UART_T11_NODE1_RXD_R")
	)
	(via
		(at 131.96824 -198.041006)
		(size 0.6604)
		(drill 0.3302)
		(layers "F.Cu" "B.Cu")
		(net "UART_T9_NODE1_RXD_R")
	)
	(segment
		(start 132.352542 -196.855334)
		(end 134.63524 -194.572636)
		(width 0.1016)
		(layer "B.Cu")
		(net "UART_T9_NODE1_RXD_R")
	)
	(segment
		(start 131.015486 -201.983848)
		(end 131.015486 -205.199488)
		(width 0.1016)
		(layer "B.Cu")
		(net "UART_T9_NODE1_RXD_R")
	)
	(segment
		(start 131.45516 -198.554086)
		(end 131.45516 -201.544174)
		(width 0.1016)
		(layer "B.Cu")
		(net "UART_T9_NODE1_RXD_R")
	)
	(segment
		(start 131.96824 -198.041006)
		(end 131.45516 -198.554086)
		(width 0.1016)
		(layer "B.Cu")
		(net "UART_T9_NODE1_RXD_R")
	)
	(segment
		(start 132.352542 -197.656704)
		(end 132.352542 -196.855334)
		(width 0.1016)
		(layer "B.Cu")
		(net "UART_T9_NODE1_RXD_R")
	)
	(segment
		(start 135.36676 -190.811658)
		(end 135.36676 -188.272674)
		(width 0.1016)
		(layer "B.Cu")
		(net "UART_T9_NODE1_RXD_R")
	)
	(segment
		(start 131.96824 -198.041006)
		(end 132.352542 -197.656704)
		(width 0.1016)
		(layer "B.Cu")
		(net "UART_T9_NODE1_RXD_R")
	)
	(segment
		(start 134.63524 -191.543178)
		(end 135.36676 -190.811658)
		(width 0.1016)
		(layer "B.Cu")
		(net "UART_T9_NODE1_RXD_R")
	)
	(segment
		(start 131.45516 -201.544174)
		(end 131.015486 -201.983848)
		(width 0.1016)
		(layer "B.Cu")
		(net "UART_T9_NODE1_RXD_R")
	)
	(segment
		(start 134.63524 -194.572636)
		(end 134.63524 -191.543178)
		(width 0.1016)
		(layer "B.Cu")
		(net "UART_T9_NODE1_RXD_R")
	)
	(via
		(at 151.53386 -199.695816)
		(size 0.6604)
		(drill 0.3302)
		(layers "F.Cu" "B.Cu")
		(net "T11_NODE1_EN_R")
	)
	(segment
		(start 155.559252 -187.765182)
		(end 155.05176 -188.272674)
		(width 0.1016)
		(layer "B.Cu")
		(net "T11_NODE1_EN_R")
	)
	(segment
		(start 152.4254 -198.804276)
		(end 151.53386 -199.695816)
		(width 0.1016)
		(layer "B.Cu")
		(net "T11_NODE1_EN_R")
	)
	(segment
		(start 155.05176 -185.351674)
		(end 155.05176 -186.657742)
		(width 0.1016)
		(layer "B.Cu")
		(net "T11_NODE1_EN_R")
	)
	(segment
		(start 155.05176 -186.657742)
		(end 155.559252 -187.165234)
		(width 0.1016)
		(layer "B.Cu")
		(net "T11_NODE1_EN_R")
	)
	(segment
		(start 152.4254 -196.798184)
		(end 152.4254 -198.804276)
		(width 0.1016)
		(layer "B.Cu")
		(net "T11_NODE1_EN_R")
	)
	(segment
		(start 151.0157 -202.07732)
		(end 151.0157 -205.199488)
		(width 0.1016)
		(layer "B.Cu")
		(net "T11_NODE1_EN_R")
	)
	(segment
		(start 155.05176 -194.171824)
		(end 152.4254 -196.798184)
		(width 0.1016)
		(layer "B.Cu")
		(net "T11_NODE1_EN_R")
	)
	(segment
		(start 151.53386 -201.55916)
		(end 151.0157 -202.07732)
		(width 0.1016)
		(layer "B.Cu")
		(net "T11_NODE1_EN_R")
	)
	(segment
		(start 151.53386 -199.695816)
		(end 151.53386 -201.55916)
		(width 0.1016)
		(layer "B.Cu")
		(net "T11_NODE1_EN_R")
	)
	(segment
		(start 155.559252 -187.165234)
		(end 155.559252 -187.765182)
		(width 0.1016)
		(layer "B.Cu")
		(net "T11_NODE1_EN_R")
	)
	(segment
		(start 155.05176 -188.272674)
		(end 155.05176 -194.171824)
		(width 0.1016)
		(layer "B.Cu")
		(net "T11_NODE1_EN_R")
	)
	(segment
		(start 144.69872 -195.860924)
		(end 144.01546 -196.544184)
		(width 0.1016)
		(layer "F.Cu")
		(net "UART_T12_NODE3_TXD_R")
	)
	(segment
		(start 144.01546 -196.544184)
		(end 144.01546 -205.199488)
		(width 0.1016)
		(layer "F.Cu")
		(net "UART_T12_NODE3_TXD_R")
	)
	(segment
		(start 144.51076 -193.902584)
		(end 144.51076 -188.526674)
		(width 0.1016)
		(layer "F.Cu")
		(net "UART_T12_NODE3_TXD_R")
	)
	(segment
		(start 144.51076 -185.605674)
		(end 144.51076 -186.13247)
		(width 0.1016)
		(layer "F.Cu")
		(net "UART_T12_NODE3_TXD_R")
	)
	(segment
		(start 145.091912 -187.945522)
		(end 144.51076 -188.526674)
		(width 0.1016)
		(layer "F.Cu")
		(net "UART_T12_NODE3_TXD_R")
	)
	(segment
		(start 145.091912 -186.713622)
		(end 145.091912 -187.945522)
		(width 0.1016)
		(layer "F.Cu")
		(net "UART_T12_NODE3_TXD_R")
	)
	(segment
		(start 144.51076 -186.13247)
		(end 145.091912 -186.713622)
		(width 0.1016)
		(layer "F.Cu")
		(net "UART_T12_NODE3_TXD_R")
	)
	(segment
		(start 144.69872 -194.090544)
		(end 144.51076 -193.902584)
		(width 0.1016)
		(layer "F.Cu")
		(net "UART_T12_NODE3_TXD_R")
	)
	(segment
		(start 144.69872 -195.860924)
		(end 144.69872 -194.090544)
		(width 0.1016)
		(layer "F.Cu")
		(net "UART_T12_NODE3_TXD_R")
	)
	(via
		(at 144.69872 -195.860924)
		(size 0.508)
		(drill 0.254)
		(layers "F.Cu" "B.Cu")
		(net "UART_T12_NODE3_TXD_R")
	)
	(via
		(at 154.015694 -199.48906)
		(size 0.6604)
		(drill 0.3302)
		(layers "F.Cu" "B.Cu")
		(net "I2C_PSU3_R_SCL")
	)
	(segment
		(start 157.33776 -188.272674)
		(end 156.972 -188.638434)
		(width 0.1016)
		(layer "B.Cu")
		(net "I2C_PSU3_R_SCL")
	)
	(segment
		(start 157.88386 -187.810394)
		(end 157.53588 -188.158374)
		(width 0.1016)
		(layer "B.Cu")
		(net "I2C_PSU3_R_SCL")
	)
	(segment
		(start 154.015694 -197.669658)
		(end 154.015694 -199.48906)
		(width 0.1016)
		(layer "B.Cu")
		(net "I2C_PSU3_R_SCL")
	)
	(segment
		(start 156.972 -188.638434)
		(end 156.972 -194.713352)
		(width 0.1016)
		(layer "B.Cu")
		(net "I2C_PSU3_R_SCL")
	)
	(segment
		(start 154.015694 -199.48906)
		(end 154.015694 -205.199488)
		(width 0.1016)
		(layer "B.Cu")
		(net "I2C_PSU3_R_SCL")
	)
	(segment
		(start 157.33776 -185.351674)
		(end 157.33776 -185.6232)
		(width 0.1016)
		(layer "B.Cu")
		(net "I2C_PSU3_R_SCL")
	)
	(segment
		(start 157.33776 -185.6232)
		(end 157.88386 -186.1693)
		(width 0.1016)
		(layer "B.Cu")
		(net "I2C_PSU3_R_SCL")
	)
	(segment
		(start 157.45206 -188.158374)
		(end 157.33776 -188.272674)
		(width 0.1016)
		(layer "B.Cu")
		(net "I2C_PSU3_R_SCL")
	)
	(segment
		(start 157.53588 -188.158374)
		(end 157.45206 -188.158374)
		(width 0.1016)
		(layer "B.Cu")
		(net "I2C_PSU3_R_SCL")
	)
	(segment
		(start 157.88386 -186.1693)
		(end 157.88386 -187.810394)
		(width 0.1016)
		(layer "B.Cu")
		(net "I2C_PSU3_R_SCL")
	)
	(segment
		(start 156.972 -194.713352)
		(end 154.015694 -197.669658)
		(width 0.1016)
		(layer "B.Cu")
		(net "I2C_PSU3_R_SCL")
	)
	(segment
		(start 142.9258 -196.187314)
		(end 143.36776 -195.745354)
		(width 0.1016)
		(layer "F.Cu")
		(net "UART_T12_NODE4_RXD_R")
	)
	(segment
		(start 143.015462 -205.199488)
		(end 143.015462 -196.276976)
		(width 0.1016)
		(layer "F.Cu")
		(net "UART_T12_NODE4_RXD_R")
	)
	(segment
		(start 143.36776 -195.745354)
		(end 143.36776 -188.526674)
		(width 0.1016)
		(layer "F.Cu")
		(net "UART_T12_NODE4_RXD_R")
	)
	(segment
		(start 143.015462 -196.276976)
		(end 142.9258 -196.187314)
		(width 0.1016)
		(layer "F.Cu")
		(net "UART_T12_NODE4_RXD_R")
	)
	(via
		(at 142.9258 -196.187314)
		(size 0.508)
		(drill 0.254)
		(layers "F.Cu" "B.Cu")
		(net "UART_T12_NODE4_RXD_R")
	)
	(via
		(at 148.30552 -197.929754)
		(size 0.6604)
		(drill 0.3302)
		(layers "F.Cu" "B.Cu")
		(net "T11_NODE4_EN_R")
	)
	(segment
		(start 151.62276 -185.351674)
		(end 151.62276 -186.24804)
		(width 0.1016)
		(layer "B.Cu")
		(net "T11_NODE4_EN_R")
	)
	(segment
		(start 148.30298 -196.086476)
		(end 148.30298 -197.927468)
		(width 0.1016)
		(layer "B.Cu")
		(net "T11_NODE4_EN_R")
	)
	(segment
		(start 151.151844 -187.801758)
		(end 151.62276 -188.272674)
		(width 0.1016)
		(layer "B.Cu")
		(net "T11_NODE4_EN_R")
	)
	(segment
		(start 148.30298 -197.927468)
		(end 148.305266 -197.929754)
		(width 0.1016)
		(layer "B.Cu")
		(net "T11_NODE4_EN_R")
	)
	(segment
		(start 151.62276 -186.24804)
		(end 151.151844 -186.718956)
		(width 0.1016)
		(layer "B.Cu")
		(net "T11_NODE4_EN_R")
	)
	(segment
		(start 151.62276 -192.766696)
		(end 148.30298 -196.086476)
		(width 0.1016)
		(layer "B.Cu")
		(net "T11_NODE4_EN_R")
	)
	(segment
		(start 151.62276 -188.272674)
		(end 151.62276 -192.766696)
		(width 0.1016)
		(layer "B.Cu")
		(net "T11_NODE4_EN_R")
	)
	(segment
		(start 148.015706 -198.219314)
		(end 148.015706 -205.199488)
		(width 0.1016)
		(layer "B.Cu")
		(net "T11_NODE4_EN_R")
	)
	(segment
		(start 148.305266 -197.929754)
		(end 148.015706 -198.219314)
		(width 0.1016)
		(layer "B.Cu")
		(net "T11_NODE4_EN_R")
	)
	(segment
		(start 148.30552 -197.929754)
		(end 148.305266 -197.929754)
		(width 0.1016)
		(layer "B.Cu")
		(net "T11_NODE4_EN_R")
	)
	(segment
		(start 151.151844 -186.718956)
		(end 151.151844 -187.801758)
		(width 0.1016)
		(layer "B.Cu")
		(net "T11_NODE4_EN_R")
	)
	(via
		(at 145.09242 -199.423274)
		(size 0.6604)
		(drill 0.3302)
		(layers "F.Cu" "B.Cu")
		(net "UART_T11_NODE1_TXD_R")
	)
	(segment
		(start 149.33676 -188.272674)
		(end 149.33676 -192.679066)
		(width 0.1016)
		(layer "B.Cu")
		(net "UART_T11_NODE1_TXD_R")
	)
	(segment
		(start 148.701252 -187.637166)
		(end 149.33676 -188.272674)
		(width 0.1016)
		(layer "B.Cu")
		(net "UART_T11_NODE1_TXD_R")
	)
	(segment
		(start 149.33676 -186.085734)
		(end 148.701252 -186.721242)
		(width 0.1016)
		(layer "B.Cu")
		(net "UART_T11_NODE1_TXD_R")
	)
	(segment
		(start 145.015712 -205.199488)
		(end 145.015712 -199.499982)
		(width 0.1016)
		(layer "B.Cu")
		(net "UART_T11_NODE1_TXD_R")
	)
	(segment
		(start 146.3548 -195.661026)
		(end 146.3548 -198.160894)
		(width 0.1016)
		(layer "B.Cu")
		(net "UART_T11_NODE1_TXD_R")
	)
	(segment
		(start 146.3548 -198.160894)
		(end 145.09242 -199.423274)
		(width 0.1016)
		(layer "B.Cu")
		(net "UART_T11_NODE1_TXD_R")
	)
	(segment
		(start 149.33676 -185.351674)
		(end 149.33676 -186.085734)
		(width 0.1016)
		(layer "B.Cu")
		(net "UART_T11_NODE1_TXD_R")
	)
	(segment
		(start 148.701252 -186.721242)
		(end 148.701252 -187.637166)
		(width 0.1016)
		(layer "B.Cu")
		(net "UART_T11_NODE1_TXD_R")
	)
	(segment
		(start 145.015712 -199.499982)
		(end 145.09242 -199.423274)
		(width 0.1016)
		(layer "B.Cu")
		(net "UART_T11_NODE1_TXD_R")
	)
	(segment
		(start 149.33676 -192.679066)
		(end 146.3548 -195.661026)
		(width 0.1016)
		(layer "B.Cu")
		(net "UART_T11_NODE1_TXD_R")
	)
	(via
		(at 150.23084 -198.144384)
		(size 0.6604)
		(drill 0.3302)
		(layers "F.Cu" "B.Cu")
		(net "T11_NODE2_EN_R")
	)
	(segment
		(start 153.90876 -188.274198)
		(end 153.90876 -188.272674)
		(width 0.1016)
		(layer "B.Cu")
		(net "T11_NODE2_EN_R")
	)
	(segment
		(start 153.90876 -185.351674)
		(end 153.90876 -186.085734)
		(width 0.1016)
		(layer "B.Cu")
		(net "T11_NODE2_EN_R")
	)
	(segment
		(start 153.400252 -187.764166)
		(end 153.90876 -188.272674)
		(width 0.1016)
		(layer "B.Cu")
		(net "T11_NODE2_EN_R")
	)
	(segment
		(start 150.015702 -205.199488)
		(end 150.015702 -198.359522)
		(width 0.1016)
		(layer "B.Cu")
		(net "T11_NODE2_EN_R")
	)
	(segment
		(start 153.400252 -186.594242)
		(end 153.400252 -187.764166)
		(width 0.1016)
		(layer "B.Cu")
		(net "T11_NODE2_EN_R")
	)
	(segment
		(start 154.069796 -194.104514)
		(end 154.069796 -188.435234)
		(width 0.1016)
		(layer "B.Cu")
		(net "T11_NODE2_EN_R")
	)
	(segment
		(start 150.23084 -197.94347)
		(end 154.069796 -194.104514)
		(width 0.1016)
		(layer "B.Cu")
		(net "T11_NODE2_EN_R")
	)
	(segment
		(start 150.23084 -198.144384)
		(end 150.23084 -197.94347)
		(width 0.1016)
		(layer "B.Cu")
		(net "T11_NODE2_EN_R")
	)
	(segment
		(start 154.069796 -188.435234)
		(end 153.90876 -188.274198)
		(width 0.1016)
		(layer "B.Cu")
		(net "T11_NODE2_EN_R")
	)
	(segment
		(start 153.90876 -186.085734)
		(end 153.400252 -186.594242)
		(width 0.1016)
		(layer "B.Cu")
		(net "T11_NODE2_EN_R")
	)
	(segment
		(start 150.015702 -198.359522)
		(end 150.23084 -198.144384)
		(width 0.1016)
		(layer "B.Cu")
		(net "T11_NODE2_EN_R")
	)
	(via
		(at 149.015704 -199.648064)
		(size 0.6604)
		(drill 0.3302)
		(layers "F.Cu" "B.Cu")
		(net "T11_NODE3_EN_R")
	)
	(segment
		(start 149.015704 -198.380858)
		(end 152.76576 -194.630802)
		(width 0.1016)
		(layer "B.Cu")
		(net "T11_NODE3_EN_R")
	)
	(segment
		(start 152.257252 -186.594242)
		(end 152.257252 -187.764166)
		(width 0.1016)
		(layer "B.Cu")
		(net "T11_NODE3_EN_R")
	)
	(segment
		(start 152.76576 -194.630802)
		(end 152.76576 -188.272674)
		(width 0.1016)
		(layer "B.Cu")
		(net "T11_NODE3_EN_R")
	)
	(segment
		(start 152.257252 -187.764166)
		(end 152.76576 -188.272674)
		(width 0.1016)
		(layer "B.Cu")
		(net "T11_NODE3_EN_R")
	)
	(segment
		(start 152.76576 -185.351674)
		(end 152.76576 -186.085734)
		(width 0.1016)
		(layer "B.Cu")
		(net "T11_NODE3_EN_R")
	)
	(segment
		(start 152.76576 -186.085734)
		(end 152.257252 -186.594242)
		(width 0.1016)
		(layer "B.Cu")
		(net "T11_NODE3_EN_R")
	)
	(segment
		(start 149.015704 -199.648064)
		(end 149.015704 -198.380858)
		(width 0.1016)
		(layer "B.Cu")
		(net "T11_NODE3_EN_R")
	)
	(segment
		(start 149.015704 -205.199488)
		(end 149.015704 -199.648064)
		(width 0.1016)
		(layer "B.Cu")
		(net "T11_NODE3_EN_R")
	)
	(via
		(at 136.47928 -199.719692)
		(size 0.6604)
		(drill 0.3302)
		(layers "F.Cu" "B.Cu")
		(net "T9_NODE1_EN_R")
	)
	(segment
		(start 139.48156 -186.54395)
		(end 139.93876 -186.08675)
		(width 0.1016)
		(layer "B.Cu")
		(net "T9_NODE1_EN_R")
	)
	(segment
		(start 136.47928 -201.889614)
		(end 136.017 -202.351894)
		(width 0.1016)
		(layer "B.Cu")
		(net "T9_NODE1_EN_R")
	)
	(segment
		(start 136.017 -202.351894)
		(end 136.015476 -202.351894)
		(width 0.1016)
		(layer "B.Cu")
		(net "T9_NODE1_EN_R")
	)
	(segment
		(start 137.5156 -193.65087)
		(end 139.93876 -191.22771)
		(width 0.1016)
		(layer "B.Cu")
		(net "T9_NODE1_EN_R")
	)
	(segment
		(start 139.93876 -186.08675)
		(end 139.93876 -185.351674)
		(width 0.1016)
		(layer "B.Cu")
		(net "T9_NODE1_EN_R")
	)
	(segment
		(start 136.47928 -199.719692)
		(end 136.47928 -201.889614)
		(width 0.1016)
		(layer "B.Cu")
		(net "T9_NODE1_EN_R")
	)
	(segment
		(start 139.48156 -187.815474)
		(end 139.48156 -186.54395)
		(width 0.1016)
		(layer "B.Cu")
		(net "T9_NODE1_EN_R")
	)
	(segment
		(start 136.47928 -197.421246)
		(end 137.5156 -196.384926)
		(width 0.1016)
		(layer "B.Cu")
		(net "T9_NODE1_EN_R")
	)
	(segment
		(start 136.47928 -199.719692)
		(end 136.47928 -197.421246)
		(width 0.1016)
		(layer "B.Cu")
		(net "T9_NODE1_EN_R")
	)
	(segment
		(start 139.93876 -188.272674)
		(end 139.48156 -187.815474)
		(width 0.1016)
		(layer "B.Cu")
		(net "T9_NODE1_EN_R")
	)
	(segment
		(start 139.93876 -191.22771)
		(end 139.93876 -188.272674)
		(width 0.1016)
		(layer "B.Cu")
		(net "T9_NODE1_EN_R")
	)
	(segment
		(start 137.5156 -196.384926)
		(end 137.5156 -193.65087)
		(width 0.1016)
		(layer "B.Cu")
		(net "T9_NODE1_EN_R")
	)
	(segment
		(start 136.015476 -202.351894)
		(end 136.015476 -205.199488)
		(width 0.1016)
		(layer "B.Cu")
		(net "T9_NODE1_EN_R")
	)
	(segment
		(start 71.61022 -196.39026)
		(end 71.10476 -195.8848)
		(width 0.1016)
		(layer "F.Cu")
		(net "UART_T4_NODE4_RXD_R")
	)
	(segment
		(start 71.49338 -201.430636)
		(end 71.49338 -196.5071)
		(width 0.1016)
		(layer "F.Cu")
		(net "UART_T4_NODE4_RXD_R")
	)
	(segment
		(start 71.10476 -195.8848)
		(end 71.10476 -188.526674)
		(width 0.1016)
		(layer "F.Cu")
		(net "UART_T4_NODE4_RXD_R")
	)
	(segment
		(start 71.015098 -201.908918)
		(end 71.49338 -201.430636)
		(width 0.1016)
		(layer "F.Cu")
		(net "UART_T4_NODE4_RXD_R")
	)
	(segment
		(start 71.015098 -205.199488)
		(end 71.015098 -201.908918)
		(width 0.1016)
		(layer "F.Cu")
		(net "UART_T4_NODE4_RXD_R")
	)
	(segment
		(start 71.49338 -196.5071)
		(end 71.61022 -196.39026)
		(width 0.1016)
		(layer "F.Cu")
		(net "UART_T4_NODE4_RXD_R")
	)
	(via
		(at 71.61022 -196.39026)
		(size 0.508)
		(drill 0.254)
		(layers "F.Cu" "B.Cu")
		(net "UART_T4_NODE4_RXD_R")
	)
	(via
		(at 153.015696 -197.730872)
		(size 0.6604)
		(drill 0.3302)
		(layers "F.Cu" "B.Cu")
		(net "I2C_PSU3_R_SDA")
	)
	(segment
		(start 156.19476 -193.771012)
		(end 153.015696 -196.950076)
		(width 0.1016)
		(layer "B.Cu")
		(net "I2C_PSU3_R_SDA")
	)
	(segment
		(start 156.19476 -188.272674)
		(end 156.19476 -193.771012)
		(width 0.1016)
		(layer "B.Cu")
		(net "I2C_PSU3_R_SDA")
	)
	(segment
		(start 156.75356 -187.713874)
		(end 156.19476 -188.272674)
		(width 0.1016)
		(layer "B.Cu")
		(net "I2C_PSU3_R_SDA")
	)
	(segment
		(start 153.015696 -196.950076)
		(end 153.015696 -197.730872)
		(width 0.1016)
		(layer "B.Cu")
		(net "I2C_PSU3_R_SDA")
	)
	(segment
		(start 153.015696 -205.199488)
		(end 153.015696 -197.730872)
		(width 0.1016)
		(layer "B.Cu")
		(net "I2C_PSU3_R_SDA")
	)
	(segment
		(start 156.19476 -186.017662)
		(end 156.75356 -186.576462)
		(width 0.1016)
		(layer "B.Cu")
		(net "I2C_PSU3_R_SDA")
	)
	(segment
		(start 156.75356 -186.576462)
		(end 156.75356 -187.713874)
		(width 0.1016)
		(layer "B.Cu")
		(net "I2C_PSU3_R_SDA")
	)
	(segment
		(start 156.19476 -185.351674)
		(end 156.19476 -186.017662)
		(width 0.1016)
		(layer "B.Cu")
		(net "I2C_PSU3_R_SDA")
	)
	(via
		(at 44.97578 -199.576944)
		(size 0.6604)
		(drill 0.3302)
		(layers "F.Cu" "B.Cu")
		(net "PSU6_DC_OK_R")
	)
	(segment
		(start 46.466252 -186.594242)
		(end 46.466252 -188.088016)
		(width 0.1016)
		(layer "B.Cu")
		(net "PSU6_DC_OK_R")
	)
	(segment
		(start 47.10176 -185.958734)
		(end 46.466252 -186.594242)
		(width 0.1016)
		(layer "B.Cu")
		(net "PSU6_DC_OK_R")
	)
	(segment
		(start 46.90491 -188.526674)
		(end 47.10176 -188.526674)
		(width 0.1016)
		(layer "B.Cu")
		(net "PSU6_DC_OK_R")
	)
	(segment
		(start 45.014896 -199.61606)
		(end 44.97578 -199.576944)
		(width 0.1016)
		(layer "B.Cu")
		(net "PSU6_DC_OK_R")
	)
	(segment
		(start 45.014896 -205.199488)
		(end 45.014896 -199.61606)
		(width 0.1016)
		(layer "B.Cu")
		(net "PSU6_DC_OK_R")
	)
	(segment
		(start 45.93082 -192.084706)
		(end 45.93082 -197.480428)
		(width 0.1016)
		(layer "B.Cu")
		(net "PSU6_DC_OK_R")
	)
	(segment
		(start 46.466252 -188.088016)
		(end 46.90491 -188.526674)
		(width 0.1016)
		(layer "B.Cu")
		(net "PSU6_DC_OK_R")
	)
	(segment
		(start 47.10176 -185.605674)
		(end 47.10176 -185.958734)
		(width 0.1016)
		(layer "B.Cu")
		(net "PSU6_DC_OK_R")
	)
	(segment
		(start 45.93082 -197.480428)
		(end 44.97578 -198.435468)
		(width 0.1016)
		(layer "B.Cu")
		(net "PSU6_DC_OK_R")
	)
	(segment
		(start 47.10176 -190.913766)
		(end 45.93082 -192.084706)
		(width 0.1016)
		(layer "B.Cu")
		(net "PSU6_DC_OK_R")
	)
	(segment
		(start 47.10176 -188.526674)
		(end 47.10176 -190.913766)
		(width 0.1016)
		(layer "B.Cu")
		(net "PSU6_DC_OK_R")
	)
	(segment
		(start 44.97578 -198.435468)
		(end 44.97578 -199.576944)
		(width 0.1016)
		(layer "B.Cu")
		(net "PSU6_DC_OK_R")
	)
	(segment
		(start 142.8877 -187.863734)
		(end 142.22476 -188.526674)
		(width 0.1016)
		(layer "F.Cu")
		(net "UART_T12_NODE4_TXD_R")
	)
	(segment
		(start 142.478252 -201.766932)
		(end 142.015464 -202.22972)
		(width 0.1016)
		(layer "F.Cu")
		(net "UART_T12_NODE4_TXD_R")
	)
	(segment
		(start 141.97838 -198.162418)
		(end 142.2781 -198.462138)
		(width 0.1016)
		(layer "F.Cu")
		(net "UART_T12_NODE4_TXD_R")
	)
	(segment
		(start 141.97838 -191.13754)
		(end 141.97838 -198.162418)
		(width 0.1016)
		(layer "F.Cu")
		(net "UART_T12_NODE4_TXD_R")
	)
	(segment
		(start 142.015464 -202.22972)
		(end 142.015464 -205.199488)
		(width 0.1016)
		(layer "F.Cu")
		(net "UART_T12_NODE4_TXD_R")
	)
	(segment
		(start 142.2781 -198.462138)
		(end 142.478252 -198.66229)
		(width 0.1016)
		(layer "F.Cu")
		(net "UART_T12_NODE4_TXD_R")
	)
	(segment
		(start 142.478252 -198.66229)
		(end 142.478252 -201.766932)
		(width 0.1016)
		(layer "F.Cu")
		(net "UART_T12_NODE4_TXD_R")
	)
	(segment
		(start 142.22476 -190.89116)
		(end 141.97838 -191.13754)
		(width 0.1016)
		(layer "F.Cu")
		(net "UART_T12_NODE4_TXD_R")
	)
	(segment
		(start 142.8877 -186.59729)
		(end 142.8877 -187.863734)
		(width 0.1016)
		(layer "F.Cu")
		(net "UART_T12_NODE4_TXD_R")
	)
	(segment
		(start 142.22476 -188.526674)
		(end 142.22476 -190.89116)
		(width 0.1016)
		(layer "F.Cu")
		(net "UART_T12_NODE4_TXD_R")
	)
	(segment
		(start 142.22476 -185.93435)
		(end 142.8877 -186.59729)
		(width 0.1016)
		(layer "F.Cu")
		(net "UART_T12_NODE4_TXD_R")
	)
	(segment
		(start 142.22476 -185.605674)
		(end 142.22476 -185.93435)
		(width 0.1016)
		(layer "F.Cu")
		(net "UART_T12_NODE4_TXD_R")
	)
	(via
		(at 142.2781 -198.462138)
		(size 0.508)
		(drill 0.254)
		(layers "F.Cu" "B.Cu")
		(net "UART_T12_NODE4_TXD_R")
	)
	(via
		(at 127.62992 -198.725028)
		(size 0.6604)
		(drill 0.3302)
		(layers "F.Cu" "B.Cu")
		(net "UART_T9_NODE2_TXD_R")
	)
	(segment
		(start 131.93776 -185.351674)
		(end 131.93776 -186.170062)
		(width 0.1016)
		(layer "B.Cu")
		(net "UART_T9_NODE2_TXD_R")
	)
	(segment
		(start 127.779272 -198.87438)
		(end 127.62992 -198.725028)
		(width 0.1016)
		(layer "B.Cu")
		(net "UART_T9_NODE2_TXD_R")
	)
	(segment
		(start 132.58038 -186.812682)
		(end 132.58038 -187.630054)
		(width 0.1016)
		(layer "B.Cu")
		(net "UART_T9_NODE2_TXD_R")
	)
	(segment
		(start 131.93776 -188.272674)
		(end 131.93776 -193.28511)
		(width 0.1016)
		(layer "B.Cu")
		(net "UART_T9_NODE2_TXD_R")
	)
	(segment
		(start 131.93776 -186.170062)
		(end 132.58038 -186.812682)
		(width 0.1016)
		(layer "B.Cu")
		(net "UART_T9_NODE2_TXD_R")
	)
	(segment
		(start 127.779272 -201.172318)
		(end 127.779272 -198.87438)
		(width 0.1016)
		(layer "B.Cu")
		(net "UART_T9_NODE2_TXD_R")
	)
	(segment
		(start 127.62992 -197.59295)
		(end 127.62992 -198.725028)
		(width 0.1016)
		(layer "B.Cu")
		(net "UART_T9_NODE2_TXD_R")
	)
	(segment
		(start 131.93776 -193.28511)
		(end 127.62992 -197.59295)
		(width 0.1016)
		(layer "B.Cu")
		(net "UART_T9_NODE2_TXD_R")
	)
	(segment
		(start 132.58038 -187.630054)
		(end 131.93776 -188.272674)
		(width 0.1016)
		(layer "B.Cu")
		(net "UART_T9_NODE2_TXD_R")
	)
	(segment
		(start 128.015492 -205.199488)
		(end 128.015492 -201.408538)
		(width 0.1016)
		(layer "B.Cu")
		(net "UART_T9_NODE2_TXD_R")
	)
	(segment
		(start 128.015492 -201.408538)
		(end 127.779272 -201.172318)
		(width 0.1016)
		(layer "B.Cu")
		(net "UART_T9_NODE2_TXD_R")
	)
	(segment
		(start 126.22276 -185.956448)
		(end 126.51232 -186.246008)
		(width 0.1016)
		(layer "F.Cu")
		(net "UART_T9_NODE4_RXD_R")
	)
	(segment
		(start 126.22276 -185.605674)
		(end 126.22276 -185.956448)
		(width 0.1016)
		(layer "F.Cu")
		(net "UART_T9_NODE4_RXD_R")
	)
	(via
		(at 124.0155 -199.810878)
		(size 0.6604)
		(drill 0.3302)
		(layers "F.Cu" "B.Cu")
		(net "UART_T9_NODE4_RXD_R")
	)
	(via
		(at 126.51232 -186.246008)
		(size 0.508)
		(drill 0.254)
		(layers "F.Cu" "B.Cu")
		(net "UART_T9_NODE4_RXD_R")
	)
	(segment
		(start 124.0155 -199.810878)
		(end 124.0155 -205.199488)
		(width 0.1016)
		(layer "B.Cu")
		(net "UART_T9_NODE4_RXD_R")
	)
	(segment
		(start 128.50876 -192.321942)
		(end 124.0155 -196.815202)
		(width 0.1016)
		(layer "B.Cu")
		(net "UART_T9_NODE4_RXD_R")
	)
	(segment
		(start 126.51232 -187.411868)
		(end 128.50876 -189.408308)
		(width 0.1016)
		(layer "B.Cu")
		(net "UART_T9_NODE4_RXD_R")
	)
	(segment
		(start 124.0155 -196.815202)
		(end 124.0155 -199.810878)
		(width 0.1016)
		(layer "B.Cu")
		(net "UART_T9_NODE4_RXD_R")
	)
	(segment
		(start 126.51232 -186.246008)
		(end 126.51232 -187.411868)
		(width 0.1016)
		(layer "B.Cu")
		(net "UART_T9_NODE4_RXD_R")
	)
	(segment
		(start 128.50876 -189.408308)
		(end 128.50876 -192.321942)
		(width 0.1016)
		(layer "B.Cu")
		(net "UART_T9_NODE4_RXD_R")
	)
	(via
		(at 135.015478 -199.743568)
		(size 0.6604)
		(drill 0.3302)
		(layers "F.Cu" "B.Cu")
		(net "T9_NODE2_EN_R")
	)
	(segment
		(start 135.015478 -197.477634)
		(end 135.015478 -199.743568)
		(width 0.1016)
		(layer "B.Cu")
		(net "T9_NODE2_EN_R")
	)
	(segment
		(start 138.79576 -185.351674)
		(end 138.79576 -186.08675)
		(width 0.1016)
		(layer "B.Cu")
		(net "T9_NODE2_EN_R")
	)
	(segment
		(start 138.287252 -186.595258)
		(end 138.287252 -187.764166)
		(width 0.1016)
		(layer "B.Cu")
		(net "T9_NODE2_EN_R")
	)
	(segment
		(start 138.79576 -188.272674)
		(end 138.79576 -190.956438)
		(width 0.1016)
		(layer "B.Cu")
		(net "T9_NODE2_EN_R")
	)
	(segment
		(start 136.515602 -193.236596)
		(end 136.515602 -195.97751)
		(width 0.1016)
		(layer "B.Cu")
		(net "T9_NODE2_EN_R")
	)
	(segment
		(start 136.515602 -195.97751)
		(end 135.015478 -197.477634)
		(width 0.1016)
		(layer "B.Cu")
		(net "T9_NODE2_EN_R")
	)
	(segment
		(start 138.79576 -186.08675)
		(end 138.287252 -186.595258)
		(width 0.1016)
		(layer "B.Cu")
		(net "T9_NODE2_EN_R")
	)
	(segment
		(start 138.287252 -187.764166)
		(end 138.79576 -188.272674)
		(width 0.1016)
		(layer "B.Cu")
		(net "T9_NODE2_EN_R")
	)
	(segment
		(start 138.79576 -190.956438)
		(end 136.515602 -193.236596)
		(width 0.1016)
		(layer "B.Cu")
		(net "T9_NODE2_EN_R")
	)
	(segment
		(start 135.015478 -205.199488)
		(end 135.015478 -199.743568)
		(width 0.1016)
		(layer "B.Cu")
		(net "T9_NODE2_EN_R")
	)
	(segment
		(start 70.009258 -188.574172)
		(end 70.009258 -197.533768)
		(width 0.1016)
		(layer "F.Cu")
		(net "UART_T4_NODE4_TXD_R")
	)
	(segment
		(start 69.96176 -185.605674)
		(end 69.96176 -185.7375)
		(width 0.1016)
		(layer "F.Cu")
		(net "UART_T4_NODE4_TXD_R")
	)
	(segment
		(start 69.96176 -188.526674)
		(end 70.009258 -188.574172)
		(width 0.1016)
		(layer "F.Cu")
		(net "UART_T4_NODE4_TXD_R")
	)
	(segment
		(start 69.96176 -185.7375)
		(end 69.40296 -186.2963)
		(width 0.1016)
		(layer "F.Cu")
		(net "UART_T4_NODE4_TXD_R")
	)
	(segment
		(start 70.0151 -197.53961)
		(end 70.009258 -197.533768)
		(width 0.1016)
		(layer "F.Cu")
		(net "UART_T4_NODE4_TXD_R")
	)
	(segment
		(start 69.40296 -186.2963)
		(end 69.40296 -187.967874)
		(width 0.1016)
		(layer "F.Cu")
		(net "UART_T4_NODE4_TXD_R")
	)
	(segment
		(start 69.40296 -187.967874)
		(end 69.96176 -188.526674)
		(width 0.1016)
		(layer "F.Cu")
		(net "UART_T4_NODE4_TXD_R")
	)
	(segment
		(start 70.0151 -205.199488)
		(end 70.0151 -197.53961)
		(width 0.1016)
		(layer "F.Cu")
		(net "UART_T4_NODE4_TXD_R")
	)
	(via
		(at 70.009258 -197.533768)
		(size 0.508)
		(drill 0.254)
		(layers "F.Cu" "B.Cu")
		(net "UART_T4_NODE4_TXD_R")
	)
	(via
		(at 129.286 -196.95541)
		(size 0.6604)
		(drill 0.3302)
		(layers "F.Cu" "B.Cu")
		(net "UART_T9_NODE2_RXD_R")
	)
	(segment
		(start 128.45034 -197.79107)
		(end 128.45034 -199.990202)
		(width 0.1016)
		(layer "B.Cu")
		(net "UART_T9_NODE2_RXD_R")
	)
	(segment
		(start 133.08076 -188.272674)
		(end 133.08076 -193.16065)
		(width 0.1016)
		(layer "B.Cu")
		(net "UART_T9_NODE2_RXD_R")
	)
	(segment
		(start 129.01549 -200.555352)
		(end 129.01549 -205.199488)
		(width 0.1016)
		(layer "B.Cu")
		(net "UART_T9_NODE2_RXD_R")
	)
	(segment
		(start 128.45034 -199.990202)
		(end 129.01549 -200.555352)
		(width 0.1016)
		(layer "B.Cu")
		(net "UART_T9_NODE2_RXD_R")
	)
	(segment
		(start 133.08076 -193.16065)
		(end 129.286 -196.95541)
		(width 0.1016)
		(layer "B.Cu")
		(net "UART_T9_NODE2_RXD_R")
	)
	(segment
		(start 129.286 -196.95541)
		(end 128.45034 -197.79107)
		(width 0.1016)
		(layer "B.Cu")
		(net "UART_T9_NODE2_RXD_R")
	)
	(segment
		(start 174.244 -196.6976)
		(end 170.0276 -196.6976)
		(width 0.1016)
		(layer "F.Cu")
		(net "I2C_PDB_R_SCL")
	)
	(segment
		(start 178.015646 -205.199488)
		(end 178.015646 -200.469246)
		(width 0.1016)
		(layer "F.Cu")
		(net "I2C_PDB_R_SCL")
	)
	(segment
		(start 167.005 -193.675)
		(end 167.005 -193.421)
		(width 0.1016)
		(layer "F.Cu")
		(net "I2C_PDB_R_SCL")
	)
	(segment
		(start 170.0276 -196.6976)
		(end 167.005 -193.675)
		(width 0.1016)
		(layer "F.Cu")
		(net "I2C_PDB_R_SCL")
	)
	(segment
		(start 178.015646 -200.469246)
		(end 174.244 -196.6976)
		(width 0.1016)
		(layer "F.Cu")
		(net "I2C_PDB_R_SCL")
	)
	(segment
		(start 167.80764 -192.61836)
		(end 167.005 -193.421)
		(width 0.1016)
		(layer "F.Cu")
		(net "I2C_PDB_R_SCL")
	)
	(segment
		(start 167.80764 -188.59754)
		(end 167.80764 -192.61836)
		(width 0.1016)
		(layer "F.Cu")
		(net "I2C_PDB_R_SCL")
	)
	(via
		(at 167.005 -193.421)
		(size 0.508)
		(drill 0.254)
		(layers "F.Cu" "B.Cu")
		(net "I2C_PDB_R_SCL")
	)
	(segment
		(start 166.79164 -189.14364)
		(end 166.79164 -188.59754)
		(width 0.1016)
		(layer "B.Cu")
		(net "I2C_PDB_R_SCL")
	)
	(segment
		(start 167.005 -193.421)
		(end 167.005 -189.357)
		(width 0.1016)
		(layer "B.Cu")
		(net "I2C_PDB_R_SCL")
	)
	(segment
		(start 167.005 -189.357)
		(end 166.79164 -189.14364)
		(width 0.1016)
		(layer "B.Cu")
		(net "I2C_PDB_R_SCL")
	)
	(via
		(at 126.46152 -199.616822)
		(size 0.6604)
		(drill 0.3302)
		(layers "F.Cu" "B.Cu")
		(net "UART_T9_NODE3_RXD_R")
	)
	(segment
		(start 126.2253 -197.008496)
		(end 126.2253 -198.29399)
		(width 0.1016)
		(layer "B.Cu")
		(net "UART_T9_NODE3_RXD_R")
	)
	(segment
		(start 130.79476 -192.439036)
		(end 126.2253 -197.008496)
		(width 0.1016)
		(layer "B.Cu")
		(net "UART_T9_NODE3_RXD_R")
	)
	(segment
		(start 130.79476 -188.272674)
		(end 130.79476 -192.439036)
		(width 0.1016)
		(layer "B.Cu")
		(net "UART_T9_NODE3_RXD_R")
	)
	(segment
		(start 126.45136 -201.45756)
		(end 126.45136 -199.626982)
		(width 0.1016)
		(layer "B.Cu")
		(net "UART_T9_NODE3_RXD_R")
	)
	(segment
		(start 126.45136 -199.626982)
		(end 126.46152 -199.616822)
		(width 0.1016)
		(layer "B.Cu")
		(net "UART_T9_NODE3_RXD_R")
	)
	(segment
		(start 126.015496 -205.199488)
		(end 126.015496 -201.893424)
		(width 0.1016)
		(layer "B.Cu")
		(net "UART_T9_NODE3_RXD_R")
	)
	(segment
		(start 126.2253 -198.29399)
		(end 126.46152 -198.53021)
		(width 0.1016)
		(layer "B.Cu")
		(net "UART_T9_NODE3_RXD_R")
	)
	(segment
		(start 126.46152 -198.53021)
		(end 126.46152 -199.616822)
		(width 0.1016)
		(layer "B.Cu")
		(net "UART_T9_NODE3_RXD_R")
	)
	(segment
		(start 126.015496 -201.893424)
		(end 126.45136 -201.45756)
		(width 0.1016)
		(layer "B.Cu")
		(net "UART_T9_NODE3_RXD_R")
	)
	(segment
		(start 63.015114 -205.199488)
		(end 63.015114 -200.704704)
		(width 0.1016)
		(layer "F.Cu")
		(net "UART_T2_NODE1_RXD_R")
	)
	(segment
		(start 64.12738 -193.438526)
		(end 64.24676 -193.319146)
		(width 0.1016)
		(layer "F.Cu")
		(net "UART_T2_NODE1_RXD_R")
	)
	(segment
		(start 64.12738 -199.592438)
		(end 64.12738 -193.438526)
		(width 0.1016)
		(layer "F.Cu")
		(net "UART_T2_NODE1_RXD_R")
	)
	(segment
		(start 63.015114 -200.704704)
		(end 64.12738 -199.592438)
		(width 0.1016)
		(layer "F.Cu")
		(net "UART_T2_NODE1_RXD_R")
	)
	(segment
		(start 64.24676 -193.319146)
		(end 64.24676 -188.526674)
		(width 0.1016)
		(layer "F.Cu")
		(net "UART_T2_NODE1_RXD_R")
	)
	(via
		(at 64.12738 -199.592438)
		(size 0.508)
		(drill 0.254)
		(layers "F.Cu" "B.Cu")
		(net "UART_T2_NODE1_RXD_R")
	)
	(segment
		(start 165.7604 -193.7004)
		(end 165.7604 -190.26124)
		(width 0.1016)
		(layer "F.Cu")
		(net "I2C_PDB_R_SDA")
	)
	(segment
		(start 165.77564 -190.246)
		(end 166.28364 -189.738)
		(width 0.1016)
		(layer "F.Cu")
		(net "I2C_PDB_R_SDA")
	)
	(segment
		(start 177.015648 -203.032868)
		(end 177.33518 -202.713336)
		(width 0.1016)
		(layer "F.Cu")
		(net "I2C_PDB_R_SDA")
	)
	(segment
		(start 173.8376 -197.0024)
		(end 169.0624 -197.0024)
		(width 0.1016)
		(layer "F.Cu")
		(net "I2C_PDB_R_SDA")
	)
	(segment
		(start 177.33518 -202.713336)
		(end 177.33518 -200.49998)
		(width 0.1016)
		(layer "F.Cu")
		(net "I2C_PDB_R_SDA")
	)
	(segment
		(start 165.7604 -190.26124)
		(end 165.77564 -190.246)
		(width 0.1016)
		(layer "F.Cu")
		(net "I2C_PDB_R_SDA")
	)
	(segment
		(start 177.33518 -200.49998)
		(end 173.8376 -197.0024)
		(width 0.1016)
		(layer "F.Cu")
		(net "I2C_PDB_R_SDA")
	)
	(segment
		(start 177.015648 -205.199488)
		(end 177.015648 -203.032868)
		(width 0.1016)
		(layer "F.Cu")
		(net "I2C_PDB_R_SDA")
	)
	(segment
		(start 169.0624 -197.0024)
		(end 165.7604 -193.7004)
		(width 0.1016)
		(layer "F.Cu")
		(net "I2C_PDB_R_SDA")
	)
	(segment
		(start 166.28364 -189.738)
		(end 166.28364 -188.59754)
		(width 0.1016)
		(layer "F.Cu")
		(net "I2C_PDB_R_SDA")
	)
	(via
		(at 165.77564 -190.246)
		(size 0.508)
		(drill 0.254)
		(layers "F.Cu" "B.Cu")
		(net "I2C_PDB_R_SDA")
	)
	(segment
		(start 165.77564 -188.59754)
		(end 165.77564 -190.246)
		(width 0.1016)
		(layer "B.Cu")
		(net "I2C_PDB_R_SDA")
	)
	(segment
		(start 62.52464 -186.338718)
		(end 62.52464 -187.947554)
		(width 0.1016)
		(layer "F.Cu")
		(net "UART_T2_NODE1_TXD_R")
	)
	(segment
		(start 62.52464 -187.947554)
		(end 63.10376 -188.526674)
		(width 0.1016)
		(layer "F.Cu")
		(net "UART_T2_NODE1_TXD_R")
	)
	(segment
		(start 63.10376 -185.759598)
		(end 62.52464 -186.338718)
		(width 0.1016)
		(layer "F.Cu")
		(net "UART_T2_NODE1_TXD_R")
	)
	(segment
		(start 63.10376 -188.526674)
		(end 63.10376 -197.683882)
		(width 0.1016)
		(layer "F.Cu")
		(net "UART_T2_NODE1_TXD_R")
	)
	(segment
		(start 62.015116 -205.199488)
		(end 62.015116 -198.772526)
		(width 0.1016)
		(layer "F.Cu")
		(net "UART_T2_NODE1_TXD_R")
	)
	(segment
		(start 62.015116 -198.772526)
		(end 62.9666 -197.821042)
		(width 0.1016)
		(layer "F.Cu")
		(net "UART_T2_NODE1_TXD_R")
	)
	(segment
		(start 63.10376 -185.605674)
		(end 63.10376 -185.759598)
		(width 0.1016)
		(layer "F.Cu")
		(net "UART_T2_NODE1_TXD_R")
	)
	(segment
		(start 63.10376 -197.683882)
		(end 62.9666 -197.821042)
		(width 0.1016)
		(layer "F.Cu")
		(net "UART_T2_NODE1_TXD_R")
	)
	(via
		(at 62.9666 -197.821042)
		(size 0.508)
		(drill 0.254)
		(layers "F.Cu" "B.Cu")
		(net "UART_T2_NODE1_TXD_R")
	)
	(segment
		(start 61.015118 -202.105768)
		(end 61.52642 -201.594466)
		(width 0.1016)
		(layer "F.Cu")
		(net "UART_T2_NODE2_RXD_R")
	)
	(segment
		(start 61.015118 -205.199488)
		(end 61.015118 -202.105768)
		(width 0.1016)
		(layer "F.Cu")
		(net "UART_T2_NODE2_RXD_R")
	)
	(segment
		(start 61.52642 -201.594466)
		(end 61.52642 -196.799962)
		(width 0.1016)
		(layer "F.Cu")
		(net "UART_T2_NODE2_RXD_R")
	)
	(segment
		(start 61.52642 -196.086984)
		(end 61.96076 -195.652644)
		(width 0.1016)
		(layer "F.Cu")
		(net "UART_T2_NODE2_RXD_R")
	)
	(segment
		(start 61.96076 -195.652644)
		(end 61.96076 -188.526674)
		(width 0.1016)
		(layer "F.Cu")
		(net "UART_T2_NODE2_RXD_R")
	)
	(segment
		(start 61.52642 -196.799962)
		(end 61.52642 -196.086984)
		(width 0.1016)
		(layer "F.Cu")
		(net "UART_T2_NODE2_RXD_R")
	)
	(via
		(at 61.52642 -196.799962)
		(size 0.508)
		(drill 0.254)
		(layers "F.Cu" "B.Cu")
		(net "UART_T2_NODE2_RXD_R")
	)
	(segment
		(start 60.81776 -196.109082)
		(end 60.81776 -188.526674)
		(width 0.1016)
		(layer "F.Cu")
		(net "UART_T2_NODE2_TXD_R")
	)
	(segment
		(start 60.81776 -185.605674)
		(end 60.81776 -185.672476)
		(width 0.1016)
		(layer "F.Cu")
		(net "UART_T2_NODE2_TXD_R")
	)
	(segment
		(start 60.01512 -199.800718)
		(end 59.98972 -199.775318)
		(width 0.1016)
		(layer "F.Cu")
		(net "UART_T2_NODE2_TXD_R")
	)
	(segment
		(start 60.25896 -188.275214)
		(end 60.51042 -188.526674)
		(width 0.1016)
		(layer "F.Cu")
		(net "UART_T2_NODE2_TXD_R")
	)
	(segment
		(start 59.98972 -199.775318)
		(end 59.98972 -196.937122)
		(width 0.1016)
		(layer "F.Cu")
		(net "UART_T2_NODE2_TXD_R")
	)
	(segment
		(start 60.01512 -205.199488)
		(end 60.01512 -199.800718)
		(width 0.1016)
		(layer "F.Cu")
		(net "UART_T2_NODE2_TXD_R")
	)
	(segment
		(start 60.81776 -185.672476)
		(end 60.25896 -186.231276)
		(width 0.1016)
		(layer "F.Cu")
		(net "UART_T2_NODE2_TXD_R")
	)
	(segment
		(start 60.51042 -188.526674)
		(end 60.81776 -188.526674)
		(width 0.1016)
		(layer "F.Cu")
		(net "UART_T2_NODE2_TXD_R")
	)
	(segment
		(start 60.25896 -186.231276)
		(end 60.25896 -188.275214)
		(width 0.1016)
		(layer "F.Cu")
		(net "UART_T2_NODE2_TXD_R")
	)
	(segment
		(start 59.98972 -196.937122)
		(end 60.81776 -196.109082)
		(width 0.1016)
		(layer "F.Cu")
		(net "UART_T2_NODE2_TXD_R")
	)
	(via
		(at 59.98972 -199.775318)
		(size 0.508)
		(drill 0.254)
		(layers "F.Cu" "B.Cu")
		(net "UART_T2_NODE2_TXD_R")
	)
	(segment
		(start 68.371466 -188.526674)
		(end 68.81876 -188.526674)
		(width 0.1016)
		(layer "F.Cu")
		(net "T2_NODE1_EN_R")
	)
	(segment
		(start 68.81876 -189.448694)
		(end 68.81876 -188.526674)
		(width 0.1016)
		(layer "F.Cu")
		(net "T2_NODE1_EN_R")
	)
	(segment
		(start 68.015104 -200.018142)
		(end 69.13245 -198.900796)
		(width 0.1016)
		(layer "F.Cu")
		(net "T2_NODE1_EN_R")
	)
	(segment
		(start 69.13245 -198.900796)
		(end 69.13245 -189.762384)
		(width 0.1016)
		(layer "F.Cu")
		(net "T2_NODE1_EN_R")
	)
	(segment
		(start 68.81876 -185.605674)
		(end 68.19138 -186.233054)
		(width 0.1016)
		(layer "F.Cu")
		(net "T2_NODE1_EN_R")
	)
	(segment
		(start 68.19138 -188.346588)
		(end 68.371466 -188.526674)
		(width 0.1016)
		(layer "F.Cu")
		(net "T2_NODE1_EN_R")
	)
	(segment
		(start 68.015104 -205.199488)
		(end 68.015104 -200.018142)
		(width 0.1016)
		(layer "F.Cu")
		(net "T2_NODE1_EN_R")
	)
	(segment
		(start 69.13245 -189.762384)
		(end 68.81876 -189.448694)
		(width 0.1016)
		(layer "F.Cu")
		(net "T2_NODE1_EN_R")
	)
	(segment
		(start 68.19138 -186.233054)
		(end 68.19138 -188.346588)
		(width 0.1016)
		(layer "F.Cu")
		(net "T2_NODE1_EN_R")
	)
	(via
		(at 69.13245 -198.900796)
		(size 0.508)
		(drill 0.254)
		(layers "F.Cu" "B.Cu")
		(net "T2_NODE1_EN_R")
	)
	(segment
		(start 82.290666 -188.526674)
		(end 82.53476 -188.526674)
		(width 0.1016)
		(layer "F.Cu")
		(net "T4_NODE1_EN_R")
	)
	(segment
		(start 82.53476 -188.526674)
		(end 82.53476 -196.75856)
		(width 0.1016)
		(layer "F.Cu")
		(net "T4_NODE1_EN_R")
	)
	(segment
		(start 82.00898 -186.131454)
		(end 82.00898 -188.244988)
		(width 0.1016)
		(layer "F.Cu")
		(net "T4_NODE1_EN_R")
	)
	(segment
		(start 82.53476 -196.75856)
		(end 82.87512 -197.09892)
		(width 0.1016)
		(layer "F.Cu")
		(net "T4_NODE1_EN_R")
	)
	(segment
		(start 82.87512 -197.09892)
		(end 82.79638 -197.17766)
		(width 0.1016)
		(layer "F.Cu")
		(net "T4_NODE1_EN_R")
	)
	(segment
		(start 82.79638 -202.65898)
		(end 83.015074 -202.877674)
		(width 0.1016)
		(layer "F.Cu")
		(net "T4_NODE1_EN_R")
	)
	(segment
		(start 83.015074 -202.877674)
		(end 83.015074 -205.199488)
		(width 0.1016)
		(layer "F.Cu")
		(net "T4_NODE1_EN_R")
	)
	(segment
		(start 82.00898 -188.244988)
		(end 82.290666 -188.526674)
		(width 0.1016)
		(layer "F.Cu")
		(net "T4_NODE1_EN_R")
	)
	(segment
		(start 82.53476 -185.605674)
		(end 82.00898 -186.131454)
		(width 0.1016)
		(layer "F.Cu")
		(net "T4_NODE1_EN_R")
	)
	(segment
		(start 82.79638 -197.17766)
		(end 82.79638 -202.65898)
		(width 0.1016)
		(layer "F.Cu")
		(net "T4_NODE1_EN_R")
	)
	(via
		(at 82.87512 -197.09892)
		(size 0.508)
		(drill 0.254)
		(layers "F.Cu" "B.Cu")
		(net "T4_NODE1_EN_R")
	)
	(via
		(at 46.6471 -196.680328)
		(size 0.6604)
		(drill 0.3302)
		(layers "F.Cu" "B.Cu")
		(net "PSU5_DC_OK_R")
	)
	(segment
		(start 48.24476 -186.08675)
		(end 47.6123 -186.71921)
		(width 0.1016)
		(layer "B.Cu")
		(net "PSU5_DC_OK_R")
	)
	(segment
		(start 48.24476 -190.3857)
		(end 48.24476 -188.526674)
		(width 0.1016)
		(layer "B.Cu")
		(net "PSU5_DC_OK_R")
	)
	(segment
		(start 47.00905 -196.318378)
		(end 47.00905 -191.62141)
		(width 0.1016)
		(layer "B.Cu")
		(net "PSU5_DC_OK_R")
	)
	(segment
		(start 46.6471 -196.680328)
		(end 47.00905 -196.318378)
		(width 0.1016)
		(layer "B.Cu")
		(net "PSU5_DC_OK_R")
	)
	(segment
		(start 48.24476 -185.605674)
		(end 48.24476 -186.08675)
		(width 0.1016)
		(layer "B.Cu")
		(net "PSU5_DC_OK_R")
	)
	(segment
		(start 47.00778 -198.536306)
		(end 47.00778 -197.041008)
		(width 0.1016)
		(layer "B.Cu")
		(net "PSU5_DC_OK_R")
	)
	(segment
		(start 46.014894 -205.199488)
		(end 46.014894 -199.529192)
		(width 0.1016)
		(layer "B.Cu")
		(net "PSU5_DC_OK_R")
	)
	(segment
		(start 46.014894 -199.529192)
		(end 47.00778 -198.536306)
		(width 0.1016)
		(layer "B.Cu")
		(net "PSU5_DC_OK_R")
	)
	(segment
		(start 47.00905 -191.62141)
		(end 48.24476 -190.3857)
		(width 0.1016)
		(layer "B.Cu")
		(net "PSU5_DC_OK_R")
	)
	(segment
		(start 47.00778 -197.041008)
		(end 46.6471 -196.680328)
		(width 0.1016)
		(layer "B.Cu")
		(net "PSU5_DC_OK_R")
	)
	(segment
		(start 47.6123 -187.894214)
		(end 48.24476 -188.526674)
		(width 0.1016)
		(layer "B.Cu")
		(net "PSU5_DC_OK_R")
	)
	(segment
		(start 47.6123 -186.71921)
		(end 47.6123 -187.894214)
		(width 0.1016)
		(layer "B.Cu")
		(net "PSU5_DC_OK_R")
	)
	(segment
		(start 115.34648 -199.624442)
		(end 115.34648 -193.64706)
		(width 0.1016)
		(layer "F.Cu")
		(net "UART_T8_NODE3_RXD_R")
	)
	(segment
		(start 116.18976 -192.80378)
		(end 116.18976 -188.526674)
		(width 0.1016)
		(layer "F.Cu")
		(net "UART_T8_NODE3_RXD_R")
	)
	(segment
		(start 115.34648 -193.64706)
		(end 116.18976 -192.80378)
		(width 0.1016)
		(layer "F.Cu")
		(net "UART_T8_NODE3_RXD_R")
	)
	(segment
		(start 115.015518 -199.955404)
		(end 115.015518 -205.199488)
		(width 0.1016)
		(layer "F.Cu")
		(net "UART_T8_NODE3_RXD_R")
	)
	(segment
		(start 115.34648 -199.624442)
		(end 115.015518 -199.955404)
		(width 0.1016)
		(layer "F.Cu")
		(net "UART_T8_NODE3_RXD_R")
	)
	(via
		(at 115.34648 -199.624442)
		(size 0.508)
		(drill 0.254)
		(layers "F.Cu" "B.Cu")
		(net "UART_T8_NODE3_RXD_R")
	)
	(segment
		(start 80.7339 -186.263534)
		(end 80.7339 -188.120782)
		(width 0.1016)
		(layer "F.Cu")
		(net "T4_NODE2_EN_R")
	)
	(segment
		(start 82.015076 -196.702934)
		(end 81.39176 -196.079618)
		(width 0.1016)
		(layer "F.Cu")
		(net "T4_NODE2_EN_R")
	)
	(segment
		(start 81.139792 -188.526674)
		(end 81.39176 -188.526674)
		(width 0.1016)
		(layer "F.Cu")
		(net "T4_NODE2_EN_R")
	)
	(segment
		(start 82.015076 -205.199488)
		(end 82.015076 -196.702934)
		(width 0.1016)
		(layer "F.Cu")
		(net "T4_NODE2_EN_R")
	)
	(segment
		(start 81.39176 -196.079618)
		(end 81.39176 -188.526674)
		(width 0.1016)
		(layer "F.Cu")
		(net "T4_NODE2_EN_R")
	)
	(segment
		(start 80.7339 -188.120782)
		(end 81.139792 -188.526674)
		(width 0.1016)
		(layer "F.Cu")
		(net "T4_NODE2_EN_R")
	)
	(segment
		(start 81.39176 -185.605674)
		(end 80.7339 -186.263534)
		(width 0.1016)
		(layer "F.Cu")
		(net "T4_NODE2_EN_R")
	)
	(via
		(at 81.39176 -196.079618)
		(size 0.508)
		(drill 0.254)
		(layers "F.Cu" "B.Cu")
		(net "T4_NODE2_EN_R")
	)
	(segment
		(start 81.446878 -197.7517)
		(end 81.446878 -198.01713)
		(width 0.1016)
		(layer "F.Cu")
		(net "T4_NODE3_EN_R")
	)
	(segment
		(start 81.015078 -202.13828)
		(end 81.015078 -205.199488)
		(width 0.1016)
		(layer "F.Cu")
		(net "T4_NODE3_EN_R")
	)
	(segment
		(start 79.976218 -188.526674)
		(end 80.24876 -188.526674)
		(width 0.1016)
		(layer "F.Cu")
		(net "T4_NODE3_EN_R")
	)
	(segment
		(start 80.24876 -185.605674)
		(end 79.64932 -186.205114)
		(width 0.1016)
		(layer "F.Cu")
		(net "T4_NODE3_EN_R")
	)
	(segment
		(start 81.446878 -201.70648)
		(end 81.015078 -202.13828)
		(width 0.1016)
		(layer "F.Cu")
		(net "T4_NODE3_EN_R")
	)
	(segment
		(start 79.64932 -186.205114)
		(end 79.64932 -188.199776)
		(width 0.1016)
		(layer "F.Cu")
		(net "T4_NODE3_EN_R")
	)
	(segment
		(start 80.24876 -188.526674)
		(end 80.24876 -196.553582)
		(width 0.1016)
		(layer "F.Cu")
		(net "T4_NODE3_EN_R")
	)
	(segment
		(start 81.446878 -198.01713)
		(end 81.446878 -201.70648)
		(width 0.1016)
		(layer "F.Cu")
		(net "T4_NODE3_EN_R")
	)
	(segment
		(start 80.24876 -196.553582)
		(end 81.446878 -197.7517)
		(width 0.1016)
		(layer "F.Cu")
		(net "T4_NODE3_EN_R")
	)
	(segment
		(start 79.64932 -188.199776)
		(end 79.976218 -188.526674)
		(width 0.1016)
		(layer "F.Cu")
		(net "T4_NODE3_EN_R")
	)
	(via
		(at 81.446878 -198.01713)
		(size 0.508)
		(drill 0.254)
		(layers "F.Cu" "B.Cu")
		(net "T4_NODE3_EN_R")
	)
	(segment
		(start 119.03456 -185.272172)
		(end 118.93042 -185.376312)
		(width 0.1016)
		(layer "F.Cu")
		(net "UART_T8_NODE1_TXD_R")
	)
	(segment
		(start 119.03456 -184.389776)
		(end 119.03456 -185.272172)
		(width 0.1016)
		(layer "F.Cu")
		(net "UART_T8_NODE1_TXD_R")
	)
	(segment
		(start 118.93042 -185.376312)
		(end 118.93042 -187.81141)
		(width 0.1016)
		(layer "F.Cu")
		(net "UART_T8_NODE1_TXD_R")
	)
	(segment
		(start 119.01551 -193.93281)
		(end 119.61876 -193.32956)
		(width 0.1016)
		(layer "F.Cu")
		(net "UART_T8_NODE1_TXD_R")
	)
	(segment
		(start 119.5197 -183.904636)
		(end 119.03456 -184.389776)
		(width 0.1016)
		(layer "F.Cu")
		(net "UART_T8_NODE1_TXD_R")
	)
	(segment
		(start 118.93042 -187.81141)
		(end 119.61876 -188.49975)
		(width 0.1016)
		(layer "F.Cu")
		(net "UART_T8_NODE1_TXD_R")
	)
	(segment
		(start 119.61876 -188.49975)
		(end 119.61876 -188.526674)
		(width 0.1016)
		(layer "F.Cu")
		(net "UART_T8_NODE1_TXD_R")
	)
	(segment
		(start 119.61876 -193.32956)
		(end 119.61876 -188.526674)
		(width 0.1016)
		(layer "F.Cu")
		(net "UART_T8_NODE1_TXD_R")
	)
	(segment
		(start 119.01551 -205.199488)
		(end 119.01551 -193.93281)
		(width 0.1016)
		(layer "F.Cu")
		(net "UART_T8_NODE1_TXD_R")
	)
	(via
		(at 119.5197 -183.904636)
		(size 0.508)
		(drill 0.254)
		(layers "F.Cu" "B.Cu")
		(net "UART_T8_NODE1_TXD_R")
	)
	(via
		(at 131.374388 -171.174918)
		(size 0.508)
		(drill 0.254)
		(layers "F.Cu" "B.Cu")
		(net "UART_T8_NODE1_TXD_R")
	)
	(segment
		(start 131.03098 -171.174918)
		(end 131.374388 -171.174918)
		(width 0.1016)
		(layer "B.Cu")
		(net "UART_T8_NODE1_TXD_R")
	)
	(segment
		(start 129.868422 -171.36364)
		(end 130.842258 -171.36364)
		(width 0.1016)
		(layer "B.Cu")
		(net "UART_T8_NODE1_TXD_R")
	)
	(segment
		(start 130.842258 -171.36364)
		(end 131.03098 -171.174918)
		(width 0.1016)
		(layer "B.Cu")
		(net "UART_T8_NODE1_TXD_R")
	)
	(segment
		(start 119.83339 -183.590946)
		(end 119.5197 -183.904636)
		(width 0.1143)
		(layer "In7.Cu")
		(net "UART_T8_NODE1_TXD_R")
	)
	(segment
		(start 120.39473 -183.590946)
		(end 119.83339 -183.590946)
		(width 0.1143)
		(layer "In7.Cu")
		(net "UART_T8_NODE1_TXD_R")
	)
	(segment
		(start 128.0033 -182.11927)
		(end 125.902974 -184.219596)
		(width 0.1143)
		(layer "In7.Cu")
		(net "UART_T8_NODE1_TXD_R")
	)
	(segment
		(start 132.250688 -172.051218)
		(end 132.250688 -176.88433)
		(width 0.1143)
		(layer "In7.Cu")
		(net "UART_T8_NODE1_TXD_R")
	)
	(segment
		(start 125.902974 -184.219596)
		(end 121.02338 -184.219596)
		(width 0.1143)
		(layer "In7.Cu")
		(net "UART_T8_NODE1_TXD_R")
	)
	(segment
		(start 121.02338 -184.219596)
		(end 120.39473 -183.590946)
		(width 0.1143)
		(layer "In7.Cu")
		(net "UART_T8_NODE1_TXD_R")
	)
	(segment
		(start 131.374388 -171.174918)
		(end 132.250688 -172.051218)
		(width 0.1143)
		(layer "In7.Cu")
		(net "UART_T8_NODE1_TXD_R")
	)
	(segment
		(start 128.0033 -181.131718)
		(end 128.0033 -182.11927)
		(width 0.1143)
		(layer "In7.Cu")
		(net "UART_T8_NODE1_TXD_R")
	)
	(segment
		(start 132.250688 -176.88433)
		(end 128.0033 -181.131718)
		(width 0.1143)
		(layer "In7.Cu")
		(net "UART_T8_NODE1_TXD_R")
	)
	(segment
		(start 79.10576 -197.352666)
		(end 80.01508 -198.261986)
		(width 0.1016)
		(layer "F.Cu")
		(net "T4_NODE4_EN_R")
	)
	(segment
		(start 78.871572 -188.526674)
		(end 79.10576 -188.526674)
		(width 0.1016)
		(layer "F.Cu")
		(net "T4_NODE4_EN_R")
	)
	(segment
		(start 79.10576 -185.605674)
		(end 78.64856 -186.062874)
		(width 0.1016)
		(layer "F.Cu")
		(net "T4_NODE4_EN_R")
	)
	(segment
		(start 80.01508 -205.199488)
		(end 80.01508 -198.261986)
		(width 0.1016)
		(layer "F.Cu")
		(net "T4_NODE4_EN_R")
	)
	(segment
		(start 79.10576 -188.526674)
		(end 79.10576 -197.352666)
		(width 0.1016)
		(layer "F.Cu")
		(net "T4_NODE4_EN_R")
	)
	(segment
		(start 78.64856 -188.303662)
		(end 78.871572 -188.526674)
		(width 0.1016)
		(layer "F.Cu")
		(net "T4_NODE4_EN_R")
	)
	(segment
		(start 78.64856 -186.062874)
		(end 78.64856 -188.303662)
		(width 0.1016)
		(layer "F.Cu")
		(net "T4_NODE4_EN_R")
	)
	(via
		(at 80.01508 -198.261986)
		(size 0.508)
		(drill 0.254)
		(layers "F.Cu" "B.Cu")
		(net "T4_NODE4_EN_R")
	)
	(segment
		(start 118.47576 -193.158872)
		(end 118.47576 -188.526674)
		(width 0.1016)
		(layer "F.Cu")
		(net "UART_T8_NODE2_RXD_R")
	)
	(segment
		(start 117.7925 -198.234808)
		(end 117.934232 -198.093076)
		(width 0.1016)
		(layer "F.Cu")
		(net "UART_T8_NODE2_RXD_R")
	)
	(segment
		(start 117.934232 -193.7004)
		(end 118.47576 -193.158872)
		(width 0.1016)
		(layer "F.Cu")
		(net "UART_T8_NODE2_RXD_R")
	)
	(segment
		(start 117.934232 -198.37654)
		(end 117.7925 -198.234808)
		(width 0.1016)
		(layer "F.Cu")
		(net "UART_T8_NODE2_RXD_R")
	)
	(segment
		(start 118.015512 -205.199488)
		(end 117.934232 -205.118208)
		(width 0.1016)
		(layer "F.Cu")
		(net "UART_T8_NODE2_RXD_R")
	)
	(segment
		(start 117.934232 -205.118208)
		(end 117.934232 -198.37654)
		(width 0.1016)
		(layer "F.Cu")
		(net "UART_T8_NODE2_RXD_R")
	)
	(segment
		(start 117.934232 -198.093076)
		(end 117.934232 -193.7004)
		(width 0.1016)
		(layer "F.Cu")
		(net "UART_T8_NODE2_RXD_R")
	)
	(via
		(at 117.7925 -198.234808)
		(size 0.508)
		(drill 0.254)
		(layers "F.Cu" "B.Cu")
		(net "UART_T8_NODE2_RXD_R")
	)
	(segment
		(start 159.62376 -186.139836)
		(end 160.08096 -186.597036)
		(width 0.1016)
		(layer "F.Cu")
		(net "FAN_PWM_R")
	)
	(segment
		(start 159.62376 -185.605674)
		(end 159.62376 -186.139836)
		(width 0.1016)
		(layer "F.Cu")
		(net "FAN_PWM_R")
	)
	(segment
		(start 160.08096 -188.450728)
		(end 160.005014 -188.526674)
		(width 0.1016)
		(layer "F.Cu")
		(net "FAN_PWM_R")
	)
	(segment
		(start 159.49676 -188.653674)
		(end 159.62376 -188.526674)
		(width 0.1016)
		(layer "F.Cu")
		(net "FAN_PWM_R")
	)
	(segment
		(start 160.005014 -188.526674)
		(end 159.62376 -188.526674)
		(width 0.1016)
		(layer "F.Cu")
		(net "FAN_PWM_R")
	)
	(segment
		(start 160.08096 -186.597036)
		(end 160.08096 -188.450728)
		(width 0.1016)
		(layer "F.Cu")
		(net "FAN_PWM_R")
	)
	(segment
		(start 159.49676 -189.387734)
		(end 159.49676 -188.653674)
		(width 0.1016)
		(layer "F.Cu")
		(net "FAN_PWM_R")
	)
	(segment
		(start 158.49854 -189.573154)
		(end 159.31134 -189.573154)
		(width 0.1016)
		(layer "F.Cu")
		(net "FAN_PWM_R")
	)
	(segment
		(start 159.31134 -189.573154)
		(end 159.49676 -189.387734)
		(width 0.1016)
		(layer "F.Cu")
		(net "FAN_PWM_R")
	)
	(via
		(at 158.49854 -189.573154)
		(size 0.508)
		(drill 0.254)
		(layers "F.Cu" "B.Cu")
		(net "FAN_PWM_R")
	)
	(segment
		(start 155.58389 -200.311512)
		(end 155.58389 -201.536046)
		(width 0.1016)
		(layer "B.Cu")
		(net "FAN_PWM_R")
	)
	(segment
		(start 158.49854 -189.573154)
		(end 158.49854 -194.115182)
		(width 0.1016)
		(layer "B.Cu")
		(net "FAN_PWM_R")
	)
	(segment
		(start 156.35224 -199.543162)
		(end 155.58389 -200.311512)
		(width 0.1016)
		(layer "B.Cu")
		(net "FAN_PWM_R")
	)
	(segment
		(start 155.58389 -201.536046)
		(end 156.01569 -201.967846)
		(width 0.1016)
		(layer "B.Cu")
		(net "FAN_PWM_R")
	)
	(segment
		(start 156.01569 -201.967846)
		(end 156.01569 -205.199488)
		(width 0.1016)
		(layer "B.Cu")
		(net "FAN_PWM_R")
	)
	(segment
		(start 158.49854 -194.115182)
		(end 156.35224 -196.261482)
		(width 0.1016)
		(layer "B.Cu")
		(net "FAN_PWM_R")
	)
	(segment
		(start 156.35224 -196.261482)
		(end 156.35224 -199.543162)
		(width 0.1016)
		(layer "B.Cu")
		(net "FAN_PWM_R")
	)
	(segment
		(start 112.24514 -188.026294)
		(end 111.74476 -188.526674)
		(width 0.1016)
		(layer "F.Cu")
		(net "T6_NODE1_EN_R")
	)
	(segment
		(start 111.74476 -185.785506)
		(end 112.24514 -186.285886)
		(width 0.1016)
		(layer "F.Cu")
		(net "T6_NODE1_EN_R")
	)
	(segment
		(start 110.3503 -197.71614)
		(end 110.3503 -194.14998)
		(width 0.1016)
		(layer "F.Cu")
		(net "T6_NODE1_EN_R")
	)
	(segment
		(start 110.37316 -197.739)
		(end 110.3503 -197.71614)
		(width 0.1016)
		(layer "F.Cu")
		(net "T6_NODE1_EN_R")
	)
	(segment
		(start 110.3503 -194.14998)
		(end 111.74476 -192.75552)
		(width 0.1016)
		(layer "F.Cu")
		(net "T6_NODE1_EN_R")
	)
	(segment
		(start 112.24514 -186.285886)
		(end 112.24514 -188.026294)
		(width 0.1016)
		(layer "F.Cu")
		(net "T6_NODE1_EN_R")
	)
	(segment
		(start 111.74476 -192.75552)
		(end 111.74476 -188.526674)
		(width 0.1016)
		(layer "F.Cu")
		(net "T6_NODE1_EN_R")
	)
	(segment
		(start 110.015528 -205.199488)
		(end 110.015528 -198.096632)
		(width 0.1016)
		(layer "F.Cu")
		(net "T6_NODE1_EN_R")
	)
	(segment
		(start 111.74476 -185.605674)
		(end 111.74476 -185.785506)
		(width 0.1016)
		(layer "F.Cu")
		(net "T6_NODE1_EN_R")
	)
	(segment
		(start 110.015528 -198.096632)
		(end 110.37316 -197.739)
		(width 0.1016)
		(layer "F.Cu")
		(net "T6_NODE1_EN_R")
	)
	(via
		(at 110.37316 -197.739)
		(size 0.508)
		(drill 0.254)
		(layers "F.Cu" "B.Cu")
		(net "T6_NODE1_EN_R")
	)
	(segment
		(start 117.5385 -199.895714)
		(end 117.5385 -202.023726)
		(width 0.1016)
		(layer "F.Cu")
		(net "UART_T8_NODE2_TXD_R")
	)
	(segment
		(start 117.02796 -189.346078)
		(end 117.02796 -199.385174)
		(width 0.1016)
		(layer "F.Cu")
		(net "UART_T8_NODE2_TXD_R")
	)
	(segment
		(start 117.08638 -186.282838)
		(end 116.77396 -186.595258)
		(width 0.1016)
		(layer "F.Cu")
		(net "UART_T8_NODE2_TXD_R")
	)
	(segment
		(start 117.23751 -199.594724)
		(end 117.5385 -199.895714)
		(width 0.1016)
		(layer "F.Cu")
		(net "UART_T8_NODE2_TXD_R")
	)
	(segment
		(start 117.33276 -189.041278)
		(end 117.02796 -189.346078)
		(width 0.1016)
		(layer "F.Cu")
		(net "UART_T8_NODE2_TXD_R")
	)
	(segment
		(start 117.5385 -202.023726)
		(end 117.015514 -202.546712)
		(width 0.1016)
		(layer "F.Cu")
		(net "UART_T8_NODE2_TXD_R")
	)
	(segment
		(start 116.77396 -186.595258)
		(end 116.77396 -187.94095)
		(width 0.1016)
		(layer "F.Cu")
		(net "UART_T8_NODE2_TXD_R")
	)
	(segment
		(start 116.77396 -187.94095)
		(end 117.33276 -188.49975)
		(width 0.1016)
		(layer "F.Cu")
		(net "UART_T8_NODE2_TXD_R")
	)
	(segment
		(start 117.33276 -188.526674)
		(end 117.33276 -189.041278)
		(width 0.1016)
		(layer "F.Cu")
		(net "UART_T8_NODE2_TXD_R")
	)
	(segment
		(start 117.33276 -188.49975)
		(end 117.33276 -188.526674)
		(width 0.1016)
		(layer "F.Cu")
		(net "UART_T8_NODE2_TXD_R")
	)
	(segment
		(start 117.08638 -183.82996)
		(end 117.08638 -186.282838)
		(width 0.1016)
		(layer "F.Cu")
		(net "UART_T8_NODE2_TXD_R")
	)
	(segment
		(start 117.02796 -199.385174)
		(end 117.23751 -199.594724)
		(width 0.1016)
		(layer "F.Cu")
		(net "UART_T8_NODE2_TXD_R")
	)
	(segment
		(start 117.015514 -202.546712)
		(end 117.015514 -205.199488)
		(width 0.1016)
		(layer "F.Cu")
		(net "UART_T8_NODE2_TXD_R")
	)
	(segment
		(start 116.8273 -183.57088)
		(end 117.08638 -183.82996)
		(width 0.1016)
		(layer "F.Cu")
		(net "UART_T8_NODE2_TXD_R")
	)
	(via
		(at 131.522724 -170.205908)
		(size 0.508)
		(drill 0.254)
		(layers "F.Cu" "B.Cu")
		(net "UART_T8_NODE2_TXD_R")
	)
	(via
		(at 117.23751 -199.594724)
		(size 0.508)
		(drill 0.254)
		(layers "F.Cu" "B.Cu")
		(net "UART_T8_NODE2_TXD_R")
	)
	(via
		(at 116.8273 -183.57088)
		(size 0.508)
		(drill 0.254)
		(layers "F.Cu" "B.Cu")
		(net "UART_T8_NODE2_TXD_R")
	)
	(segment
		(start 131.42468 -170.303952)
		(end 131.522724 -170.205908)
		(width 0.1016)
		(layer "B.Cu")
		(net "UART_T8_NODE2_TXD_R")
	)
	(segment
		(start 130.310636 -170.303952)
		(end 131.42468 -170.303952)
		(width 0.1016)
		(layer "B.Cu")
		(net "UART_T8_NODE2_TXD_R")
	)
	(segment
		(start 132.573268 -171.256452)
		(end 131.522724 -170.205908)
		(width 0.1143)
		(layer "In7.Cu")
		(net "UART_T8_NODE2_TXD_R")
	)
	(segment
		(start 116.8273 -183.57088)
		(end 117.832124 -184.575704)
		(width 0.1143)
		(layer "In7.Cu")
		(net "UART_T8_NODE2_TXD_R")
	)
	(segment
		(start 128.3208 -182.25135)
		(end 128.3208 -181.26456)
		(width 0.1143)
		(layer "In7.Cu")
		(net "UART_T8_NODE2_TXD_R")
	)
	(segment
		(start 125.996446 -184.575704)
		(end 128.3208 -182.25135)
		(width 0.1143)
		(layer "In7.Cu")
		(net "UART_T8_NODE2_TXD_R")
	)
	(segment
		(start 128.3208 -181.26456)
		(end 132.573268 -177.012092)
		(width 0.1143)
		(layer "In7.Cu")
		(net "UART_T8_NODE2_TXD_R")
	)
	(segment
		(start 117.832124 -184.575704)
		(end 125.996446 -184.575704)
		(width 0.1143)
		(layer "In7.Cu")
		(net "UART_T8_NODE2_TXD_R")
	)
	(segment
		(start 132.573268 -177.012092)
		(end 132.573268 -171.256452)
		(width 0.1143)
		(layer "In7.Cu")
		(net "UART_T8_NODE2_TXD_R")
	)
	(segment
		(start 107.10926 -199.53859)
		(end 107.10926 -198.005192)
		(width 0.1016)
		(layer "F.Cu")
		(net "T6_NODE4_EN_R")
	)
	(segment
		(start 108.91774 -186.252612)
		(end 108.91774 -187.924694)
		(width 0.1016)
		(layer "F.Cu")
		(net "T6_NODE4_EN_R")
	)
	(segment
		(start 107.015534 -205.199488)
		(end 107.015534 -202.203812)
		(width 0.1016)
		(layer "F.Cu")
		(net "T6_NODE4_EN_R")
	)
	(segment
		(start 108.31576 -185.605674)
		(end 108.31576 -185.650632)
		(width 0.1016)
		(layer "F.Cu")
		(net "T6_NODE4_EN_R")
	)
	(segment
		(start 107.60456 -197.509892)
		(end 107.60456 -192.782952)
		(width 0.1016)
		(layer "F.Cu")
		(net "T6_NODE4_EN_R")
	)
	(segment
		(start 108.31576 -192.071752)
		(end 108.31576 -188.526674)
		(width 0.1016)
		(layer "F.Cu")
		(net "T6_NODE4_EN_R")
	)
	(segment
		(start 108.31576 -185.650632)
		(end 108.91774 -186.252612)
		(width 0.1016)
		(layer "F.Cu")
		(net "T6_NODE4_EN_R")
	)
	(segment
		(start 107.60456 -192.782952)
		(end 108.31576 -192.071752)
		(width 0.1016)
		(layer "F.Cu")
		(net "T6_NODE4_EN_R")
	)
	(segment
		(start 107.10926 -198.005192)
		(end 107.60456 -197.509892)
		(width 0.1016)
		(layer "F.Cu")
		(net "T6_NODE4_EN_R")
	)
	(segment
		(start 107.447334 -199.876664)
		(end 107.10926 -199.53859)
		(width 0.1016)
		(layer "F.Cu")
		(net "T6_NODE4_EN_R")
	)
	(segment
		(start 107.447334 -201.772012)
		(end 107.447334 -199.876664)
		(width 0.1016)
		(layer "F.Cu")
		(net "T6_NODE4_EN_R")
	)
	(segment
		(start 107.015534 -202.203812)
		(end 107.447334 -201.772012)
		(width 0.1016)
		(layer "F.Cu")
		(net "T6_NODE4_EN_R")
	)
	(segment
		(start 108.91774 -187.924694)
		(end 108.31576 -188.526674)
		(width 0.1016)
		(layer "F.Cu")
		(net "T6_NODE4_EN_R")
	)
	(via
		(at 107.10926 -198.005192)
		(size 0.508)
		(drill 0.254)
		(layers "F.Cu" "B.Cu")
		(net "T6_NODE4_EN_R")
	)
	(segment
		(start 67.67576 -185.605674)
		(end 67.1195 -186.161934)
		(width 0.1016)
		(layer "F.Cu")
		(net "T2_NODE2_EN_R")
	)
	(segment
		(start 67.015106 -205.199488)
		(end 67.015106 -197.937374)
		(width 0.1016)
		(layer "F.Cu")
		(net "T2_NODE2_EN_R")
	)
	(segment
		(start 67.015106 -197.937374)
		(end 67.14236 -197.81012)
		(width 0.1016)
		(layer "F.Cu")
		(net "T2_NODE2_EN_R")
	)
	(segment
		(start 67.67576 -195.964302)
		(end 67.14236 -196.497702)
		(width 0.1016)
		(layer "F.Cu")
		(net "T2_NODE2_EN_R")
	)
	(segment
		(start 67.14236 -196.497702)
		(end 67.14236 -197.81012)
		(width 0.1016)
		(layer "F.Cu")
		(net "T2_NODE2_EN_R")
	)
	(segment
		(start 67.1195 -186.161934)
		(end 67.1195 -188.165994)
		(width 0.1016)
		(layer "F.Cu")
		(net "T2_NODE2_EN_R")
	)
	(segment
		(start 67.48018 -188.526674)
		(end 67.67576 -188.526674)
		(width 0.1016)
		(layer "F.Cu")
		(net "T2_NODE2_EN_R")
	)
	(segment
		(start 67.67576 -188.526674)
		(end 67.67576 -195.964302)
		(width 0.1016)
		(layer "F.Cu")
		(net "T2_NODE2_EN_R")
	)
	(segment
		(start 67.1195 -188.165994)
		(end 67.48018 -188.526674)
		(width 0.1016)
		(layer "F.Cu")
		(net "T2_NODE2_EN_R")
	)
	(via
		(at 67.14236 -197.81012)
		(size 0.508)
		(drill 0.254)
		(layers "F.Cu" "B.Cu")
		(net "T2_NODE2_EN_R")
	)
	(via
		(at 47.64278 -195.73367)
		(size 0.6604)
		(drill 0.3302)
		(layers "F.Cu" "B.Cu")
		(net "PSU4_DC_OK_R")
	)
	(segment
		(start 47.69358 -195.78447)
		(end 47.69358 -199.673972)
		(width 0.1016)
		(layer "B.Cu")
		(net "PSU4_DC_OK_R")
	)
	(segment
		(start 49.38776 -185.605674)
		(end 49.38776 -186.08675)
		(width 0.1016)
		(layer "B.Cu")
		(net "PSU4_DC_OK_R")
	)
	(segment
		(start 48.000158 -191.293242)
		(end 49.38776 -189.90564)
		(width 0.1016)
		(layer "B.Cu")
		(net "PSU4_DC_OK_R")
	)
	(segment
		(start 47.64278 -195.73367)
		(end 47.69358 -195.78447)
		(width 0.1016)
		(layer "B.Cu")
		(net "PSU4_DC_OK_R")
	)
	(segment
		(start 48.78324 -187.922154)
		(end 49.38776 -188.526674)
		(width 0.1016)
		(layer "B.Cu")
		(net "PSU4_DC_OK_R")
	)
	(segment
		(start 47.014892 -200.35266)
		(end 47.014892 -205.199488)
		(width 0.1016)
		(layer "B.Cu")
		(net "PSU4_DC_OK_R")
	)
	(segment
		(start 49.38776 -186.08675)
		(end 48.78324 -186.69127)
		(width 0.1016)
		(layer "B.Cu")
		(net "PSU4_DC_OK_R")
	)
	(segment
		(start 47.69358 -199.673972)
		(end 47.014892 -200.35266)
		(width 0.1016)
		(layer "B.Cu")
		(net "PSU4_DC_OK_R")
	)
	(segment
		(start 48.78324 -186.69127)
		(end 48.78324 -187.922154)
		(width 0.1016)
		(layer "B.Cu")
		(net "PSU4_DC_OK_R")
	)
	(segment
		(start 49.38776 -189.90564)
		(end 49.38776 -188.526674)
		(width 0.1016)
		(layer "B.Cu")
		(net "PSU4_DC_OK_R")
	)
	(segment
		(start 48.000158 -195.376292)
		(end 48.000158 -191.293242)
		(width 0.1016)
		(layer "B.Cu")
		(net "PSU4_DC_OK_R")
	)
	(segment
		(start 47.64278 -195.73367)
		(end 48.000158 -195.376292)
		(width 0.1016)
		(layer "B.Cu")
		(net "PSU4_DC_OK_R")
	)
	(segment
		(start 66.396362 -188.526674)
		(end 66.53276 -188.526674)
		(width 0.1016)
		(layer "F.Cu")
		(net "T2_NODE3_EN_R")
	)
	(segment
		(start 66.015108 -205.199488)
		(end 66.015108 -202.22464)
		(width 0.1016)
		(layer "F.Cu")
		(net "T2_NODE3_EN_R")
	)
	(segment
		(start 66.53276 -194.675506)
		(end 66.53276 -188.526674)
		(width 0.1016)
		(layer "F.Cu")
		(net "T2_NODE3_EN_R")
	)
	(segment
		(start 66.91122 -195.685918)
		(end 66.91122 -195.053966)
		(width 0.1016)
		(layer "F.Cu")
		(net "T2_NODE3_EN_R")
	)
	(segment
		(start 66.57086 -196.026278)
		(end 66.91122 -195.685918)
		(width 0.1016)
		(layer "F.Cu")
		(net "T2_NODE3_EN_R")
	)
	(segment
		(start 66.57086 -201.668888)
		(end 66.57086 -196.026278)
		(width 0.1016)
		(layer "F.Cu")
		(net "T2_NODE3_EN_R")
	)
	(segment
		(start 66.53276 -185.605674)
		(end 66.0019 -186.136534)
		(width 0.1016)
		(layer "F.Cu")
		(net "T2_NODE3_EN_R")
	)
	(segment
		(start 66.0019 -188.132212)
		(end 66.396362 -188.526674)
		(width 0.1016)
		(layer "F.Cu")
		(net "T2_NODE3_EN_R")
	)
	(segment
		(start 66.91122 -195.053966)
		(end 66.53276 -194.675506)
		(width 0.1016)
		(layer "F.Cu")
		(net "T2_NODE3_EN_R")
	)
	(segment
		(start 66.0019 -186.136534)
		(end 66.0019 -188.132212)
		(width 0.1016)
		(layer "F.Cu")
		(net "T2_NODE3_EN_R")
	)
	(segment
		(start 66.015108 -202.22464)
		(end 66.57086 -201.668888)
		(width 0.1016)
		(layer "F.Cu")
		(net "T2_NODE3_EN_R")
	)
	(via
		(at 66.91122 -195.685918)
		(size 0.508)
		(drill 0.254)
		(layers "F.Cu" "B.Cu")
		(net "T2_NODE3_EN_R")
	)
	(via
		(at 48.534574 -199.584564)
		(size 0.6604)
		(drill 0.3302)
		(layers "F.Cu" "B.Cu")
		(net "PSU3_DC_OK_R")
	)
	(segment
		(start 49.54524 -196.923914)
		(end 49.54524 -191.162432)
		(width 0.1016)
		(layer "B.Cu")
		(net "PSU3_DC_OK_R")
	)
	(segment
		(start 49.009046 -197.460108)
		(end 49.54524 -196.923914)
		(width 0.1016)
		(layer "B.Cu")
		(net "PSU3_DC_OK_R")
	)
	(segment
		(start 48.01489 -200.104248)
		(end 48.534574 -199.584564)
		(width 0.1016)
		(layer "B.Cu")
		(net "PSU3_DC_OK_R")
	)
	(segment
		(start 48.534574 -199.584564)
		(end 49.009046 -199.110092)
		(width 0.1016)
		(layer "B.Cu")
		(net "PSU3_DC_OK_R")
	)
	(segment
		(start 49.54524 -191.162432)
		(end 50.53076 -190.176912)
		(width 0.1016)
		(layer "B.Cu")
		(net "PSU3_DC_OK_R")
	)
	(segment
		(start 49.84496 -187.840874)
		(end 50.53076 -188.526674)
		(width 0.1016)
		(layer "B.Cu")
		(net "PSU3_DC_OK_R")
	)
	(segment
		(start 50.53076 -185.605674)
		(end 50.53076 -186.21375)
		(width 0.1016)
		(layer "B.Cu")
		(net "PSU3_DC_OK_R")
	)
	(segment
		(start 49.009046 -199.110092)
		(end 49.009046 -197.460108)
		(width 0.1016)
		(layer "B.Cu")
		(net "PSU3_DC_OK_R")
	)
	(segment
		(start 48.01489 -205.199488)
		(end 48.01489 -200.104248)
		(width 0.1016)
		(layer "B.Cu")
		(net "PSU3_DC_OK_R")
	)
	(segment
		(start 50.53076 -190.176912)
		(end 50.53076 -188.526674)
		(width 0.1016)
		(layer "B.Cu")
		(net "PSU3_DC_OK_R")
	)
	(segment
		(start 50.53076 -186.21375)
		(end 49.84496 -186.89955)
		(width 0.1016)
		(layer "B.Cu")
		(net "PSU3_DC_OK_R")
	)
	(segment
		(start 49.84496 -186.89955)
		(end 49.84496 -187.840874)
		(width 0.1016)
		(layer "B.Cu")
		(net "PSU3_DC_OK_R")
	)
	(segment
		(start 65.01511 -197.872858)
		(end 65.1891 -197.698868)
		(width 0.1016)
		(layer "F.Cu")
		(net "T2_NODE4_EN_R")
	)
	(segment
		(start 65.38976 -189.496446)
		(end 65.38976 -188.526674)
		(width 0.1016)
		(layer "F.Cu")
		(net "T2_NODE4_EN_R")
	)
	(segment
		(start 64.9097 -186.085734)
		(end 64.9097 -188.165994)
		(width 0.1016)
		(layer "F.Cu")
		(net "T2_NODE4_EN_R")
	)
	(segment
		(start 65.01511 -205.199488)
		(end 65.01511 -197.872858)
		(width 0.1016)
		(layer "F.Cu")
		(net "T2_NODE4_EN_R")
	)
	(segment
		(start 65.27038 -188.526674)
		(end 65.38976 -188.526674)
		(width 0.1016)
		(layer "F.Cu")
		(net "T2_NODE4_EN_R")
	)
	(segment
		(start 64.9097 -188.165994)
		(end 65.27038 -188.526674)
		(width 0.1016)
		(layer "F.Cu")
		(net "T2_NODE4_EN_R")
	)
	(segment
		(start 65.1891 -197.698868)
		(end 65.1891 -189.697106)
		(width 0.1016)
		(layer "F.Cu")
		(net "T2_NODE4_EN_R")
	)
	(segment
		(start 65.1891 -189.697106)
		(end 65.38976 -189.496446)
		(width 0.1016)
		(layer "F.Cu")
		(net "T2_NODE4_EN_R")
	)
	(segment
		(start 65.38976 -185.605674)
		(end 64.9097 -186.085734)
		(width 0.1016)
		(layer "F.Cu")
		(net "T2_NODE4_EN_R")
	)
	(via
		(at 65.1891 -197.698868)
		(size 0.508)
		(drill 0.254)
		(layers "F.Cu" "B.Cu")
		(net "T2_NODE4_EN_R")
	)
	(via
		(at 53.4035 -199.369426)
		(size 0.6604)
		(drill 0.3302)
		(layers "F.Cu" "B.Cu")
		(net "UART_T1_NODE1_RXD_R")
	)
	(segment
		(start 53.4035 -199.415654)
		(end 53.01488 -199.804274)
		(width 0.1016)
		(layer "B.Cu")
		(net "UART_T1_NODE1_RXD_R")
	)
	(segment
		(start 55.10276 -190.603886)
		(end 55.10276 -188.526674)
		(width 0.1016)
		(layer "B.Cu")
		(net "UART_T1_NODE1_RXD_R")
	)
	(segment
		(start 53.4035 -199.369426)
		(end 53.4035 -199.415654)
		(width 0.1016)
		(layer "B.Cu")
		(net "UART_T1_NODE1_RXD_R")
	)
	(segment
		(start 53.4035 -199.369426)
		(end 53.4035 -192.303146)
		(width 0.1016)
		(layer "B.Cu")
		(net "UART_T1_NODE1_RXD_R")
	)
	(segment
		(start 53.01488 -199.804274)
		(end 53.01488 -205.199488)
		(width 0.1016)
		(layer "B.Cu")
		(net "UART_T1_NODE1_RXD_R")
	)
	(segment
		(start 53.4035 -192.303146)
		(end 55.10276 -190.603886)
		(width 0.1016)
		(layer "B.Cu")
		(net "UART_T1_NODE1_RXD_R")
	)
	(segment
		(start 24.14524 -44.627292)
		(end 24.752046 -45.234098)
		(width 0.1016)
		(layer "F.Cu")
		(net "I2C_VIDREAR_5V_SDA")
	)
	(segment
		(start 17.227804 -45.915834)
		(end 17.234662 -45.908976)
		(width 0.1016)
		(layer "F.Cu")
		(net "I2C_VIDREAR_5V_SDA")
	)
	(segment
		(start 17.234662 -45.908976)
		(end 18.21942 -45.908976)
		(width 0.1016)
		(layer "F.Cu")
		(net "I2C_VIDREAR_5V_SDA")
	)
	(segment
		(start 24.14524 -40.591994)
		(end 24.14524 -44.627292)
		(width 0.1016)
		(layer "F.Cu")
		(net "I2C_VIDREAR_5V_SDA")
	)
	(segment
		(start 24.752046 -45.234098)
		(end 24.752046 -45.978064)
		(width 0.1016)
		(layer "F.Cu")
		(net "I2C_VIDREAR_5V_SDA")
	)
	(segment
		(start 21.24964 -45.978064)
		(end 24.752046 -45.978064)
		(width 0.1016)
		(layer "F.Cu")
		(net "I2C_VIDREAR_5V_SDA")
	)
	(segment
		(start 18.21942 -45.908976)
		(end 18.438368 -45.908976)
		(width 0.1016)
		(layer "F.Cu")
		(net "I2C_VIDREAR_5V_SDA")
	)
	(segment
		(start 20.6502 -45.378624)
		(end 21.24964 -45.978064)
		(width 0.1016)
		(layer "F.Cu")
		(net "I2C_VIDREAR_5V_SDA")
	)
	(segment
		(start 18.438368 -45.908976)
		(end 18.96872 -45.378624)
		(width 0.1016)
		(layer "F.Cu")
		(net "I2C_VIDREAR_5V_SDA")
	)
	(segment
		(start 18.96872 -45.378624)
		(end 20.6502 -45.378624)
		(width 0.1016)
		(layer "F.Cu")
		(net "I2C_VIDREAR_5V_SDA")
	)
	(segment
		(start 16.552926 -45.915834)
		(end 17.227804 -45.915834)
		(width 0.1016)
		(layer "F.Cu")
		(net "I2C_VIDREAR_5V_SDA")
	)
	(via
		(at 17.234662 -45.908976)
		(size 0.508)
		(drill 0.254)
		(layers "F.Cu" "B.Cu")
		(net "I2C_VIDREAR_5V_SDA")
	)
	(segment
		(start 82.494882 -179.874672)
		(end 82.494882 -178.759358)
		(width 0.1016)
		(layer "F.Cu")
		(net "SDC_RST_N")
	)
	(segment
		(start 83.03006 -171.744386)
		(end 82.42808 -172.346366)
		(width 0.1016)
		(layer "F.Cu")
		(net "SDC_RST_N")
	)
	(segment
		(start 82.42808 -178.489356)
		(end 82.32648 -178.590956)
		(width 0.1016)
		(layer "F.Cu")
		(net "SDC_RST_N")
	)
	(segment
		(start 82.494882 -178.759358)
		(end 82.32648 -178.590956)
		(width 0.1016)
		(layer "F.Cu")
		(net "SDC_RST_N")
	)
	(segment
		(start 82.42808 -172.346366)
		(end 82.42808 -178.489356)
		(width 0.1016)
		(layer "F.Cu")
		(net "SDC_RST_N")
	)
	(via
		(at 82.32648 -178.590956)
		(size 0.508)
		(drill 0.254)
		(layers "F.Cu" "B.Cu")
		(net "SDC_RST_N")
	)
	(via
		(at 85.18906 -169.64533)
		(size 0.508)
		(drill 0.254)
		(layers "F.Cu" "B.Cu")
		(net "SDC_RST_N")
	)
	(via
		(at 83.03006 -171.744386)
		(size 0.508)
		(drill 0.254)
		(layers "F.Cu" "B.Cu")
		(net "SDC_RST_N")
	)
	(segment
		(start 85.70468 -169.12971)
		(end 85.70468 -167.927782)
		(width 0.1016)
		(layer "B.Cu")
		(net "SDC_RST_N")
	)
	(segment
		(start 85.70468 -167.927782)
		(end 86.678008 -166.954454)
		(width 0.1016)
		(layer "B.Cu")
		(net "SDC_RST_N")
	)
	(segment
		(start 86.678008 -166.954454)
		(end 87.748872 -166.954454)
		(width 0.1016)
		(layer "B.Cu")
		(net "SDC_RST_N")
	)
	(segment
		(start 85.18906 -169.64533)
		(end 85.70468 -169.12971)
		(width 0.1016)
		(layer "B.Cu")
		(net "SDC_RST_N")
	)
	(segment
		(start 85.129116 -169.64533)
		(end 83.03006 -171.744386)
		(width 0.1143)
		(layer "In7.Cu")
		(net "SDC_RST_N")
	)
	(segment
		(start 85.18906 -169.64533)
		(end 85.129116 -169.64533)
		(width 0.1143)
		(layer "In7.Cu")
		(net "SDC_RST_N")
	)
	(segment
		(start 140.025882 -178.858672)
		(end 140.025882 -177.607722)
		(width 0.1016)
		(layer "F.Cu")
		(net "UART3_RESET_N")
	)
	(segment
		(start 116.87048 -168.318942)
		(end 117.45976 -168.908222)
		(width 0.1016)
		(layer "F.Cu")
		(net "UART3_RESET_N")
	)
	(segment
		(start 118.93804 -168.750742)
		(end 118.93804 -168.748964)
		(width 0.1016)
		(layer "F.Cu")
		(net "UART3_RESET_N")
	)
	(segment
		(start 112.271302 -166.52113)
		(end 113.121948 -166.52113)
		(width 0.1016)
		(layer "F.Cu")
		(net "UART3_RESET_N")
	)
	(segment
		(start 116.87048 -166.997126)
		(end 116.87048 -168.318942)
		(width 0.1016)
		(layer "F.Cu")
		(net "UART3_RESET_N")
	)
	(segment
		(start 118.78056 -168.908222)
		(end 118.93804 -168.750742)
		(width 0.1016)
		(layer "F.Cu")
		(net "UART3_RESET_N")
	)
	(segment
		(start 114.76736 -165.60673)
		(end 115.480084 -165.60673)
		(width 0.1016)
		(layer "F.Cu")
		(net "UART3_RESET_N")
	)
	(segment
		(start 115.480084 -165.60673)
		(end 116.87048 -166.997126)
		(width 0.1016)
		(layer "F.Cu")
		(net "UART3_RESET_N")
	)
	(segment
		(start 114.036348 -165.60673)
		(end 114.76736 -165.60673)
		(width 0.1016)
		(layer "F.Cu")
		(net "UART3_RESET_N")
	)
	(segment
		(start 113.121948 -166.52113)
		(end 114.036348 -165.60673)
		(width 0.1016)
		(layer "F.Cu")
		(net "UART3_RESET_N")
	)
	(segment
		(start 117.45976 -168.908222)
		(end 118.78056 -168.908222)
		(width 0.1016)
		(layer "F.Cu")
		(net "UART3_RESET_N")
	)
	(via
		(at 118.93804 -168.748964)
		(size 0.508)
		(drill 0.254)
		(layers "F.Cu" "B.Cu")
		(net "UART3_RESET_N")
	)
	(via
		(at 140.025882 -177.607722)
		(size 0.508)
		(drill 0.254)
		(layers "F.Cu" "B.Cu")
		(net "UART3_RESET_N")
	)
	(segment
		(start 118.93804 -168.748964)
		(end 119.33174 -169.142664)
		(width 0.1143)
		(layer "In6.Cu")
		(net "UART3_RESET_N")
	)
	(segment
		(start 138.914886 -175.933862)
		(end 140.025882 -177.044858)
		(width 0.1143)
		(layer "In6.Cu")
		(net "UART3_RESET_N")
	)
	(segment
		(start 119.33174 -169.142664)
		(end 119.33174 -170.1673)
		(width 0.1143)
		(layer "In6.Cu")
		(net "UART3_RESET_N")
	)
	(segment
		(start 128.809496 -175.170592)
		(end 129.192782 -175.553878)
		(width 0.1143)
		(layer "In6.Cu")
		(net "UART3_RESET_N")
	)
	(segment
		(start 128.347216 -175.170592)
		(end 128.809496 -175.170592)
		(width 0.1143)
		(layer "In6.Cu")
		(net "UART3_RESET_N")
	)
	(segment
		(start 121.93778 -172.409866)
		(end 122.160284 -172.187362)
		(width 0.1143)
		(layer "In6.Cu")
		(net "UART3_RESET_N")
	)
	(segment
		(start 131.633976 -175.933862)
		(end 138.914886 -175.933862)
		(width 0.1143)
		(layer "In6.Cu")
		(net "UART3_RESET_N")
	)
	(segment
		(start 131.100576 -175.400462)
		(end 131.633976 -175.933862)
		(width 0.1143)
		(layer "In6.Cu")
		(net "UART3_RESET_N")
	)
	(segment
		(start 119.33174 -170.1673)
		(end 121.574306 -172.409866)
		(width 0.1143)
		(layer "In6.Cu")
		(net "UART3_RESET_N")
	)
	(segment
		(start 140.025882 -177.044858)
		(end 140.025882 -177.607722)
		(width 0.1143)
		(layer "In6.Cu")
		(net "UART3_RESET_N")
	)
	(segment
		(start 130.73634 -175.400462)
		(end 131.100576 -175.400462)
		(width 0.1143)
		(layer "In6.Cu")
		(net "UART3_RESET_N")
	)
	(segment
		(start 125.820678 -173.070012)
		(end 126.464822 -173.070012)
		(width 0.1143)
		(layer "In6.Cu")
		(net "UART3_RESET_N")
	)
	(segment
		(start 129.192782 -175.553878)
		(end 130.582924 -175.553878)
		(width 0.1143)
		(layer "In6.Cu")
		(net "UART3_RESET_N")
	)
	(segment
		(start 127.53848 -174.14367)
		(end 127.53848 -174.361856)
		(width 0.1143)
		(layer "In6.Cu")
		(net "UART3_RESET_N")
	)
	(segment
		(start 121.574306 -172.409866)
		(end 121.93778 -172.409866)
		(width 0.1143)
		(layer "In6.Cu")
		(net "UART3_RESET_N")
	)
	(segment
		(start 124.938028 -172.187362)
		(end 125.820678 -173.070012)
		(width 0.1143)
		(layer "In6.Cu")
		(net "UART3_RESET_N")
	)
	(segment
		(start 127.53848 -174.361856)
		(end 128.347216 -175.170592)
		(width 0.1143)
		(layer "In6.Cu")
		(net "UART3_RESET_N")
	)
	(segment
		(start 126.464822 -173.070012)
		(end 127.53848 -174.14367)
		(width 0.1143)
		(layer "In6.Cu")
		(net "UART3_RESET_N")
	)
	(segment
		(start 122.160284 -172.187362)
		(end 124.938028 -172.187362)
		(width 0.1143)
		(layer "In6.Cu")
		(net "UART3_RESET_N")
	)
	(segment
		(start 130.582924 -175.553878)
		(end 130.73634 -175.400462)
		(width 0.1143)
		(layer "In6.Cu")
		(net "UART3_RESET_N")
	)
	(segment
		(start 105.770426 -170.965876)
		(end 104.67721 -170.965876)
		(width 0.1016)
		(layer "F.Cu")
		(net "FNACTRL1_ADD")
	)
	(segment
		(start 104.492298 -170.927268)
		(end 104.56545 -170.854116)
		(width 0.1016)
		(layer "F.Cu")
		(net "FNACTRL1_ADD")
	)
	(segment
		(start 104.67721 -170.965876)
		(end 104.56545 -170.854116)
		(width 0.1016)
		(layer "F.Cu")
		(net "FNACTRL1_ADD")
	)
	(segment
		(start 105.770426 -171.990512)
		(end 105.770426 -170.965876)
		(width 0.1016)
		(layer "F.Cu")
		(net "FNACTRL1_ADD")
	)
	(segment
		(start 103.214932 -170.927268)
		(end 104.492298 -170.927268)
		(width 0.1016)
		(layer "F.Cu")
		(net "FNACTRL1_ADD")
	)
	(via
		(at 104.56545 -170.854116)
		(size 0.508)
		(drill 0.254)
		(layers "F.Cu" "B.Cu")
		(net "FNACTRL1_ADD")
	)
	(segment
		(start 104.95407 -172.832268)
		(end 105.065322 -172.721016)
		(width 0.1016)
		(layer "F.Cu")
		(net "I2C_ALERT_FNACTRL1_N")
	)
	(segment
		(start 105.770426 -173.004988)
		(end 105.349294 -173.004988)
		(width 0.1016)
		(layer "F.Cu")
		(net "I2C_ALERT_FNACTRL1_N")
	)
	(segment
		(start 105.349294 -173.004988)
		(end 105.065322 -172.721016)
		(width 0.1016)
		(layer "F.Cu")
		(net "I2C_ALERT_FNACTRL1_N")
	)
	(segment
		(start 103.214932 -172.832268)
		(end 104.95407 -172.832268)
		(width 0.1016)
		(layer "F.Cu")
		(net "I2C_ALERT_FNACTRL1_N")
	)
	(via
		(at 105.065322 -172.721016)
		(size 0.508)
		(drill 0.254)
		(layers "F.Cu" "B.Cu")
		(net "I2C_ALERT_FNACTRL1_N")
	)
	(segment
		(start 44.367196 -186.12485)
		(end 44.939712 -185.552334)
		(width 0.1016)
		(layer "F.Cu")
		(net "MATE_N")
	)
	(segment
		(start 45.641006 -182.63743)
		(end 45.92828 -182.350156)
		(width 0.1016)
		(layer "F.Cu")
		(net "MATE_N")
	)
	(segment
		(start 44.939712 -185.552334)
		(end 44.939712 -185.27903)
		(width 0.1016)
		(layer "F.Cu")
		(net "MATE_N")
	)
	(segment
		(start 44.939712 -185.27903)
		(end 45.641006 -184.577736)
		(width 0.1016)
		(layer "F.Cu")
		(net "MATE_N")
	)
	(segment
		(start 45.641006 -184.577736)
		(end 45.641006 -184.016142)
		(width 0.1016)
		(layer "F.Cu")
		(net "MATE_N")
	)
	(segment
		(start 43.80357 -186.12485)
		(end 44.367196 -186.12485)
		(width 0.1016)
		(layer "F.Cu")
		(net "MATE_N")
	)
	(segment
		(start 45.641006 -184.016142)
		(end 45.641006 -182.63743)
		(width 0.1016)
		(layer "F.Cu")
		(net "MATE_N")
	)
	(via
		(at 45.92828 -182.350156)
		(size 0.508)
		(drill 0.254)
		(layers "F.Cu" "B.Cu")
		(net "MATE_N")
	)
	(segment
		(start 33.0962 -186.3852)
		(end 33.0962 -184.3532)
		(width 0.1016)
		(layer "B.Cu")
		(net "MATE_N")
	)
	(segment
		(start 10.2616 -102.0318)
		(end 13.0048 -102.0318)
		(width 0.1016)
		(layer "B.Cu")
		(net "MATE_N")
	)
	(segment
		(start 11.8364 -135.3566)
		(end 8.4582 -135.3566)
		(width 0.1016)
		(layer "B.Cu")
		(net "MATE_N")
	)
	(segment
		(start 45.642022 -182.636414)
		(end 45.92828 -182.350156)
		(width 0.1016)
		(layer "B.Cu")
		(net "MATE_N")
	)
	(segment
		(start 31.0388 -40.9956)
		(end 28.6766 -38.6334)
		(width 0.1016)
		(layer "B.Cu")
		(net "MATE_N")
	)
	(segment
		(start 43.8912 -186.2582)
		(end 43.8912 -190.1698)
		(width 0.1016)
		(layer "B.Cu")
		(net "MATE_N")
	)
	(segment
		(start 6.1214 -133.0198)
		(end 6.1214 -106.172)
		(width 0.1016)
		(layer "B.Cu")
		(net "MATE_N")
	)
	(segment
		(start 33.0962 -184.3532)
		(end 34.036 -183.4134)
		(width 0.1016)
		(layer "B.Cu")
		(net "MATE_N")
	)
	(segment
		(start 8.4582 -135.3566)
		(end 6.1214 -133.0198)
		(width 0.1016)
		(layer "B.Cu")
		(net "MATE_N")
	)
	(segment
		(start 45.642022 -184.522618)
		(end 45.642022 -182.636414)
		(width 0.1016)
		(layer "B.Cu")
		(net "MATE_N")
	)
	(segment
		(start 43.1038 -185.4708)
		(end 43.8912 -186.2582)
		(width 0.1016)
		(layer "B.Cu")
		(net "MATE_N")
	)
	(segment
		(start 16.103092 -38.6334)
		(end 5.298186 -27.828494)
		(width 0.1016)
		(layer "B.Cu")
		(net "MATE_N")
	)
	(segment
		(start 43.6626 -184.2008)
		(end 43.1038 -184.7596)
		(width 0.1016)
		(layer "B.Cu")
		(net "MATE_N")
	)
	(segment
		(start 33.7566 -189.9666)
		(end 33.7566 -187.0456)
		(width 0.1016)
		(layer "B.Cu")
		(net "MATE_N")
	)
	(segment
		(start 44.898818 -184.522618)
		(end 44.577 -184.2008)
		(width 0.1016)
		(layer "B.Cu")
		(net "MATE_N")
	)
	(segment
		(start 6.1214 -106.172)
		(end 10.2616 -102.0318)
		(width 0.1016)
		(layer "B.Cu")
		(net "MATE_N")
	)
	(segment
		(start 28.6766 -38.6334)
		(end 16.103092 -38.6334)
		(width 0.1016)
		(layer "B.Cu")
		(net "MATE_N")
	)
	(segment
		(start 13.9954 -140.2588)
		(end 13.9954 -137.5156)
		(width 0.1016)
		(layer "B.Cu")
		(net "MATE_N")
	)
	(segment
		(start 32.2072 -155.2702)
		(end 30.5054 -153.5684)
		(width 0.1016)
		(layer "B.Cu")
		(net "MATE_N")
	)
	(segment
		(start 45.642022 -184.522618)
		(end 44.898818 -184.522618)
		(width 0.1016)
		(layer "B.Cu")
		(net "MATE_N")
	)
	(segment
		(start 44.577 -184.2008)
		(end 43.6626 -184.2008)
		(width 0.1016)
		(layer "B.Cu")
		(net "MATE_N")
	)
	(segment
		(start 34.417 -190.627)
		(end 33.7566 -189.9666)
		(width 0.1016)
		(layer "B.Cu")
		(net "MATE_N")
	)
	(segment
		(start 34.036 -181.864)
		(end 32.3088 -180.1368)
		(width 0.1016)
		(layer "B.Cu")
		(net "MATE_N")
	)
	(segment
		(start 31.0388 -62.7126)
		(end 31.0388 -40.9956)
		(width 0.1016)
		(layer "B.Cu")
		(net "MATE_N")
	)
	(segment
		(start 23.3934 -153.5684)
		(end 20.6248 -150.7998)
		(width 0.1016)
		(layer "B.Cu")
		(net "MATE_N")
	)
	(segment
		(start 11.5062 -142.748)
		(end 13.9954 -140.2588)
		(width 0.1016)
		(layer "B.Cu")
		(net "MATE_N")
	)
	(segment
		(start 20.6248 -150.7998)
		(end 14.7574 -150.7998)
		(width 0.1016)
		(layer "B.Cu")
		(net "MATE_N")
	)
	(segment
		(start 28.3718 -65.3796)
		(end 31.0388 -62.7126)
		(width 0.1016)
		(layer "B.Cu")
		(net "MATE_N")
	)
	(segment
		(start 14.7574 -150.7998)
		(end 11.5062 -147.5486)
		(width 0.1016)
		(layer "B.Cu")
		(net "MATE_N")
	)
	(segment
		(start 32.3088 -170.5356)
		(end 31.496 -169.7228)
		(width 0.1016)
		(layer "B.Cu")
		(net "MATE_N")
	)
	(segment
		(start 34.036 -183.4134)
		(end 34.036 -181.864)
		(width 0.1016)
		(layer "B.Cu")
		(net "MATE_N")
	)
	(segment
		(start 33.7566 -187.0456)
		(end 33.0962 -186.3852)
		(width 0.1016)
		(layer "B.Cu")
		(net "MATE_N")
	)
	(segment
		(start 32.2072 -168.1226)
		(end 32.2072 -155.2702)
		(width 0.1016)
		(layer "B.Cu")
		(net "MATE_N")
	)
	(segment
		(start 30.5054 -153.5684)
		(end 23.3934 -153.5684)
		(width 0.1016)
		(layer "B.Cu")
		(net "MATE_N")
	)
	(segment
		(start 13.0048 -102.0318)
		(end 15.3416 -99.695)
		(width 0.1016)
		(layer "B.Cu")
		(net "MATE_N")
	)
	(segment
		(start 15.3416 -89.9668)
		(end 28.3718 -76.9366)
		(width 0.1016)
		(layer "B.Cu")
		(net "MATE_N")
	)
	(segment
		(start 43.1038 -184.7596)
		(end 43.1038 -185.4708)
		(width 0.1016)
		(layer "B.Cu")
		(net "MATE_N")
	)
	(segment
		(start 28.3718 -76.9366)
		(end 28.3718 -65.3796)
		(width 0.1016)
		(layer "B.Cu")
		(net "MATE_N")
	)
	(segment
		(start 43.434 -190.627)
		(end 34.417 -190.627)
		(width 0.1016)
		(layer "B.Cu")
		(net "MATE_N")
	)
	(segment
		(start 13.9954 -137.5156)
		(end 11.8364 -135.3566)
		(width 0.1016)
		(layer "B.Cu")
		(net "MATE_N")
	)
	(segment
		(start 32.3088 -180.1368)
		(end 32.3088 -170.5356)
		(width 0.1016)
		(layer "B.Cu")
		(net "MATE_N")
	)
	(segment
		(start 11.5062 -147.5486)
		(end 11.5062 -142.748)
		(width 0.1016)
		(layer "B.Cu")
		(net "MATE_N")
	)
	(segment
		(start 31.496 -168.8338)
		(end 32.2072 -168.1226)
		(width 0.1016)
		(layer "B.Cu")
		(net "MATE_N")
	)
	(segment
		(start 43.8912 -190.1698)
		(end 43.434 -190.627)
		(width 0.1016)
		(layer "B.Cu")
		(net "MATE_N")
	)
	(segment
		(start 15.3416 -99.695)
		(end 15.3416 -89.9668)
		(width 0.1016)
		(layer "B.Cu")
		(net "MATE_N")
	)
	(segment
		(start 31.496 -169.7228)
		(end 31.496 -168.8338)
		(width 0.1016)
		(layer "B.Cu")
		(net "MATE_N")
	)
	(segment
		(start 35.255454 -183.415178)
		(end 34.904172 -183.415178)
		(width 0.508)
		(layer "F.Cu")
		(net "P12V_PDB")
	)
	(segment
		(start 45.285406 -176.28616)
		(end 45.96257 -176.28616)
		(width 0.508)
		(layer "F.Cu")
		(net "P12V_PDB")
	)
	(segment
		(start 36.729416 -185.559954)
		(end 37.682424 -185.559954)
		(width 0.508)
		(layer "F.Cu")
		(net "P12V_PDB")
	)
	(segment
		(start 35.668712 -184.193942)
		(end 35.668712 -183.828436)
		(width 0.508)
		(layer "F.Cu")
		(net "P12V_PDB")
	)
	(segment
		(start 46.815248 -176.740566)
		(end 46.2153 -177.340514)
		(width 0.508)
		(layer "F.Cu")
		(net "P12V_PDB")
	)
	(segment
		(start 38.126416 -186.003946)
		(end 38.126416 -186.583066)
		(width 0.508)
		(layer "F.Cu")
		(net "P12V_PDB")
	)
	(segment
		(start 35.668712 -183.828436)
		(end 35.255454 -183.415178)
		(width 0.508)
		(layer "F.Cu")
		(net "P12V_PDB")
	)
	(segment
		(start 35.668712 -184.193942)
		(end 35.668712 -184.49925)
		(width 0.508)
		(layer "F.Cu")
		(net "P12V_PDB")
	)
	(segment
		(start 34.904172 -183.415178)
		(end 34.63925 -183.150256)
		(width 0.508)
		(layer "F.Cu")
		(net "P12V_PDB")
	)
	(segment
		(start 45.96257 -176.28616)
		(end 46.162976 -176.486566)
		(width 0.508)
		(layer "F.Cu")
		(net "P12V_PDB")
	)
	(segment
		(start 35.668712 -184.49925)
		(end 36.729416 -185.559954)
		(width 0.508)
		(layer "F.Cu")
		(net "P12V_PDB")
	)
	(segment
		(start 37.682424 -185.559954)
		(end 38.126416 -186.003946)
		(width 0.508)
		(layer "F.Cu")
		(net "P12V_PDB")
	)
	(segment
		(start 46.815248 -176.247298)
		(end 46.815248 -176.740566)
		(width 0.508)
		(layer "F.Cu")
		(net "P12V_PDB")
	)
	(segment
		(start 34.63925 -183.150256)
		(end 34.63925 -182.215282)
		(width 0.254)
		(layer "F.Cu")
		(net "P12V_PDB")
	)
	(via
		(at 12.14628 -101.302058)
		(size 0.508)
		(drill 0.254)
		(layers "F.Cu" "B.Cu")
		(net "P12V_PDB")
	)
	(via
		(at 12.62888 -169.776648)
		(size 0.508)
		(drill 0.254)
		(layers "F.Cu" "B.Cu")
		(net "P12V_PDB")
	)
	(via
		(at 12.6365 -98.37547)
		(size 0.508)
		(drill 0.254)
		(layers "F.Cu" "B.Cu")
		(net "P12V_PDB")
	)
	(via
		(at 46.162976 -176.486566)
		(size 0.508)
		(drill 0.254)
		(layers "F.Cu" "B.Cu")
		(net "P12V_PDB")
	)
	(via
		(at 36.84016 -188.148214)
		(size 0.508)
		(drill 0.254)
		(layers "F.Cu" "B.Cu")
		(net "P12V_PDB")
	)
	(via
		(at 16.45666 -197.301358)
		(size 0.508)
		(drill 0.254)
		(layers "F.Cu" "B.Cu")
		(net "P12V_PDB")
	)
	(via
		(at 46.2153 -177.340514)
		(size 0.508)
		(drill 0.254)
		(layers "F.Cu" "B.Cu")
		(net "P12V_PDB")
	)
	(via
		(at 2.96672 -166.70909)
		(size 0.508)
		(drill 0.254)
		(layers "F.Cu" "B.Cu")
		(net "P12V_PDB")
	)
	(via
		(at 3.556 -167.225726)
		(size 0.508)
		(drill 0.254)
		(layers "F.Cu" "B.Cu")
		(net "P12V_PDB")
	)
	(via
		(at 14.94536 -198.906638)
		(size 0.508)
		(drill 0.254)
		(layers "F.Cu" "B.Cu")
		(net "P12V_PDB")
	)
	(via
		(at 39.42842 -188.025786)
		(size 0.508)
		(drill 0.254)
		(layers "F.Cu" "B.Cu")
		(net "P12V_PDB")
	)
	(via
		(at 2.37744 -166.101522)
		(size 0.508)
		(drill 0.254)
		(layers "F.Cu" "B.Cu")
		(net "P12V_PDB")
	)
	(via
		(at 17.18564 -197.980808)
		(size 0.508)
		(drill 0.254)
		(layers "F.Cu" "B.Cu")
		(net "P12V_PDB")
	)
	(via
		(at 15.33398 -197.322694)
		(size 0.508)
		(drill 0.254)
		(layers "F.Cu" "B.Cu")
		(net "P12V_PDB")
	)
	(via
		(at 3.5433 -98.708464)
		(size 0.508)
		(drill 0.254)
		(layers "F.Cu" "B.Cu")
		(net "P12V_PDB")
	)
	(via
		(at 36.736274 -186.93257)
		(size 0.508)
		(drill 0.254)
		(layers "F.Cu" "B.Cu")
		(net "P12V_PDB")
	)
	(via
		(at 4.62534 -98.17862)
		(size 0.508)
		(drill 0.254)
		(layers "F.Cu" "B.Cu")
		(net "P12V_PDB")
	)
	(via
		(at 15.82166 -198.025766)
		(size 0.508)
		(drill 0.254)
		(layers "F.Cu" "B.Cu")
		(net "P12V_PDB")
	)
	(via
		(at 3.61696 -100.295964)
		(size 0.508)
		(drill 0.254)
		(layers "F.Cu" "B.Cu")
		(net "P12V_PDB")
	)
	(via
		(at 40.355774 -185.619136)
		(size 0.508)
		(drill 0.254)
		(layers "F.Cu" "B.Cu")
		(net "P12V_PDB")
	)
	(via
		(at 39.36238 -187.189364)
		(size 0.508)
		(drill 0.254)
		(layers "F.Cu" "B.Cu")
		(net "P12V_PDB")
	)
	(via
		(at 12.91336 -100.523294)
		(size 0.508)
		(drill 0.254)
		(layers "F.Cu" "B.Cu")
		(net "P12V_PDB")
	)
	(via
		(at 2.35204 -167.213534)
		(size 0.508)
		(drill 0.254)
		(layers "F.Cu" "B.Cu")
		(net "P12V_PDB")
	)
	(via
		(at 42.562272 -188.80709)
		(size 0.508)
		(drill 0.254)
		(layers "F.Cu" "B.Cu")
		(net "P12V_PDB")
	)
	(via
		(at 15.05204 -198.07301)
		(size 0.508)
		(drill 0.254)
		(layers "F.Cu" "B.Cu")
		(net "P12V_PDB")
	)
	(via
		(at 41.143174 -185.619136)
		(size 0.508)
		(drill 0.254)
		(layers "F.Cu" "B.Cu")
		(net "P12V_PDB")
	)
	(via
		(at 15.93342 -198.804276)
		(size 0.508)
		(drill 0.254)
		(layers "F.Cu" "B.Cu")
		(net "P12V_PDB")
	)
	(via
		(at 37.41166 -189.004702)
		(size 0.508)
		(drill 0.254)
		(layers "F.Cu" "B.Cu")
		(net "P12V_PDB")
	)
	(via
		(at 3.59156 -99.523804)
		(size 0.508)
		(drill 0.254)
		(layers "F.Cu" "B.Cu")
		(net "P12V_PDB")
	)
	(via
		(at 13.13688 -97.741232)
		(size 0.508)
		(drill 0.254)
		(layers "F.Cu" "B.Cu")
		(net "P12V_PDB")
	)
	(via
		(at 39.2176 -189.061598)
		(size 0.508)
		(drill 0.254)
		(layers "F.Cu" "B.Cu")
		(net "P12V_PDB")
	)
	(via
		(at 3.40106 -100.975922)
		(size 0.508)
		(drill 0.254)
		(layers "F.Cu" "B.Cu")
		(net "P12V_PDB")
	)
	(via
		(at 13.54836 -99.855528)
		(size 0.508)
		(drill 0.254)
		(layers "F.Cu" "B.Cu")
		(net "P12V_PDB")
	)
	(via
		(at 16.98244 -198.809864)
		(size 0.508)
		(drill 0.254)
		(layers "F.Cu" "B.Cu")
		(net "P12V_PDB")
	)
	(via
		(at 41.31056 -188.957458)
		(size 0.508)
		(drill 0.254)
		(layers "F.Cu" "B.Cu")
		(net "P12V_PDB")
	)
	(via
		(at 3.59918 -166.113714)
		(size 0.508)
		(drill 0.254)
		(layers "F.Cu" "B.Cu")
		(net "P12V_PDB")
	)
	(via
		(at 42.062146 -185.540904)
		(size 0.508)
		(drill 0.254)
		(layers "F.Cu" "B.Cu")
		(net "P12V_PDB")
	)
	(via
		(at 40.37838 -188.957458)
		(size 0.508)
		(drill 0.254)
		(layers "F.Cu" "B.Cu")
		(net "P12V_PDB")
	)
	(segment
		(start 102.433882 -175.553624)
		(end 101.845872 -174.965614)
		(width 0.1016)
		(layer "F.Cu")
		(net "I2C_COM3_SDA")
	)
	(segment
		(start 104.6734 -176.068482)
		(end 104.158542 -175.553624)
		(width 0.1016)
		(layer "F.Cu")
		(net "I2C_COM3_SDA")
	)
	(segment
		(start 115.54079 -171.971716)
		(end 114.76736 -171.971716)
		(width 0.1016)
		(layer "F.Cu")
		(net "I2C_COM3_SDA")
	)
	(segment
		(start 103.103172 -175.553624)
		(end 102.433882 -175.553624)
		(width 0.1016)
		(layer "F.Cu")
		(net "I2C_COM3_SDA")
	)
	(segment
		(start 113.598706 -171.609512)
		(end 113.96091 -171.971716)
		(width 0.1016)
		(layer "F.Cu")
		(net "I2C_COM3_SDA")
	)
	(segment
		(start 106.116374 -175.07966)
		(end 105.528364 -175.07966)
		(width 0.1016)
		(layer "F.Cu")
		(net "I2C_COM3_SDA")
	)
	(segment
		(start 104.158542 -175.553624)
		(end 103.103172 -175.553624)
		(width 0.1016)
		(layer "F.Cu")
		(net "I2C_COM3_SDA")
	)
	(segment
		(start 101.845872 -174.965614)
		(end 101.845872 -174.421546)
		(width 0.1016)
		(layer "F.Cu")
		(net "I2C_COM3_SDA")
	)
	(segment
		(start 112.467644 -164.305234)
		(end 112.954816 -164.305234)
		(width 0.1016)
		(layer "F.Cu")
		(net "I2C_COM3_SDA")
	)
	(segment
		(start 119.374158 -171.829984)
		(end 119.065802 -172.13834)
		(width 0.1016)
		(layer "F.Cu")
		(net "I2C_COM3_SDA")
	)
	(segment
		(start 112.954816 -164.305234)
		(end 113.411 -163.84905)
		(width 0.1016)
		(layer "F.Cu")
		(net "I2C_COM3_SDA")
	)
	(segment
		(start 104.871012 -175.737012)
		(end 104.871012 -176.068482)
		(width 0.1016)
		(layer "F.Cu")
		(net "I2C_COM3_SDA")
	)
	(segment
		(start 112.27181 -171.609512)
		(end 113.598706 -171.609512)
		(width 0.1016)
		(layer "F.Cu")
		(net "I2C_COM3_SDA")
	)
	(segment
		(start 113.96091 -171.971716)
		(end 114.76736 -171.971716)
		(width 0.1016)
		(layer "F.Cu")
		(net "I2C_COM3_SDA")
	)
	(segment
		(start 105.528364 -175.07966)
		(end 104.871012 -175.737012)
		(width 0.1016)
		(layer "F.Cu")
		(net "I2C_COM3_SDA")
	)
	(segment
		(start 119.065802 -172.13834)
		(end 115.707414 -172.13834)
		(width 0.1016)
		(layer "F.Cu")
		(net "I2C_COM3_SDA")
	)
	(segment
		(start 115.707414 -172.13834)
		(end 115.54079 -171.971716)
		(width 0.1016)
		(layer "F.Cu")
		(net "I2C_COM3_SDA")
	)
	(segment
		(start 104.871012 -176.068482)
		(end 104.6734 -176.068482)
		(width 0.1016)
		(layer "F.Cu")
		(net "I2C_COM3_SDA")
	)
	(via
		(at 152.586944 -169.77995)
		(size 0.508)
		(drill 0.254)
		(layers "F.Cu" "B.Cu")
		(net "I2C_COM3_SDA")
	)
	(via
		(at 101.845872 -174.421546)
		(size 0.508)
		(drill 0.254)
		(layers "F.Cu" "B.Cu")
		(net "I2C_COM3_SDA")
	)
	(via
		(at 119.374158 -171.829984)
		(size 0.508)
		(drill 0.254)
		(layers "F.Cu" "B.Cu")
		(net "I2C_COM3_SDA")
	)
	(via
		(at 104.871012 -176.068482)
		(size 0.508)
		(drill 0.254)
		(layers "F.Cu" "B.Cu")
		(net "I2C_COM3_SDA")
	)
	(via
		(at 155.680156 -179.73802)
		(size 0.508)
		(drill 0.254)
		(layers "F.Cu" "B.Cu")
		(net "I2C_COM3_SDA")
	)
	(via
		(at 113.411 -163.84905)
		(size 0.508)
		(drill 0.254)
		(layers "F.Cu" "B.Cu")
		(net "I2C_COM3_SDA")
	)
	(via
		(at 85.32241 -171.452794)
		(size 0.508)
		(drill 0.254)
		(layers "F.Cu" "B.Cu")
		(net "I2C_COM3_SDA")
	)
	(via
		(at 50.975768 -178.836574)
		(size 0.508)
		(drill 0.254)
		(layers "F.Cu" "B.Cu")
		(net "I2C_COM3_SDA")
	)
	(segment
		(start 118.586504 -174.27956)
		(end 119.36476 -174.27956)
		(width 0.1016)
		(layer "B.Cu")
		(net "I2C_COM3_SDA")
	)
	(segment
		(start 119.676418 -172.87748)
		(end 119.423688 -173.13021)
		(width 0.1016)
		(layer "B.Cu")
		(net "I2C_COM3_SDA")
	)
	(segment
		(start 114.01806 -163.24199)
		(end 113.411 -163.84905)
		(width 0.1016)
		(layer "B.Cu")
		(net "I2C_COM3_SDA")
	)
	(segment
		(start 86.360254 -170.814746)
		(end 86.70544 -170.46956)
		(width 0.1016)
		(layer "B.Cu")
		(net "I2C_COM3_SDA")
	)
	(segment
		(start 152.40889 -169.77995)
		(end 152.586944 -169.77995)
		(width 0.1016)
		(layer "B.Cu")
		(net "I2C_COM3_SDA")
	)
	(segment
		(start 52.30876 -179.240688)
		(end 51.379882 -179.240688)
		(width 0.1016)
		(layer "B.Cu")
		(net "I2C_COM3_SDA")
	)
	(segment
		(start 85.49132 -171.452794)
		(end 86.129368 -170.814746)
		(width 0.1016)
		(layer "B.Cu")
		(net "I2C_COM3_SDA")
	)
	(segment
		(start 101.877114 -174.421546)
		(end 101.845872 -174.421546)
		(width 0.1016)
		(layer "B.Cu")
		(net "I2C_COM3_SDA")
	)
	(segment
		(start 86.129368 -170.814746)
		(end 86.360254 -170.814746)
		(width 0.1016)
		(layer "B.Cu")
		(net "I2C_COM3_SDA")
	)
	(segment
		(start 114.092482 -164.491416)
		(end 114.053366 -164.491416)
		(width 0.1016)
		(layer "B.Cu")
		(net "I2C_COM3_SDA")
	)
	(segment
		(start 119.423688 -173.13021)
		(end 118.685564 -173.13021)
		(width 0.1016)
		(layer "B.Cu")
		(net "I2C_COM3_SDA")
	)
	(segment
		(start 114.611404 -163.24199)
		(end 114.01806 -163.24199)
		(width 0.1016)
		(layer "B.Cu")
		(net "I2C_COM3_SDA")
	)
	(segment
		(start 103.36276 -173.64456)
		(end 102.6541 -173.64456)
		(width 0.1016)
		(layer "B.Cu")
		(net "I2C_COM3_SDA")
	)
	(segment
		(start 86.70544 -170.46956)
		(end 87.74176 -170.46956)
		(width 0.1016)
		(layer "B.Cu")
		(net "I2C_COM3_SDA")
	)
	(segment
		(start 118.685564 -173.13021)
		(end 118.43766 -173.378114)
		(width 0.1016)
		(layer "B.Cu")
		(net "I2C_COM3_SDA")
	)
	(segment
		(start 119.676418 -172.132244)
		(end 119.676418 -172.87748)
		(width 0.1016)
		(layer "B.Cu")
		(net "I2C_COM3_SDA")
	)
	(segment
		(start 119.374158 -171.829984)
		(end 119.676418 -172.132244)
		(width 0.1016)
		(layer "B.Cu")
		(net "I2C_COM3_SDA")
	)
	(segment
		(start 150.98776 -170.59656)
		(end 151.59228 -170.59656)
		(width 0.1016)
		(layer "B.Cu")
		(net "I2C_COM3_SDA")
	)
	(segment
		(start 118.43766 -174.130716)
		(end 118.586504 -174.27956)
		(width 0.1016)
		(layer "B.Cu")
		(net "I2C_COM3_SDA")
	)
	(segment
		(start 151.59228 -170.59656)
		(end 152.40889 -169.77995)
		(width 0.1016)
		(layer "B.Cu")
		(net "I2C_COM3_SDA")
	)
	(segment
		(start 85.32241 -171.452794)
		(end 85.49132 -171.452794)
		(width 0.1016)
		(layer "B.Cu")
		(net "I2C_COM3_SDA")
	)
	(segment
		(start 118.43766 -173.378114)
		(end 118.43766 -174.130716)
		(width 0.1016)
		(layer "B.Cu")
		(net "I2C_COM3_SDA")
	)
	(segment
		(start 114.053366 -164.491416)
		(end 113.411 -163.84905)
		(width 0.1016)
		(layer "B.Cu")
		(net "I2C_COM3_SDA")
	)
	(segment
		(start 51.379882 -179.240688)
		(end 50.975768 -178.836574)
		(width 0.1016)
		(layer "B.Cu")
		(net "I2C_COM3_SDA")
	)
	(segment
		(start 102.6541 -173.64456)
		(end 101.877114 -174.421546)
		(width 0.1016)
		(layer "B.Cu")
		(net "I2C_COM3_SDA")
	)
	(segment
		(start 118.63578 -164.898832)
		(end 116.765832 -164.898832)
		(width 0.1143)
		(layer "In6.Cu")
		(net "I2C_COM3_SDA")
	)
	(segment
		(start 101.28885 -174.421546)
		(end 101.845872 -174.421546)
		(width 0.1143)
		(layer "In6.Cu")
		(net "I2C_COM3_SDA")
	)
	(segment
		(start 145.455894 -178.833272)
		(end 140.631672 -178.833272)
		(width 0.1143)
		(layer "In6.Cu")
		(net "I2C_COM3_SDA")
	)
	(segment
		(start 121.287794 -173.74362)
		(end 119.374158 -171.829984)
		(width 0.1143)
		(layer "In6.Cu")
		(net "I2C_COM3_SDA")
	)
	(segment
		(start 126.312168 -173.438312)
		(end 125.948948 -173.438312)
		(width 0.1143)
		(layer "In6.Cu")
		(net "I2C_COM3_SDA")
	)
	(segment
		(start 142.77721 -166.17442)
		(end 142.77721 -165.354508)
		(width 0.1143)
		(layer "In6.Cu")
		(net "I2C_COM3_SDA")
	)
	(segment
		(start 99.712526 -172.845222)
		(end 101.28885 -174.421546)
		(width 0.1143)
		(layer "In6.Cu")
		(net "I2C_COM3_SDA")
	)
	(segment
		(start 121.55932 -163.04895)
		(end 120.307862 -164.300408)
		(width 0.1143)
		(layer "In6.Cu")
		(net "I2C_COM3_SDA")
	)
	(segment
		(start 122.811032 -161.797238)
		(end 121.921524 -162.686746)
		(width 0.1143)
		(layer "In6.Cu")
		(net "I2C_COM3_SDA")
	)
	(segment
		(start 127.055626 -174.656242)
		(end 127.055626 -174.18177)
		(width 0.1143)
		(layer "In6.Cu")
		(net "I2C_COM3_SDA")
	)
	(segment
		(start 121.81586 -162.686746)
		(end 121.55932 -162.943286)
		(width 0.1143)
		(layer "In6.Cu")
		(net "I2C_COM3_SDA")
	)
	(segment
		(start 116.765832 -164.898832)
		(end 116.7638 -164.8968)
		(width 0.1143)
		(layer "In6.Cu")
		(net "I2C_COM3_SDA")
	)
	(segment
		(start 128.701546 -176.302162)
		(end 127.055626 -174.656242)
		(width 0.1143)
		(layer "In6.Cu")
		(net "I2C_COM3_SDA")
	)
	(segment
		(start 121.95302 -173.74362)
		(end 121.287794 -173.74362)
		(width 0.1143)
		(layer "In6.Cu")
		(net "I2C_COM3_SDA")
	)
	(segment
		(start 152.586944 -169.77995)
		(end 147.443444 -169.77995)
		(width 0.1143)
		(layer "In6.Cu")
		(net "I2C_COM3_SDA")
	)
	(segment
		(start 152.131268 -178.197764)
		(end 146.091402 -178.197764)
		(width 0.1143)
		(layer "In6.Cu")
		(net "I2C_COM3_SDA")
	)
	(segment
		(start 84.133436 -170.26382)
		(end 85.32241 -171.452794)
		(width 0.1143)
		(layer "In6.Cu")
		(net "I2C_COM3_SDA")
	)
	(segment
		(start 120.307862 -164.300408)
		(end 119.234204 -164.300408)
		(width 0.1143)
		(layer "In6.Cu")
		(net "I2C_COM3_SDA")
	)
	(segment
		(start 125.948948 -173.438312)
		(end 125.632972 -173.754288)
		(width 0.1143)
		(layer "In6.Cu")
		(net "I2C_COM3_SDA")
	)
	(segment
		(start 139.87526 -162.452558)
		(end 130.86334 -162.452558)
		(width 0.1143)
		(layer "In6.Cu")
		(net "I2C_COM3_SDA")
	)
	(segment
		(start 94.506796 -172.559726)
		(end 94.966536 -173.019466)
		(width 0.1143)
		(layer "In6.Cu")
		(net "I2C_COM3_SDA")
	)
	(segment
		(start 143.03375 -166.43096)
		(end 142.77721 -166.17442)
		(width 0.1143)
		(layer "In6.Cu")
		(net "I2C_COM3_SDA")
	)
	(segment
		(start 92.8878 -172.559726)
		(end 94.506796 -172.559726)
		(width 0.1143)
		(layer "In6.Cu")
		(net "I2C_COM3_SDA")
	)
	(segment
		(start 85.501226 -171.452794)
		(end 86.440518 -172.392086)
		(width 0.1143)
		(layer "In6.Cu")
		(net "I2C_COM3_SDA")
	)
	(segment
		(start 121.921524 -162.686746)
		(end 121.81586 -162.686746)
		(width 0.1143)
		(layer "In6.Cu")
		(net "I2C_COM3_SDA")
	)
	(segment
		(start 121.55932 -162.943286)
		(end 121.55932 -163.04895)
		(width 0.1143)
		(layer "In6.Cu")
		(net "I2C_COM3_SDA")
	)
	(segment
		(start 146.091402 -178.197764)
		(end 145.455894 -178.833272)
		(width 0.1143)
		(layer "In6.Cu")
		(net "I2C_COM3_SDA")
	)
	(segment
		(start 94.966536 -173.019466)
		(end 98.692716 -173.019466)
		(width 0.1143)
		(layer "In6.Cu")
		(net "I2C_COM3_SDA")
	)
	(segment
		(start 81.646776 -169.188892)
		(end 82.721704 -170.26382)
		(width 0.1143)
		(layer "In6.Cu")
		(net "I2C_COM3_SDA")
	)
	(segment
		(start 75.11034 -164.848032)
		(end 77.677264 -164.848032)
		(width 0.1143)
		(layer "In6.Cu")
		(net "I2C_COM3_SDA")
	)
	(segment
		(start 92.72016 -172.392086)
		(end 92.8878 -172.559726)
		(width 0.1143)
		(layer "In6.Cu")
		(net "I2C_COM3_SDA")
	)
	(segment
		(start 138.762232 -176.302162)
		(end 128.701546 -176.302162)
		(width 0.1143)
		(layer "In6.Cu")
		(net "I2C_COM3_SDA")
	)
	(segment
		(start 140.631672 -178.833272)
		(end 139.464034 -177.665634)
		(width 0.1143)
		(layer "In6.Cu")
		(net "I2C_COM3_SDA")
	)
	(segment
		(start 67.56908 -177.903124)
		(end 68.076826 -178.41087)
		(width 0.1143)
		(layer "In6.Cu")
		(net "I2C_COM3_SDA")
	)
	(segment
		(start 155.680156 -179.73802)
		(end 155.359862 -179.417726)
		(width 0.1143)
		(layer "In6.Cu")
		(net "I2C_COM3_SDA")
	)
	(segment
		(start 71.62546 -178.41087)
		(end 72.44334 -177.59299)
		(width 0.1143)
		(layer "In6.Cu")
		(net "I2C_COM3_SDA")
	)
	(segment
		(start 147.443444 -169.77995)
		(end 144.094454 -166.43096)
		(width 0.1143)
		(layer "In6.Cu")
		(net "I2C_COM3_SDA")
	)
	(segment
		(start 116.586 -164.8968)
		(end 115.53825 -163.84905)
		(width 0.1143)
		(layer "In6.Cu")
		(net "I2C_COM3_SDA")
	)
	(segment
		(start 115.53825 -163.84905)
		(end 113.411 -163.84905)
		(width 0.1143)
		(layer "In6.Cu")
		(net "I2C_COM3_SDA")
	)
	(segment
		(start 127.055626 -174.18177)
		(end 126.312168 -173.438312)
		(width 0.1143)
		(layer "In6.Cu")
		(net "I2C_COM3_SDA")
	)
	(segment
		(start 50.975768 -178.836574)
		(end 57.997852 -178.836574)
		(width 0.1143)
		(layer "In6.Cu")
		(net "I2C_COM3_SDA")
	)
	(segment
		(start 86.440518 -172.392086)
		(end 92.72016 -172.392086)
		(width 0.1143)
		(layer "In6.Cu")
		(net "I2C_COM3_SDA")
	)
	(segment
		(start 142.77721 -165.354508)
		(end 139.87526 -162.452558)
		(width 0.1143)
		(layer "In6.Cu")
		(net "I2C_COM3_SDA")
	)
	(segment
		(start 139.464034 -177.003964)
		(end 138.762232 -176.302162)
		(width 0.1143)
		(layer "In6.Cu")
		(net "I2C_COM3_SDA")
	)
	(segment
		(start 68.076826 -178.41087)
		(end 71.62546 -178.41087)
		(width 0.1143)
		(layer "In6.Cu")
		(net "I2C_COM3_SDA")
	)
	(segment
		(start 153.35123 -179.417726)
		(end 152.131268 -178.197764)
		(width 0.1143)
		(layer "In6.Cu")
		(net "I2C_COM3_SDA")
	)
	(segment
		(start 130.86334 -162.452558)
		(end 130.20802 -161.797238)
		(width 0.1143)
		(layer "In6.Cu")
		(net "I2C_COM3_SDA")
	)
	(segment
		(start 130.20802 -161.797238)
		(end 122.811032 -161.797238)
		(width 0.1143)
		(layer "In6.Cu")
		(net "I2C_COM3_SDA")
	)
	(segment
		(start 122.051826 -173.644814)
		(end 121.95302 -173.74362)
		(width 0.1143)
		(layer "In6.Cu")
		(net "I2C_COM3_SDA")
	)
	(segment
		(start 144.094454 -166.43096)
		(end 143.03375 -166.43096)
		(width 0.1143)
		(layer "In6.Cu")
		(net "I2C_COM3_SDA")
	)
	(segment
		(start 77.677264 -164.848032)
		(end 81.646776 -168.817544)
		(width 0.1143)
		(layer "In6.Cu")
		(net "I2C_COM3_SDA")
	)
	(segment
		(start 125.632972 -173.754288)
		(end 124.787152 -173.754288)
		(width 0.1143)
		(layer "In6.Cu")
		(net "I2C_COM3_SDA")
	)
	(segment
		(start 116.7638 -164.8968)
		(end 116.586 -164.8968)
		(width 0.1143)
		(layer "In6.Cu")
		(net "I2C_COM3_SDA")
	)
	(segment
		(start 81.646776 -168.817544)
		(end 81.646776 -169.188892)
		(width 0.1143)
		(layer "In6.Cu")
		(net "I2C_COM3_SDA")
	)
	(segment
		(start 98.86696 -172.845222)
		(end 99.712526 -172.845222)
		(width 0.1143)
		(layer "In6.Cu")
		(net "I2C_COM3_SDA")
	)
	(segment
		(start 85.32241 -171.452794)
		(end 85.501226 -171.452794)
		(width 0.1143)
		(layer "In6.Cu")
		(net "I2C_COM3_SDA")
	)
	(segment
		(start 119.234204 -164.300408)
		(end 118.63578 -164.898832)
		(width 0.1143)
		(layer "In6.Cu")
		(net "I2C_COM3_SDA")
	)
	(segment
		(start 72.44334 -177.59299)
		(end 72.44334 -167.515032)
		(width 0.1143)
		(layer "In6.Cu")
		(net "I2C_COM3_SDA")
	)
	(segment
		(start 124.787152 -173.754288)
		(end 124.677678 -173.644814)
		(width 0.1143)
		(layer "In6.Cu")
		(net "I2C_COM3_SDA")
	)
	(segment
		(start 124.677678 -173.644814)
		(end 122.051826 -173.644814)
		(width 0.1143)
		(layer "In6.Cu")
		(net "I2C_COM3_SDA")
	)
	(segment
		(start 72.44334 -167.515032)
		(end 75.11034 -164.848032)
		(width 0.1143)
		(layer "In6.Cu")
		(net "I2C_COM3_SDA")
	)
	(segment
		(start 58.931302 -177.903124)
		(end 67.56908 -177.903124)
		(width 0.1143)
		(layer "In6.Cu")
		(net "I2C_COM3_SDA")
	)
	(segment
		(start 139.464034 -177.665634)
		(end 139.464034 -177.003964)
		(width 0.1143)
		(layer "In6.Cu")
		(net "I2C_COM3_SDA")
	)
	(segment
		(start 57.997852 -178.836574)
		(end 58.931302 -177.903124)
		(width 0.1143)
		(layer "In6.Cu")
		(net "I2C_COM3_SDA")
	)
	(segment
		(start 98.692716 -173.019466)
		(end 98.86696 -172.845222)
		(width 0.1143)
		(layer "In6.Cu")
		(net "I2C_COM3_SDA")
	)
	(segment
		(start 155.359862 -179.417726)
		(end 153.35123 -179.417726)
		(width 0.1143)
		(layer "In6.Cu")
		(net "I2C_COM3_SDA")
	)
	(segment
		(start 82.721704 -170.26382)
		(end 84.133436 -170.26382)
		(width 0.1143)
		(layer "In6.Cu")
		(net "I2C_COM3_SDA")
	)
	(segment
		(start 119.232934 -171.971208)
		(end 119.374158 -171.829984)
		(width 0.1143)
		(layer "In7.Cu")
		(net "I2C_COM3_SDA")
	)
	(segment
		(start 104.871012 -176.068482)
		(end 104.174798 -175.372268)
		(width 0.1143)
		(layer "In7.Cu")
		(net "I2C_COM3_SDA")
	)
	(segment
		(start 109.546136 -171.171362)
		(end 112.40897 -171.171362)
		(width 0.1143)
		(layer "In7.Cu")
		(net "I2C_COM3_SDA")
	)
	(segment
		(start 113.208816 -171.971208)
		(end 119.232934 -171.971208)
		(width 0.1143)
		(layer "In7.Cu")
		(net "I2C_COM3_SDA")
	)
	(segment
		(start 105.165398 -173.699678)
		(end 106.471212 -173.699678)
		(width 0.1143)
		(layer "In7.Cu")
		(net "I2C_COM3_SDA")
	)
	(segment
		(start 153.71953 -170.581066)
		(end 152.918414 -169.77995)
		(width 0.1143)
		(layer "In7.Cu")
		(net "I2C_COM3_SDA")
	)
	(segment
		(start 154.46502 -178.522884)
		(end 153.940256 -178.522884)
		(width 0.1143)
		(layer "In7.Cu")
		(net "I2C_COM3_SDA")
	)
	(segment
		(start 152.918414 -169.77995)
		(end 152.586944 -169.77995)
		(width 0.1143)
		(layer "In7.Cu")
		(net "I2C_COM3_SDA")
	)
	(segment
		(start 108.89234 -171.27855)
		(end 109.438948 -171.27855)
		(width 0.1143)
		(layer "In7.Cu")
		(net "I2C_COM3_SDA")
	)
	(segment
		(start 104.174798 -174.577248)
		(end 104.431338 -174.320708)
		(width 0.1143)
		(layer "In7.Cu")
		(net "I2C_COM3_SDA")
	)
	(segment
		(start 104.174798 -175.372268)
		(end 104.174798 -174.577248)
		(width 0.1143)
		(layer "In7.Cu")
		(net "I2C_COM3_SDA")
	)
	(segment
		(start 153.940256 -178.522884)
		(end 153.46807 -178.050698)
		(width 0.1143)
		(layer "In7.Cu")
		(net "I2C_COM3_SDA")
	)
	(segment
		(start 155.680156 -179.73802)
		(end 154.46502 -178.522884)
		(width 0.1143)
		(layer "In7.Cu")
		(net "I2C_COM3_SDA")
	)
	(segment
		(start 153.46807 -177.3809)
		(end 153.71953 -177.12944)
		(width 0.1143)
		(layer "In7.Cu")
		(net "I2C_COM3_SDA")
	)
	(segment
		(start 112.40897 -171.171362)
		(end 113.208816 -171.971208)
		(width 0.1143)
		(layer "In7.Cu")
		(net "I2C_COM3_SDA")
	)
	(segment
		(start 106.471212 -173.699678)
		(end 108.89234 -171.27855)
		(width 0.1143)
		(layer "In7.Cu")
		(net "I2C_COM3_SDA")
	)
	(segment
		(start 153.46807 -178.050698)
		(end 153.46807 -177.3809)
		(width 0.1143)
		(layer "In7.Cu")
		(net "I2C_COM3_SDA")
	)
	(segment
		(start 104.431338 -174.320708)
		(end 104.544368 -174.320708)
		(width 0.1143)
		(layer "In7.Cu")
		(net "I2C_COM3_SDA")
	)
	(segment
		(start 153.71953 -177.12944)
		(end 153.71953 -170.581066)
		(width 0.1143)
		(layer "In7.Cu")
		(net "I2C_COM3_SDA")
	)
	(segment
		(start 109.438948 -171.27855)
		(end 109.546136 -171.171362)
		(width 0.1143)
		(layer "In7.Cu")
		(net "I2C_COM3_SDA")
	)
	(segment
		(start 104.544368 -174.320708)
		(end 105.165398 -173.699678)
		(width 0.1143)
		(layer "In7.Cu")
		(net "I2C_COM3_SDA")
	)
	(segment
		(start 118.989348 -172.44314)
		(end 119.244618 -172.69841)
		(width 0.1016)
		(layer "F.Cu")
		(net "I2C_COM3_SCL")
	)
	(segment
		(start 101.556566 -176.124616)
		(end 101.556566 -175.308514)
		(width 0.1016)
		(layer "F.Cu")
		(net "I2C_COM3_SCL")
	)
	(segment
		(start 93.676216 -173.290992)
		(end 93.3831 -172.997876)
		(width 0.1016)
		(layer "F.Cu")
		(net "I2C_COM3_SCL")
	)
	(segment
		(start 102.255574 -176.823624)
		(end 101.556566 -176.124616)
		(width 0.1016)
		(layer "F.Cu")
		(net "I2C_COM3_SCL")
	)
	(segment
		(start 112.469168 -163.282122)
		(end 112.733328 -163.282122)
		(width 0.1016)
		(layer "F.Cu")
		(net "I2C_COM3_SCL")
	)
	(segment
		(start 114.103658 -162.356546)
		(end 114.76736 -162.356546)
		(width 0.1016)
		(layer "F.Cu")
		(net "I2C_COM3_SCL")
	)
	(segment
		(start 112.27181 -172.625512)
		(end 112.27562 -172.621702)
		(width 0.1016)
		(layer "F.Cu")
		(net "I2C_COM3_SCL")
	)
	(segment
		(start 113.135156 -162.880294)
		(end 113.57991 -162.880294)
		(width 0.1016)
		(layer "F.Cu")
		(net "I2C_COM3_SCL")
	)
	(segment
		(start 103.103172 -176.823624)
		(end 102.255574 -176.823624)
		(width 0.1016)
		(layer "F.Cu")
		(net "I2C_COM3_SCL")
	)
	(segment
		(start 114.76736 -172.621702)
		(end 115.580414 -172.621702)
		(width 0.1016)
		(layer "F.Cu")
		(net "I2C_COM3_SCL")
	)
	(segment
		(start 93.3831 -172.997876)
		(end 93.234764 -172.997876)
		(width 0.1016)
		(layer "F.Cu")
		(net "I2C_COM3_SCL")
	)
	(segment
		(start 112.27562 -172.621702)
		(end 114.76736 -172.621702)
		(width 0.1016)
		(layer "F.Cu")
		(net "I2C_COM3_SCL")
	)
	(segment
		(start 113.57991 -162.880294)
		(end 114.103658 -162.356546)
		(width 0.1016)
		(layer "F.Cu")
		(net "I2C_COM3_SCL")
	)
	(segment
		(start 114.76736 -162.356546)
		(end 115.728242 -162.356546)
		(width 0.1016)
		(layer "F.Cu")
		(net "I2C_COM3_SCL")
	)
	(segment
		(start 115.758976 -172.44314)
		(end 118.989348 -172.44314)
		(width 0.1016)
		(layer "F.Cu")
		(net "I2C_COM3_SCL")
	)
	(segment
		(start 117.647212 -164.275516)
		(end 117.647212 -164.460682)
		(width 0.1016)
		(layer "F.Cu")
		(net "I2C_COM3_SCL")
	)
	(segment
		(start 115.728242 -162.356546)
		(end 117.647212 -164.275516)
		(width 0.1016)
		(layer "F.Cu")
		(net "I2C_COM3_SCL")
	)
	(segment
		(start 112.733328 -163.282122)
		(end 113.135156 -162.880294)
		(width 0.1016)
		(layer "F.Cu")
		(net "I2C_COM3_SCL")
	)
	(segment
		(start 94.051882 -173.290992)
		(end 93.676216 -173.290992)
		(width 0.1016)
		(layer "F.Cu")
		(net "I2C_COM3_SCL")
	)
	(segment
		(start 115.580414 -172.621702)
		(end 115.758976 -172.44314)
		(width 0.1016)
		(layer "F.Cu")
		(net "I2C_COM3_SCL")
	)
	(via
		(at 104.612948 -174.758858)
		(size 0.508)
		(drill 0.254)
		(layers "F.Cu" "B.Cu")
		(net "I2C_COM3_SCL")
	)
	(via
		(at 154.67965 -179.855876)
		(size 0.508)
		(drill 0.254)
		(layers "F.Cu" "B.Cu")
		(net "I2C_COM3_SCL")
	)
	(via
		(at 152.992328 -170.473624)
		(size 0.508)
		(drill 0.254)
		(layers "F.Cu" "B.Cu")
		(net "I2C_COM3_SCL")
	)
	(via
		(at 85.60562 -172.185076)
		(size 0.508)
		(drill 0.254)
		(layers "F.Cu" "B.Cu")
		(net "I2C_COM3_SCL")
	)
	(via
		(at 117.647212 -164.460682)
		(size 0.508)
		(drill 0.254)
		(layers "F.Cu" "B.Cu")
		(net "I2C_COM3_SCL")
	)
	(via
		(at 50.185828 -178.682396)
		(size 0.508)
		(drill 0.254)
		(layers "F.Cu" "B.Cu")
		(net "I2C_COM3_SCL")
	)
	(via
		(at 101.556566 -175.308514)
		(size 0.508)
		(drill 0.254)
		(layers "F.Cu" "B.Cu")
		(net "I2C_COM3_SCL")
	)
	(via
		(at 119.244618 -172.69841)
		(size 0.508)
		(drill 0.254)
		(layers "F.Cu" "B.Cu")
		(net "I2C_COM3_SCL")
	)
	(via
		(at 93.234764 -172.997876)
		(size 0.508)
		(drill 0.254)
		(layers "F.Cu" "B.Cu")
		(net "I2C_COM3_SCL")
	)
	(segment
		(start 118.686072 -172.69841)
		(end 118.13286 -173.251622)
		(width 0.1016)
		(layer "B.Cu")
		(net "I2C_COM3_SCL")
	)
	(segment
		(start 52.30876 -178.590702)
		(end 51.634898 -178.590702)
		(width 0.1016)
		(layer "B.Cu")
		(net "I2C_COM3_SCL")
	)
	(segment
		(start 51.634898 -178.590702)
		(end 51.44897 -178.404774)
		(width 0.1016)
		(layer "B.Cu")
		(net "I2C_COM3_SCL")
	)
	(segment
		(start 85.60562 -172.185076)
		(end 85.60562 -171.895262)
		(width 0.1016)
		(layer "B.Cu")
		(net "I2C_COM3_SCL")
	)
	(segment
		(start 103.36276 -174.294546)
		(end 102.64394 -174.294546)
		(width 0.1016)
		(layer "B.Cu")
		(net "I2C_COM3_SCL")
	)
	(segment
		(start 152.441148 -170.473624)
		(end 152.992328 -170.473624)
		(width 0.1016)
		(layer "B.Cu")
		(net "I2C_COM3_SCL")
	)
	(segment
		(start 151.668226 -171.246546)
		(end 152.441148 -170.473624)
		(width 0.1016)
		(layer "B.Cu")
		(net "I2C_COM3_SCL")
	)
	(segment
		(start 102.64394 -174.294546)
		(end 101.629972 -175.308514)
		(width 0.1016)
		(layer "B.Cu")
		(net "I2C_COM3_SCL")
	)
	(segment
		(start 85.60562 -171.895262)
		(end 86.381336 -171.119546)
		(width 0.1016)
		(layer "B.Cu")
		(net "I2C_COM3_SCL")
	)
	(segment
		(start 86.381336 -171.119546)
		(end 87.74176 -171.119546)
		(width 0.1016)
		(layer "B.Cu")
		(net "I2C_COM3_SCL")
	)
	(segment
		(start 101.629972 -175.308514)
		(end 101.556566 -175.308514)
		(width 0.1016)
		(layer "B.Cu")
		(net "I2C_COM3_SCL")
	)
	(segment
		(start 118.627652 -174.929546)
		(end 119.36476 -174.929546)
		(width 0.1016)
		(layer "B.Cu")
		(net "I2C_COM3_SCL")
	)
	(segment
		(start 117.622574 -164.48532)
		(end 117.647212 -164.460682)
		(width 0.1016)
		(layer "B.Cu")
		(net "I2C_COM3_SCL")
	)
	(segment
		(start 51.44897 -178.404774)
		(end 50.46345 -178.404774)
		(width 0.1016)
		(layer "B.Cu")
		(net "I2C_COM3_SCL")
	)
	(segment
		(start 150.98776 -171.246546)
		(end 151.668226 -171.246546)
		(width 0.1016)
		(layer "B.Cu")
		(net "I2C_COM3_SCL")
	)
	(segment
		(start 104.148636 -174.294546)
		(end 103.36276 -174.294546)
		(width 0.1016)
		(layer "B.Cu")
		(net "I2C_COM3_SCL")
	)
	(segment
		(start 50.46345 -178.404774)
		(end 50.185828 -178.682396)
		(width 0.1016)
		(layer "B.Cu")
		(net "I2C_COM3_SCL")
	)
	(segment
		(start 119.244618 -172.69841)
		(end 118.686072 -172.69841)
		(width 0.1016)
		(layer "B.Cu")
		(net "I2C_COM3_SCL")
	)
	(segment
		(start 104.612948 -174.758858)
		(end 104.148636 -174.294546)
		(width 0.1016)
		(layer "B.Cu")
		(net "I2C_COM3_SCL")
	)
	(segment
		(start 115.12169 -164.48532)
		(end 117.622574 -164.48532)
		(width 0.1016)
		(layer "B.Cu")
		(net "I2C_COM3_SCL")
	)
	(segment
		(start 118.13286 -173.251622)
		(end 118.13286 -174.434754)
		(width 0.1016)
		(layer "B.Cu")
		(net "I2C_COM3_SCL")
	)
	(segment
		(start 118.13286 -174.434754)
		(end 118.627652 -174.929546)
		(width 0.1016)
		(layer "B.Cu")
		(net "I2C_COM3_SCL")
	)
	(segment
		(start 148.81606 -178.756818)
		(end 149.264116 -179.204874)
		(width 0.1143)
		(layer "In6.Cu")
		(net "I2C_COM3_SCL")
	)
	(segment
		(start 119.105934 -163.932108)
		(end 119.18315 -163.854892)
		(width 0.1143)
		(layer "In6.Cu")
		(net "I2C_COM3_SCL")
	)
	(segment
		(start 119.08028 -163.932108)
		(end 119.105934 -163.932108)
		(width 0.1143)
		(layer "In6.Cu")
		(net "I2C_COM3_SCL")
	)
	(segment
		(start 131.492752 -161.642552)
		(end 132.2197 -161.642552)
		(width 0.1143)
		(layer "In6.Cu")
		(net "I2C_COM3_SCL")
	)
	(segment
		(start 153.025094 -170.440858)
		(end 152.992328 -170.473624)
		(width 0.1143)
		(layer "In6.Cu")
		(net "I2C_COM3_SCL")
	)
	(segment
		(start 66.124582 -178.779424)
		(end 66.01206 -178.666902)
		(width 0.1143)
		(layer "In6.Cu")
		(net "I2C_COM3_SCL")
	)
	(segment
		(start 60.772548 -179.03825)
		(end 60.15609 -178.421792)
		(width 0.1143)
		(layer "In6.Cu")
		(net "I2C_COM3_SCL")
	)
	(segment
		(start 77.52461 -165.216332)
		(end 75.262994 -165.216332)
		(width 0.1143)
		(layer "In6.Cu")
		(net "I2C_COM3_SCL")
	)
	(segment
		(start 92.358464 -173.383194)
		(end 90.572082 -173.383194)
		(width 0.1143)
		(layer "In6.Cu")
		(net "I2C_COM3_SCL")
	)
	(segment
		(start 146.234658 -178.756818)
		(end 148.81606 -178.756818)
		(width 0.1143)
		(layer "In6.Cu")
		(net "I2C_COM3_SCL")
	)
	(segment
		(start 147.591018 -169.3418)
		(end 152.768554 -169.3418)
		(width 0.1143)
		(layer "In6.Cu")
		(net "I2C_COM3_SCL")
	)
	(segment
		(start 85.60562 -172.185076)
		(end 84.867496 -172.185076)
		(width 0.1143)
		(layer "In6.Cu")
		(net "I2C_COM3_SCL")
	)
	(segment
		(start 78.73238 -166.424102)
		(end 77.52461 -165.216332)
		(width 0.1143)
		(layer "In6.Cu")
		(net "I2C_COM3_SCL")
	)
	(segment
		(start 69.558408 -179.531772)
		(end 68.80606 -178.779424)
		(width 0.1143)
		(layer "In6.Cu")
		(net "I2C_COM3_SCL")
	)
	(segment
		(start 117.647212 -164.460682)
		(end 118.551706 -164.460682)
		(width 0.1143)
		(layer "In6.Cu")
		(net "I2C_COM3_SCL")
	)
	(segment
		(start 136.821926 -176.670462)
		(end 138.24204 -178.090576)
		(width 0.1143)
		(layer "In6.Cu")
		(net "I2C_COM3_SCL")
	)
	(segment
		(start 119.18315 -163.854892)
		(end 119.598186 -163.854892)
		(width 0.1143)
		(layer "In6.Cu")
		(net "I2C_COM3_SCL")
	)
	(segment
		(start 101.556566 -175.308514)
		(end 100.087176 -173.839124)
		(width 0.1143)
		(layer "In6.Cu")
		(net "I2C_COM3_SCL")
	)
	(segment
		(start 138.24204 -178.090576)
		(end 139.366244 -178.090576)
		(width 0.1143)
		(layer "In6.Cu")
		(net "I2C_COM3_SCL")
	)
	(segment
		(start 137.84072 -161.88436)
		(end 139.10564 -161.88436)
		(width 0.1143)
		(layer "In6.Cu")
		(net "I2C_COM3_SCL")
	)
	(segment
		(start 137.406126 -161.449766)
		(end 137.84072 -161.88436)
		(width 0.1143)
		(layer "In6.Cu")
		(net "I2C_COM3_SCL")
	)
	(segment
		(start 140.47724 -179.201572)
		(end 145.789904 -179.201572)
		(width 0.1143)
		(layer "In6.Cu")
		(net "I2C_COM3_SCL")
	)
	(segment
		(start 140.40104 -161.53384)
		(end 140.40104 -162.151822)
		(width 0.1143)
		(layer "In6.Cu")
		(net "I2C_COM3_SCL")
	)
	(segment
		(start 119.598186 -163.854892)
		(end 122.083322 -161.369756)
		(width 0.1143)
		(layer "In6.Cu")
		(net "I2C_COM3_SCL")
	)
	(segment
		(start 152.617424 -179.204874)
		(end 153.268426 -179.855876)
		(width 0.1143)
		(layer "In6.Cu")
		(net "I2C_COM3_SCL")
	)
	(segment
		(start 59.79287 -178.421792)
		(end 58.939938 -179.274724)
		(width 0.1143)
		(layer "In6.Cu")
		(net "I2C_COM3_SCL")
	)
	(segment
		(start 128.520444 -161.369756)
		(end 129.2352 -160.655)
		(width 0.1143)
		(layer "In6.Cu")
		(net "I2C_COM3_SCL")
	)
	(segment
		(start 66.01206 -178.666902)
		(end 64.254888 -178.666902)
		(width 0.1143)
		(layer "In6.Cu")
		(net "I2C_COM3_SCL")
	)
	(segment
		(start 140.40104 -162.151822)
		(end 147.591018 -169.3418)
		(width 0.1143)
		(layer "In6.Cu")
		(net "I2C_COM3_SCL")
	)
	(segment
		(start 130.5052 -160.655)
		(end 131.492752 -161.642552)
		(width 0.1143)
		(layer "In6.Cu")
		(net "I2C_COM3_SCL")
	)
	(segment
		(start 132.412486 -161.449766)
		(end 137.406126 -161.449766)
		(width 0.1143)
		(layer "In6.Cu")
		(net "I2C_COM3_SCL")
	)
	(segment
		(start 152.768554 -169.3418)
		(end 153.025094 -169.59834)
		(width 0.1143)
		(layer "In6.Cu")
		(net "I2C_COM3_SCL")
	)
	(segment
		(start 125.698504 -174.188628)
		(end 128.180338 -176.670462)
		(width 0.1143)
		(layer "In6.Cu")
		(net "I2C_COM3_SCL")
	)
	(segment
		(start 153.268426 -179.855876)
		(end 154.67965 -179.855876)
		(width 0.1143)
		(layer "In6.Cu")
		(net "I2C_COM3_SCL")
	)
	(segment
		(start 93.234764 -172.997876)
		(end 92.929202 -173.303438)
		(width 0.1143)
		(layer "In6.Cu")
		(net "I2C_COM3_SCL")
	)
	(segment
		(start 72.83323 -167.646096)
		(end 72.83323 -177.724054)
		(width 0.1143)
		(layer "In6.Cu")
		(net "I2C_COM3_SCL")
	)
	(segment
		(start 90.572082 -173.383194)
		(end 90.199718 -173.01083)
		(width 0.1143)
		(layer "In6.Cu")
		(net "I2C_COM3_SCL")
	)
	(segment
		(start 128.180338 -176.670462)
		(end 136.821926 -176.670462)
		(width 0.1143)
		(layer "In6.Cu")
		(net "I2C_COM3_SCL")
	)
	(segment
		(start 50.778156 -179.274724)
		(end 50.185828 -178.682396)
		(width 0.1143)
		(layer "In6.Cu")
		(net "I2C_COM3_SCL")
	)
	(segment
		(start 60.15609 -178.421792)
		(end 59.79287 -178.421792)
		(width 0.1143)
		(layer "In6.Cu")
		(net "I2C_COM3_SCL")
	)
	(segment
		(start 121.067322 -174.521114)
		(end 122.413268 -174.521114)
		(width 0.1143)
		(layer "In6.Cu")
		(net "I2C_COM3_SCL")
	)
	(segment
		(start 100.087176 -173.839124)
		(end 94.878652 -173.839124)
		(width 0.1143)
		(layer "In6.Cu")
		(net "I2C_COM3_SCL")
	)
	(segment
		(start 83.945984 -171.263564)
		(end 82.64652 -171.263564)
		(width 0.1143)
		(layer "In6.Cu")
		(net "I2C_COM3_SCL")
	)
	(segment
		(start 71.025512 -179.531772)
		(end 69.558408 -179.531772)
		(width 0.1143)
		(layer "In6.Cu")
		(net "I2C_COM3_SCL")
	)
	(segment
		(start 78.73238 -167.349424)
		(end 78.73238 -166.424102)
		(width 0.1143)
		(layer "In6.Cu")
		(net "I2C_COM3_SCL")
	)
	(segment
		(start 145.789904 -179.201572)
		(end 146.234658 -178.756818)
		(width 0.1143)
		(layer "In6.Cu")
		(net "I2C_COM3_SCL")
	)
	(segment
		(start 129.2352 -160.655)
		(end 130.5052 -160.655)
		(width 0.1143)
		(layer "In6.Cu")
		(net "I2C_COM3_SCL")
	)
	(segment
		(start 84.867496 -172.185076)
		(end 83.945984 -171.263564)
		(width 0.1143)
		(layer "In6.Cu")
		(net "I2C_COM3_SCL")
	)
	(segment
		(start 94.878652 -173.839124)
		(end 94.037404 -172.997876)
		(width 0.1143)
		(layer "In6.Cu")
		(net "I2C_COM3_SCL")
	)
	(segment
		(start 64.254888 -178.666902)
		(end 63.88354 -179.03825)
		(width 0.1143)
		(layer "In6.Cu")
		(net "I2C_COM3_SCL")
	)
	(segment
		(start 68.80606 -178.779424)
		(end 66.124582 -178.779424)
		(width 0.1143)
		(layer "In6.Cu")
		(net "I2C_COM3_SCL")
	)
	(segment
		(start 118.551706 -164.460682)
		(end 119.08028 -163.932108)
		(width 0.1143)
		(layer "In6.Cu")
		(net "I2C_COM3_SCL")
	)
	(segment
		(start 132.2197 -161.642552)
		(end 132.412486 -161.449766)
		(width 0.1143)
		(layer "In6.Cu")
		(net "I2C_COM3_SCL")
	)
	(segment
		(start 75.262994 -165.216332)
		(end 72.83323 -167.646096)
		(width 0.1143)
		(layer "In6.Cu")
		(net "I2C_COM3_SCL")
	)
	(segment
		(start 139.366244 -178.090576)
		(end 140.47724 -179.201572)
		(width 0.1143)
		(layer "In6.Cu")
		(net "I2C_COM3_SCL")
	)
	(segment
		(start 82.64652 -171.263564)
		(end 78.73238 -167.349424)
		(width 0.1143)
		(layer "In6.Cu")
		(net "I2C_COM3_SCL")
	)
	(segment
		(start 140.2588 -161.3916)
		(end 140.40104 -161.53384)
		(width 0.1143)
		(layer "In6.Cu")
		(net "I2C_COM3_SCL")
	)
	(segment
		(start 86.431374 -173.01083)
		(end 85.60562 -172.185076)
		(width 0.1143)
		(layer "In6.Cu")
		(net "I2C_COM3_SCL")
	)
	(segment
		(start 72.83323 -177.724054)
		(end 71.025512 -179.531772)
		(width 0.1143)
		(layer "In6.Cu")
		(net "I2C_COM3_SCL")
	)
	(segment
		(start 58.939938 -179.274724)
		(end 50.778156 -179.274724)
		(width 0.1143)
		(layer "In6.Cu")
		(net "I2C_COM3_SCL")
	)
	(segment
		(start 139.5984 -161.3916)
		(end 140.2588 -161.3916)
		(width 0.1143)
		(layer "In6.Cu")
		(net "I2C_COM3_SCL")
	)
	(segment
		(start 122.413268 -174.521114)
		(end 122.745754 -174.188628)
		(width 0.1143)
		(layer "In6.Cu")
		(net "I2C_COM3_SCL")
	)
	(segment
		(start 94.037404 -172.997876)
		(end 93.234764 -172.997876)
		(width 0.1143)
		(layer "In6.Cu")
		(net "I2C_COM3_SCL")
	)
	(segment
		(start 92.43822 -173.303438)
		(end 92.358464 -173.383194)
		(width 0.1143)
		(layer "In6.Cu")
		(net "I2C_COM3_SCL")
	)
	(segment
		(start 119.244618 -172.69841)
		(end 121.067322 -174.521114)
		(width 0.1143)
		(layer "In6.Cu")
		(net "I2C_COM3_SCL")
	)
	(segment
		(start 90.199718 -173.01083)
		(end 86.431374 -173.01083)
		(width 0.1143)
		(layer "In6.Cu")
		(net "I2C_COM3_SCL")
	)
	(segment
		(start 153.025094 -169.59834)
		(end 153.025094 -170.440858)
		(width 0.1143)
		(layer "In6.Cu")
		(net "I2C_COM3_SCL")
	)
	(segment
		(start 139.10564 -161.88436)
		(end 139.5984 -161.3916)
		(width 0.1143)
		(layer "In6.Cu")
		(net "I2C_COM3_SCL")
	)
	(segment
		(start 63.88354 -179.03825)
		(end 60.772548 -179.03825)
		(width 0.1143)
		(layer "In6.Cu")
		(net "I2C_COM3_SCL")
	)
	(segment
		(start 92.929202 -173.303438)
		(end 92.43822 -173.303438)
		(width 0.1143)
		(layer "In6.Cu")
		(net "I2C_COM3_SCL")
	)
	(segment
		(start 149.264116 -179.204874)
		(end 152.617424 -179.204874)
		(width 0.1143)
		(layer "In6.Cu")
		(net "I2C_COM3_SCL")
	)
	(segment
		(start 122.083322 -161.369756)
		(end 128.520444 -161.369756)
		(width 0.1143)
		(layer "In6.Cu")
		(net "I2C_COM3_SCL")
	)
	(segment
		(start 122.745754 -174.188628)
		(end 125.698504 -174.188628)
		(width 0.1143)
		(layer "In6.Cu")
		(net "I2C_COM3_SCL")
	)
	(segment
		(start 109.603032 -171.637198)
		(end 109.59338 -171.64685)
		(width 0.1143)
		(layer "In7.Cu")
		(net "I2C_COM3_SCL")
	)
	(segment
		(start 154.474164 -179.65039)
		(end 154.67965 -179.855876)
		(width 0.1143)
		(layer "In7.Cu")
		(net "I2C_COM3_SCL")
	)
	(segment
		(start 105.945432 -174.758858)
		(end 104.612948 -174.758858)
		(width 0.1143)
		(layer "In7.Cu")
		(net "I2C_COM3_SCL")
	)
	(segment
		(start 110.527846 -172.067474)
		(end 110.09757 -171.637198)
		(width 0.1143)
		(layer "In7.Cu")
		(net "I2C_COM3_SCL")
	)
	(segment
		(start 110.09757 -171.637198)
		(end 109.603032 -171.637198)
		(width 0.1143)
		(layer "In7.Cu")
		(net "I2C_COM3_SCL")
	)
	(segment
		(start 153.03373 -178.940206)
		(end 153.743914 -179.65039)
		(width 0.1143)
		(layer "In7.Cu")
		(net "I2C_COM3_SCL")
	)
	(segment
		(start 112.705388 -172.69841)
		(end 112.074452 -172.067474)
		(width 0.1143)
		(layer "In7.Cu")
		(net "I2C_COM3_SCL")
	)
	(segment
		(start 153.35123 -172.688504)
		(end 153.03373 -173.006004)
		(width 0.1143)
		(layer "In7.Cu")
		(net "I2C_COM3_SCL")
	)
	(segment
		(start 152.992328 -170.473624)
		(end 152.992328 -170.476926)
		(width 0.1143)
		(layer "In7.Cu")
		(net "I2C_COM3_SCL")
	)
	(segment
		(start 153.743914 -179.65039)
		(end 154.474164 -179.65039)
		(width 0.1143)
		(layer "In7.Cu")
		(net "I2C_COM3_SCL")
	)
	(segment
		(start 153.35123 -170.835828)
		(end 153.35123 -172.688504)
		(width 0.1143)
		(layer "In7.Cu")
		(net "I2C_COM3_SCL")
	)
	(segment
		(start 109.59338 -171.64685)
		(end 109.057186 -171.64685)
		(width 0.1143)
		(layer "In7.Cu")
		(net "I2C_COM3_SCL")
	)
	(segment
		(start 152.992328 -170.476926)
		(end 153.35123 -170.835828)
		(width 0.1143)
		(layer "In7.Cu")
		(net "I2C_COM3_SCL")
	)
	(segment
		(start 119.244618 -172.69841)
		(end 112.705388 -172.69841)
		(width 0.1143)
		(layer "In7.Cu")
		(net "I2C_COM3_SCL")
	)
	(segment
		(start 112.074452 -172.067474)
		(end 110.527846 -172.067474)
		(width 0.1143)
		(layer "In7.Cu")
		(net "I2C_COM3_SCL")
	)
	(segment
		(start 153.03373 -173.006004)
		(end 153.03373 -178.940206)
		(width 0.1143)
		(layer "In7.Cu")
		(net "I2C_COM3_SCL")
	)
	(segment
		(start 109.057186 -171.64685)
		(end 105.945432 -174.758858)
		(width 0.1143)
		(layer "In7.Cu")
		(net "I2C_COM3_SCL")
	)
	(segment
		(start 103.879142 -167.065706)
		(end 104.50703 -166.437818)
		(width 0.1016)
		(layer "F.Cu")
		(net "I2C_ALERT_FNACTRL2_N")
	)
	(segment
		(start 105.770426 -166.848282)
		(end 105.494836 -166.848282)
		(width 0.1016)
		(layer "F.Cu")
		(net "I2C_ALERT_FNACTRL2_N")
	)
	(segment
		(start 105.494836 -166.848282)
		(end 105.084372 -166.437818)
		(width 0.1016)
		(layer "F.Cu")
		(net "I2C_ALERT_FNACTRL2_N")
	)
	(segment
		(start 104.50703 -166.437818)
		(end 105.084372 -166.437818)
		(width 0.1016)
		(layer "F.Cu")
		(net "I2C_ALERT_FNACTRL2_N")
	)
	(segment
		(start 103.214932 -167.065706)
		(end 103.879142 -167.065706)
		(width 0.1016)
		(layer "F.Cu")
		(net "I2C_ALERT_FNACTRL2_N")
	)
	(via
		(at 105.084372 -166.437818)
		(size 0.508)
		(drill 0.254)
		(layers "F.Cu" "B.Cu")
		(net "I2C_ALERT_FNACTRL2_N")
	)
	(segment
		(start 51.67376 -182.928006)
		(end 51.717194 -182.97144)
		(width 0.1016)
		(layer "F.Cu")
		(net "PSU2_AC_OK")
	)
	(segment
		(start 51.67376 -182.638192)
		(end 51.67376 -182.928006)
		(width 0.1016)
		(layer "F.Cu")
		(net "PSU2_AC_OK")
	)
	(segment
		(start 51.717194 -182.97144)
		(end 51.717194 -183.464962)
		(width 0.1016)
		(layer "F.Cu")
		(net "PSU2_AC_OK")
	)
	(segment
		(start 51.67376 -184.805574)
		(end 51.67376 -184.237884)
		(width 0.1016)
		(layer "F.Cu")
		(net "PSU2_AC_OK")
	)
	(segment
		(start 51.67376 -184.237884)
		(end 51.717194 -184.19445)
		(width 0.1016)
		(layer "F.Cu")
		(net "PSU2_AC_OK")
	)
	(segment
		(start 51.717194 -184.19445)
		(end 51.717194 -183.464962)
		(width 0.1016)
		(layer "F.Cu")
		(net "PSU2_AC_OK")
	)
	(via
		(at 56.22036 -177.29073)
		(size 0.508)
		(drill 0.254)
		(layers "F.Cu" "B.Cu")
		(net "PSU2_AC_OK")
	)
	(via
		(at 51.717194 -183.464962)
		(size 0.508)
		(drill 0.254)
		(layers "F.Cu" "B.Cu")
		(net "PSU2_AC_OK")
	)
	(segment
		(start 58.15076 -177.29073)
		(end 56.22036 -177.29073)
		(width 0.1016)
		(layer "B.Cu")
		(net "PSU2_AC_OK")
	)
	(segment
		(start 52.90566 -180.88229)
		(end 56.22036 -177.56759)
		(width 0.1143)
		(layer "In2.Cu")
		(net "PSU2_AC_OK")
	)
	(segment
		(start 56.22036 -177.56759)
		(end 56.22036 -177.29073)
		(width 0.1143)
		(layer "In2.Cu")
		(net "PSU2_AC_OK")
	)
	(segment
		(start 51.717194 -183.464962)
		(end 52.90566 -182.276496)
		(width 0.1143)
		(layer "In2.Cu")
		(net "PSU2_AC_OK")
	)
	(segment
		(start 52.90566 -182.276496)
		(end 52.90566 -180.88229)
		(width 0.1143)
		(layer "In2.Cu")
		(net "PSU2_AC_OK")
	)
	(segment
		(start 60.586112 -172.302424)
		(end 60.26785 -172.620686)
		(width 0.1016)
		(layer "F.Cu")
		(net "PSU2_DC_OK")
	)
	(segment
		(start 61.085222 -172.302424)
		(end 60.586112 -172.302424)
		(width 0.1016)
		(layer "F.Cu")
		(net "PSU2_DC_OK")
	)
	(via
		(at 60.26785 -172.620686)
		(size 0.508)
		(drill 0.254)
		(layers "F.Cu" "B.Cu")
		(net "PSU2_DC_OK")
	)
	(segment
		(start 58.91403 -173.39056)
		(end 59.683904 -172.620686)
		(width 0.1016)
		(layer "B.Cu")
		(net "PSU2_DC_OK")
	)
	(segment
		(start 59.683904 -172.620686)
		(end 60.26785 -172.620686)
		(width 0.1016)
		(layer "B.Cu")
		(net "PSU2_DC_OK")
	)
	(segment
		(start 58.15076 -173.39056)
		(end 58.91403 -173.39056)
		(width 0.1016)
		(layer "B.Cu")
		(net "PSU2_DC_OK")
	)
	(segment
		(start 47.242222 -172.302424)
		(end 47.242222 -173.39818)
		(width 0.1016)
		(layer "F.Cu")
		(net "PSU6_DC_OK")
	)
	(via
		(at 47.242222 -173.39818)
		(size 0.508)
		(drill 0.254)
		(layers "F.Cu" "B.Cu")
		(net "PSU6_DC_OK")
	)
	(segment
		(start 52.30876 -174.690532)
		(end 51.052222 -174.690532)
		(width 0.1016)
		(layer "B.Cu")
		(net "PSU6_DC_OK")
	)
	(segment
		(start 51.052222 -174.690532)
		(end 50.906172 -174.544482)
		(width 0.1016)
		(layer "B.Cu")
		(net "PSU6_DC_OK")
	)
	(segment
		(start 50.906172 -174.544482)
		(end 49.117758 -174.544482)
		(width 0.1016)
		(layer "B.Cu")
		(net "PSU6_DC_OK")
	)
	(segment
		(start 47.971456 -173.39818)
		(end 47.242222 -173.39818)
		(width 0.1016)
		(layer "B.Cu")
		(net "PSU6_DC_OK")
	)
	(segment
		(start 49.117758 -174.544482)
		(end 47.971456 -173.39818)
		(width 0.1016)
		(layer "B.Cu")
		(net "PSU6_DC_OK")
	)
	(segment
		(start 50.69586 -173.088554)
		(end 50.69586 -173.448472)
		(width 0.1016)
		(layer "F.Cu")
		(net "PSU5_DC_OK")
	)
	(segment
		(start 50.798222 -172.302424)
		(end 50.798222 -172.986192)
		(width 0.1016)
		(layer "F.Cu")
		(net "PSU5_DC_OK")
	)
	(segment
		(start 50.798222 -172.986192)
		(end 50.69586 -173.088554)
		(width 0.1016)
		(layer "F.Cu")
		(net "PSU5_DC_OK")
	)
	(via
		(at 50.69586 -173.448472)
		(size 0.508)
		(drill 0.254)
		(layers "F.Cu" "B.Cu")
		(net "PSU5_DC_OK")
	)
	(segment
		(start 52.30876 -174.040546)
		(end 51.287934 -174.040546)
		(width 0.1016)
		(layer "B.Cu")
		(net "PSU5_DC_OK")
	)
	(segment
		(start 51.287934 -174.040546)
		(end 50.69586 -173.448472)
		(width 0.1016)
		(layer "B.Cu")
		(net "PSU5_DC_OK")
	)
	(segment
		(start 55.43296 -171.305982)
		(end 55.43296 -172.781214)
		(width 0.1016)
		(layer "F.Cu")
		(net "PSU3_DC_OK")
	)
	(segment
		(start 57.656222 -172.85462)
		(end 57.656222 -172.302424)
		(width 0.1016)
		(layer "F.Cu")
		(net "PSU3_DC_OK")
	)
	(segment
		(start 55.43296 -172.781214)
		(end 55.82412 -173.172374)
		(width 0.1016)
		(layer "F.Cu")
		(net "PSU3_DC_OK")
	)
	(segment
		(start 55.82412 -173.172374)
		(end 57.338468 -173.172374)
		(width 0.1016)
		(layer "F.Cu")
		(net "PSU3_DC_OK")
	)
	(segment
		(start 57.338468 -173.172374)
		(end 57.656222 -172.85462)
		(width 0.1016)
		(layer "F.Cu")
		(net "PSU3_DC_OK")
	)
	(via
		(at 55.43296 -171.305982)
		(size 0.508)
		(drill 0.254)
		(layers "F.Cu" "B.Cu")
		(net "PSU3_DC_OK")
	)
	(segment
		(start 55.334662 -171.305982)
		(end 53.90007 -172.740574)
		(width 0.1016)
		(layer "B.Cu")
		(net "PSU3_DC_OK")
	)
	(segment
		(start 53.90007 -172.740574)
		(end 52.30876 -172.740574)
		(width 0.1016)
		(layer "B.Cu")
		(net "PSU3_DC_OK")
	)
	(segment
		(start 55.43296 -171.305982)
		(end 55.334662 -171.305982)
		(width 0.1016)
		(layer "B.Cu")
		(net "PSU3_DC_OK")
	)
	(segment
		(start 53.090318 -183.089804)
		(end 53.090318 -183.475376)
		(width 0.1016)
		(layer "F.Cu")
		(net "PSU1_AC_OK")
	)
	(segment
		(start 52.81676 -183.748934)
		(end 53.090318 -183.475376)
		(width 0.1016)
		(layer "F.Cu")
		(net "PSU1_AC_OK")
	)
	(segment
		(start 52.81676 -184.805574)
		(end 52.81676 -183.748934)
		(width 0.1016)
		(layer "F.Cu")
		(net "PSU1_AC_OK")
	)
	(segment
		(start 52.81676 -182.646574)
		(end 52.81676 -182.816246)
		(width 0.1016)
		(layer "F.Cu")
		(net "PSU1_AC_OK")
	)
	(segment
		(start 52.81676 -182.816246)
		(end 53.090318 -183.089804)
		(width 0.1016)
		(layer "F.Cu")
		(net "PSU1_AC_OK")
	)
	(via
		(at 56.830214 -177.940716)
		(size 0.508)
		(drill 0.254)
		(layers "F.Cu" "B.Cu")
		(net "PSU1_AC_OK")
	)
	(via
		(at 53.090318 -183.475376)
		(size 0.508)
		(drill 0.254)
		(layers "F.Cu" "B.Cu")
		(net "PSU1_AC_OK")
	)
	(segment
		(start 58.15076 -177.940716)
		(end 56.830214 -177.940716)
		(width 0.1016)
		(layer "B.Cu")
		(net "PSU1_AC_OK")
	)
	(segment
		(start 53.95214 -181.821074)
		(end 53.29428 -182.478934)
		(width 0.1143)
		(layer "In2.Cu")
		(net "PSU1_AC_OK")
	)
	(segment
		(start 56.830214 -177.940716)
		(end 53.95214 -180.81879)
		(width 0.1143)
		(layer "In2.Cu")
		(net "PSU1_AC_OK")
	)
	(segment
		(start 53.29428 -183.271414)
		(end 53.090318 -183.475376)
		(width 0.1143)
		(layer "In2.Cu")
		(net "PSU1_AC_OK")
	)
	(segment
		(start 53.95214 -180.81879)
		(end 53.95214 -181.821074)
		(width 0.1143)
		(layer "In2.Cu")
		(net "PSU1_AC_OK")
	)
	(segment
		(start 53.29428 -182.478934)
		(end 53.29428 -183.271414)
		(width 0.1143)
		(layer "In2.Cu")
		(net "PSU1_AC_OK")
	)
	(segment
		(start 49.165764 -183.214772)
		(end 49.165764 -183.472582)
		(width 0.1016)
		(layer "F.Cu")
		(net "PSU4_AC_OK")
	)
	(segment
		(start 49.38776 -184.805574)
		(end 49.38776 -184.29859)
		(width 0.1016)
		(layer "F.Cu")
		(net "PSU4_AC_OK")
	)
	(segment
		(start 49.38776 -182.638192)
		(end 49.38776 -182.992776)
		(width 0.1016)
		(layer "F.Cu")
		(net "PSU4_AC_OK")
	)
	(segment
		(start 49.38776 -184.29859)
		(end 49.165764 -184.076594)
		(width 0.1016)
		(layer "F.Cu")
		(net "PSU4_AC_OK")
	)
	(segment
		(start 49.38776 -182.992776)
		(end 49.165764 -183.214772)
		(width 0.1016)
		(layer "F.Cu")
		(net "PSU4_AC_OK")
	)
	(segment
		(start 49.165764 -184.076594)
		(end 49.165764 -183.472582)
		(width 0.1016)
		(layer "F.Cu")
		(net "PSU4_AC_OK")
	)
	(via
		(at 56.02732 -175.990504)
		(size 0.508)
		(drill 0.254)
		(layers "F.Cu" "B.Cu")
		(net "PSU4_AC_OK")
	)
	(via
		(at 49.165764 -183.472582)
		(size 0.508)
		(drill 0.254)
		(layers "F.Cu" "B.Cu")
		(net "PSU4_AC_OK")
	)
	(segment
		(start 58.15076 -175.990504)
		(end 56.02732 -175.990504)
		(width 0.1016)
		(layer "B.Cu")
		(net "PSU4_AC_OK")
	)
	(segment
		(start 55.47995 -175.990504)
		(end 51.74361 -179.726844)
		(width 0.1143)
		(layer "In2.Cu")
		(net "PSU4_AC_OK")
	)
	(segment
		(start 49.393856 -183.472582)
		(end 49.165764 -183.472582)
		(width 0.1143)
		(layer "In2.Cu")
		(net "PSU4_AC_OK")
	)
	(segment
		(start 51.74361 -179.726844)
		(end 51.74361 -181.122828)
		(width 0.1143)
		(layer "In2.Cu")
		(net "PSU4_AC_OK")
	)
	(segment
		(start 56.02732 -175.990504)
		(end 55.47995 -175.990504)
		(width 0.1143)
		(layer "In2.Cu")
		(net "PSU4_AC_OK")
	)
	(segment
		(start 51.74361 -181.122828)
		(end 49.393856 -183.472582)
		(width 0.1143)
		(layer "In2.Cu")
		(net "PSU4_AC_OK")
	)
	(segment
		(start 50.53076 -184.20588)
		(end 50.435764 -184.110884)
		(width 0.1016)
		(layer "F.Cu")
		(net "PSU3_AC_OK")
	)
	(segment
		(start 50.53076 -184.805574)
		(end 50.53076 -184.20588)
		(width 0.1016)
		(layer "F.Cu")
		(net "PSU3_AC_OK")
	)
	(segment
		(start 50.53076 -183.382666)
		(end 50.435764 -183.477662)
		(width 0.1016)
		(layer "F.Cu")
		(net "PSU3_AC_OK")
	)
	(segment
		(start 50.435764 -184.110884)
		(end 50.435764 -183.477662)
		(width 0.1016)
		(layer "F.Cu")
		(net "PSU3_AC_OK")
	)
	(segment
		(start 50.53076 -182.646574)
		(end 50.53076 -183.382666)
		(width 0.1016)
		(layer "F.Cu")
		(net "PSU3_AC_OK")
	)
	(via
		(at 50.435764 -183.477662)
		(size 0.508)
		(drill 0.254)
		(layers "F.Cu" "B.Cu")
		(net "PSU3_AC_OK")
	)
	(via
		(at 56.821578 -176.640744)
		(size 0.508)
		(drill 0.254)
		(layers "F.Cu" "B.Cu")
		(net "PSU3_AC_OK")
	)
	(segment
		(start 58.15076 -176.640744)
		(end 56.821578 -176.640744)
		(width 0.1016)
		(layer "B.Cu")
		(net "PSU3_AC_OK")
	)
	(segment
		(start 50.435764 -183.477662)
		(end 52.62118 -181.292246)
		(width 0.1143)
		(layer "In2.Cu")
		(net "PSU3_AC_OK")
	)
	(segment
		(start 52.62118 -179.885086)
		(end 55.865522 -176.640744)
		(width 0.1143)
		(layer "In2.Cu")
		(net "PSU3_AC_OK")
	)
	(segment
		(start 55.865522 -176.640744)
		(end 56.821578 -176.640744)
		(width 0.1143)
		(layer "In2.Cu")
		(net "PSU3_AC_OK")
	)
	(segment
		(start 52.62118 -181.292246)
		(end 52.62118 -179.885086)
		(width 0.1143)
		(layer "In2.Cu")
		(net "PSU3_AC_OK")
	)
	(segment
		(start 64.255142 -173.360334)
		(end 64.514222 -173.101254)
		(width 0.1016)
		(layer "F.Cu")
		(net "PSU1_DC_OK")
	)
	(segment
		(start 64.514222 -173.101254)
		(end 64.514222 -172.302424)
		(width 0.1016)
		(layer "F.Cu")
		(net "PSU1_DC_OK")
	)
	(segment
		(start 62.17412 -173.360334)
		(end 64.255142 -173.360334)
		(width 0.1016)
		(layer "F.Cu")
		(net "PSU1_DC_OK")
	)
	(via
		(at 62.17412 -173.360334)
		(size 0.508)
		(drill 0.254)
		(layers "F.Cu" "B.Cu")
		(net "PSU1_DC_OK")
	)
	(segment
		(start 62.17412 -173.362366)
		(end 61.49594 -174.040546)
		(width 0.1016)
		(layer "B.Cu")
		(net "PSU1_DC_OK")
	)
	(segment
		(start 62.17412 -173.360334)
		(end 62.17412 -173.362366)
		(width 0.1016)
		(layer "B.Cu")
		(net "PSU1_DC_OK")
	)
	(segment
		(start 61.49594 -174.040546)
		(end 58.15076 -174.040546)
		(width 0.1016)
		(layer "B.Cu")
		(net "PSU1_DC_OK")
	)
	(segment
		(start 53.73624 -170.32605)
		(end 54.19471 -170.78452)
		(width 0.1016)
		(layer "F.Cu")
		(net "PSU4_DC_OK")
	)
	(segment
		(start 54.19471 -170.78452)
		(end 54.19471 -172.302424)
		(width 0.1016)
		(layer "F.Cu")
		(net "PSU4_DC_OK")
	)
	(via
		(at 53.73624 -170.32605)
		(size 0.508)
		(drill 0.254)
		(layers "F.Cu" "B.Cu")
		(net "PSU4_DC_OK")
	)
	(segment
		(start 53.056282 -171.991782)
		(end 51.878992 -171.991782)
		(width 0.1016)
		(layer "B.Cu")
		(net "PSU4_DC_OK")
	)
	(segment
		(start 51.878992 -171.991782)
		(end 51.38166 -172.489114)
		(width 0.1016)
		(layer "B.Cu")
		(net "PSU4_DC_OK")
	)
	(segment
		(start 51.38166 -173.14545)
		(end 51.62677 -173.39056)
		(width 0.1016)
		(layer "B.Cu")
		(net "PSU4_DC_OK")
	)
	(segment
		(start 53.73624 -170.32605)
		(end 53.73624 -171.311824)
		(width 0.1016)
		(layer "B.Cu")
		(net "PSU4_DC_OK")
	)
	(segment
		(start 51.62677 -173.39056)
		(end 52.30876 -173.39056)
		(width 0.1016)
		(layer "B.Cu")
		(net "PSU4_DC_OK")
	)
	(segment
		(start 51.38166 -172.489114)
		(end 51.38166 -173.14545)
		(width 0.1016)
		(layer "B.Cu")
		(net "PSU4_DC_OK")
	)
	(segment
		(start 53.73624 -171.311824)
		(end 53.056282 -171.991782)
		(width 0.1016)
		(layer "B.Cu")
		(net "PSU4_DC_OK")
	)
	(segment
		(start 47.10176 -182.69585)
		(end 46.625764 -183.171846)
		(width 0.1016)
		(layer "F.Cu")
		(net "PSU6_AC_OK")
	)
	(segment
		(start 47.10176 -184.805574)
		(end 47.10176 -184.35701)
		(width 0.1016)
		(layer "F.Cu")
		(net "PSU6_AC_OK")
	)
	(segment
		(start 47.10176 -184.35701)
		(end 46.625764 -183.881014)
		(width 0.1016)
		(layer "F.Cu")
		(net "PSU6_AC_OK")
	)
	(segment
		(start 47.10176 -182.646574)
		(end 47.10176 -182.69585)
		(width 0.1016)
		(layer "F.Cu")
		(net "PSU6_AC_OK")
	)
	(segment
		(start 46.625764 -183.881014)
		(end 46.625764 -183.477662)
		(width 0.1016)
		(layer "F.Cu")
		(net "PSU6_AC_OK")
	)
	(segment
		(start 46.625764 -183.171846)
		(end 46.625764 -183.477662)
		(width 0.1016)
		(layer "F.Cu")
		(net "PSU6_AC_OK")
	)
	(via
		(at 46.625764 -183.477662)
		(size 0.508)
		(drill 0.254)
		(layers "F.Cu" "B.Cu")
		(net "PSU6_AC_OK")
	)
	(via
		(at 56.981344 -174.690532)
		(size 0.508)
		(drill 0.254)
		(layers "F.Cu" "B.Cu")
		(net "PSU6_AC_OK")
	)
	(segment
		(start 58.15076 -174.690532)
		(end 56.981344 -174.690532)
		(width 0.1016)
		(layer "B.Cu")
		(net "PSU6_AC_OK")
	)
	(segment
		(start 48.28159 -181.821836)
		(end 48.28159 -179.440586)
		(width 0.1143)
		(layer "In2.Cu")
		(net "PSU6_AC_OK")
	)
	(segment
		(start 49.223422 -178.498754)
		(end 49.684178 -178.498754)
		(width 0.1143)
		(layer "In2.Cu")
		(net "PSU6_AC_OK")
	)
	(segment
		(start 49.684178 -178.498754)
		(end 53.4924 -174.690532)
		(width 0.1143)
		(layer "In2.Cu")
		(net "PSU6_AC_OK")
	)
	(segment
		(start 53.4924 -174.690532)
		(end 56.981344 -174.690532)
		(width 0.1143)
		(layer "In2.Cu")
		(net "PSU6_AC_OK")
	)
	(segment
		(start 46.625764 -183.477662)
		(end 48.28159 -181.821836)
		(width 0.1143)
		(layer "In2.Cu")
		(net "PSU6_AC_OK")
	)
	(segment
		(start 48.28159 -179.440586)
		(end 49.223422 -178.498754)
		(width 0.1143)
		(layer "In2.Cu")
		(net "PSU6_AC_OK")
	)
	(segment
		(start 47.895764 -183.183784)
		(end 47.895764 -183.477662)
		(width 0.1016)
		(layer "F.Cu")
		(net "PSU5_AC_OK")
	)
	(segment
		(start 48.24476 -182.646574)
		(end 48.24476 -182.834788)
		(width 0.1016)
		(layer "F.Cu")
		(net "PSU5_AC_OK")
	)
	(segment
		(start 48.24476 -182.834788)
		(end 47.895764 -183.183784)
		(width 0.1016)
		(layer "F.Cu")
		(net "PSU5_AC_OK")
	)
	(segment
		(start 48.24476 -184.372758)
		(end 47.895764 -184.023762)
		(width 0.1016)
		(layer "F.Cu")
		(net "PSU5_AC_OK")
	)
	(segment
		(start 48.24476 -184.805574)
		(end 48.24476 -184.372758)
		(width 0.1016)
		(layer "F.Cu")
		(net "PSU5_AC_OK")
	)
	(segment
		(start 47.895764 -184.023762)
		(end 47.895764 -183.477662)
		(width 0.1016)
		(layer "F.Cu")
		(net "PSU5_AC_OK")
	)
	(via
		(at 47.895764 -183.477662)
		(size 0.508)
		(drill 0.254)
		(layers "F.Cu" "B.Cu")
		(net "PSU5_AC_OK")
	)
	(via
		(at 56.91124 -175.340518)
		(size 0.508)
		(drill 0.254)
		(layers "F.Cu" "B.Cu")
		(net "PSU5_AC_OK")
	)
	(segment
		(start 58.15076 -175.340518)
		(end 56.91124 -175.340518)
		(width 0.1016)
		(layer "B.Cu")
		(net "PSU5_AC_OK")
	)
	(segment
		(start 51.500024 -179.452524)
		(end 50.7492 -179.452524)
		(width 0.1143)
		(layer "In2.Cu")
		(net "PSU5_AC_OK")
	)
	(segment
		(start 49.382426 -180.819298)
		(end 49.382426 -181.991)
		(width 0.1143)
		(layer "In2.Cu")
		(net "PSU5_AC_OK")
	)
	(segment
		(start 55.61203 -175.340518)
		(end 51.500024 -179.452524)
		(width 0.1143)
		(layer "In2.Cu")
		(net "PSU5_AC_OK")
	)
	(segment
		(start 50.7492 -179.452524)
		(end 49.382426 -180.819298)
		(width 0.1143)
		(layer "In2.Cu")
		(net "PSU5_AC_OK")
	)
	(segment
		(start 49.382426 -181.991)
		(end 47.895764 -183.477662)
		(width 0.1143)
		(layer "In2.Cu")
		(net "PSU5_AC_OK")
	)
	(segment
		(start 56.91124 -175.340518)
		(end 55.61203 -175.340518)
		(width 0.1143)
		(layer "In2.Cu")
		(net "PSU5_AC_OK")
	)
	(segment
		(start 98.161856 -162.627818)
		(end 97.290636 -162.627818)
		(width 0.508)
		(layer "F.Cu")
		(net "P12V_AUX")
	)
	(segment
		(start 80.502252 -104.195626)
		(end 80.502252 -104.787954)
		(width 0.508)
		(layer "F.Cu")
		(net "P12V_AUX")
	)
	(segment
		(start 120.496838 -150.866856)
		(end 119.68226 -150.866856)
		(width 0.508)
		(layer "F.Cu")
		(net "P12V_AUX")
	)
	(segment
		(start 106.025188 -160.489138)
		(end 106.025188 -161.948368)
		(width 0.508)
		(layer "F.Cu")
		(net "P12V_AUX")
	)
	(segment
		(start 80.502252 -104.787954)
		(end 80.31226 -104.977946)
		(width 0.508)
		(layer "F.Cu")
		(net "P12V_AUX")
	)
	(segment
		(start 107.925616 -150.067772)
		(end 107.925616 -148.915882)
		(width 0.508)
		(layer "F.Cu")
		(net "P12V_AUX")
	)
	(segment
		(start 115.922298 -150.44293)
		(end 115.79606 -150.569168)
		(width 0.508)
		(layer "F.Cu")
		(net "P12V_AUX")
	)
	(segment
		(start 62.841632 -159.642556)
		(end 63.249302 -159.642556)
		(width 0.4572)
		(layer "F.Cu")
		(net "P12V_AUX")
	)
	(segment
		(start 107.988354 -153.54808)
		(end 107.988354 -154.540966)
		(width 0.508)
		(layer "F.Cu")
		(net "P12V_AUX")
	)
	(segment
		(start 191.769492 -115.705128)
		(end 192.657476 -115.705128)
		(width 0.508)
		(layer "F.Cu")
		(net "P12V_AUX")
	)
	(segment
		(start 62.563502 -159.920686)
		(end 62.841632 -159.642556)
		(width 0.4572)
		(layer "F.Cu")
		(net "P12V_AUX")
	)
	(segment
		(start 115.922298 -149.24278)
		(end 115.922298 -150.44293)
		(width 0.508)
		(layer "F.Cu")
		(net "P12V_AUX")
	)
	(via
		(at 38.58641 -171.467272)
		(size 0.508)
		(drill 0.254)
		(layers "F.Cu" "B.Cu")
		(net "P12V_AUX")
	)
	(via
		(at 79.559658 -149.918928)
		(size 0.508)
		(drill 0.254)
		(layers "F.Cu" "B.Cu")
		(net "P12V_AUX")
	)
	(via
		(at 42.83583 -174.768256)
		(size 0.508)
		(drill 0.254)
		(layers "F.Cu" "B.Cu")
		(net "P12V_AUX")
	)
	(via
		(at 43.083226 -176.10709)
		(size 0.508)
		(drill 0.254)
		(layers "F.Cu" "B.Cu")
		(net "P12V_AUX")
	)
	(via
		(at 118.513098 -131.004056)
		(size 0.508)
		(drill 0.254)
		(layers "F.Cu" "B.Cu")
		(net "P12V_AUX")
	)
	(via
		(at 49.494694 -3.289808)
		(size 0.508)
		(drill 0.254)
		(layers "F.Cu" "B.Cu")
		(net "P12V_AUX")
	)
	(via
		(at 70.044564 -13.404088)
		(size 0.508)
		(drill 0.254)
		(layers "F.Cu" "B.Cu")
		(net "P12V_AUX")
	)
	(via
		(at 50.438558 -3.904996)
		(size 0.508)
		(drill 0.254)
		(layers "F.Cu" "B.Cu")
		(net "P12V_AUX")
	)
	(via
		(at 37.62756 -167.668448)
		(size 0.508)
		(drill 0.254)
		(layers "F.Cu" "B.Cu")
		(net "P12V_AUX")
	)
	(via
		(at 45.09135 -114.794284)
		(size 0.508)
		(drill 0.254)
		(layers "F.Cu" "B.Cu")
		(net "P12V_AUX")
	)
	(via
		(at 12.08786 -117.824504)
		(size 0.508)
		(drill 0.254)
		(layers "F.Cu" "B.Cu")
		(net "P12V_AUX")
	)
	(via
		(at 37.715698 -171.714414)
		(size 0.508)
		(drill 0.254)
		(layers "F.Cu" "B.Cu")
		(net "P12V_AUX")
	)
	(via
		(at 52.01539 -3.495548)
		(size 0.508)
		(drill 0.254)
		(layers "F.Cu" "B.Cu")
		(net "P12V_AUX")
	)
	(via
		(at 118.743984 -130.347466)
		(size 0.508)
		(drill 0.254)
		(layers "F.Cu" "B.Cu")
		(net "P12V_AUX")
	)
	(via
		(at 41.952418 -173.052994)
		(size 0.508)
		(drill 0.254)
		(layers "F.Cu" "B.Cu")
		(net "P12V_AUX")
	)
	(via
		(at 70.0532 -12.753848)
		(size 0.508)
		(drill 0.254)
		(layers "F.Cu" "B.Cu")
		(net "P12V_AUX")
	)
	(via
		(at 43.026584 -178.055524)
		(size 0.508)
		(drill 0.254)
		(layers "F.Cu" "B.Cu")
		(net "P12V_AUX")
	)
	(via
		(at 42.994072 -179.147216)
		(size 0.508)
		(drill 0.254)
		(layers "F.Cu" "B.Cu")
		(net "P12V_AUX")
	)
	(via
		(at 46.32198 -111.556292)
		(size 0.6604)
		(drill 0.3302)
		(layers "F.Cu" "B.Cu")
		(net "P12V_AUX")
	)
	(via
		(at 41.913048 -171.675298)
		(size 0.508)
		(drill 0.254)
		(layers "F.Cu" "B.Cu")
		(net "P12V_AUX")
	)
	(via
		(at 38.498018 -174.645066)
		(size 0.508)
		(drill 0.254)
		(layers "F.Cu" "B.Cu")
		(net "P12V_AUX")
	)
	(via
		(at 46.868842 -112.24641)
		(size 0.508)
		(drill 0.254)
		(layers "F.Cu" "B.Cu")
		(net "P12V_AUX")
	)
	(via
		(at 42.069512 -175.587406)
		(size 0.508)
		(drill 0.254)
		(layers "F.Cu" "B.Cu")
		(net "P12V_AUX")
	)
	(via
		(at 118.766844 -128.728978)
		(size 0.508)
		(drill 0.254)
		(layers "F.Cu" "B.Cu")
		(net "P12V_AUX")
	)
	(via
		(at 71.138288 -8.71982)
		(size 0.508)
		(drill 0.254)
		(layers "F.Cu" "B.Cu")
		(net "P12V_AUX")
	)
	(via
		(at 92.99956 -103.540306)
		(size 0.508)
		(drill 0.254)
		(layers "F.Cu" "B.Cu")
		(net "P12V_AUX")
	)
	(via
		(at 42.49801 -173.975522)
		(size 0.508)
		(drill 0.254)
		(layers "F.Cu" "B.Cu")
		(net "P12V_AUX")
	)
	(via
		(at 78.973426 -150.88616)
		(size 0.508)
		(drill 0.254)
		(layers "F.Cu" "B.Cu")
		(net "P12V_AUX")
	)
	(via
		(at 45.75175 -114.794284)
		(size 0.508)
		(drill 0.254)
		(layers "F.Cu" "B.Cu")
		(net "P12V_AUX")
	)
	(via
		(at 77.782166 -152.466802)
		(size 0.508)
		(drill 0.254)
		(layers "F.Cu" "B.Cu")
		(net "P12V_AUX")
	)
	(via
		(at 12.65682 -118.235984)
		(size 0.508)
		(drill 0.254)
		(layers "F.Cu" "B.Cu")
		(net "P12V_AUX")
	)
	(via
		(at 101.877114 -149.111716)
		(size 0.508)
		(drill 0.254)
		(layers "F.Cu" "B.Cu")
		(net "P12V_AUX")
	)
	(via
		(at 104.01808 -161.896298)
		(size 0.508)
		(drill 0.254)
		(layers "F.Cu" "B.Cu")
		(net "P12V_AUX")
	)
	(via
		(at 80.31226 -104.977946)
		(size 0.508)
		(drill 0.254)
		(layers "F.Cu" "B.Cu")
		(net "P12V_AUX")
	)
	(via
		(at 78.899258 -149.918928)
		(size 0.508)
		(drill 0.254)
		(layers "F.Cu" "B.Cu")
		(net "P12V_AUX")
	)
	(via
		(at 117.74551 -130.993642)
		(size 0.508)
		(drill 0.254)
		(layers "F.Cu" "B.Cu")
		(net "P12V_AUX")
	)
	(via
		(at 107.988354 -154.540966)
		(size 0.508)
		(drill 0.254)
		(layers "F.Cu" "B.Cu")
		(net "P12V_AUX")
	)
	(via
		(at 13.12418 -117.57279)
		(size 0.508)
		(drill 0.254)
		(layers "F.Cu" "B.Cu")
		(net "P12V_AUX")
	)
	(via
		(at 101.190044 -149.130004)
		(size 0.508)
		(drill 0.254)
		(layers "F.Cu" "B.Cu")
		(net "P12V_AUX")
	)
	(via
		(at 40.665654 -174.742348)
		(size 0.508)
		(drill 0.254)
		(layers "F.Cu" "B.Cu")
		(net "P12V_AUX")
	)
	(via
		(at 41.679368 -174.755556)
		(size 0.508)
		(drill 0.254)
		(layers "F.Cu" "B.Cu")
		(net "P12V_AUX")
	)
	(via
		(at 39.613078 -171.402502)
		(size 0.508)
		(drill 0.254)
		(layers "F.Cu" "B.Cu")
		(net "P12V_AUX")
	)
	(via
		(at 118.789958 -129.55397)
		(size 0.508)
		(drill 0.254)
		(layers "F.Cu" "B.Cu")
		(net "P12V_AUX")
	)
	(via
		(at 52.064412 -2.69367)
		(size 0.508)
		(drill 0.254)
		(layers "F.Cu" "B.Cu")
		(net "P12V_AUX")
	)
	(via
		(at 51.269646 -3.884168)
		(size 0.508)
		(drill 0.254)
		(layers "F.Cu" "B.Cu")
		(net "P12V_AUX")
	)
	(via
		(at 12.49299 -120.069102)
		(size 0.508)
		(drill 0.254)
		(layers "F.Cu" "B.Cu")
		(net "P12V_AUX")
	)
	(via
		(at 119.68226 -150.866856)
		(size 0.508)
		(drill 0.254)
		(layers "F.Cu" "B.Cu")
		(net "P12V_AUX")
	)
	(via
		(at 91.5289 -100.551742)
		(size 0.508)
		(drill 0.254)
		(layers "F.Cu" "B.Cu")
		(net "P12V_AUX")
	)
	(via
		(at 41.406572 -173.832774)
		(size 0.508)
		(drill 0.254)
		(layers "F.Cu" "B.Cu")
		(net "P12V_AUX")
	)
	(via
		(at 99.06 -144.10563)
		(size 0.508)
		(drill 0.254)
		(layers "F.Cu" "B.Cu")
		(net "P12V_AUX")
	)
	(via
		(at 101.902514 -153.323798)
		(size 0.6604)
		(drill 0.3302)
		(layers "F.Cu" "B.Cu")
		(net "P12V_AUX")
	)
	(via
		(at 42.994072 -177.139346)
		(size 0.508)
		(drill 0.254)
		(layers "F.Cu" "B.Cu")
		(net "P12V_AUX")
	)
	(via
		(at 106.74223 -161.545016)
		(size 0.508)
		(drill 0.254)
		(layers "F.Cu" "B.Cu")
		(net "P12V_AUX")
	)
	(via
		(at 70.67423 -7.884922)
		(size 0.6604)
		(drill 0.3302)
		(layers "F.Cu" "B.Cu")
		(net "P12V_AUX")
	)
	(via
		(at 115.79606 -150.569168)
		(size 0.508)
		(drill 0.254)
		(layers "F.Cu" "B.Cu")
		(net "P12V_AUX")
	)
	(via
		(at 79.608426 -150.88616)
		(size 0.508)
		(drill 0.254)
		(layers "F.Cu" "B.Cu")
		(net "P12V_AUX")
	)
	(via
		(at 107.925616 -148.915882)
		(size 0.508)
		(drill 0.254)
		(layers "F.Cu" "B.Cu")
		(net "P12V_AUX")
	)
	(via
		(at 100.508054 -161.90722)
		(size 0.508)
		(drill 0.254)
		(layers "F.Cu" "B.Cu")
		(net "P12V_AUX")
	)
	(via
		(at 40.53586 -173.4947)
		(size 0.508)
		(drill 0.254)
		(layers "F.Cu" "B.Cu")
		(net "P12V_AUX")
	)
	(via
		(at 97.290636 -162.627818)
		(size 0.508)
		(drill 0.254)
		(layers "F.Cu" "B.Cu")
		(net "P12V_AUX")
	)
	(via
		(at 11.9888 -118.684548)
		(size 0.508)
		(drill 0.254)
		(layers "F.Cu" "B.Cu")
		(net "P12V_AUX")
	)
	(via
		(at 63.249302 -159.642556)
		(size 0.508)
		(drill 0.254)
		(layers "F.Cu" "B.Cu")
		(net "P12V_AUX")
	)
	(via
		(at 40.668448 -171.44746)
		(size 0.508)
		(drill 0.254)
		(layers "F.Cu" "B.Cu")
		(net "P12V_AUX")
	)
	(via
		(at 101.961188 -151.70658)
		(size 0.508)
		(drill 0.254)
		(layers "F.Cu" "B.Cu")
		(net "P12V_AUX")
	)
	(via
		(at 39.5351 -173.10481)
		(size 0.508)
		(drill 0.254)
		(layers "F.Cu" "B.Cu")
		(net "P12V_AUX")
	)
	(via
		(at 38.664388 -172.312076)
		(size 0.508)
		(drill 0.254)
		(layers "F.Cu" "B.Cu")
		(net "P12V_AUX")
	)
	(via
		(at 12.59586 -119.235728)
		(size 0.508)
		(drill 0.254)
		(layers "F.Cu" "B.Cu")
		(net "P12V_AUX")
	)
	(via
		(at 70.477888 -9.514586)
		(size 0.508)
		(drill 0.254)
		(layers "F.Cu" "B.Cu")
		(net "P12V_AUX")
	)
	(via
		(at 101.961188 -152.34158)
		(size 0.508)
		(drill 0.254)
		(layers "F.Cu" "B.Cu")
		(net "P12V_AUX")
	)
	(via
		(at 192.657476 -115.705128)
		(size 0.508)
		(drill 0.254)
		(layers "F.Cu" "B.Cu")
		(net "P12V_AUX")
	)
	(via
		(at 101.45776 -161.88436)
		(size 0.508)
		(drill 0.254)
		(layers "F.Cu" "B.Cu")
		(net "P12V_AUX")
	)
	(via
		(at 38.31336 -173.338744)
		(size 0.508)
		(drill 0.254)
		(layers "F.Cu" "B.Cu")
		(net "P12V_AUX")
	)
	(via
		(at 106.025188 -161.948368)
		(size 0.508)
		(drill 0.254)
		(layers "F.Cu" "B.Cu")
		(net "P12V_AUX")
	)
	(via
		(at 49.48555 -2.589784)
		(size 0.508)
		(drill 0.254)
		(layers "F.Cu" "B.Cu")
		(net "P12V_AUX")
	)
	(via
		(at 101.300788 -152.501346)
		(size 0.508)
		(drill 0.254)
		(layers "F.Cu" "B.Cu")
		(net "P12V_AUX")
	)
	(via
		(at 70.477888 -8.879586)
		(size 0.508)
		(drill 0.254)
		(layers "F.Cu" "B.Cu")
		(net "P12V_AUX")
	)
	(via
		(at 41.146476 -172.32503)
		(size 0.508)
		(drill 0.254)
		(layers "F.Cu" "B.Cu")
		(net "P12V_AUX")
	)
	(via
		(at 105.34904 -161.60115)
		(size 0.508)
		(drill 0.254)
		(layers "F.Cu" "B.Cu")
		(net "P12V_AUX")
	)
	(via
		(at 46.208442 -113.041176)
		(size 0.508)
		(drill 0.254)
		(layers "F.Cu" "B.Cu")
		(net "P12V_AUX")
	)
	(via
		(at 39.950898 -172.247052)
		(size 0.508)
		(drill 0.254)
		(layers "F.Cu" "B.Cu")
		(net "P12V_AUX")
	)
	(via
		(at 46.208442 -112.406176)
		(size 0.508)
		(drill 0.254)
		(layers "F.Cu" "B.Cu")
		(net "P12V_AUX")
	)
	(segment
		(start 115.028726 -142.746984)
		(end 118.564914 -139.210796)
		(width 0.508)
		(layer "B.Cu")
		(net "P12V_AUX")
	)
	(segment
		(start 92.99956 -101.655118)
		(end 91.896184 -100.551742)
		(width 0.508)
		(layer "B.Cu")
		(net "P12V_AUX")
	)
	(segment
		(start 100.345748 -142.746984)
		(end 115.028726 -142.746984)
		(width 0.508)
		(layer "B.Cu")
		(net "P12V_AUX")
	)
	(segment
		(start 118.564914 -139.210796)
		(end 118.564914 -131.055872)
		(width 0.508)
		(layer "B.Cu")
		(net "P12V_AUX")
	)
	(segment
		(start 91.896184 -100.551742)
		(end 91.5289 -100.551742)
		(width 0.508)
		(layer "B.Cu")
		(net "P12V_AUX")
	)
	(segment
		(start 99.06 -144.032732)
		(end 100.345748 -142.746984)
		(width 0.508)
		(layer "B.Cu")
		(net "P12V_AUX")
	)
	(segment
		(start 92.99956 -103.540306)
		(end 92.99956 -101.655118)
		(width 0.508)
		(layer "B.Cu")
		(net "P12V_AUX")
	)
	(segment
		(start 99.06 -144.10563)
		(end 99.06 -144.032732)
		(width 0.508)
		(layer "B.Cu")
		(net "P12V_AUX")
	)
	(segment
		(start 118.564914 -131.055872)
		(end 118.513098 -131.004056)
		(width 0.508)
		(layer "B.Cu")
		(net "P12V_AUX")
	)
	(segment
		(start 88.57742 -107.22356)
		(end 90.8431 -109.48924)
		(width 0.508)
		(layer "In2.Cu")
		(net "P12V_AUX")
	)
	(segment
		(start 97.610676 -144.429988)
		(end 98.735642 -144.429988)
		(width 0.508)
		(layer "In2.Cu")
		(net "P12V_AUX")
	)
	(segment
		(start 91.5289 -100.551742)
		(end 88.57742 -103.503222)
		(width 0.508)
		(layer "In2.Cu")
		(net "P12V_AUX")
	)
	(segment
		(start 90.25128 -132.911088)
		(end 90.25128 -137.070592)
		(width 0.508)
		(layer "In2.Cu")
		(net "P12V_AUX")
	)
	(segment
		(start 90.8431 -109.48924)
		(end 90.8431 -132.319268)
		(width 0.508)
		(layer "In2.Cu")
		(net "P12V_AUX")
	)
	(segment
		(start 90.25128 -137.070592)
		(end 97.610676 -144.429988)
		(width 0.508)
		(layer "In2.Cu")
		(net "P12V_AUX")
	)
	(segment
		(start 90.8431 -132.319268)
		(end 90.25128 -132.911088)
		(width 0.508)
		(layer "In2.Cu")
		(net "P12V_AUX")
	)
	(segment
		(start 98.735642 -144.429988)
		(end 99.06 -144.10563)
		(width 0.508)
		(layer "In2.Cu")
		(net "P12V_AUX")
	)
	(segment
		(start 88.57742 -103.503222)
		(end 88.57742 -107.22356)
		(width 0.508)
		(layer "In2.Cu")
		(net "P12V_AUX")
	)
	(segment
		(start 54.88432 -163.080446)
		(end 54.88432 -166.132764)
		(width 0.508)
		(layer "In6.Cu")
		(net "P12V_AUX")
	)
	(segment
		(start 44.12488 -169.244264)
		(end 43.939714 -169.059098)
		(width 0.508)
		(layer "In6.Cu")
		(net "P12V_AUX")
	)
	(segment
		(start 51.77282 -169.244264)
		(end 44.12488 -169.244264)
		(width 0.508)
		(layer "In6.Cu")
		(net "P12V_AUX")
	)
	(segment
		(start 61.08319 -159.064452)
		(end 57.163208 -159.064452)
		(width 0.508)
		(layer "In6.Cu")
		(net "P12V_AUX")
	)
	(segment
		(start 57.163208 -159.064452)
		(end 56.25846 -159.9692)
		(width 0.508)
		(layer "In6.Cu")
		(net "P12V_AUX")
	)
	(segment
		(start 63.249302 -159.642556)
		(end 61.661294 -159.642556)
		(width 0.508)
		(layer "In6.Cu")
		(net "P12V_AUX")
	)
	(segment
		(start 56.25846 -159.9692)
		(end 56.25846 -161.706306)
		(width 0.508)
		(layer "In6.Cu")
		(net "P12V_AUX")
	)
	(segment
		(start 38.466776 -168.507664)
		(end 37.62756 -167.668448)
		(width 0.508)
		(layer "In6.Cu")
		(net "P12V_AUX")
	)
	(segment
		(start 39.2176 -168.507664)
		(end 38.466776 -168.507664)
		(width 0.508)
		(layer "In6.Cu")
		(net "P12V_AUX")
	)
	(segment
		(start 43.939714 -169.059098)
		(end 39.769034 -169.059098)
		(width 0.508)
		(layer "In6.Cu")
		(net "P12V_AUX")
	)
	(segment
		(start 54.88432 -166.132764)
		(end 51.77282 -169.244264)
		(width 0.508)
		(layer "In6.Cu")
		(net "P12V_AUX")
	)
	(segment
		(start 56.25846 -161.706306)
		(end 54.88432 -163.080446)
		(width 0.508)
		(layer "In6.Cu")
		(net "P12V_AUX")
	)
	(segment
		(start 39.769034 -169.059098)
		(end 39.2176 -168.507664)
		(width 0.508)
		(layer "In6.Cu")
		(net "P12V_AUX")
	)
	(segment
		(start 61.661294 -159.642556)
		(end 61.08319 -159.064452)
		(width 0.508)
		(layer "In6.Cu")
		(net "P12V_AUX")
	)
	(segment
		(start 81.13014 -103.912162)
		(end 81.13014 -104.160066)
		(width 0.508)
		(layer "In7.Cu")
		(net "P12V_AUX")
	)
	(segment
		(start 81.501996 -103.540306)
		(end 81.13014 -103.912162)
		(width 0.508)
		(layer "In7.Cu")
		(net "P12V_AUX")
	)
	(segment
		(start 81.13014 -104.160066)
		(end 80.31226 -104.977946)
		(width 0.508)
		(layer "In7.Cu")
		(net "P12V_AUX")
	)
	(segment
		(start 92.99956 -103.540306)
		(end 81.501996 -103.540306)
		(width 0.508)
		(layer "In7.Cu")
		(net "P12V_AUX")
	)
	(segment
		(start 51.32832 -159.20339)
		(end 51.32832 -159.44723)
		(width 0.1016)
		(layer "F.Cu")
		(net "LAN1_LED_ACT_N")
	)
	(segment
		(start 53.161946 -160.014158)
		(end 52.35702 -160.014158)
		(width 0.1016)
		(layer "F.Cu")
		(net "LAN1_LED_ACT_N")
	)
	(segment
		(start 51.32832 -159.44723)
		(end 52.126134 -160.245044)
		(width 0.1016)
		(layer "F.Cu")
		(net "LAN1_LED_ACT_N")
	)
	(segment
		(start 49.79797 -157.67304)
		(end 51.32832 -159.20339)
		(width 0.1016)
		(layer "F.Cu")
		(net "LAN1_LED_ACT_N")
	)
	(segment
		(start 49.117504 -157.67304)
		(end 49.79797 -157.67304)
		(width 0.1016)
		(layer "F.Cu")
		(net "LAN1_LED_ACT_N")
	)
	(segment
		(start 52.35702 -160.014158)
		(end 52.126134 -160.245044)
		(width 0.1016)
		(layer "F.Cu")
		(net "LAN1_LED_ACT_N")
	)
	(via
		(at 52.126134 -160.245044)
		(size 0.508)
		(drill 0.254)
		(layers "F.Cu" "B.Cu")
		(net "LAN1_LED_ACT_N")
	)
	(segment
		(start 38.749986 -155.724606)
		(end 38.608762 -155.583382)
		(width 0.10414)
		(layer "F.Cu")
		(net "LAN1_MDI1_DP")
	)
	(segment
		(start 28.331414 -158.891986)
		(end 27.477974 -158.891986)
		(width 0.10414)
		(layer "F.Cu")
		(net "LAN1_MDI1_DP")
	)
	(segment
		(start 39.579042 -155.673044)
		(end 39.52748 -155.724606)
		(width 0.10414)
		(layer "F.Cu")
		(net "LAN1_MDI1_DP")
	)
	(segment
		(start 27.060144 -158.474156)
		(end 26.34615 -158.474156)
		(width 0.10414)
		(layer "F.Cu")
		(net "LAN1_MDI1_DP")
	)
	(segment
		(start 40.0177 -155.673044)
		(end 39.579042 -155.673044)
		(width 0.10414)
		(layer "F.Cu")
		(net "LAN1_MDI1_DP")
	)
	(segment
		(start 27.477974 -158.891986)
		(end 27.060144 -158.474156)
		(width 0.10414)
		(layer "F.Cu")
		(net "LAN1_MDI1_DP")
	)
	(segment
		(start 38.608762 -155.583382)
		(end 36.34994 -155.583382)
		(width 0.10414)
		(layer "F.Cu")
		(net "LAN1_MDI1_DP")
	)
	(segment
		(start 39.52748 -155.724606)
		(end 38.749986 -155.724606)
		(width 0.10414)
		(layer "F.Cu")
		(net "LAN1_MDI1_DP")
	)
	(segment
		(start 31.640018 -155.583382)
		(end 28.331414 -158.891986)
		(width 0.10414)
		(layer "F.Cu")
		(net "LAN1_MDI1_DP")
	)
	(segment
		(start 36.34994 -155.583382)
		(end 31.640018 -155.583382)
		(width 0.10414)
		(layer "F.Cu")
		(net "LAN1_MDI1_DP")
	)
	(via
		(at 36.34994 -155.583382)
		(size 0.4064)
		(drill 0.2032)
		(layers "F.Cu" "B.Cu")
		(net "LAN1_MDI1_DP")
	)
	(segment
		(start 39.721536 -156.172916)
		(end 39.707566 -156.158946)
		(width 0.10414)
		(layer "F.Cu")
		(net "LAN1_MDI1_DN")
	)
	(segment
		(start 40.0177 -156.172916)
		(end 39.721536 -156.172916)
		(width 0.10414)
		(layer "F.Cu")
		(net "LAN1_MDI1_DN")
	)
	(segment
		(start 27.477974 -159.326326)
		(end 27.060144 -159.744156)
		(width 0.10414)
		(layer "F.Cu")
		(net "LAN1_MDI1_DN")
	)
	(segment
		(start 28.07208 -159.326326)
		(end 27.477974 -159.326326)
		(width 0.10414)
		(layer "F.Cu")
		(net "LAN1_MDI1_DN")
	)
	(segment
		(start 38.5699 -156.158946)
		(end 38.428676 -156.017722)
		(width 0.10414)
		(layer "F.Cu")
		(net "LAN1_MDI1_DN")
	)
	(segment
		(start 38.428676 -156.017722)
		(end 31.820104 -156.017722)
		(width 0.10414)
		(layer "F.Cu")
		(net "LAN1_MDI1_DN")
	)
	(segment
		(start 31.820104 -156.017722)
		(end 28.5115 -159.326326)
		(width 0.10414)
		(layer "F.Cu")
		(net "LAN1_MDI1_DN")
	)
	(segment
		(start 39.707566 -156.158946)
		(end 38.5699 -156.158946)
		(width 0.10414)
		(layer "F.Cu")
		(net "LAN1_MDI1_DN")
	)
	(segment
		(start 28.5115 -159.326326)
		(end 28.07208 -159.326326)
		(width 0.10414)
		(layer "F.Cu")
		(net "LAN1_MDI1_DN")
	)
	(segment
		(start 27.060144 -159.744156)
		(end 26.34615 -159.744156)
		(width 0.10414)
		(layer "F.Cu")
		(net "LAN1_MDI1_DN")
	)
	(via
		(at 28.07208 -159.326326)
		(size 0.4064)
		(drill 0.2032)
		(layers "F.Cu" "B.Cu")
		(net "LAN1_MDI1_DN")
	)
	(segment
		(start 44.317666 -159.472884)
		(end 44.317666 -160.524444)
		(width 0.254)
		(layer "F.Cu")
		(net "P1V05_LAN1")
	)
	(segment
		(start 40.0177 -153.172922)
		(end 38.969188 -153.172922)
		(width 0.254)
		(layer "F.Cu")
		(net "P1V05_LAN1")
	)
	(segment
		(start 49.117504 -151.673052)
		(end 49.638458 -151.673052)
		(width 0.254)
		(layer "F.Cu")
		(net "P1V05_LAN1")
	)
	(segment
		(start 45.817536 -149.474174)
		(end 46.05782 -149.23389)
		(width 0.254)
		(layer "F.Cu")
		(net "P1V05_LAN1")
	)
	(segment
		(start 49.948846 -156.172916)
		(end 50.09642 -156.32049)
		(width 0.254)
		(layer "F.Cu")
		(net "P1V05_LAN1")
	)
	(segment
		(start 46.317662 -159.472884)
		(end 46.317662 -160.429448)
		(width 0.254)
		(layer "F.Cu")
		(net "P1V05_LAN1")
	)
	(segment
		(start 45.817536 -150.37308)
		(end 45.817536 -149.474174)
		(width 0.254)
		(layer "F.Cu")
		(net "P1V05_LAN1")
	)
	(segment
		(start 42.31767 -150.37308)
		(end 42.31767 -149.31644)
		(width 0.254)
		(layer "F.Cu")
		(net "P1V05_LAN1")
	)
	(segment
		(start 49.638458 -151.673052)
		(end 50.09642 -151.21509)
		(width 0.254)
		(layer "F.Cu")
		(net "P1V05_LAN1")
	)
	(segment
		(start 49.117504 -156.172916)
		(end 49.948846 -156.172916)
		(width 0.254)
		(layer "F.Cu")
		(net "P1V05_LAN1")
	)
	(via
		(at 50.34534 -155.21559)
		(size 0.6604)
		(drill 0.3302)
		(layers "F.Cu" "B.Cu")
		(net "P1V05_LAN1")
	)
	(via
		(at 46.317662 -160.429448)
		(size 0.508)
		(drill 0.254)
		(layers "F.Cu" "B.Cu")
		(net "P1V05_LAN1")
	)
	(via
		(at 38.969188 -153.172922)
		(size 0.508)
		(drill 0.254)
		(layers "F.Cu" "B.Cu")
		(net "P1V05_LAN1")
	)
	(via
		(at 44.317666 -160.524444)
		(size 0.508)
		(drill 0.254)
		(layers "F.Cu" "B.Cu")
		(net "P1V05_LAN1")
	)
	(via
		(at 46.05782 -149.23389)
		(size 0.508)
		(drill 0.254)
		(layers "F.Cu" "B.Cu")
		(net "P1V05_LAN1")
	)
	(via
		(at 42.31767 -149.31644)
		(size 0.508)
		(drill 0.254)
		(layers "F.Cu" "B.Cu")
		(net "P1V05_LAN1")
	)
	(via
		(at 48.12284 -149.33041)
		(size 0.6604)
		(drill 0.3302)
		(layers "F.Cu" "B.Cu")
		(net "P1V05_LAN1")
	)
	(via
		(at 50.09642 -151.21509)
		(size 0.508)
		(drill 0.254)
		(layers "F.Cu" "B.Cu")
		(net "P1V05_LAN1")
	)
	(via
		(at 50.09642 -156.32049)
		(size 0.508)
		(drill 0.254)
		(layers "F.Cu" "B.Cu")
		(net "P1V05_LAN1")
	)
	(segment
		(start 46.56582 -149.87524)
		(end 46.56582 -149.74189)
		(width 0.508)
		(layer "B.Cu")
		(net "P1V05_LAN1")
	)
	(segment
		(start 46.56582 -149.74189)
		(end 46.05782 -149.23389)
		(width 0.508)
		(layer "B.Cu")
		(net "P1V05_LAN1")
	)
	(segment
		(start 49.15027 -156.14269)
		(end 49.91862 -156.14269)
		(width 0.508)
		(layer "B.Cu")
		(net "P1V05_LAN1")
	)
	(segment
		(start 39.96817 -153.70429)
		(end 39.500556 -153.70429)
		(width 0.508)
		(layer "B.Cu")
		(net "P1V05_LAN1")
	)
	(segment
		(start 49.15027 -151.06269)
		(end 49.94402 -151.06269)
		(width 0.508)
		(layer "B.Cu")
		(net "P1V05_LAN1")
	)
	(segment
		(start 49.94402 -151.06269)
		(end 50.09642 -151.21509)
		(width 0.508)
		(layer "B.Cu")
		(net "P1V05_LAN1")
	)
	(segment
		(start 43.00982 -149.82444)
		(end 42.82567 -149.82444)
		(width 0.508)
		(layer "B.Cu")
		(net "P1V05_LAN1")
	)
	(segment
		(start 39.500556 -153.70429)
		(end 38.969188 -153.172922)
		(width 0.508)
		(layer "B.Cu")
		(net "P1V05_LAN1")
	)
	(segment
		(start 49.91862 -156.14269)
		(end 50.09642 -156.32049)
		(width 0.508)
		(layer "B.Cu")
		(net "P1V05_LAN1")
	)
	(segment
		(start 42.82567 -149.82444)
		(end 42.31767 -149.31644)
		(width 0.508)
		(layer "B.Cu")
		(net "P1V05_LAN1")
	)
	(segment
		(start 135.622284 -28.6639)
		(end 136.13384 -28.6639)
		(width 0.254)
		(layer "F.Cu")
		(net "GNDA")
	)
	(segment
		(start 136.38657 -26.169366)
		(end 136.38657 -25.465278)
		(width 0.508)
		(layer "F.Cu")
		(net "GNDA")
	)
	(segment
		(start 135.261604 -29.02458)
		(end 135.622284 -28.6639)
		(width 0.254)
		(layer "F.Cu")
		(net "GNDA")
	)
	(segment
		(start 141.208252 -25.412192)
		(end 141.208252 -24.712168)
		(width 0.508)
		(layer "F.Cu")
		(net "GNDA")
	)
	(segment
		(start 145.380202 -26.193242)
		(end 144.667986 -26.193242)
		(width 0.508)
		(layer "F.Cu")
		(net "GNDA")
	)
	(segment
		(start 135.261604 -30.079696)
		(end 135.261604 -29.02458)
		(width 0.254)
		(layer "F.Cu")
		(net "GNDA")
	)
	(segment
		(start 142.478252 -25.583642)
		(end 142.478252 -24.68753)
		(width 0.508)
		(layer "F.Cu")
		(net "GNDA")
	)
	(via
		(at 136.38657 -25.465278)
		(size 0.508)
		(drill 0.254)
		(layers "F.Cu" "B.Cu")
		(net "GNDA")
	)
	(via
		(at 136.13384 -28.6639)
		(size 0.508)
		(drill 0.254)
		(layers "F.Cu" "B.Cu")
		(net "GNDA")
	)
	(via
		(at 144.667986 -26.193242)
		(size 0.508)
		(drill 0.254)
		(layers "F.Cu" "B.Cu")
		(net "GNDA")
	)
	(via
		(at 142.478252 -24.68753)
		(size 0.508)
		(drill 0.254)
		(layers "F.Cu" "B.Cu")
		(net "GNDA")
	)
	(via
		(at 143.79067 -28.579572)
		(size 0.6604)
		(drill 0.3302)
		(layers "F.Cu" "B.Cu")
		(net "GNDA")
	)
	(via
		(at 141.208252 -24.712168)
		(size 0.508)
		(drill 0.254)
		(layers "F.Cu" "B.Cu")
		(net "GNDA")
	)
	(segment
		(start 35.468814 -158.428436)
		(end 34.85642 -158.428436)
		(width 0.10414)
		(layer "F.Cu")
		(net "LAN1_MDI2_DN")
	)
	(segment
		(start 39.48684 -157.14853)
		(end 36.74872 -157.14853)
		(width 0.10414)
		(layer "F.Cu")
		(net "LAN1_MDI2_DN")
	)
	(segment
		(start 36.74872 -157.14853)
		(end 35.468814 -158.428436)
		(width 0.10414)
		(layer "F.Cu")
		(net "LAN1_MDI2_DN")
	)
	(segment
		(start 29.763212 -161.866326)
		(end 27.477974 -161.866326)
		(width 0.10414)
		(layer "F.Cu")
		(net "LAN1_MDI2_DN")
	)
	(segment
		(start 27.060144 -162.284156)
		(end 26.34615 -162.284156)
		(width 0.10414)
		(layer "F.Cu")
		(net "LAN1_MDI2_DN")
	)
	(segment
		(start 27.477974 -161.866326)
		(end 27.060144 -162.284156)
		(width 0.10414)
		(layer "F.Cu")
		(net "LAN1_MDI2_DN")
	)
	(segment
		(start 32.147764 -159.481774)
		(end 32.147764 -159.48152)
		(width 0.10414)
		(layer "F.Cu")
		(net "LAN1_MDI2_DN")
	)
	(segment
		(start 39.511224 -157.172914)
		(end 39.48684 -157.14853)
		(width 0.10414)
		(layer "F.Cu")
		(net "LAN1_MDI2_DN")
	)
	(segment
		(start 34.85642 -158.428436)
		(end 33.201102 -158.428436)
		(width 0.10414)
		(layer "F.Cu")
		(net "LAN1_MDI2_DN")
	)
	(segment
		(start 32.147764 -159.48152)
		(end 29.763212 -161.866326)
		(width 0.10414)
		(layer "F.Cu")
		(net "LAN1_MDI2_DN")
	)
	(segment
		(start 40.0177 -157.172914)
		(end 39.511224 -157.172914)
		(width 0.10414)
		(layer "F.Cu")
		(net "LAN1_MDI2_DN")
	)
	(segment
		(start 33.201102 -158.428436)
		(end 32.147764 -159.481774)
		(width 0.10414)
		(layer "F.Cu")
		(net "LAN1_MDI2_DN")
	)
	(via
		(at 34.85642 -158.428436)
		(size 0.4064)
		(drill 0.2032)
		(layers "F.Cu" "B.Cu")
		(net "LAN1_MDI2_DN")
	)
	(segment
		(start 26.34615 -166.094156)
		(end 27.060144 -166.094156)
		(width 0.10414)
		(layer "F.Cu")
		(net "LAN1_MDI3_DP")
	)
	(segment
		(start 39.4208 -158.212536)
		(end 38.19144 -158.212536)
		(width 0.10414)
		(layer "F.Cu")
		(net "LAN1_MDI3_DP")
	)
	(segment
		(start 28.819348 -166.511986)
		(end 37.118798 -158.212536)
		(width 0.10414)
		(layer "F.Cu")
		(net "LAN1_MDI3_DP")
	)
	(segment
		(start 27.477974 -166.511986)
		(end 28.819348 -166.511986)
		(width 0.10414)
		(layer "F.Cu")
		(net "LAN1_MDI3_DP")
	)
	(segment
		(start 37.118798 -158.212536)
		(end 38.19144 -158.212536)
		(width 0.10414)
		(layer "F.Cu")
		(net "LAN1_MDI3_DP")
	)
	(segment
		(start 27.060144 -166.094156)
		(end 27.477974 -166.511986)
		(width 0.10414)
		(layer "F.Cu")
		(net "LAN1_MDI3_DP")
	)
	(segment
		(start 39.4589 -158.172912)
		(end 39.4208 -158.211012)
		(width 0.10414)
		(layer "F.Cu")
		(net "LAN1_MDI3_DP")
	)
	(segment
		(start 40.0177 -158.172912)
		(end 39.4589 -158.172912)
		(width 0.10414)
		(layer "F.Cu")
		(net "LAN1_MDI3_DP")
	)
	(segment
		(start 39.4208 -158.211012)
		(end 39.4208 -158.212536)
		(width 0.10414)
		(layer "F.Cu")
		(net "LAN1_MDI3_DP")
	)
	(via
		(at 38.19144 -158.212536)
		(size 0.4064)
		(drill 0.2032)
		(layers "F.Cu" "B.Cu")
		(net "LAN1_MDI3_DP")
	)
	(segment
		(start 49.88814 -163.4998)
		(end 49.88814 -163.55695)
		(width 0.1016)
		(layer "F.Cu")
		(net "SMB_LAN1_DAT")
	)
	(segment
		(start 49.88814 -163.55695)
		(end 49.36744 -164.07765)
		(width 0.1016)
		(layer "F.Cu")
		(net "SMB_LAN1_DAT")
	)
	(segment
		(start 49.36744 -164.07765)
		(end 49.36744 -165.5191)
		(width 0.1016)
		(layer "F.Cu")
		(net "SMB_LAN1_DAT")
	)
	(segment
		(start 48.63592 -162.34029)
		(end 48.7299 -162.34029)
		(width 0.1016)
		(layer "F.Cu")
		(net "SMB_LAN1_DAT")
	)
	(segment
		(start 49.36744 -165.5191)
		(end 49.88814 -166.0398)
		(width 0.1016)
		(layer "F.Cu")
		(net "SMB_LAN1_DAT")
	)
	(segment
		(start 48.52162 -162.34029)
		(end 48.63592 -162.34029)
		(width 0.1016)
		(layer "F.Cu")
		(net "SMB_LAN1_DAT")
	)
	(segment
		(start 49.88814 -163.49853)
		(end 49.88814 -163.4998)
		(width 0.1016)
		(layer "F.Cu")
		(net "SMB_LAN1_DAT")
	)
	(segment
		(start 48.7299 -162.34029)
		(end 49.88814 -163.49853)
		(width 0.1016)
		(layer "F.Cu")
		(net "SMB_LAN1_DAT")
	)
	(segment
		(start 46.817534 -159.472884)
		(end 46.817534 -160.636204)
		(width 0.1016)
		(layer "F.Cu")
		(net "SMB_LAN1_DAT")
	)
	(segment
		(start 46.817534 -160.636204)
		(end 48.52162 -162.34029)
		(width 0.1016)
		(layer "F.Cu")
		(net "SMB_LAN1_DAT")
	)
	(via
		(at 48.63592 -162.34029)
		(size 0.508)
		(drill 0.254)
		(layers "F.Cu" "B.Cu")
		(net "SMB_LAN1_DAT")
	)
	(segment
		(start 27.14498 -167.280336)
		(end 27.14498 -167.27932)
		(width 0.10414)
		(layer "F.Cu")
		(net "LAN1_MDI3_DN")
	)
	(segment
		(start 39.41826 -158.646876)
		(end 37.298884 -158.646876)
		(width 0.10414)
		(layer "F.Cu")
		(net "LAN1_MDI3_DN")
	)
	(segment
		(start 39.444422 -158.673038)
		(end 39.41826 -158.646876)
		(width 0.10414)
		(layer "F.Cu")
		(net "LAN1_MDI3_DN")
	)
	(segment
		(start 28.999434 -166.946326)
		(end 28.22448 -166.946326)
		(width 0.10414)
		(layer "F.Cu")
		(net "LAN1_MDI3_DN")
	)
	(segment
		(start 37.298884 -158.646876)
		(end 28.999434 -166.946326)
		(width 0.10414)
		(layer "F.Cu")
		(net "LAN1_MDI3_DN")
	)
	(segment
		(start 40.0177 -158.673038)
		(end 39.444422 -158.673038)
		(width 0.10414)
		(layer "F.Cu")
		(net "LAN1_MDI3_DN")
	)
	(segment
		(start 26.34615 -167.364156)
		(end 27.06116 -167.364156)
		(width 0.10414)
		(layer "F.Cu")
		(net "LAN1_MDI3_DN")
	)
	(segment
		(start 27.06116 -167.364156)
		(end 27.14498 -167.280336)
		(width 0.10414)
		(layer "F.Cu")
		(net "LAN1_MDI3_DN")
	)
	(segment
		(start 27.14498 -167.27932)
		(end 27.477974 -166.946326)
		(width 0.10414)
		(layer "F.Cu")
		(net "LAN1_MDI3_DN")
	)
	(segment
		(start 27.477974 -166.946326)
		(end 28.22448 -166.946326)
		(width 0.10414)
		(layer "F.Cu")
		(net "LAN1_MDI3_DN")
	)
	(via
		(at 28.22448 -166.946326)
		(size 0.4064)
		(drill 0.2032)
		(layers "F.Cu" "B.Cu")
		(net "LAN1_MDI3_DN")
	)
	(segment
		(start 39.46652 -154.17292)
		(end 39.440104 -154.199336)
		(width 0.10414)
		(layer "F.Cu")
		(net "LAN1_MDI0_DP")
	)
	(segment
		(start 40.0177 -154.17292)
		(end 39.46652 -154.17292)
		(width 0.10414)
		(layer "F.Cu")
		(net "LAN1_MDI0_DP")
	)
	(segment
		(start 27.060144 -153.394156)
		(end 27.477974 -153.811986)
		(width 0.10414)
		(layer "F.Cu")
		(net "LAN1_MDI0_DP")
	)
	(segment
		(start 39.440104 -154.199336)
		(end 37.999416 -154.199336)
		(width 0.10414)
		(layer "F.Cu")
		(net "LAN1_MDI0_DP")
	)
	(segment
		(start 27.477974 -153.811986)
		(end 29.2481 -153.811986)
		(width 0.10414)
		(layer "F.Cu")
		(net "LAN1_MDI0_DP")
	)
	(segment
		(start 37.612066 -153.811986)
		(end 29.2481 -153.811986)
		(width 0.10414)
		(layer "F.Cu")
		(net "LAN1_MDI0_DP")
	)
	(segment
		(start 26.34615 -153.394156)
		(end 27.060144 -153.394156)
		(width 0.10414)
		(layer "F.Cu")
		(net "LAN1_MDI0_DP")
	)
	(segment
		(start 37.999416 -154.199336)
		(end 37.612066 -153.811986)
		(width 0.10414)
		(layer "F.Cu")
		(net "LAN1_MDI0_DP")
	)
	(via
		(at 29.2481 -153.811986)
		(size 0.4064)
		(drill 0.2032)
		(layers "F.Cu" "B.Cu")
		(net "LAN1_MDI0_DP")
	)
	(segment
		(start 33.88614 -154.246326)
		(end 27.477974 -154.246326)
		(width 0.10414)
		(layer "F.Cu")
		(net "LAN1_MDI0_DN")
	)
	(segment
		(start 27.477974 -154.246326)
		(end 27.060144 -154.664156)
		(width 0.10414)
		(layer "F.Cu")
		(net "LAN1_MDI0_DN")
	)
	(segment
		(start 27.060144 -154.664156)
		(end 26.34615 -154.664156)
		(width 0.10414)
		(layer "F.Cu")
		(net "LAN1_MDI0_DN")
	)
	(segment
		(start 37.43198 -154.246326)
		(end 33.88614 -154.246326)
		(width 0.10414)
		(layer "F.Cu")
		(net "LAN1_MDI0_DN")
	)
	(segment
		(start 37.81933 -154.633676)
		(end 37.43198 -154.246326)
		(width 0.10414)
		(layer "F.Cu")
		(net "LAN1_MDI0_DN")
	)
	(segment
		(start 39.45128 -154.673046)
		(end 39.41191 -154.633676)
		(width 0.10414)
		(layer "F.Cu")
		(net "LAN1_MDI0_DN")
	)
	(segment
		(start 40.0177 -154.673046)
		(end 39.45128 -154.673046)
		(width 0.10414)
		(layer "F.Cu")
		(net "LAN1_MDI0_DN")
	)
	(segment
		(start 39.41191 -154.633676)
		(end 37.81933 -154.633676)
		(width 0.10414)
		(layer "F.Cu")
		(net "LAN1_MDI0_DN")
	)
	(via
		(at 33.88614 -154.246326)
		(size 0.4064)
		(drill 0.2032)
		(layers "F.Cu" "B.Cu")
		(net "LAN1_MDI0_DN")
	)
	(segment
		(start 49.117504 -152.172924)
		(end 49.900586 -152.172924)
		(width 0.254)
		(layer "F.Cu")
		(net "P1V9_LAN1")
	)
	(segment
		(start 49.900586 -152.172924)
		(end 50.04562 -152.02789)
		(width 0.254)
		(layer "F.Cu")
		(net "P1V9_LAN1")
	)
	(segment
		(start 40.0177 -155.172918)
		(end 39.042848 -155.172918)
		(width 0.254)
		(layer "F.Cu")
		(net "P1V9_LAN1")
	)
	(segment
		(start 42.817542 -159.472884)
		(end 42.817542 -160.132268)
		(width 0.254)
		(layer "F.Cu")
		(net "P1V9_LAN1")
	)
	(segment
		(start 40.0177 -152.67305)
		(end 39.23538 -152.67305)
		(width 0.254)
		(layer "F.Cu")
		(net "P1V9_LAN1")
	)
	(segment
		(start 41.317672 -159.472884)
		(end 41.317672 -160.501838)
		(width 0.254)
		(layer "F.Cu")
		(net "P1V9_LAN1")
	)
	(segment
		(start 42.817542 -160.132268)
		(end 42.55262 -160.39719)
		(width 0.254)
		(layer "F.Cu")
		(net "P1V9_LAN1")
	)
	(segment
		(start 40.0177 -151.673052)
		(end 38.995858 -151.673052)
		(width 0.254)
		(layer "F.Cu")
		(net "P1V9_LAN1")
	)
	(segment
		(start 49.117504 -153.673048)
		(end 50.014378 -153.673048)
		(width 0.254)
		(layer "F.Cu")
		(net "P1V9_LAN1")
	)
	(segment
		(start 40.0177 -157.67304)
		(end 39.10457 -157.67304)
		(width 0.254)
		(layer "F.Cu")
		(net "P1V9_LAN1")
	)
	(segment
		(start 42.55262 -160.39719)
		(end 42.55262 -160.51149)
		(width 0.254)
		(layer "F.Cu")
		(net "P1V9_LAN1")
	)
	(segment
		(start 39.23538 -152.67305)
		(end 38.94582 -152.38349)
		(width 0.254)
		(layer "F.Cu")
		(net "P1V9_LAN1")
	)
	(via
		(at 24.29764 -134.965948)
		(size 0.508)
		(drill 0.254)
		(layers "F.Cu" "B.Cu")
		(net "P1V9_LAN1")
	)
	(via
		(at 38.720268 -159.481774)
		(size 0.6604)
		(drill 0.3302)
		(layers "F.Cu" "B.Cu")
		(net "P1V9_LAN1")
	)
	(via
		(at 24.20874 -164.460174)
		(size 0.508)
		(drill 0.254)
		(layers "F.Cu" "B.Cu")
		(net "P1V9_LAN1")
	)
	(via
		(at 24.706072 -136.41197)
		(size 0.508)
		(drill 0.254)
		(layers "F.Cu" "B.Cu")
		(net "P1V9_LAN1")
	)
	(via
		(at 38.94582 -152.38349)
		(size 0.508)
		(drill 0.254)
		(layers "F.Cu" "B.Cu")
		(net "P1V9_LAN1")
	)
	(via
		(at 24.4348 -156.54655)
		(size 0.508)
		(drill 0.254)
		(layers "F.Cu" "B.Cu")
		(net "P1V9_LAN1")
	)
	(via
		(at 23.89378 -157.222444)
		(size 0.508)
		(drill 0.254)
		(layers "F.Cu" "B.Cu")
		(net "P1V9_LAN1")
	)
	(via
		(at 41.317672 -160.501838)
		(size 0.508)
		(drill 0.254)
		(layers "F.Cu" "B.Cu")
		(net "P1V9_LAN1")
	)
	(via
		(at 24.730964 -137.895838)
		(size 0.508)
		(drill 0.254)
		(layers "F.Cu" "B.Cu")
		(net "P1V9_LAN1")
	)
	(via
		(at 38.995858 -151.673052)
		(size 0.508)
		(drill 0.254)
		(layers "F.Cu" "B.Cu")
		(net "P1V9_LAN1")
	)
	(via
		(at 23.475188 -134.894574)
		(size 0.508)
		(drill 0.254)
		(layers "F.Cu" "B.Cu")
		(net "P1V9_LAN1")
	)
	(via
		(at 23.89378 -155.915614)
		(size 0.508)
		(drill 0.254)
		(layers "F.Cu" "B.Cu")
		(net "P1V9_LAN1")
	)
	(via
		(at 50.014378 -153.673048)
		(size 0.508)
		(drill 0.254)
		(layers "F.Cu" "B.Cu")
		(net "P1V9_LAN1")
	)
	(via
		(at 25.095962 -135.025638)
		(size 0.508)
		(drill 0.254)
		(layers "F.Cu" "B.Cu")
		(net "P1V9_LAN1")
	)
	(via
		(at 50.04562 -152.02789)
		(size 0.508)
		(drill 0.254)
		(layers "F.Cu" "B.Cu")
		(net "P1V9_LAN1")
	)
	(via
		(at 24.2189 -163.598352)
		(size 0.508)
		(drill 0.254)
		(layers "F.Cu" "B.Cu")
		(net "P1V9_LAN1")
	)
	(via
		(at 24.83866 -155.904438)
		(size 0.508)
		(drill 0.254)
		(layers "F.Cu" "B.Cu")
		(net "P1V9_LAN1")
	)
	(via
		(at 39.10457 -157.67304)
		(size 0.508)
		(drill 0.254)
		(layers "F.Cu" "B.Cu")
		(net "P1V9_LAN1")
	)
	(via
		(at 24.99614 -164.815012)
		(size 0.508)
		(drill 0.254)
		(layers "F.Cu" "B.Cu")
		(net "P1V9_LAN1")
	)
	(via
		(at 25.01392 -164.139118)
		(size 0.508)
		(drill 0.254)
		(layers "F.Cu" "B.Cu")
		(net "P1V9_LAN1")
	)
	(via
		(at 24.98598 -157.290008)
		(size 0.508)
		(drill 0.254)
		(layers "F.Cu" "B.Cu")
		(net "P1V9_LAN1")
	)
	(via
		(at 42.55262 -160.51149)
		(size 0.508)
		(drill 0.254)
		(layers "F.Cu" "B.Cu")
		(net "P1V9_LAN1")
	)
	(via
		(at 39.042848 -155.172918)
		(size 0.508)
		(drill 0.254)
		(layers "F.Cu" "B.Cu")
		(net "P1V9_LAN1")
	)
	(segment
		(start 49.714912 -153.373582)
		(end 50.014378 -153.673048)
		(width 0.508)
		(layer "B.Cu")
		(net "P1V9_LAN1")
	)
	(segment
		(start 49.297336 -154.39009)
		(end 50.014378 -153.673048)
		(width 0.508)
		(layer "B.Cu")
		(net "P1V9_LAN1")
	)
	(segment
		(start 49.944528 -152.128982)
		(end 50.04562 -152.02789)
		(width 0.508)
		(layer "B.Cu")
		(net "P1V9_LAN1")
	)
	(segment
		(start 49.158652 -153.373582)
		(end 49.714912 -153.373582)
		(width 0.508)
		(layer "B.Cu")
		(net "P1V9_LAN1")
	)
	(segment
		(start 49.158652 -152.128982)
		(end 49.944528 -152.128982)
		(width 0.508)
		(layer "B.Cu")
		(net "P1V9_LAN1")
	)
	(segment
		(start 49.15027 -154.39009)
		(end 49.297336 -154.39009)
		(width 0.508)
		(layer "B.Cu")
		(net "P1V9_LAN1")
	)
	(segment
		(start 175.164496 -41.788334)
		(end 175.586644 -42.210482)
		(width 0.10668)
		(layer "F.Cu")
		(net "USB1_L_DN")
	)
	(segment
		(start 170.128946 -40.663114)
		(end 171.117006 -40.663114)
		(width 0.10668)
		(layer "F.Cu")
		(net "USB1_L_DN")
	)
	(segment
		(start 176.76622 -45.103288)
		(end 175.15967 -45.103288)
		(width 0.10668)
		(layer "F.Cu")
		(net "USB1_L_DN")
	)
	(segment
		(start 175.15967 -45.103288)
		(end 174.83201 -44.775628)
		(width 0.10668)
		(layer "F.Cu")
		(net "USB1_L_DN")
	)
	(segment
		(start 173.262544 -41.355772)
		(end 173.486064 -41.355772)
		(width 0.10668)
		(layer "F.Cu")
		(net "USB1_L_DN")
	)
	(segment
		(start 171.117006 -40.663114)
		(end 171.119038 -40.665146)
		(width 0.10668)
		(layer "F.Cu")
		(net "USB1_L_DN")
	)
	(segment
		(start 174.83201 -44.775628)
		(end 174.83201 -44.561506)
		(width 0.10668)
		(layer "F.Cu")
		(net "USB1_L_DN")
	)
	(segment
		(start 171.915074 -41.007538)
		(end 172.91431 -41.007538)
		(width 0.10668)
		(layer "F.Cu")
		(net "USB1_L_DN")
	)
	(segment
		(start 171.119038 -40.665146)
		(end 171.572682 -40.665146)
		(width 0.10668)
		(layer "F.Cu")
		(net "USB1_L_DN")
	)
	(segment
		(start 171.572682 -40.665146)
		(end 171.915074 -41.007538)
		(width 0.10668)
		(layer "F.Cu")
		(net "USB1_L_DN")
	)
	(segment
		(start 175.586644 -43.806872)
		(end 175.586644 -42.718228)
		(width 0.10668)
		(layer "F.Cu")
		(net "USB1_L_DN")
	)
	(segment
		(start 173.486064 -41.355772)
		(end 173.918626 -41.788334)
		(width 0.10668)
		(layer "F.Cu")
		(net "USB1_L_DN")
	)
	(segment
		(start 174.83201 -44.561506)
		(end 175.586644 -43.806872)
		(width 0.10668)
		(layer "F.Cu")
		(net "USB1_L_DN")
	)
	(segment
		(start 180.23713 -42.88409)
		(end 178.985418 -42.88409)
		(width 0.10668)
		(layer "F.Cu")
		(net "USB1_L_DN")
	)
	(segment
		(start 178.985418 -42.88409)
		(end 176.76622 -45.103288)
		(width 0.10668)
		(layer "F.Cu")
		(net "USB1_L_DN")
	)
	(segment
		(start 173.918626 -41.788334)
		(end 175.164496 -41.788334)
		(width 0.10668)
		(layer "F.Cu")
		(net "USB1_L_DN")
	)
	(segment
		(start 175.586644 -42.210482)
		(end 175.586644 -42.718228)
		(width 0.10668)
		(layer "F.Cu")
		(net "USB1_L_DN")
	)
	(segment
		(start 172.91431 -41.007538)
		(end 173.262544 -41.355772)
		(width 0.10668)
		(layer "F.Cu")
		(net "USB1_L_DN")
	)
	(segment
		(start 181.09565 -42.02557)
		(end 180.23713 -42.88409)
		(width 0.10668)
		(layer "F.Cu")
		(net "USB1_L_DN")
	)
	(segment
		(start 152.510998 -142.48638)
		(end 152.510998 -141.587982)
		(width 0.1016)
		(layer "F.Cu")
		(net "PCH_I2C_ALERT_N")
	)
	(segment
		(start 51.03114 -166.8399)
		(end 51.03114 -167.57269)
		(width 0.1016)
		(layer "F.Cu")
		(net "PCH_I2C_ALERT_N")
	)
	(segment
		(start 153.11882 -140.98016)
		(end 153.62428 -140.98016)
		(width 0.1016)
		(layer "F.Cu")
		(net "PCH_I2C_ALERT_N")
	)
	(segment
		(start 152.510998 -141.587982)
		(end 153.11882 -140.98016)
		(width 0.1016)
		(layer "F.Cu")
		(net "PCH_I2C_ALERT_N")
	)
	(via
		(at 51.03114 -167.57269)
		(size 0.508)
		(drill 0.254)
		(layers "F.Cu" "B.Cu")
		(net "PCH_I2C_ALERT_N")
	)
	(via
		(at 153.62428 -140.98016)
		(size 0.508)
		(drill 0.254)
		(layers "F.Cu" "B.Cu")
		(net "PCH_I2C_ALERT_N")
	)
	(segment
		(start 87.60587 -164.224208)
		(end 86.3473 -164.224208)
		(width 0.1143)
		(layer "In2.Cu")
		(net "PCH_I2C_ALERT_N")
	)
	(segment
		(start 92.46997 -164.791898)
		(end 92.10548 -164.791898)
		(width 0.1143)
		(layer "In2.Cu")
		(net "PCH_I2C_ALERT_N")
	)
	(segment
		(start 104.8258 -167.27424)
		(end 101.320092 -167.27424)
		(width 0.1143)
		(layer "In2.Cu")
		(net "PCH_I2C_ALERT_N")
	)
	(segment
		(start 101.320092 -167.27424)
		(end 101.00437 -167.589962)
		(width 0.1143)
		(layer "In2.Cu")
		(net "PCH_I2C_ALERT_N")
	)
	(segment
		(start 118.787418 -167.117776)
		(end 118.36908 -166.699438)
		(width 0.1143)
		(layer "In2.Cu")
		(net "PCH_I2C_ALERT_N")
	)
	(segment
		(start 153.73096 -141.08684)
		(end 153.73096 -141.262608)
		(width 0.1143)
		(layer "In2.Cu")
		(net "PCH_I2C_ALERT_N")
	)
	(segment
		(start 51.54168 -167.57269)
		(end 51.03114 -167.57269)
		(width 0.1143)
		(layer "In2.Cu")
		(net "PCH_I2C_ALERT_N")
	)
	(segment
		(start 129.993136 -163.90874)
		(end 128.654556 -162.57016)
		(width 0.1143)
		(layer "In2.Cu")
		(net "PCH_I2C_ALERT_N")
	)
	(segment
		(start 134.796022 -163.90874)
		(end 129.993136 -163.90874)
		(width 0.1143)
		(layer "In2.Cu")
		(net "PCH_I2C_ALERT_N")
	)
	(segment
		(start 81.280254 -164.373306)
		(end 76.68514 -164.373306)
		(width 0.1143)
		(layer "In2.Cu")
		(net "PCH_I2C_ALERT_N")
	)
	(segment
		(start 92.79636 -165.137846)
		(end 92.79636 -165.118288)
		(width 0.1143)
		(layer "In2.Cu")
		(net "PCH_I2C_ALERT_N")
	)
	(segment
		(start 91.560904 -165.336474)
		(end 88.718136 -165.336474)
		(width 0.1143)
		(layer "In2.Cu")
		(net "PCH_I2C_ALERT_N")
	)
	(segment
		(start 85.8393 -163.716208)
		(end 85.310472 -163.716208)
		(width 0.1143)
		(layer "In2.Cu")
		(net "PCH_I2C_ALERT_N")
	)
	(segment
		(start 118.36908 -166.699438)
		(end 116.688108 -166.699438)
		(width 0.1143)
		(layer "In2.Cu")
		(net "PCH_I2C_ALERT_N")
	)
	(segment
		(start 120.44172 -163.020248)
		(end 120.44172 -165.852856)
		(width 0.1143)
		(layer "In2.Cu")
		(net "PCH_I2C_ALERT_N")
	)
	(segment
		(start 88.718136 -165.336474)
		(end 87.60587 -164.224208)
		(width 0.1143)
		(layer "In2.Cu")
		(net "PCH_I2C_ALERT_N")
	)
	(segment
		(start 105.206292 -167.654732)
		(end 104.8258 -167.27424)
		(width 0.1143)
		(layer "In2.Cu")
		(net "PCH_I2C_ALERT_N")
	)
	(segment
		(start 152.36952 -152.815544)
		(end 152.36952 -155.958032)
		(width 0.1143)
		(layer "In2.Cu")
		(net "PCH_I2C_ALERT_N")
	)
	(segment
		(start 119.1768 -167.117776)
		(end 118.787418 -167.117776)
		(width 0.1143)
		(layer "In2.Cu")
		(net "PCH_I2C_ALERT_N")
	)
	(segment
		(start 59.428126 -167.50665)
		(end 51.60772 -167.50665)
		(width 0.1143)
		(layer "In2.Cu")
		(net "PCH_I2C_ALERT_N")
	)
	(segment
		(start 152.36952 -155.958032)
		(end 146.788632 -161.53892)
		(width 0.1143)
		(layer "In2.Cu")
		(net "PCH_I2C_ALERT_N")
	)
	(segment
		(start 153.759408 -143.814292)
		(end 153.759408 -145.273522)
		(width 0.1143)
		(layer "In2.Cu")
		(net "PCH_I2C_ALERT_N")
	)
	(segment
		(start 113.00968 -166.205154)
		(end 111.560102 -167.654732)
		(width 0.1143)
		(layer "In2.Cu")
		(net "PCH_I2C_ALERT_N")
	)
	(segment
		(start 76.68514 -164.373306)
		(end 74.781156 -166.277036)
		(width 0.1143)
		(layer "In2.Cu")
		(net "PCH_I2C_ALERT_N")
	)
	(segment
		(start 101.00437 -167.589962)
		(end 100.440744 -167.589962)
		(width 0.1143)
		(layer "In2.Cu")
		(net "PCH_I2C_ALERT_N")
	)
	(segment
		(start 95.731838 -165.598856)
		(end 93.25737 -165.598856)
		(width 0.1143)
		(layer "In2.Cu")
		(net "PCH_I2C_ALERT_N")
	)
	(segment
		(start 72.315832 -168.11371)
		(end 67.101466 -168.11371)
		(width 0.1143)
		(layer "In2.Cu")
		(net "PCH_I2C_ALERT_N")
	)
	(segment
		(start 153.965148 -141.496796)
		(end 153.965148 -143.608552)
		(width 0.1143)
		(layer "In2.Cu")
		(net "PCH_I2C_ALERT_N")
	)
	(segment
		(start 81.961482 -163.692078)
		(end 81.280254 -164.373306)
		(width 0.1143)
		(layer "In2.Cu")
		(net "PCH_I2C_ALERT_N")
	)
	(segment
		(start 86.3473 -164.224208)
		(end 85.8393 -163.716208)
		(width 0.1143)
		(layer "In2.Cu")
		(net "PCH_I2C_ALERT_N")
	)
	(segment
		(start 66.91122 -167.923464)
		(end 59.84494 -167.923464)
		(width 0.1143)
		(layer "In2.Cu")
		(net "PCH_I2C_ALERT_N")
	)
	(segment
		(start 140.268452 -163.138358)
		(end 135.566404 -163.138358)
		(width 0.1143)
		(layer "In2.Cu")
		(net "PCH_I2C_ALERT_N")
	)
	(segment
		(start 153.965148 -143.608552)
		(end 153.759408 -143.814292)
		(width 0.1143)
		(layer "In2.Cu")
		(net "PCH_I2C_ALERT_N")
	)
	(segment
		(start 146.788632 -161.53892)
		(end 143.48968 -161.53892)
		(width 0.1143)
		(layer "In2.Cu")
		(net "PCH_I2C_ALERT_N")
	)
	(segment
		(start 143.48968 -161.53892)
		(end 142.559786 -162.468814)
		(width 0.1143)
		(layer "In2.Cu")
		(net "PCH_I2C_ALERT_N")
	)
	(segment
		(start 140.937996 -162.468814)
		(end 140.268452 -163.138358)
		(width 0.1143)
		(layer "In2.Cu")
		(net "PCH_I2C_ALERT_N")
	)
	(segment
		(start 111.560102 -167.654732)
		(end 105.206292 -167.654732)
		(width 0.1143)
		(layer "In2.Cu")
		(net "PCH_I2C_ALERT_N")
	)
	(segment
		(start 153.62428 -140.98016)
		(end 153.73096 -141.08684)
		(width 0.1143)
		(layer "In2.Cu")
		(net "PCH_I2C_ALERT_N")
	)
	(segment
		(start 96.24822 -166.115238)
		(end 95.731838 -165.598856)
		(width 0.1143)
		(layer "In2.Cu")
		(net "PCH_I2C_ALERT_N")
	)
	(segment
		(start 116.688108 -166.699438)
		(end 116.193824 -166.205154)
		(width 0.1143)
		(layer "In2.Cu")
		(net "PCH_I2C_ALERT_N")
	)
	(segment
		(start 85.286342 -163.692078)
		(end 81.961482 -163.692078)
		(width 0.1143)
		(layer "In2.Cu")
		(net "PCH_I2C_ALERT_N")
	)
	(segment
		(start 116.193824 -166.205154)
		(end 113.00968 -166.205154)
		(width 0.1143)
		(layer "In2.Cu")
		(net "PCH_I2C_ALERT_N")
	)
	(segment
		(start 128.654556 -162.57016)
		(end 125.895608 -162.57016)
		(width 0.1143)
		(layer "In2.Cu")
		(net "PCH_I2C_ALERT_N")
	)
	(segment
		(start 120.44172 -165.852856)
		(end 119.1768 -167.117776)
		(width 0.1143)
		(layer "In2.Cu")
		(net "PCH_I2C_ALERT_N")
	)
	(segment
		(start 153.304494 -151.88057)
		(end 152.36952 -152.815544)
		(width 0.1143)
		(layer "In2.Cu")
		(net "PCH_I2C_ALERT_N")
	)
	(segment
		(start 74.152506 -166.277036)
		(end 72.315832 -168.11371)
		(width 0.1143)
		(layer "In2.Cu")
		(net "PCH_I2C_ALERT_N")
	)
	(segment
		(start 135.566404 -163.138358)
		(end 134.796022 -163.90874)
		(width 0.1143)
		(layer "In2.Cu")
		(net "PCH_I2C_ALERT_N")
	)
	(segment
		(start 85.310472 -163.716208)
		(end 85.286342 -163.692078)
		(width 0.1143)
		(layer "In2.Cu")
		(net "PCH_I2C_ALERT_N")
	)
	(segment
		(start 92.10548 -164.791898)
		(end 91.560904 -165.336474)
		(width 0.1143)
		(layer "In2.Cu")
		(net "PCH_I2C_ALERT_N")
	)
	(segment
		(start 125.264164 -161.938716)
		(end 121.523252 -161.938716)
		(width 0.1143)
		(layer "In2.Cu")
		(net "PCH_I2C_ALERT_N")
	)
	(segment
		(start 125.895608 -162.57016)
		(end 125.264164 -161.938716)
		(width 0.1143)
		(layer "In2.Cu")
		(net "PCH_I2C_ALERT_N")
	)
	(segment
		(start 51.60772 -167.50665)
		(end 51.54168 -167.57269)
		(width 0.1143)
		(layer "In2.Cu")
		(net "PCH_I2C_ALERT_N")
	)
	(segment
		(start 100.440744 -167.589962)
		(end 98.96602 -166.115238)
		(width 0.1143)
		(layer "In2.Cu")
		(net "PCH_I2C_ALERT_N")
	)
	(segment
		(start 74.781156 -166.277036)
		(end 74.152506 -166.277036)
		(width 0.1143)
		(layer "In2.Cu")
		(net "PCH_I2C_ALERT_N")
	)
	(segment
		(start 142.559786 -162.468814)
		(end 140.937996 -162.468814)
		(width 0.1143)
		(layer "In2.Cu")
		(net "PCH_I2C_ALERT_N")
	)
	(segment
		(start 153.73096 -141.262608)
		(end 153.965148 -141.496796)
		(width 0.1143)
		(layer "In2.Cu")
		(net "PCH_I2C_ALERT_N")
	)
	(segment
		(start 98.96602 -166.115238)
		(end 96.24822 -166.115238)
		(width 0.1143)
		(layer "In2.Cu")
		(net "PCH_I2C_ALERT_N")
	)
	(segment
		(start 153.759408 -145.273522)
		(end 153.304494 -145.728436)
		(width 0.1143)
		(layer "In2.Cu")
		(net "PCH_I2C_ALERT_N")
	)
	(segment
		(start 93.25737 -165.598856)
		(end 92.79636 -165.137846)
		(width 0.1143)
		(layer "In2.Cu")
		(net "PCH_I2C_ALERT_N")
	)
	(segment
		(start 121.523252 -161.938716)
		(end 120.44172 -163.020248)
		(width 0.1143)
		(layer "In2.Cu")
		(net "PCH_I2C_ALERT_N")
	)
	(segment
		(start 59.84494 -167.923464)
		(end 59.428126 -167.50665)
		(width 0.1143)
		(layer "In2.Cu")
		(net "PCH_I2C_ALERT_N")
	)
	(segment
		(start 153.304494 -145.728436)
		(end 153.304494 -151.88057)
		(width 0.1143)
		(layer "In2.Cu")
		(net "PCH_I2C_ALERT_N")
	)
	(segment
		(start 92.79636 -165.118288)
		(end 92.46997 -164.791898)
		(width 0.1143)
		(layer "In2.Cu")
		(net "PCH_I2C_ALERT_N")
	)
	(segment
		(start 67.101466 -168.11371)
		(end 66.91122 -167.923464)
		(width 0.1143)
		(layer "In2.Cu")
		(net "PCH_I2C_ALERT_N")
	)
	(segment
		(start 179.115974 -43.19905)
		(end 176.896776 -45.418248)
		(width 0.10668)
		(layer "F.Cu")
		(net "USB1_L_DP")
	)
	(segment
		(start 181.09565 -44.05757)
		(end 180.23713 -43.19905)
		(width 0.10668)
		(layer "F.Cu")
		(net "USB1_L_DP")
	)
	(segment
		(start 180.23713 -43.19905)
		(end 179.115974 -43.19905)
		(width 0.10668)
		(layer "F.Cu")
		(net "USB1_L_DP")
	)
	(segment
		(start 171.572682 -41.66489)
		(end 171.915074 -41.322498)
		(width 0.10668)
		(layer "F.Cu")
		(net "USB1_L_DP")
	)
	(segment
		(start 173.686724 -43.765216)
		(end 173.686724 -42.718228)
		(width 0.10668)
		(layer "F.Cu")
		(net "USB1_L_DP")
	)
	(segment
		(start 174.51705 -44.906184)
		(end 174.51705 -44.595542)
		(width 0.10668)
		(layer "F.Cu")
		(net "USB1_L_DP")
	)
	(segment
		(start 172.783754 -41.322498)
		(end 173.131988 -41.670732)
		(width 0.10668)
		(layer "F.Cu")
		(net "USB1_L_DP")
	)
	(segment
		(start 171.119038 -41.66489)
		(end 171.572682 -41.66489)
		(width 0.10668)
		(layer "F.Cu")
		(net "USB1_L_DP")
	)
	(segment
		(start 170.128946 -41.679114)
		(end 171.104814 -41.679114)
		(width 0.10668)
		(layer "F.Cu")
		(net "USB1_L_DP")
	)
	(segment
		(start 174.51705 -44.595542)
		(end 173.686724 -43.765216)
		(width 0.10668)
		(layer "F.Cu")
		(net "USB1_L_DP")
	)
	(segment
		(start 171.104814 -41.679114)
		(end 171.119038 -41.66489)
		(width 0.10668)
		(layer "F.Cu")
		(net "USB1_L_DP")
	)
	(segment
		(start 171.915074 -41.322498)
		(end 172.783754 -41.322498)
		(width 0.10668)
		(layer "F.Cu")
		(net "USB1_L_DP")
	)
	(segment
		(start 173.686724 -42.004234)
		(end 173.686724 -42.718228)
		(width 0.10668)
		(layer "F.Cu")
		(net "USB1_L_DP")
	)
	(segment
		(start 173.131988 -41.670732)
		(end 173.353222 -41.670732)
		(width 0.10668)
		(layer "F.Cu")
		(net "USB1_L_DP")
	)
	(segment
		(start 175.029114 -45.418248)
		(end 174.51705 -44.906184)
		(width 0.10668)
		(layer "F.Cu")
		(net "USB1_L_DP")
	)
	(segment
		(start 173.353222 -41.670732)
		(end 173.686724 -42.004234)
		(width 0.10668)
		(layer "F.Cu")
		(net "USB1_L_DP")
	)
	(segment
		(start 176.896776 -45.418248)
		(end 175.029114 -45.418248)
		(width 0.10668)
		(layer "F.Cu")
		(net "USB1_L_DP")
	)
	(segment
		(start 171.468542 -37.955728)
		(end 171.064936 -37.955728)
		(width 0.10668)
		(layer "F.Cu")
		(net "USB0_L_DP")
	)
	(segment
		(start 171.06392 -37.954712)
		(end 171.064936 -37.955728)
		(width 0.10668)
		(layer "F.Cu")
		(net "USB0_L_DP")
	)
	(segment
		(start 174.073566 -41.143682)
		(end 173.686724 -40.75684)
		(width 0.10668)
		(layer "F.Cu")
		(net "USB0_L_DP")
	)
	(segment
		(start 176.826164 -41.596056)
		(end 175.809148 -41.596056)
		(width 0.10668)
		(layer "F.Cu")
		(net "USB0_L_DP")
	)
	(segment
		(start 182.482998 -43.19905)
		(end 182.052722 -42.768774)
		(width 0.10668)
		(layer "F.Cu")
		(net "USB0_L_DP")
	)
	(segment
		(start 177.458624 -40.963596)
		(end 176.826164 -41.596056)
		(width 0.10668)
		(layer "F.Cu")
		(net "USB0_L_DP")
	)
	(segment
		(start 173.984666 -37.613336)
		(end 171.810934 -37.613336)
		(width 0.10668)
		(layer "F.Cu")
		(net "USB0_L_DP")
	)
	(segment
		(start 182.052722 -41.405048)
		(end 181.61127 -40.963596)
		(width 0.10668)
		(layer "F.Cu")
		(net "USB0_L_DP")
	)
	(segment
		(start 173.686724 -39.31793)
		(end 174.54626 -38.458394)
		(width 0.10668)
		(layer "F.Cu")
		(net "USB0_L_DP")
	)
	(segment
		(start 174.54626 -38.17493)
		(end 173.984666 -37.613336)
		(width 0.10668)
		(layer "F.Cu")
		(net "USB0_L_DP")
	)
	(segment
		(start 182.052722 -42.768774)
		(end 182.052722 -41.405048)
		(width 0.10668)
		(layer "F.Cu")
		(net "USB0_L_DP")
	)
	(segment
		(start 175.356774 -41.143682)
		(end 174.073566 -41.143682)
		(width 0.10668)
		(layer "F.Cu")
		(net "USB0_L_DP")
	)
	(segment
		(start 174.54626 -38.458394)
		(end 174.54626 -38.17493)
		(width 0.10668)
		(layer "F.Cu")
		(net "USB0_L_DP")
	)
	(segment
		(start 182.85333 -43.19905)
		(end 182.482998 -43.19905)
		(width 0.10668)
		(layer "F.Cu")
		(net "USB0_L_DP")
	)
	(segment
		(start 170.049444 -37.954712)
		(end 171.06392 -37.954712)
		(width 0.10668)
		(layer "F.Cu")
		(net "USB0_L_DP")
	)
	(segment
		(start 181.61127 -40.963596)
		(end 177.458624 -40.963596)
		(width 0.10668)
		(layer "F.Cu")
		(net "USB0_L_DP")
	)
	(segment
		(start 173.686724 -40.75684)
		(end 173.686724 -40.268144)
		(width 0.10668)
		(layer "F.Cu")
		(net "USB0_L_DP")
	)
	(segment
		(start 173.686724 -40.268144)
		(end 173.686724 -39.31793)
		(width 0.10668)
		(layer "F.Cu")
		(net "USB0_L_DP")
	)
	(segment
		(start 175.809148 -41.596056)
		(end 175.356774 -41.143682)
		(width 0.10668)
		(layer "F.Cu")
		(net "USB0_L_DP")
	)
	(segment
		(start 183.71185 -44.05757)
		(end 182.85333 -43.19905)
		(width 0.10668)
		(layer "F.Cu")
		(net "USB0_L_DP")
	)
	(segment
		(start 171.810934 -37.613336)
		(end 171.468542 -37.955728)
		(width 0.10668)
		(layer "F.Cu")
		(net "USB0_L_DP")
	)
	(segment
		(start 181.741826 -40.648636)
		(end 177.328068 -40.648636)
		(width 0.10668)
		(layer "F.Cu")
		(net "USB0_L_DN")
	)
	(segment
		(start 182.613554 -42.88409)
		(end 182.367682 -42.638218)
		(width 0.10668)
		(layer "F.Cu")
		(net "USB0_L_DN")
	)
	(segment
		(start 183.71185 -42.02557)
		(end 182.85333 -42.88409)
		(width 0.10668)
		(layer "F.Cu")
		(net "USB0_L_DN")
	)
	(segment
		(start 171.468542 -36.955984)
		(end 171.064936 -36.955984)
		(width 0.10668)
		(layer "F.Cu")
		(net "USB0_L_DN")
	)
	(segment
		(start 175.586644 -40.268144)
		(end 175.586644 -39.204138)
		(width 0.10668)
		(layer "F.Cu")
		(net "USB0_L_DN")
	)
	(segment
		(start 182.367682 -42.638218)
		(end 182.367682 -41.274492)
		(width 0.10668)
		(layer "F.Cu")
		(net "USB0_L_DN")
	)
	(segment
		(start 171.810934 -37.298376)
		(end 171.468542 -36.955984)
		(width 0.10668)
		(layer "F.Cu")
		(net "USB0_L_DN")
	)
	(segment
		(start 182.85333 -42.88409)
		(end 182.613554 -42.88409)
		(width 0.10668)
		(layer "F.Cu")
		(net "USB0_L_DN")
	)
	(segment
		(start 175.586644 -40.933624)
		(end 175.586644 -40.268144)
		(width 0.10668)
		(layer "F.Cu")
		(net "USB0_L_DN")
	)
	(segment
		(start 174.86122 -38.044374)
		(end 174.115222 -37.298376)
		(width 0.10668)
		(layer "F.Cu")
		(net "USB0_L_DN")
	)
	(segment
		(start 177.328068 -40.648636)
		(end 176.695608 -41.281096)
		(width 0.10668)
		(layer "F.Cu")
		(net "USB0_L_DN")
	)
	(segment
		(start 170.238166 -36.938712)
		(end 170.255438 -36.955984)
		(width 0.10668)
		(layer "F.Cu")
		(net "USB0_L_DN")
	)
	(segment
		(start 182.367682 -41.274492)
		(end 181.741826 -40.648636)
		(width 0.10668)
		(layer "F.Cu")
		(net "USB0_L_DN")
	)
	(segment
		(start 170.049444 -36.938712)
		(end 170.238166 -36.938712)
		(width 0.10668)
		(layer "F.Cu")
		(net "USB0_L_DN")
	)
	(segment
		(start 170.255438 -36.955984)
		(end 171.064936 -36.955984)
		(width 0.10668)
		(layer "F.Cu")
		(net "USB0_L_DN")
	)
	(segment
		(start 174.86122 -38.478714)
		(end 174.86122 -38.044374)
		(width 0.10668)
		(layer "F.Cu")
		(net "USB0_L_DN")
	)
	(segment
		(start 174.115222 -37.298376)
		(end 171.810934 -37.298376)
		(width 0.10668)
		(layer "F.Cu")
		(net "USB0_L_DN")
	)
	(segment
		(start 175.586644 -39.204138)
		(end 174.86122 -38.478714)
		(width 0.10668)
		(layer "F.Cu")
		(net "USB0_L_DN")
	)
	(segment
		(start 176.695608 -41.281096)
		(end 175.934116 -41.281096)
		(width 0.10668)
		(layer "F.Cu")
		(net "USB0_L_DN")
	)
	(segment
		(start 175.934116 -41.281096)
		(end 175.586644 -40.933624)
		(width 0.10668)
		(layer "F.Cu")
		(net "USB0_L_DN")
	)
	(segment
		(start 42.40022 -147.30349)
		(end 42.40022 -146.92249)
		(width 0.1016)
		(layer "F.Cu")
		(net "LAN1_NC_SI_RXD0")
	)
	(segment
		(start 43.317668 -148.220938)
		(end 42.40022 -147.30349)
		(width 0.1016)
		(layer "F.Cu")
		(net "LAN1_NC_SI_RXD0")
	)
	(segment
		(start 43.317668 -150.37308)
		(end 43.317668 -148.220938)
		(width 0.1016)
		(layer "F.Cu")
		(net "LAN1_NC_SI_RXD0")
	)
	(segment
		(start 42.332402 -146.204432)
		(end 42.332402 -146.854672)
		(width 0.1016)
		(layer "F.Cu")
		(net "LAN1_NC_SI_RXD0")
	)
	(segment
		(start 42.332402 -146.854672)
		(end 42.40022 -146.92249)
		(width 0.1016)
		(layer "F.Cu")
		(net "LAN1_NC_SI_RXD0")
	)
	(via
		(at 42.40022 -146.92249)
		(size 0.508)
		(drill 0.254)
		(layers "F.Cu" "B.Cu")
		(net "LAN1_NC_SI_RXD0")
	)
	(segment
		(start 42.817542 -148.812758)
		(end 42.30878 -148.303996)
		(width 0.1016)
		(layer "F.Cu")
		(net "LAN1_NC_SI_RXD1")
	)
	(segment
		(start 41.316402 -146.727672)
		(end 41.316402 -146.204432)
		(width 0.1016)
		(layer "F.Cu")
		(net "LAN1_NC_SI_RXD1")
	)
	(segment
		(start 41.67378 -147.08505)
		(end 41.316402 -146.727672)
		(width 0.1016)
		(layer "F.Cu")
		(net "LAN1_NC_SI_RXD1")
	)
	(segment
		(start 41.67378 -147.668996)
		(end 41.67378 -147.08505)
		(width 0.1016)
		(layer "F.Cu")
		(net "LAN1_NC_SI_RXD1")
	)
	(segment
		(start 42.30878 -148.303996)
		(end 41.67378 -147.668996)
		(width 0.1016)
		(layer "F.Cu")
		(net "LAN1_NC_SI_RXD1")
	)
	(segment
		(start 42.817542 -150.37308)
		(end 42.817542 -148.812758)
		(width 0.1016)
		(layer "F.Cu")
		(net "LAN1_NC_SI_RXD1")
	)
	(via
		(at 42.30878 -148.303996)
		(size 0.508)
		(drill 0.254)
		(layers "F.Cu" "B.Cu")
		(net "LAN1_NC_SI_RXD1")
	)
	(segment
		(start 59.504326 -151.638254)
		(end 59.504326 -153.068782)
		(width 0.1016)
		(layer "F.Cu")
		(net "LAN1_NVM_WP_N")
	)
	(segment
		(start 62.534546 -151.481028)
		(end 61.939678 -151.481028)
		(width 0.1016)
		(layer "F.Cu")
		(net "LAN1_NVM_WP_N")
	)
	(segment
		(start 59.9821 -151.16048)
		(end 59.504326 -151.638254)
		(width 0.1016)
		(layer "F.Cu")
		(net "LAN1_NVM_WP_N")
	)
	(segment
		(start 61.939678 -151.481028)
		(end 61.67882 -151.741886)
		(width 0.1016)
		(layer "F.Cu")
		(net "LAN1_NVM_WP_N")
	)
	(segment
		(start 61.67882 -151.741886)
		(end 61.67882 -151.74341)
		(width 0.1016)
		(layer "F.Cu")
		(net "LAN1_NVM_WP_N")
	)
	(segment
		(start 61.67882 -151.741886)
		(end 61.097414 -151.16048)
		(width 0.1016)
		(layer "F.Cu")
		(net "LAN1_NVM_WP_N")
	)
	(segment
		(start 61.097414 -151.16048)
		(end 59.9821 -151.16048)
		(width 0.1016)
		(layer "F.Cu")
		(net "LAN1_NVM_WP_N")
	)
	(via
		(at 61.67882 -151.74341)
		(size 0.508)
		(drill 0.254)
		(layers "F.Cu" "B.Cu")
		(net "LAN1_NVM_WP_N")
	)
	(segment
		(start 40.24122 -146.23034)
		(end 40.24122 -146.44751)
		(width 0.1016)
		(layer "F.Cu")
		(net "LAN1_NC_SI_CRS_DV")
	)
	(segment
		(start 40.96512 -148.036534)
		(end 40.96512 -147.72259)
		(width 0.1016)
		(layer "F.Cu")
		(net "LAN1_NC_SI_CRS_DV")
	)
	(segment
		(start 41.817544 -148.888958)
		(end 40.96512 -148.036534)
		(width 0.1016)
		(layer "F.Cu")
		(net "LAN1_NC_SI_CRS_DV")
	)
	(segment
		(start 41.817544 -150.37308)
		(end 41.817544 -148.888958)
		(width 0.1016)
		(layer "F.Cu")
		(net "LAN1_NC_SI_CRS_DV")
	)
	(segment
		(start 40.96512 -147.17141)
		(end 40.96512 -147.72259)
		(width 0.1016)
		(layer "F.Cu")
		(net "LAN1_NC_SI_CRS_DV")
	)
	(segment
		(start 40.24122 -146.44751)
		(end 40.96512 -147.17141)
		(width 0.1016)
		(layer "F.Cu")
		(net "LAN1_NC_SI_CRS_DV")
	)
	(via
		(at 40.96512 -147.72259)
		(size 0.508)
		(drill 0.254)
		(layers "F.Cu" "B.Cu")
		(net "LAN1_NC_SI_CRS_DV")
	)
	(segment
		(start 58.234326 -158.351982)
		(end 58.234326 -159.744156)
		(width 0.1016)
		(layer "F.Cu")
		(net "LAN1_NVM_HOLD_N")
	)
	(segment
		(start 57.195466 -161.528506)
		(end 57.195466 -160.783016)
		(width 0.1016)
		(layer "F.Cu")
		(net "LAN1_NVM_HOLD_N")
	)
	(segment
		(start 58.234326 -159.744156)
		(end 57.98566 -159.992822)
		(width 0.1016)
		(layer "F.Cu")
		(net "LAN1_NVM_HOLD_N")
	)
	(segment
		(start 57.195466 -160.783016)
		(end 57.98566 -159.992822)
		(width 0.1016)
		(layer "F.Cu")
		(net "LAN1_NVM_HOLD_N")
	)
	(via
		(at 57.98566 -159.992822)
		(size 0.508)
		(drill 0.254)
		(layers "F.Cu" "B.Cu")
		(net "LAN1_NVM_HOLD_N")
	)
	(segment
		(start 44.516802 -146.930872)
		(end 44.53382 -146.94789)
		(width 0.1016)
		(layer "F.Cu")
		(net "LAN1_NC_SI_TDX1")
	)
	(segment
		(start 44.317666 -147.164044)
		(end 44.53382 -146.94789)
		(width 0.1016)
		(layer "F.Cu")
		(net "LAN1_NC_SI_TDX1")
	)
	(segment
		(start 44.516802 -146.229832)
		(end 44.516802 -146.930872)
		(width 0.1016)
		(layer "F.Cu")
		(net "LAN1_NC_SI_TDX1")
	)
	(segment
		(start 44.317666 -150.37308)
		(end 44.317666 -147.164044)
		(width 0.1016)
		(layer "F.Cu")
		(net "LAN1_NC_SI_TDX1")
	)
	(via
		(at 44.53382 -146.94789)
		(size 0.508)
		(drill 0.254)
		(layers "F.Cu" "B.Cu")
		(net "LAN1_NC_SI_TDX1")
	)
	(segment
		(start 69.665088 -89.542366)
		(end 70.627494 -90.504772)
		(width 0.1016)
		(layer "F.Cu")
		(net "LAN2_DISABLE_N")
	)
	(segment
		(start 69.665088 -88.905588)
		(end 69.665088 -89.542366)
		(width 0.1016)
		(layer "F.Cu")
		(net "LAN2_DISABLE_N")
	)
	(segment
		(start 69.922644 -88.187784)
		(end 69.922644 -88.648032)
		(width 0.1016)
		(layer "F.Cu")
		(net "LAN2_DISABLE_N")
	)
	(segment
		(start 155.799028 -151.34717)
		(end 156.470096 -151.34717)
		(width 0.1016)
		(layer "F.Cu")
		(net "LAN2_DISABLE_N")
	)
	(segment
		(start 69.611748 -87.700358)
		(end 69.611748 -87.876888)
		(width 0.1016)
		(layer "F.Cu")
		(net "LAN2_DISABLE_N")
	)
	(segment
		(start 153.295096 -150.918164)
		(end 153.74366 -150.918164)
		(width 0.1016)
		(layer "F.Cu")
		(net "LAN2_DISABLE_N")
	)
	(segment
		(start 153.062178 -150.14067)
		(end 153.062178 -150.685246)
		(width 0.1016)
		(layer "F.Cu")
		(net "LAN2_DISABLE_N")
	)
	(segment
		(start 70.627494 -90.504772)
		(end 72.614536 -90.504772)
		(width 0.1016)
		(layer "F.Cu")
		(net "LAN2_DISABLE_N")
	)
	(segment
		(start 153.062178 -150.685246)
		(end 153.295096 -150.918164)
		(width 0.1016)
		(layer "F.Cu")
		(net "LAN2_DISABLE_N")
	)
	(segment
		(start 69.611748 -87.876888)
		(end 69.922644 -88.187784)
		(width 0.1016)
		(layer "F.Cu")
		(net "LAN2_DISABLE_N")
	)
	(segment
		(start 155.370022 -150.918164)
		(end 155.799028 -151.34717)
		(width 0.1016)
		(layer "F.Cu")
		(net "LAN2_DISABLE_N")
	)
	(segment
		(start 69.922644 -88.648032)
		(end 69.665088 -88.905588)
		(width 0.1016)
		(layer "F.Cu")
		(net "LAN2_DISABLE_N")
	)
	(segment
		(start 72.614536 -90.504772)
		(end 72.64908 -90.539316)
		(width 0.1016)
		(layer "F.Cu")
		(net "LAN2_DISABLE_N")
	)
	(segment
		(start 153.74366 -150.918164)
		(end 155.370022 -150.918164)
		(width 0.1016)
		(layer "F.Cu")
		(net "LAN2_DISABLE_N")
	)
	(via
		(at 153.74366 -150.918164)
		(size 0.508)
		(drill 0.254)
		(layers "F.Cu" "B.Cu")
		(net "LAN2_DISABLE_N")
	)
	(via
		(at 98.99396 -102.80015)
		(size 0.508)
		(drill 0.254)
		(layers "F.Cu" "B.Cu")
		(net "LAN2_DISABLE_N")
	)
	(via
		(at 74.49566 -98.993198)
		(size 0.508)
		(drill 0.254)
		(layers "F.Cu" "B.Cu")
		(net "LAN2_DISABLE_N")
	)
	(via
		(at 97.4725 -111.012732)
		(size 0.508)
		(drill 0.254)
		(layers "F.Cu" "B.Cu")
		(net "LAN2_DISABLE_N")
	)
	(via
		(at 72.64908 -90.539316)
		(size 0.508)
		(drill 0.254)
		(layers "F.Cu" "B.Cu")
		(net "LAN2_DISABLE_N")
	)
	(segment
		(start 73.500234 -91.39047)
		(end 73.500234 -94.644464)
		(width 0.1016)
		(layer "B.Cu")
		(net "LAN2_DISABLE_N")
	)
	(segment
		(start 73.37298 -94.771718)
		(end 73.37298 -96.619568)
		(width 0.1016)
		(layer "B.Cu")
		(net "LAN2_DISABLE_N")
	)
	(segment
		(start 73.37298 -96.619568)
		(end 74.49566 -97.742248)
		(width 0.1016)
		(layer "B.Cu")
		(net "LAN2_DISABLE_N")
	)
	(segment
		(start 73.500234 -94.644464)
		(end 73.37298 -94.771718)
		(width 0.1016)
		(layer "B.Cu")
		(net "LAN2_DISABLE_N")
	)
	(segment
		(start 72.64908 -90.539316)
		(end 73.500234 -91.39047)
		(width 0.1016)
		(layer "B.Cu")
		(net "LAN2_DISABLE_N")
	)
	(segment
		(start 74.49566 -97.742248)
		(end 74.49566 -98.993198)
		(width 0.1016)
		(layer "B.Cu")
		(net "LAN2_DISABLE_N")
	)
	(segment
		(start 97.4725 -111.012732)
		(end 97.4725 -104.32161)
		(width 0.1143)
		(layer "In2.Cu")
		(net "LAN2_DISABLE_N")
	)
	(segment
		(start 97.4725 -104.32161)
		(end 98.99396 -102.80015)
		(width 0.1143)
		(layer "In2.Cu")
		(net "LAN2_DISABLE_N")
	)
	(segment
		(start 99.55022 -111.012732)
		(end 99.836986 -110.725966)
		(width 0.1143)
		(layer "In7.Cu")
		(net "LAN2_DISABLE_N")
	)
	(segment
		(start 85.04809 -101.678232)
		(end 97.872042 -101.678232)
		(width 0.1143)
		(layer "In7.Cu")
		(net "LAN2_DISABLE_N")
	)
	(segment
		(start 74.49566 -98.993198)
		(end 75.651614 -98.993198)
		(width 0.1143)
		(layer "In7.Cu")
		(net "LAN2_DISABLE_N")
	)
	(segment
		(start 128.353312 -132.16255)
		(end 128.93548 -132.744718)
		(width 0.1143)
		(layer "In7.Cu")
		(net "LAN2_DISABLE_N")
	)
	(segment
		(start 145.250916 -132.744718)
		(end 152.226772 -139.720574)
		(width 0.1143)
		(layer "In7.Cu")
		(net "LAN2_DISABLE_N")
	)
	(segment
		(start 121.7295 -114.072924)
		(end 121.7295 -115.36172)
		(width 0.1143)
		(layer "In7.Cu")
		(net "LAN2_DISABLE_N")
	)
	(segment
		(start 123.74118 -127.870966)
		(end 128.032764 -132.16255)
		(width 0.1143)
		(layer "In7.Cu")
		(net "LAN2_DISABLE_N")
	)
	(segment
		(start 123.74118 -118.761764)
		(end 123.74118 -127.870966)
		(width 0.1143)
		(layer "In7.Cu")
		(net "LAN2_DISABLE_N")
	)
	(segment
		(start 152.226772 -149.401276)
		(end 153.74366 -150.918164)
		(width 0.1143)
		(layer "In7.Cu")
		(net "LAN2_DISABLE_N")
	)
	(segment
		(start 97.872042 -101.678232)
		(end 98.99396 -102.80015)
		(width 0.1143)
		(layer "In7.Cu")
		(net "LAN2_DISABLE_N")
	)
	(segment
		(start 128.93548 -132.744718)
		(end 145.250916 -132.744718)
		(width 0.1143)
		(layer "In7.Cu")
		(net "LAN2_DISABLE_N")
	)
	(segment
		(start 76.495656 -99.83724)
		(end 83.207098 -99.83724)
		(width 0.1143)
		(layer "In7.Cu")
		(net "LAN2_DISABLE_N")
	)
	(segment
		(start 75.651614 -98.993198)
		(end 76.495656 -99.83724)
		(width 0.1143)
		(layer "In7.Cu")
		(net "LAN2_DISABLE_N")
	)
	(segment
		(start 123.4186 -117.05082)
		(end 123.4186 -118.439184)
		(width 0.1143)
		(layer "In7.Cu")
		(net "LAN2_DISABLE_N")
	)
	(segment
		(start 97.4725 -111.012732)
		(end 99.55022 -111.012732)
		(width 0.1143)
		(layer "In7.Cu")
		(net "LAN2_DISABLE_N")
	)
	(segment
		(start 83.207098 -99.83724)
		(end 85.04809 -101.678232)
		(width 0.1143)
		(layer "In7.Cu")
		(net "LAN2_DISABLE_N")
	)
	(segment
		(start 99.836986 -110.725966)
		(end 118.382542 -110.725966)
		(width 0.1143)
		(layer "In7.Cu")
		(net "LAN2_DISABLE_N")
	)
	(segment
		(start 121.7295 -115.36172)
		(end 123.4186 -117.05082)
		(width 0.1143)
		(layer "In7.Cu")
		(net "LAN2_DISABLE_N")
	)
	(segment
		(start 118.382542 -110.725966)
		(end 121.7295 -114.072924)
		(width 0.1143)
		(layer "In7.Cu")
		(net "LAN2_DISABLE_N")
	)
	(segment
		(start 128.032764 -132.16255)
		(end 128.353312 -132.16255)
		(width 0.1143)
		(layer "In7.Cu")
		(net "LAN2_DISABLE_N")
	)
	(segment
		(start 123.4186 -118.439184)
		(end 123.74118 -118.761764)
		(width 0.1143)
		(layer "In7.Cu")
		(net "LAN2_DISABLE_N")
	)
	(segment
		(start 152.226772 -139.720574)
		(end 152.226772 -149.401276)
		(width 0.1143)
		(layer "In7.Cu")
		(net "LAN2_DISABLE_N")
	)
	(segment
		(start 44.817538 -150.37308)
		(end 44.817538 -148.569172)
		(width 0.1016)
		(layer "F.Cu")
		(net "LAN1_NC_SI_TDX0")
	)
	(segment
		(start 44.817538 -148.569172)
		(end 45.16882 -148.21789)
		(width 0.1016)
		(layer "F.Cu")
		(net "LAN1_NC_SI_TDX0")
	)
	(segment
		(start 45.532802 -147.853908)
		(end 45.16882 -148.21789)
		(width 0.1016)
		(layer "F.Cu")
		(net "LAN1_NC_SI_TDX0")
	)
	(segment
		(start 45.532802 -146.229832)
		(end 45.532802 -147.853908)
		(width 0.1016)
		(layer "F.Cu")
		(net "LAN1_NC_SI_TDX0")
	)
	(via
		(at 45.16882 -148.21789)
		(size 0.508)
		(drill 0.254)
		(layers "F.Cu" "B.Cu")
		(net "LAN1_NC_SI_TDX0")
	)
	(segment
		(start 43.41622 -147.50669)
		(end 43.79722 -147.88769)
		(width 0.1016)
		(layer "F.Cu")
		(net "LAN1_NC_SI_TX_EN")
	)
	(segment
		(start 43.79722 -147.88769)
		(end 43.79722 -148.34489)
		(width 0.1016)
		(layer "F.Cu")
		(net "LAN1_NC_SI_TX_EN")
	)
	(segment
		(start 43.41622 -146.23034)
		(end 43.41622 -147.50669)
		(width 0.1016)
		(layer "F.Cu")
		(net "LAN1_NC_SI_TX_EN")
	)
	(segment
		(start 43.81754 -148.36521)
		(end 43.79722 -148.34489)
		(width 0.1016)
		(layer "F.Cu")
		(net "LAN1_NC_SI_TX_EN")
	)
	(segment
		(start 43.81754 -150.37308)
		(end 43.81754 -148.36521)
		(width 0.1016)
		(layer "F.Cu")
		(net "LAN1_NC_SI_TX_EN")
	)
	(via
		(at 43.79722 -148.34489)
		(size 0.508)
		(drill 0.254)
		(layers "F.Cu" "B.Cu")
		(net "LAN1_NC_SI_TX_EN")
	)
	(segment
		(start 50.649378 -152.770586)
		(end 50.34534 -152.770586)
		(width 0.127)
		(layer "F.Cu")
		(net "PCIE_LAN1_RX_C_DN")
	)
	(segment
		(start 49.117504 -152.67305)
		(end 49.757584 -152.67305)
		(width 0.127)
		(layer "F.Cu")
		(net "PCIE_LAN1_RX_C_DN")
	)
	(segment
		(start 51.392074 -152.02789)
		(end 50.649378 -152.770586)
		(width 0.127)
		(layer "F.Cu")
		(net "PCIE_LAN1_RX_C_DN")
	)
	(segment
		(start 53.944012 -151.627078)
		(end 53.5432 -152.02789)
		(width 0.127)
		(layer "F.Cu")
		(net "PCIE_LAN1_RX_C_DN")
	)
	(segment
		(start 53.5432 -152.02789)
		(end 51.392074 -152.02789)
		(width 0.127)
		(layer "F.Cu")
		(net "PCIE_LAN1_RX_C_DN")
	)
	(segment
		(start 49.85512 -152.770586)
		(end 50.34534 -152.770586)
		(width 0.127)
		(layer "F.Cu")
		(net "PCIE_LAN1_RX_C_DN")
	)
	(segment
		(start 49.757584 -152.67305)
		(end 49.85512 -152.770586)
		(width 0.127)
		(layer "F.Cu")
		(net "PCIE_LAN1_RX_C_DN")
	)
	(via
		(at 50.34534 -152.770586)
		(size 0.4064)
		(drill 0.2032)
		(layers "F.Cu" "B.Cu")
		(net "PCIE_LAN1_RX_C_DN")
	)
	(segment
		(start 53.633624 -152.33269)
		(end 52.94122 -152.33269)
		(width 0.127)
		(layer "F.Cu")
		(net "PCIE_LAN1_RX_C_DP")
	)
	(segment
		(start 53.944012 -152.643078)
		(end 53.633624 -152.33269)
		(width 0.127)
		(layer "F.Cu")
		(net "PCIE_LAN1_RX_C_DP")
	)
	(segment
		(start 49.85512 -153.075386)
		(end 50.77587 -153.075386)
		(width 0.127)
		(layer "F.Cu")
		(net "PCIE_LAN1_RX_C_DP")
	)
	(segment
		(start 49.117504 -153.172922)
		(end 49.757584 -153.172922)
		(width 0.127)
		(layer "F.Cu")
		(net "PCIE_LAN1_RX_C_DP")
	)
	(segment
		(start 51.518566 -152.33269)
		(end 52.94122 -152.33269)
		(width 0.127)
		(layer "F.Cu")
		(net "PCIE_LAN1_RX_C_DP")
	)
	(segment
		(start 49.757584 -153.172922)
		(end 49.85512 -153.075386)
		(width 0.127)
		(layer "F.Cu")
		(net "PCIE_LAN1_RX_C_DP")
	)
	(segment
		(start 50.77587 -153.075386)
		(end 51.518566 -152.33269)
		(width 0.127)
		(layer "F.Cu")
		(net "PCIE_LAN1_RX_C_DP")
	)
	(via
		(at 52.94122 -152.33269)
		(size 0.4064)
		(drill 0.2032)
		(layers "F.Cu" "B.Cu")
		(net "PCIE_LAN1_RX_C_DP")
	)
	(segment
		(start 40.33774 -148.16201)
		(end 39.74592 -148.16201)
		(width 0.1016)
		(layer "F.Cu")
		(net "LAN1_NC_SI_CLK_IN")
	)
	(segment
		(start 41.317672 -149.141942)
		(end 40.33774 -148.16201)
		(width 0.1016)
		(layer "F.Cu")
		(net "LAN1_NC_SI_CLK_IN")
	)
	(segment
		(start 41.317672 -150.37308)
		(end 41.317672 -149.141942)
		(width 0.1016)
		(layer "F.Cu")
		(net "LAN1_NC_SI_CLK_IN")
	)
	(via
		(at 39.74592 -148.16201)
		(size 0.508)
		(drill 0.254)
		(layers "F.Cu" "B.Cu")
		(net "LAN1_NC_SI_CLK_IN")
	)
	(segment
		(start 39.161212 -147.577302)
		(end 39.74592 -148.16201)
		(width 0.1016)
		(layer "B.Cu")
		(net "LAN1_NC_SI_CLK_IN")
	)
	(segment
		(start 38.32479 -147.577302)
		(end 39.161212 -147.577302)
		(width 0.1016)
		(layer "B.Cu")
		(net "LAN1_NC_SI_CLK_IN")
	)
	(segment
		(start 174.636684 -40.268144)
		(end 174.636684 -39.173912)
		(width 0.508)
		(layer "F.Cu")
		(net "USBPWR_P0")
	)
	(via
		(at 177.81524 -36.825174)
		(size 0.508)
		(drill 0.254)
		(layers "F.Cu" "B.Cu")
		(net "USBPWR_P0")
	)
	(via
		(at 191.66332 -31.50108)
		(size 0.508)
		(drill 0.254)
		(layers "F.Cu" "B.Cu")
		(net "USBPWR_P0")
	)
	(via
		(at 187.54598 -31.34233)
		(size 0.508)
		(drill 0.254)
		(layers "F.Cu" "B.Cu")
		(net "USBPWR_P0")
	)
	(via
		(at 189.75832 -32.97301)
		(size 0.508)
		(drill 0.254)
		(layers "F.Cu" "B.Cu")
		(net "USBPWR_P0")
	)
	(via
		(at 184.52338 -32.171386)
		(size 0.508)
		(drill 0.254)
		(layers "F.Cu" "B.Cu")
		(net "USBPWR_P0")
	)
	(via
		(at 184.5056 -33.096962)
		(size 0.508)
		(drill 0.254)
		(layers "F.Cu" "B.Cu")
		(net "USBPWR_P0")
	)
	(via
		(at 177.3301 -34.744914)
		(size 0.508)
		(drill 0.254)
		(layers "F.Cu" "B.Cu")
		(net "USBPWR_P0")
	)
	(via
		(at 187.53836 -32.153352)
		(size 0.508)
		(drill 0.254)
		(layers "F.Cu" "B.Cu")
		(net "USBPWR_P0")
	)
	(via
		(at 177.79746 -38.006274)
		(size 0.508)
		(drill 0.254)
		(layers "F.Cu" "B.Cu")
		(net "USBPWR_P0")
	)
	(via
		(at 187.52058 -33.078928)
		(size 0.508)
		(drill 0.254)
		(layers "F.Cu" "B.Cu")
		(net "USBPWR_P0")
	)
	(via
		(at 191.67094 -32.320738)
		(size 0.508)
		(drill 0.254)
		(layers "F.Cu" "B.Cu")
		(net "USBPWR_P0")
	)
	(via
		(at 190.73622 -32.97301)
		(size 0.508)
		(drill 0.254)
		(layers "F.Cu" "B.Cu")
		(net "USBPWR_P0")
	)
	(via
		(at 174.636684 -39.173912)
		(size 0.508)
		(drill 0.254)
		(layers "F.Cu" "B.Cu")
		(net "USBPWR_P0")
	)
	(via
		(at 184.531 -31.360364)
		(size 0.508)
		(drill 0.254)
		(layers "F.Cu" "B.Cu")
		(net "USBPWR_P0")
	)
	(segment
		(start 107.99064 -162.62858)
		(end 107.99064 -160.578038)
		(width 0.1016)
		(layer "F.Cu")
		(net "I2C_PSU2_SCL")
	)
	(segment
		(start 108.17352 -160.395158)
		(end 108.173774 -160.395158)
		(width 0.1016)
		(layer "F.Cu")
		(net "I2C_PSU2_SCL")
	)
	(segment
		(start 107.99064 -160.578038)
		(end 108.17352 -160.395158)
		(width 0.1016)
		(layer "F.Cu")
		(net "I2C_PSU2_SCL")
	)
	(segment
		(start 108.173774 -160.395158)
		(end 110.81766 -160.395158)
		(width 0.1016)
		(layer "F.Cu")
		(net "I2C_PSU2_SCL")
	)
	(segment
		(start 111.221774 -162.466274)
		(end 111.0234 -162.664648)
		(width 0.1016)
		(layer "F.Cu")
		(net "I2C_PSU2_SCL")
	)
	(segment
		(start 84.82076 -184.33669)
		(end 84.99856 -184.15889)
		(width 0.1016)
		(layer "F.Cu")
		(net "I2C_PSU2_SCL")
	)
	(segment
		(start 111.0234 -162.664648)
		(end 111.0234 -163.523422)
		(width 0.1016)
		(layer "F.Cu")
		(net "I2C_PSU2_SCL")
	)
	(segment
		(start 110.81766 -160.395158)
		(end 111.221774 -160.799272)
		(width 0.1016)
		(layer "F.Cu")
		(net "I2C_PSU2_SCL")
	)
	(segment
		(start 107.990894 -162.62858)
		(end 107.99064 -162.62858)
		(width 0.1016)
		(layer "F.Cu")
		(net "I2C_PSU2_SCL")
	)
	(segment
		(start 84.82076 -184.805574)
		(end 84.82076 -184.33669)
		(width 0.1016)
		(layer "F.Cu")
		(net "I2C_PSU2_SCL")
	)
	(segment
		(start 111.221774 -160.799272)
		(end 111.221774 -162.466274)
		(width 0.1016)
		(layer "F.Cu")
		(net "I2C_PSU2_SCL")
	)
	(segment
		(start 107.990894 -162.73272)
		(end 107.990894 -162.62858)
		(width 0.1016)
		(layer "F.Cu")
		(net "I2C_PSU2_SCL")
	)
	(via
		(at 113.59134 -168.946322)
		(size 0.508)
		(drill 0.254)
		(layers "F.Cu" "B.Cu")
		(net "I2C_PSU2_SCL")
	)
	(via
		(at 112.4331 -182.74919)
		(size 0.508)
		(drill 0.254)
		(layers "F.Cu" "B.Cu")
		(net "I2C_PSU2_SCL")
	)
	(via
		(at 111.0234 -163.523422)
		(size 0.508)
		(drill 0.254)
		(layers "F.Cu" "B.Cu")
		(net "I2C_PSU2_SCL")
	)
	(via
		(at 84.99856 -184.15889)
		(size 0.508)
		(drill 0.254)
		(layers "F.Cu" "B.Cu")
		(net "I2C_PSU2_SCL")
	)
	(segment
		(start 115.28044 -180.749194)
		(end 115.28044 -171.649644)
		(width 0.1016)
		(layer "B.Cu")
		(net "I2C_PSU2_SCL")
	)
	(segment
		(start 115.76558 -181.592474)
		(end 115.76558 -181.234334)
		(width 0.1016)
		(layer "B.Cu")
		(net "I2C_PSU2_SCL")
	)
	(segment
		(start 113.59134 -169.960544)
		(end 113.59134 -168.946322)
		(width 0.1016)
		(layer "B.Cu")
		(net "I2C_PSU2_SCL")
	)
	(segment
		(start 115.76558 -181.234334)
		(end 115.28044 -180.749194)
		(width 0.1016)
		(layer "B.Cu")
		(net "I2C_PSU2_SCL")
	)
	(segment
		(start 112.4331 -182.74919)
		(end 113.16462 -182.01767)
		(width 0.1016)
		(layer "B.Cu")
		(net "I2C_PSU2_SCL")
	)
	(segment
		(start 113.16462 -182.01767)
		(end 115.340384 -182.01767)
		(width 0.1016)
		(layer "B.Cu")
		(net "I2C_PSU2_SCL")
	)
	(segment
		(start 115.340384 -182.01767)
		(end 115.76558 -181.592474)
		(width 0.1016)
		(layer "B.Cu")
		(net "I2C_PSU2_SCL")
	)
	(segment
		(start 115.28044 -171.649644)
		(end 113.59134 -169.960544)
		(width 0.1016)
		(layer "B.Cu")
		(net "I2C_PSU2_SCL")
	)
	(segment
		(start 105.090976 -181.934866)
		(end 106.075226 -182.919116)
		(width 0.1143)
		(layer "In2.Cu")
		(net "I2C_PSU2_SCL")
	)
	(segment
		(start 91.835224 -182.218584)
		(end 94.113858 -182.218584)
		(width 0.1143)
		(layer "In2.Cu")
		(net "I2C_PSU2_SCL")
	)
	(segment
		(start 95.030798 -181.934866)
		(end 105.090976 -181.934866)
		(width 0.1143)
		(layer "In2.Cu")
		(net "I2C_PSU2_SCL")
	)
	(segment
		(start 86.477856 -182.679594)
		(end 89.776046 -182.679594)
		(width 0.1143)
		(layer "In2.Cu")
		(net "I2C_PSU2_SCL")
	)
	(segment
		(start 94.18066 -182.151782)
		(end 94.813882 -182.151782)
		(width 0.1143)
		(layer "In2.Cu")
		(net "I2C_PSU2_SCL")
	)
	(segment
		(start 84.99856 -184.15889)
		(end 86.477856 -182.679594)
		(width 0.1143)
		(layer "In2.Cu")
		(net "I2C_PSU2_SCL")
	)
	(segment
		(start 94.813882 -182.151782)
		(end 95.030798 -181.934866)
		(width 0.1143)
		(layer "In2.Cu")
		(net "I2C_PSU2_SCL")
	)
	(segment
		(start 106.075226 -182.919116)
		(end 108.62437 -182.919116)
		(width 0.1143)
		(layer "In2.Cu")
		(net "I2C_PSU2_SCL")
	)
	(segment
		(start 90.07983 -182.983378)
		(end 91.07043 -182.983378)
		(width 0.1143)
		(layer "In2.Cu")
		(net "I2C_PSU2_SCL")
	)
	(segment
		(start 109.76483 -182.699406)
		(end 109.814614 -182.74919)
		(width 0.1143)
		(layer "In2.Cu")
		(net "I2C_PSU2_SCL")
	)
	(segment
		(start 109.814614 -182.74919)
		(end 112.4331 -182.74919)
		(width 0.1143)
		(layer "In2.Cu")
		(net "I2C_PSU2_SCL")
	)
	(segment
		(start 108.62437 -182.919116)
		(end 108.84408 -182.699406)
		(width 0.1143)
		(layer "In2.Cu")
		(net "I2C_PSU2_SCL")
	)
	(segment
		(start 108.84408 -182.699406)
		(end 109.76483 -182.699406)
		(width 0.1143)
		(layer "In2.Cu")
		(net "I2C_PSU2_SCL")
	)
	(segment
		(start 94.113858 -182.218584)
		(end 94.18066 -182.151782)
		(width 0.1143)
		(layer "In2.Cu")
		(net "I2C_PSU2_SCL")
	)
	(segment
		(start 91.07043 -182.983378)
		(end 91.835224 -182.218584)
		(width 0.1143)
		(layer "In2.Cu")
		(net "I2C_PSU2_SCL")
	)
	(segment
		(start 89.776046 -182.679594)
		(end 90.07983 -182.983378)
		(width 0.1143)
		(layer "In2.Cu")
		(net "I2C_PSU2_SCL")
	)
	(segment
		(start 113.59134 -168.946322)
		(end 113.573814 -168.946322)
		(width 0.1143)
		(layer "In6.Cu")
		(net "I2C_PSU2_SCL")
	)
	(segment
		(start 111.82604 -164.72916)
		(end 111.0234 -163.92652)
		(width 0.1143)
		(layer "In6.Cu")
		(net "I2C_PSU2_SCL")
	)
	(segment
		(start 111.0234 -163.92652)
		(end 111.0234 -163.523422)
		(width 0.1143)
		(layer "In6.Cu")
		(net "I2C_PSU2_SCL")
	)
	(segment
		(start 111.82604 -167.198548)
		(end 111.82604 -164.72916)
		(width 0.1143)
		(layer "In6.Cu")
		(net "I2C_PSU2_SCL")
	)
	(segment
		(start 113.573814 -168.946322)
		(end 111.82604 -167.198548)
		(width 0.1143)
		(layer "In6.Cu")
		(net "I2C_PSU2_SCL")
	)
	(segment
		(start 83.67776 -184.005982)
		(end 83.71586 -183.967882)
		(width 0.1016)
		(layer "F.Cu")
		(net "I2C_PSU2_SDA")
	)
	(segment
		(start 83.67776 -184.805574)
		(end 83.67776 -184.005982)
		(width 0.1016)
		(layer "F.Cu")
		(net "I2C_PSU2_SDA")
	)
	(segment
		(start 120.252744 -159.100266)
		(end 119.40921 -159.100266)
		(width 0.1016)
		(layer "F.Cu")
		(net "I2C_PSU2_SDA")
	)
	(segment
		(start 119.40921 -159.100266)
		(end 117.8687 -160.640776)
		(width 0.1016)
		(layer "F.Cu")
		(net "I2C_PSU2_SDA")
	)
	(segment
		(start 122.08764 -157.490414)
		(end 120.477788 -159.100266)
		(width 0.1016)
		(layer "F.Cu")
		(net "I2C_PSU2_SDA")
	)
	(segment
		(start 122.893328 -157.490414)
		(end 122.08764 -157.490414)
		(width 0.1016)
		(layer "F.Cu")
		(net "I2C_PSU2_SDA")
	)
	(segment
		(start 117.8687 -160.640776)
		(end 117.8687 -161.004758)
		(width 0.1016)
		(layer "F.Cu")
		(net "I2C_PSU2_SDA")
	)
	(segment
		(start 120.477788 -159.100266)
		(end 120.252744 -159.100266)
		(width 0.1016)
		(layer "F.Cu")
		(net "I2C_PSU2_SDA")
	)
	(via
		(at 86.44636 -162.065716)
		(size 0.508)
		(drill 0.254)
		(layers "F.Cu" "B.Cu")
		(net "I2C_PSU2_SDA")
	)
	(via
		(at 83.71586 -183.967882)
		(size 0.508)
		(drill 0.254)
		(layers "F.Cu" "B.Cu")
		(net "I2C_PSU2_SDA")
	)
	(via
		(at 117.8687 -161.004758)
		(size 0.508)
		(drill 0.254)
		(layers "F.Cu" "B.Cu")
		(net "I2C_PSU2_SDA")
	)
	(segment
		(start 111.81969 -162.423856)
		(end 109.145324 -162.423856)
		(width 0.1143)
		(layer "In2.Cu")
		(net "I2C_PSU2_SDA")
	)
	(segment
		(start 117.8687 -161.004758)
		(end 116.827554 -161.004758)
		(width 0.1143)
		(layer "In2.Cu")
		(net "I2C_PSU2_SDA")
	)
	(segment
		(start 94.14383 -161.60623)
		(end 89.276428 -161.60623)
		(width 0.1143)
		(layer "In2.Cu")
		(net "I2C_PSU2_SDA")
	)
	(segment
		(start 102.355396 -164.25037)
		(end 100.008436 -164.25037)
		(width 0.1143)
		(layer "In2.Cu")
		(net "I2C_PSU2_SDA")
	)
	(segment
		(start 109.079284 -162.489896)
		(end 108.444792 -163.124134)
		(width 0.1143)
		(layer "In2.Cu")
		(net "I2C_PSU2_SDA")
	)
	(segment
		(start 107.040172 -163.348162)
		(end 103.257604 -163.348162)
		(width 0.1143)
		(layer "In2.Cu")
		(net "I2C_PSU2_SDA")
	)
	(segment
		(start 89.276428 -161.60623)
		(end 89.05748 -161.387282)
		(width 0.1143)
		(layer "In2.Cu")
		(net "I2C_PSU2_SDA")
	)
	(segment
		(start 107.2642 -163.124134)
		(end 107.040172 -163.348162)
		(width 0.1143)
		(layer "In2.Cu")
		(net "I2C_PSU2_SDA")
	)
	(segment
		(start 112.09528 -162.699446)
		(end 111.81969 -162.423856)
		(width 0.1143)
		(layer "In2.Cu")
		(net "I2C_PSU2_SDA")
	)
	(segment
		(start 89.05748 -161.387282)
		(end 87.124794 -161.387282)
		(width 0.1143)
		(layer "In2.Cu")
		(net "I2C_PSU2_SDA")
	)
	(segment
		(start 95.263462 -162.725862)
		(end 94.14383 -161.60623)
		(width 0.1143)
		(layer "In2.Cu")
		(net "I2C_PSU2_SDA")
	)
	(segment
		(start 108.444792 -163.124134)
		(end 107.2642 -163.124134)
		(width 0.1143)
		(layer "In2.Cu")
		(net "I2C_PSU2_SDA")
	)
	(segment
		(start 97.109026 -163.065968)
		(end 96.76892 -162.725862)
		(width 0.1143)
		(layer "In2.Cu")
		(net "I2C_PSU2_SDA")
	)
	(segment
		(start 100.008436 -164.25037)
		(end 98.824034 -163.065968)
		(width 0.1143)
		(layer "In2.Cu")
		(net "I2C_PSU2_SDA")
	)
	(segment
		(start 116.827554 -161.004758)
		(end 115.132866 -162.699446)
		(width 0.1143)
		(layer "In2.Cu")
		(net "I2C_PSU2_SDA")
	)
	(segment
		(start 103.257604 -163.348162)
		(end 102.355396 -164.25037)
		(width 0.1143)
		(layer "In2.Cu")
		(net "I2C_PSU2_SDA")
	)
	(segment
		(start 115.132866 -162.699446)
		(end 112.09528 -162.699446)
		(width 0.1143)
		(layer "In2.Cu")
		(net "I2C_PSU2_SDA")
	)
	(segment
		(start 98.824034 -163.065968)
		(end 97.109026 -163.065968)
		(width 0.1143)
		(layer "In2.Cu")
		(net "I2C_PSU2_SDA")
	)
	(segment
		(start 109.145324 -162.423856)
		(end 109.079284 -162.489896)
		(width 0.1143)
		(layer "In2.Cu")
		(net "I2C_PSU2_SDA")
	)
	(segment
		(start 87.124794 -161.387282)
		(end 86.44636 -162.065716)
		(width 0.1143)
		(layer "In2.Cu")
		(net "I2C_PSU2_SDA")
	)
	(segment
		(start 96.76892 -162.725862)
		(end 95.263462 -162.725862)
		(width 0.1143)
		(layer "In2.Cu")
		(net "I2C_PSU2_SDA")
	)
	(segment
		(start 83.76793 -172.343826)
		(end 83.76793 -179.8828)
		(width 0.1143)
		(layer "In7.Cu")
		(net "I2C_PSU2_SDA")
	)
	(segment
		(start 85.7123 -167.56761)
		(end 85.62721 -167.6527)
		(width 0.1143)
		(layer "In7.Cu")
		(net "I2C_PSU2_SDA")
	)
	(segment
		(start 85.62721 -170.484546)
		(end 83.76793 -172.343826)
		(width 0.1143)
		(layer "In7.Cu")
		(net "I2C_PSU2_SDA")
	)
	(segment
		(start 86.968076 -162.994086)
		(end 86.968076 -164.802566)
		(width 0.1143)
		(layer "In7.Cu")
		(net "I2C_PSU2_SDA")
	)
	(segment
		(start 85.7123 -166.058342)
		(end 85.7123 -167.56761)
		(width 0.1143)
		(layer "In7.Cu")
		(net "I2C_PSU2_SDA")
	)
	(segment
		(start 86.44636 -162.47237)
		(end 86.968076 -162.994086)
		(width 0.1143)
		(layer "In7.Cu")
		(net "I2C_PSU2_SDA")
	)
	(segment
		(start 86.968076 -164.802566)
		(end 85.7123 -166.058342)
		(width 0.1143)
		(layer "In7.Cu")
		(net "I2C_PSU2_SDA")
	)
	(segment
		(start 84.36229 -180.47716)
		(end 84.36229 -183.321452)
		(width 0.1143)
		(layer "In7.Cu")
		(net "I2C_PSU2_SDA")
	)
	(segment
		(start 83.76793 -179.8828)
		(end 84.36229 -180.47716)
		(width 0.1143)
		(layer "In7.Cu")
		(net "I2C_PSU2_SDA")
	)
	(segment
		(start 84.36229 -183.321452)
		(end 83.71586 -183.967882)
		(width 0.1143)
		(layer "In7.Cu")
		(net "I2C_PSU2_SDA")
	)
	(segment
		(start 86.44636 -162.065716)
		(end 86.44636 -162.47237)
		(width 0.1143)
		(layer "In7.Cu")
		(net "I2C_PSU2_SDA")
	)
	(segment
		(start 85.62721 -167.6527)
		(end 85.62721 -170.484546)
		(width 0.1143)
		(layer "In7.Cu")
		(net "I2C_PSU2_SDA")
	)
	(segment
		(start 158.125414 -184.805574)
		(end 157.65018 -184.33034)
		(width 0.1016)
		(layer "F.Cu")
		(net "FAN1_TACH")
	)
	(segment
		(start 94.051882 -170.219624)
		(end 94.011242 -170.219624)
		(width 0.1016)
		(layer "F.Cu")
		(net "FAN1_TACH")
	)
	(segment
		(start 157.65018 -184.33034)
		(end 157.65018 -183.442864)
		(width 0.1016)
		(layer "F.Cu")
		(net "FAN1_TACH")
	)
	(segment
		(start 158.48076 -184.805574)
		(end 158.125414 -184.805574)
		(width 0.1016)
		(layer "F.Cu")
		(net "FAN1_TACH")
	)
	(segment
		(start 94.011242 -170.219624)
		(end 93.4974 -169.705782)
		(width 0.1016)
		(layer "F.Cu")
		(net "FAN1_TACH")
	)
	(via
		(at 157.65018 -183.442864)
		(size 0.508)
		(drill 0.254)
		(layers "F.Cu" "B.Cu")
		(net "FAN1_TACH")
	)
	(via
		(at 93.4974 -169.705782)
		(size 0.508)
		(drill 0.254)
		(layers "F.Cu" "B.Cu")
		(net "FAN1_TACH")
	)
	(segment
		(start 110.03153 -179.611528)
		(end 109.587284 -180.055774)
		(width 0.1143)
		(layer "In6.Cu")
		(net "FAN1_TACH")
	)
	(segment
		(start 108.755434 -180.055774)
		(end 108.287312 -180.523896)
		(width 0.1143)
		(layer "In6.Cu")
		(net "FAN1_TACH")
	)
	(segment
		(start 146.512026 -182.76062)
		(end 145.373852 -182.76062)
		(width 0.1143)
		(layer "In6.Cu")
		(net "FAN1_TACH")
	)
	(segment
		(start 149.78126 -183.758332)
		(end 149.78126 -183.74233)
		(width 0.1143)
		(layer "In6.Cu")
		(net "FAN1_TACH")
	)
	(segment
		(start 157.562042 -183.531002)
		(end 155.487624 -183.531002)
		(width 0.1143)
		(layer "In6.Cu")
		(net "FAN1_TACH")
	)
	(segment
		(start 145.372074 -182.758842)
		(end 142.634462 -182.758842)
		(width 0.1143)
		(layer "In6.Cu")
		(net "FAN1_TACH")
	)
	(segment
		(start 127.029972 -177.012346)
		(end 125.790452 -177.012346)
		(width 0.1143)
		(layer "In6.Cu")
		(net "FAN1_TACH")
	)
	(segment
		(start 154.88539 -182.928768)
		(end 154.290522 -182.928768)
		(width 0.1143)
		(layer "In6.Cu")
		(net "FAN1_TACH")
	)
	(segment
		(start 142.634462 -182.758842)
		(end 142.56004 -182.833264)
		(width 0.1143)
		(layer "In6.Cu")
		(net "FAN1_TACH")
	)
	(segment
		(start 105.43667 -178.753516)
		(end 104.944672 -178.753516)
		(width 0.1143)
		(layer "In6.Cu")
		(net "FAN1_TACH")
	)
	(segment
		(start 125.664722 -176.886616)
		(end 124.403358 -176.886616)
		(width 0.1143)
		(layer "In6.Cu")
		(net "FAN1_TACH")
	)
	(segment
		(start 139.392406 -179.299616)
		(end 137.874756 -179.299616)
		(width 0.1143)
		(layer "In6.Cu")
		(net "FAN1_TACH")
	)
	(segment
		(start 142.56004 -182.833264)
		(end 142.196566 -182.833264)
		(width 0.1143)
		(layer "In6.Cu")
		(net "FAN1_TACH")
	)
	(segment
		(start 125.790452 -177.012346)
		(end 125.664722 -176.886616)
		(width 0.1143)
		(layer "In6.Cu")
		(net "FAN1_TACH")
	)
	(segment
		(start 124.403358 -176.886616)
		(end 123.506992 -177.782982)
		(width 0.1143)
		(layer "In6.Cu")
		(net "FAN1_TACH")
	)
	(segment
		(start 96.034352 -169.514774)
		(end 93.688408 -169.514774)
		(width 0.1143)
		(layer "In6.Cu")
		(net "FAN1_TACH")
	)
	(segment
		(start 146.633692 -182.638954)
		(end 146.512026 -182.76062)
		(width 0.1143)
		(layer "In6.Cu")
		(net "FAN1_TACH")
	)
	(segment
		(start 140.139166 -180.775864)
		(end 140.139166 -180.046376)
		(width 0.1143)
		(layer "In6.Cu")
		(net "FAN1_TACH")
	)
	(segment
		(start 102.88778 -173.107858)
		(end 99.503738 -169.723816)
		(width 0.1143)
		(layer "In6.Cu")
		(net "FAN1_TACH")
	)
	(segment
		(start 148.677884 -182.638954)
		(end 146.633692 -182.638954)
		(width 0.1143)
		(layer "In6.Cu")
		(net "FAN1_TACH")
	)
	(segment
		(start 113.590324 -177.782982)
		(end 111.761778 -179.611528)
		(width 0.1143)
		(layer "In6.Cu")
		(net "FAN1_TACH")
	)
	(segment
		(start 96.243394 -169.723816)
		(end 96.034352 -169.514774)
		(width 0.1143)
		(layer "In6.Cu")
		(net "FAN1_TACH")
	)
	(segment
		(start 145.373852 -182.76062)
		(end 145.372074 -182.758842)
		(width 0.1143)
		(layer "In6.Cu")
		(net "FAN1_TACH")
	)
	(segment
		(start 109.587284 -180.055774)
		(end 108.755434 -180.055774)
		(width 0.1143)
		(layer "In6.Cu")
		(net "FAN1_TACH")
	)
	(segment
		(start 150.29815 -184.275222)
		(end 149.78126 -183.758332)
		(width 0.1143)
		(layer "In6.Cu")
		(net "FAN1_TACH")
	)
	(segment
		(start 108.287312 -180.523896)
		(end 107.20705 -180.523896)
		(width 0.1143)
		(layer "In6.Cu")
		(net "FAN1_TACH")
	)
	(segment
		(start 136.491218 -177.916078)
		(end 127.933704 -177.916078)
		(width 0.1143)
		(layer "In6.Cu")
		(net "FAN1_TACH")
	)
	(segment
		(start 104.944672 -178.753516)
		(end 102.88778 -176.696624)
		(width 0.1143)
		(layer "In6.Cu")
		(net "FAN1_TACH")
	)
	(segment
		(start 137.874756 -179.299616)
		(end 136.491218 -177.916078)
		(width 0.1143)
		(layer "In6.Cu")
		(net "FAN1_TACH")
	)
	(segment
		(start 107.20705 -180.523896)
		(end 105.43667 -178.753516)
		(width 0.1143)
		(layer "In6.Cu")
		(net "FAN1_TACH")
	)
	(segment
		(start 140.139166 -180.046376)
		(end 139.392406 -179.299616)
		(width 0.1143)
		(layer "In6.Cu")
		(net "FAN1_TACH")
	)
	(segment
		(start 142.196566 -182.833264)
		(end 140.139166 -180.775864)
		(width 0.1143)
		(layer "In6.Cu")
		(net "FAN1_TACH")
	)
	(segment
		(start 152.944068 -184.275222)
		(end 150.29815 -184.275222)
		(width 0.1143)
		(layer "In6.Cu")
		(net "FAN1_TACH")
	)
	(segment
		(start 111.761778 -179.611528)
		(end 110.03153 -179.611528)
		(width 0.1143)
		(layer "In6.Cu")
		(net "FAN1_TACH")
	)
	(segment
		(start 149.78126 -183.74233)
		(end 148.677884 -182.638954)
		(width 0.1143)
		(layer "In6.Cu")
		(net "FAN1_TACH")
	)
	(segment
		(start 102.88778 -176.696624)
		(end 102.88778 -173.107858)
		(width 0.1143)
		(layer "In6.Cu")
		(net "FAN1_TACH")
	)
	(segment
		(start 99.503738 -169.723816)
		(end 96.243394 -169.723816)
		(width 0.1143)
		(layer "In6.Cu")
		(net "FAN1_TACH")
	)
	(segment
		(start 123.506992 -177.782982)
		(end 113.590324 -177.782982)
		(width 0.1143)
		(layer "In6.Cu")
		(net "FAN1_TACH")
	)
	(segment
		(start 157.65018 -183.442864)
		(end 157.562042 -183.531002)
		(width 0.1143)
		(layer "In6.Cu")
		(net "FAN1_TACH")
	)
	(segment
		(start 127.933704 -177.916078)
		(end 127.029972 -177.012346)
		(width 0.1143)
		(layer "In6.Cu")
		(net "FAN1_TACH")
	)
	(segment
		(start 154.290522 -182.928768)
		(end 152.944068 -184.275222)
		(width 0.1143)
		(layer "In6.Cu")
		(net "FAN1_TACH")
	)
	(segment
		(start 155.487624 -183.531002)
		(end 154.88539 -182.928768)
		(width 0.1143)
		(layer "In6.Cu")
		(net "FAN1_TACH")
	)
	(segment
		(start 93.688408 -169.514774)
		(end 93.4974 -169.705782)
		(width 0.1143)
		(layer "In6.Cu")
		(net "FAN1_TACH")
	)
	(segment
		(start 45.651674 -165.971982)
		(end 44.167552 -164.48786)
		(width 0.1016)
		(layer "F.Cu")
		(net "LAN1_XTAL_OUT")
	)
	(segment
		(start 43.81754 -163.20897)
		(end 44.167552 -163.558982)
		(width 0.1016)
		(layer "F.Cu")
		(net "LAN1_XTAL_OUT")
	)
	(segment
		(start 43.81754 -162.501834)
		(end 43.81754 -163.20897)
		(width 0.1016)
		(layer "F.Cu")
		(net "LAN1_XTAL_OUT")
	)
	(segment
		(start 44.167552 -164.48786)
		(end 44.167552 -163.558982)
		(width 0.1016)
		(layer "F.Cu")
		(net "LAN1_XTAL_OUT")
	)
	(segment
		(start 43.81754 -162.501834)
		(end 43.81754 -159.472884)
		(width 0.1016)
		(layer "F.Cu")
		(net "LAN1_XTAL_OUT")
	)
	(via
		(at 43.81754 -162.501834)
		(size 0.508)
		(drill 0.254)
		(layers "F.Cu" "B.Cu")
		(net "LAN1_XTAL_OUT")
	)
	(segment
		(start 167.559736 -61.024262)
		(end 168.03624 -61.024262)
		(width 0.10668)
		(layer "F.Cu")
		(net "USB3_DN")
	)
	(segment
		(start 163.852352 -108.188506)
		(end 163.374832 -108.666026)
		(width 0.10668)
		(layer "F.Cu")
		(net "USB3_DN")
	)
	(segment
		(start 164.04336 -105.511346)
		(end 163.852352 -105.702354)
		(width 0.10668)
		(layer "F.Cu")
		(net "USB3_DN")
	)
	(segment
		(start 163.852352 -105.702354)
		(end 163.852352 -108.188506)
		(width 0.10668)
		(layer "F.Cu")
		(net "USB3_DN")
	)
	(segment
		(start 168.393872 -60.66663)
		(end 168.378632 -60.68187)
		(width 0.10668)
		(layer "F.Cu")
		(net "USB3_DN")
	)
	(segment
		(start 167.090852 -60.555378)
		(end 167.559736 -61.024262)
		(width 0.10668)
		(layer "F.Cu")
		(net "USB3_DN")
	)
	(segment
		(start 168.03624 -61.024262)
		(end 168.378632 -60.68187)
		(width 0.10668)
		(layer "F.Cu")
		(net "USB3_DN")
	)
	(segment
		(start 169.392346 -60.66663)
		(end 168.393872 -60.66663)
		(width 0.10668)
		(layer "F.Cu")
		(net "USB3_DN")
	)
	(segment
		(start 164.04336 -104.927908)
		(end 164.04336 -105.511346)
		(width 0.10668)
		(layer "F.Cu")
		(net "USB3_DN")
	)
	(via
		(at 163.374832 -108.666026)
		(size 0.508)
		(drill 0.254)
		(layers "F.Cu" "B.Cu")
		(net "USB3_DN")
	)
	(via
		(at 167.090852 -60.555378)
		(size 0.508)
		(drill 0.254)
		(layers "F.Cu" "B.Cu")
		(net "USB3_DN")
	)
	(segment
		(start 166.984172 -61.032898)
		(end 167.090852 -60.926218)
		(width 0.10668)
		(layer "B.Cu")
		(net "USB3_DN")
	)
	(segment
		(start 163.745672 -108.666026)
		(end 163.852352 -108.559346)
		(width 0.10668)
		(layer "B.Cu")
		(net "USB3_DN")
	)
	(segment
		(start 165.83914 -61.52642)
		(end 166.332662 -61.032898)
		(width 0.10668)
		(layer "B.Cu")
		(net "USB3_DN")
	)
	(segment
		(start 164.814758 -106.890058)
		(end 174.9044 -106.890058)
		(width 0.10668)
		(layer "B.Cu")
		(net "USB3_DN")
	)
	(segment
		(start 166.332662 -61.032898)
		(end 166.984172 -61.032898)
		(width 0.10668)
		(layer "B.Cu")
		(net "USB3_DN")
	)
	(segment
		(start 163.852352 -108.559346)
		(end 163.852352 -107.852464)
		(width 0.10668)
		(layer "B.Cu")
		(net "USB3_DN")
	)
	(segment
		(start 177.2285 -104.565958)
		(end 177.2285 -74.006964)
		(width 0.10668)
		(layer "B.Cu")
		(net "USB3_DN")
	)
	(segment
		(start 163.374832 -108.666026)
		(end 163.745672 -108.666026)
		(width 0.10668)
		(layer "B.Cu")
		(net "USB3_DN")
	)
	(segment
		(start 177.2285 -74.006964)
		(end 165.83914 -62.617604)
		(width 0.10668)
		(layer "B.Cu")
		(net "USB3_DN")
	)
	(segment
		(start 174.9044 -106.890058)
		(end 177.2285 -104.565958)
		(width 0.10668)
		(layer "B.Cu")
		(net "USB3_DN")
	)
	(segment
		(start 165.83914 -62.617604)
		(end 165.83914 -61.52642)
		(width 0.10668)
		(layer "B.Cu")
		(net "USB3_DN")
	)
	(segment
		(start 163.852352 -107.852464)
		(end 164.814758 -106.890058)
		(width 0.10668)
		(layer "B.Cu")
		(net "USB3_DN")
	)
	(segment
		(start 167.090852 -60.926218)
		(end 167.090852 -60.555378)
		(width 0.10668)
		(layer "B.Cu")
		(net "USB3_DN")
	)
	(segment
		(start 43.16222 -160.63341)
		(end 43.16222 -161.373566)
		(width 0.1016)
		(layer "F.Cu")
		(net "LAN1_XTAL_IN")
	)
	(segment
		(start 43.16222 -163.459414)
		(end 43.062652 -163.558982)
		(width 0.1016)
		(layer "F.Cu")
		(net "LAN1_XTAL_IN")
	)
	(segment
		(start 43.062652 -164.36086)
		(end 43.062652 -163.558982)
		(width 0.1016)
		(layer "F.Cu")
		(net "LAN1_XTAL_IN")
	)
	(segment
		(start 43.16222 -161.373566)
		(end 43.16222 -163.459414)
		(width 0.1016)
		(layer "F.Cu")
		(net "LAN1_XTAL_IN")
	)
	(segment
		(start 43.317668 -159.472884)
		(end 43.317668 -160.477962)
		(width 0.1016)
		(layer "F.Cu")
		(net "LAN1_XTAL_IN")
	)
	(segment
		(start 41.45153 -165.971982)
		(end 43.062652 -164.36086)
		(width 0.1016)
		(layer "F.Cu")
		(net "LAN1_XTAL_IN")
	)
	(segment
		(start 43.317668 -160.477962)
		(end 43.16222 -160.63341)
		(width 0.1016)
		(layer "F.Cu")
		(net "LAN1_XTAL_IN")
	)
	(via
		(at 43.16222 -161.373566)
		(size 0.508)
		(drill 0.254)
		(layers "F.Cu" "B.Cu")
		(net "LAN1_XTAL_IN")
	)
	(segment
		(start 167.378634 -57.3151)
		(end 167.721026 -56.972708)
		(width 0.10668)
		(layer "F.Cu")
		(net "USB2_DN")
	)
	(segment
		(start 167.695626 -105.499154)
		(end 167.695626 -107.625134)
		(width 0.10668)
		(layer "F.Cu")
		(net "USB2_DN")
	)
	(segment
		(start 169.243502 -56.98109)
		(end 168.231058 -56.98109)
		(width 0.10668)
		(layer "F.Cu")
		(net "USB2_DN")
	)
	(segment
		(start 166.861744 -57.3151)
		(end 167.378634 -57.3151)
		(width 0.10668)
		(layer "F.Cu")
		(net "USB2_DN")
	)
	(segment
		(start 167.643302 -105.44683)
		(end 167.695626 -105.499154)
		(width 0.10668)
		(layer "F.Cu")
		(net "USB2_DN")
	)
	(segment
		(start 167.643302 -104.839008)
		(end 167.643302 -105.44683)
		(width 0.10668)
		(layer "F.Cu")
		(net "USB2_DN")
	)
	(segment
		(start 166.37762 -56.830976)
		(end 166.861744 -57.3151)
		(width 0.10668)
		(layer "F.Cu")
		(net "USB2_DN")
	)
	(segment
		(start 167.721026 -56.972708)
		(end 168.222676 -56.972708)
		(width 0.10668)
		(layer "F.Cu")
		(net "USB2_DN")
	)
	(segment
		(start 167.695626 -107.625134)
		(end 167.218106 -108.102654)
		(width 0.10668)
		(layer "F.Cu")
		(net "USB2_DN")
	)
	(segment
		(start 168.231058 -56.98109)
		(end 168.222676 -56.972708)
		(width 0.10668)
		(layer "F.Cu")
		(net "USB2_DN")
	)
	(via
		(at 166.37762 -56.830976)
		(size 0.508)
		(drill 0.254)
		(layers "F.Cu" "B.Cu")
		(net "USB2_DN")
	)
	(via
		(at 167.218106 -108.102654)
		(size 0.508)
		(drill 0.254)
		(layers "F.Cu" "B.Cu")
		(net "USB2_DN")
	)
	(segment
		(start 169.86504 -64.375284)
		(end 179.46624 -73.976484)
		(width 0.10668)
		(layer "B.Cu")
		(net "USB2_DN")
	)
	(segment
		(start 179.46624 -104.48671)
		(end 174.228252 -109.724698)
		(width 0.10668)
		(layer "B.Cu")
		(net "USB2_DN")
	)
	(segment
		(start 168.347136 -109.724698)
		(end 167.695626 -109.073188)
		(width 0.10668)
		(layer "B.Cu")
		(net "USB2_DN")
	)
	(segment
		(start 167.665146 -57.296558)
		(end 169.86504 -59.496452)
		(width 0.10668)
		(layer "B.Cu")
		(net "USB2_DN")
	)
	(segment
		(start 166.843202 -57.296558)
		(end 167.665146 -57.296558)
		(width 0.10668)
		(layer "B.Cu")
		(net "USB2_DN")
	)
	(segment
		(start 169.86504 -59.496452)
		(end 169.86504 -64.375284)
		(width 0.10668)
		(layer "B.Cu")
		(net "USB2_DN")
	)
	(segment
		(start 166.37762 -56.830976)
		(end 166.843202 -57.296558)
		(width 0.10668)
		(layer "B.Cu")
		(net "USB2_DN")
	)
	(segment
		(start 179.46624 -73.976484)
		(end 179.46624 -104.48671)
		(width 0.10668)
		(layer "B.Cu")
		(net "USB2_DN")
	)
	(segment
		(start 167.695626 -109.073188)
		(end 167.695626 -108.580174)
		(width 0.10668)
		(layer "B.Cu")
		(net "USB2_DN")
	)
	(segment
		(start 174.228252 -109.724698)
		(end 168.347136 -109.724698)
		(width 0.10668)
		(layer "B.Cu")
		(net "USB2_DN")
	)
	(segment
		(start 167.695626 -108.580174)
		(end 167.218106 -108.102654)
		(width 0.10668)
		(layer "B.Cu")
		(net "USB2_DN")
	)
	(segment
		(start 115.62969 -154.503882)
		(end 115.62969 -156.14396)
		(width 0.1016)
		(layer "F.Cu")
		(net "I2C_PSU1_SDA")
	)
	(segment
		(start 53.95976 -184.805574)
		(end 53.95976 -184.633108)
		(width 0.1016)
		(layer "F.Cu")
		(net "I2C_PSU1_SDA")
	)
	(segment
		(start 119.7102 -152.5524)
		(end 118.65229 -152.5524)
		(width 0.1016)
		(layer "F.Cu")
		(net "I2C_PSU1_SDA")
	)
	(segment
		(start 118.079012 -164.816282)
		(end 117.779038 -165.116256)
		(width 0.1016)
		(layer "F.Cu")
		(net "I2C_PSU1_SDA")
	)
	(segment
		(start 118.079012 -163.832286)
		(end 118.079012 -164.816282)
		(width 0.1016)
		(layer "F.Cu")
		(net "I2C_PSU1_SDA")
	)
	(segment
		(start 54.18074 -182.962042)
		(end 54.18074 -182.642256)
		(width 0.1016)
		(layer "F.Cu")
		(net "I2C_PSU1_SDA")
	)
	(segment
		(start 115.889532 -154.24404)
		(end 115.62969 -154.503882)
		(width 0.1016)
		(layer "F.Cu")
		(net "I2C_PSU1_SDA")
	)
	(segment
		(start 54.25694 -183.038242)
		(end 54.18074 -182.962042)
		(width 0.1016)
		(layer "F.Cu")
		(net "I2C_PSU1_SDA")
	)
	(segment
		(start 117.779038 -166.42461)
		(end 117.17528 -167.028368)
		(width 0.1016)
		(layer "F.Cu")
		(net "I2C_PSU1_SDA")
	)
	(segment
		(start 117.17528 -168.078912)
		(end 117.562122 -168.465754)
		(width 0.1016)
		(layer "F.Cu")
		(net "I2C_PSU1_SDA")
	)
	(segment
		(start 117.779038 -165.116256)
		(end 117.779038 -166.42461)
		(width 0.1016)
		(layer "F.Cu")
		(net "I2C_PSU1_SDA")
	)
	(segment
		(start 116.1161 -156.63037)
		(end 116.1161 -161.869374)
		(width 0.1016)
		(layer "F.Cu")
		(net "I2C_PSU1_SDA")
	)
	(segment
		(start 120.620536 -153.498804)
		(end 121.311924 -153.498804)
		(width 0.1016)
		(layer "F.Cu")
		(net "I2C_PSU1_SDA")
	)
	(segment
		(start 54.25694 -184.335928)
		(end 54.25694 -183.038242)
		(width 0.1016)
		(layer "F.Cu")
		(net "I2C_PSU1_SDA")
	)
	(segment
		(start 118.23446 -152.97023)
		(end 118.23446 -153.72715)
		(width 0.1016)
		(layer "F.Cu")
		(net "I2C_PSU1_SDA")
	)
	(segment
		(start 53.95976 -184.633108)
		(end 54.25694 -184.335928)
		(width 0.1016)
		(layer "F.Cu")
		(net "I2C_PSU1_SDA")
	)
	(segment
		(start 117.71757 -154.24404)
		(end 115.889532 -154.24404)
		(width 0.1016)
		(layer "F.Cu")
		(net "I2C_PSU1_SDA")
	)
	(segment
		(start 118.65229 -152.5524)
		(end 118.23446 -152.97023)
		(width 0.1016)
		(layer "F.Cu")
		(net "I2C_PSU1_SDA")
	)
	(segment
		(start 115.62969 -156.14396)
		(end 116.1161 -156.63037)
		(width 0.1016)
		(layer "F.Cu")
		(net "I2C_PSU1_SDA")
	)
	(segment
		(start 117.17528 -167.028368)
		(end 117.17528 -168.078912)
		(width 0.1016)
		(layer "F.Cu")
		(net "I2C_PSU1_SDA")
	)
	(segment
		(start 117.562122 -168.465754)
		(end 117.93982 -168.465754)
		(width 0.1016)
		(layer "F.Cu")
		(net "I2C_PSU1_SDA")
	)
	(segment
		(start 120.620536 -153.498804)
		(end 120.620536 -153.462736)
		(width 0.1016)
		(layer "F.Cu")
		(net "I2C_PSU1_SDA")
	)
	(segment
		(start 121.311924 -153.498804)
		(end 121.3866 -153.424128)
		(width 0.1016)
		(layer "F.Cu")
		(net "I2C_PSU1_SDA")
	)
	(segment
		(start 120.620536 -153.462736)
		(end 119.7102 -152.5524)
		(width 0.1016)
		(layer "F.Cu")
		(net "I2C_PSU1_SDA")
	)
	(segment
		(start 121.3866 -153.424128)
		(end 122.846592 -153.424128)
		(width 0.1016)
		(layer "F.Cu")
		(net "I2C_PSU1_SDA")
	)
	(segment
		(start 118.23446 -153.72715)
		(end 117.71757 -154.24404)
		(width 0.1016)
		(layer "F.Cu")
		(net "I2C_PSU1_SDA")
	)
	(segment
		(start 116.1161 -161.869374)
		(end 118.079012 -163.832286)
		(width 0.1016)
		(layer "F.Cu")
		(net "I2C_PSU1_SDA")
	)
	(via
		(at 54.18074 -182.642256)
		(size 0.508)
		(drill 0.254)
		(layers "F.Cu" "B.Cu")
		(net "I2C_PSU1_SDA")
	)
	(via
		(at 117.93982 -168.465754)
		(size 0.508)
		(drill 0.254)
		(layers "F.Cu" "B.Cu")
		(net "I2C_PSU1_SDA")
	)
	(segment
		(start 83.822286 -164.796978)
		(end 82.7024 -164.796978)
		(width 0.1143)
		(layer "In2.Cu")
		(net "I2C_PSU1_SDA")
	)
	(segment
		(start 112.70996 -168.30548)
		(end 112.00765 -169.00779)
		(width 0.1143)
		(layer "In2.Cu")
		(net "I2C_PSU1_SDA")
	)
	(segment
		(start 77.343 -167.720264)
		(end 76.8604 -168.202864)
		(width 0.1143)
		(layer "In2.Cu")
		(net "I2C_PSU1_SDA")
	)
	(segment
		(start 70.898512 -171.186602)
		(end 66.88328 -175.201834)
		(width 0.1143)
		(layer "In2.Cu")
		(net "I2C_PSU1_SDA")
	)
	(segment
		(start 88.89746 -167.630348)
		(end 86.854284 -165.587172)
		(width 0.1143)
		(layer "In2.Cu")
		(net "I2C_PSU1_SDA")
	)
	(segment
		(start 66.88328 -176.557432)
		(end 63.016384 -180.424328)
		(width 0.1143)
		(layer "In2.Cu")
		(net "I2C_PSU1_SDA")
	)
	(segment
		(start 82.7024 -164.796978)
		(end 81.039716 -166.459662)
		(width 0.1143)
		(layer "In2.Cu")
		(net "I2C_PSU1_SDA")
	)
	(segment
		(start 92.314776 -167.95496)
		(end 92.194888 -168.074848)
		(width 0.1143)
		(layer "In2.Cu")
		(net "I2C_PSU1_SDA")
	)
	(segment
		(start 116.952014 -168.465754)
		(end 116.513864 -168.027604)
		(width 0.1143)
		(layer "In2.Cu")
		(net "I2C_PSU1_SDA")
	)
	(segment
		(start 83.90128 -164.875972)
		(end 83.822286 -164.796978)
		(width 0.1143)
		(layer "In2.Cu")
		(net "I2C_PSU1_SDA")
	)
	(segment
		(start 97.885504 -168.507156)
		(end 96.21012 -168.507156)
		(width 0.1143)
		(layer "In2.Cu")
		(net "I2C_PSU1_SDA")
	)
	(segment
		(start 55.375048 -180.424328)
		(end 54.42712 -181.372256)
		(width 0.1143)
		(layer "In2.Cu")
		(net "I2C_PSU1_SDA")
	)
	(segment
		(start 117.93982 -168.465754)
		(end 116.952014 -168.465754)
		(width 0.1143)
		(layer "In2.Cu")
		(net "I2C_PSU1_SDA")
	)
	(segment
		(start 107.264962 -169.987214)
		(end 101.048058 -169.987214)
		(width 0.1143)
		(layer "In2.Cu")
		(net "I2C_PSU1_SDA")
	)
	(segment
		(start 113.264188 -168.30548)
		(end 112.70996 -168.30548)
		(width 0.1143)
		(layer "In2.Cu")
		(net "I2C_PSU1_SDA")
	)
	(segment
		(start 73.3171 -169.56278)
		(end 73.270872 -169.516552)
		(width 0.1143)
		(layer "In2.Cu")
		(net "I2C_PSU1_SDA")
	)
	(segment
		(start 95.518732 -167.815768)
		(end 93.788484 -167.815768)
		(width 0.1143)
		(layer "In2.Cu")
		(net "I2C_PSU1_SDA")
	)
	(segment
		(start 70.819518 -171.186602)
		(end 70.898512 -171.186602)
		(width 0.1143)
		(layer "In2.Cu")
		(net "I2C_PSU1_SDA")
	)
	(segment
		(start 79.672688 -166.987474)
		(end 77.617066 -166.987474)
		(width 0.1143)
		(layer "In2.Cu")
		(net "I2C_PSU1_SDA")
	)
	(segment
		(start 77.617066 -166.987474)
		(end 77.343 -167.26154)
		(width 0.1143)
		(layer "In2.Cu")
		(net "I2C_PSU1_SDA")
	)
	(segment
		(start 109.43717 -169.51579)
		(end 109.07268 -169.51579)
		(width 0.1143)
		(layer "In2.Cu")
		(net "I2C_PSU1_SDA")
	)
	(segment
		(start 109.94517 -169.00779)
		(end 109.43717 -169.51579)
		(width 0.1143)
		(layer "In2.Cu")
		(net "I2C_PSU1_SDA")
	)
	(segment
		(start 116.513864 -168.027604)
		(end 113.542064 -168.027604)
		(width 0.1143)
		(layer "In2.Cu")
		(net "I2C_PSU1_SDA")
	)
	(segment
		(start 101.048058 -169.987214)
		(end 100.264214 -169.20337)
		(width 0.1143)
		(layer "In2.Cu")
		(net "I2C_PSU1_SDA")
	)
	(segment
		(start 112.00765 -169.00779)
		(end 109.94517 -169.00779)
		(width 0.1143)
		(layer "In2.Cu")
		(net "I2C_PSU1_SDA")
	)
	(segment
		(start 66.88328 -175.201834)
		(end 66.88328 -176.557432)
		(width 0.1143)
		(layer "In2.Cu")
		(net "I2C_PSU1_SDA")
	)
	(segment
		(start 108.04779 -169.204386)
		(end 107.264962 -169.987214)
		(width 0.1143)
		(layer "In2.Cu")
		(net "I2C_PSU1_SDA")
	)
	(segment
		(start 73.68032 -169.56278)
		(end 73.3171 -169.56278)
		(width 0.1143)
		(layer "In2.Cu")
		(net "I2C_PSU1_SDA")
	)
	(segment
		(start 75.889104 -168.202864)
		(end 75.33767 -168.754298)
		(width 0.1143)
		(layer "In2.Cu")
		(net "I2C_PSU1_SDA")
	)
	(segment
		(start 80.2005 -166.459662)
		(end 79.672688 -166.987474)
		(width 0.1143)
		(layer "In2.Cu")
		(net "I2C_PSU1_SDA")
	)
	(segment
		(start 74.488802 -168.754298)
		(end 73.68032 -169.56278)
		(width 0.1143)
		(layer "In2.Cu")
		(net "I2C_PSU1_SDA")
	)
	(segment
		(start 96.21012 -168.507156)
		(end 95.518732 -167.815768)
		(width 0.1143)
		(layer "In2.Cu")
		(net "I2C_PSU1_SDA")
	)
	(segment
		(start 88.89746 -167.646858)
		(end 88.89746 -167.630348)
		(width 0.1143)
		(layer "In2.Cu")
		(net "I2C_PSU1_SDA")
	)
	(segment
		(start 113.542064 -168.027604)
		(end 113.264188 -168.30548)
		(width 0.1143)
		(layer "In2.Cu")
		(net "I2C_PSU1_SDA")
	)
	(segment
		(start 93.788484 -167.815768)
		(end 93.649292 -167.95496)
		(width 0.1143)
		(layer "In2.Cu")
		(net "I2C_PSU1_SDA")
	)
	(segment
		(start 100.264214 -169.20337)
		(end 99.71405 -169.20337)
		(width 0.1143)
		(layer "In2.Cu")
		(net "I2C_PSU1_SDA")
	)
	(segment
		(start 54.42712 -181.372256)
		(end 54.42712 -182.395876)
		(width 0.1143)
		(layer "In2.Cu")
		(net "I2C_PSU1_SDA")
	)
	(segment
		(start 63.016384 -180.424328)
		(end 55.375048 -180.424328)
		(width 0.1143)
		(layer "In2.Cu")
		(net "I2C_PSU1_SDA")
	)
	(segment
		(start 86.14283 -165.587172)
		(end 85.43163 -164.875972)
		(width 0.1143)
		(layer "In2.Cu")
		(net "I2C_PSU1_SDA")
	)
	(segment
		(start 81.039716 -166.459662)
		(end 80.2005 -166.459662)
		(width 0.1143)
		(layer "In2.Cu")
		(net "I2C_PSU1_SDA")
	)
	(segment
		(start 73.270872 -169.516552)
		(end 72.489568 -169.516552)
		(width 0.1143)
		(layer "In2.Cu")
		(net "I2C_PSU1_SDA")
	)
	(segment
		(start 98.99904 -168.48836)
		(end 97.9043 -168.48836)
		(width 0.1143)
		(layer "In2.Cu")
		(net "I2C_PSU1_SDA")
	)
	(segment
		(start 86.854284 -165.587172)
		(end 86.14283 -165.587172)
		(width 0.1143)
		(layer "In2.Cu")
		(net "I2C_PSU1_SDA")
	)
	(segment
		(start 72.489568 -169.516552)
		(end 70.819518 -171.186602)
		(width 0.1143)
		(layer "In2.Cu")
		(net "I2C_PSU1_SDA")
	)
	(segment
		(start 109.07268 -169.51579)
		(end 108.761276 -169.204386)
		(width 0.1143)
		(layer "In2.Cu")
		(net "I2C_PSU1_SDA")
	)
	(segment
		(start 75.33767 -168.754298)
		(end 74.488802 -168.754298)
		(width 0.1143)
		(layer "In2.Cu")
		(net "I2C_PSU1_SDA")
	)
	(segment
		(start 85.43163 -164.875972)
		(end 83.90128 -164.875972)
		(width 0.1143)
		(layer "In2.Cu")
		(net "I2C_PSU1_SDA")
	)
	(segment
		(start 76.8604 -168.202864)
		(end 75.889104 -168.202864)
		(width 0.1143)
		(layer "In2.Cu")
		(net "I2C_PSU1_SDA")
	)
	(segment
		(start 54.42712 -182.395876)
		(end 54.18074 -182.642256)
		(width 0.1143)
		(layer "In2.Cu")
		(net "I2C_PSU1_SDA")
	)
	(segment
		(start 99.71405 -169.20337)
		(end 98.99904 -168.48836)
		(width 0.1143)
		(layer "In2.Cu")
		(net "I2C_PSU1_SDA")
	)
	(segment
		(start 108.761276 -169.204386)
		(end 108.04779 -169.204386)
		(width 0.1143)
		(layer "In2.Cu")
		(net "I2C_PSU1_SDA")
	)
	(segment
		(start 97.9043 -168.48836)
		(end 97.885504 -168.507156)
		(width 0.1143)
		(layer "In2.Cu")
		(net "I2C_PSU1_SDA")
	)
	(segment
		(start 89.32545 -168.074848)
		(end 88.89746 -167.646858)
		(width 0.1143)
		(layer "In2.Cu")
		(net "I2C_PSU1_SDA")
	)
	(segment
		(start 93.649292 -167.95496)
		(end 92.314776 -167.95496)
		(width 0.1143)
		(layer "In2.Cu")
		(net "I2C_PSU1_SDA")
	)
	(segment
		(start 92.194888 -168.074848)
		(end 89.32545 -168.074848)
		(width 0.1143)
		(layer "In2.Cu")
		(net "I2C_PSU1_SDA")
	)
	(segment
		(start 77.343 -167.26154)
		(end 77.343 -167.720264)
		(width 0.1143)
		(layer "In2.Cu")
		(net "I2C_PSU1_SDA")
	)
	(segment
		(start 167.090852 -61.825378)
		(end 167.577008 -61.339222)
		(width 0.10668)
		(layer "F.Cu")
		(net "USB3_DP")
	)
	(segment
		(start 164.167312 -108.188506)
		(end 164.644832 -108.666026)
		(width 0.10668)
		(layer "F.Cu")
		(net "USB3_DP")
	)
	(segment
		(start 164.443156 -105.557066)
		(end 164.167312 -105.83291)
		(width 0.10668)
		(layer "F.Cu")
		(net "USB3_DP")
	)
	(segment
		(start 168.379648 -61.68263)
		(end 168.378632 -61.681614)
		(width 0.10668)
		(layer "F.Cu")
		(net "USB3_DP")
	)
	(segment
		(start 164.443156 -104.839008)
		(end 164.443156 -105.557066)
		(width 0.10668)
		(layer "F.Cu")
		(net "USB3_DP")
	)
	(segment
		(start 164.167312 -105.83291)
		(end 164.167312 -108.188506)
		(width 0.10668)
		(layer "F.Cu")
		(net "USB3_DP")
	)
	(segment
		(start 168.03624 -61.339222)
		(end 168.378632 -61.681614)
		(width 0.10668)
		(layer "F.Cu")
		(net "USB3_DP")
	)
	(segment
		(start 169.392346 -61.68263)
		(end 168.379648 -61.68263)
		(width 0.10668)
		(layer "F.Cu")
		(net "USB3_DP")
	)
	(segment
		(start 167.577008 -61.339222)
		(end 168.03624 -61.339222)
		(width 0.10668)
		(layer "F.Cu")
		(net "USB3_DP")
	)
	(via
		(at 167.090852 -61.825378)
		(size 0.508)
		(drill 0.254)
		(layers "F.Cu" "B.Cu")
		(net "USB3_DP")
	)
	(via
		(at 164.644832 -108.666026)
		(size 0.508)
		(drill 0.254)
		(layers "F.Cu" "B.Cu")
		(net "USB3_DP")
	)
	(segment
		(start 175.034956 -107.205018)
		(end 177.54346 -104.696514)
		(width 0.10668)
		(layer "B.Cu")
		(net "USB3_DP")
	)
	(segment
		(start 166.1541 -61.656976)
		(end 166.463218 -61.347858)
		(width 0.10668)
		(layer "B.Cu")
		(net "USB3_DP")
	)
	(segment
		(start 164.273992 -108.666026)
		(end 164.167312 -108.559346)
		(width 0.10668)
		(layer "B.Cu")
		(net "USB3_DP")
	)
	(segment
		(start 177.54346 -104.696514)
		(end 177.54346 -73.876408)
		(width 0.10668)
		(layer "B.Cu")
		(net "USB3_DP")
	)
	(segment
		(start 166.463218 -61.347858)
		(end 166.984172 -61.347858)
		(width 0.10668)
		(layer "B.Cu")
		(net "USB3_DP")
	)
	(segment
		(start 164.167312 -108.559346)
		(end 164.167312 -107.98302)
		(width 0.10668)
		(layer "B.Cu")
		(net "USB3_DP")
	)
	(segment
		(start 177.54346 -73.876408)
		(end 166.1541 -62.487048)
		(width 0.10668)
		(layer "B.Cu")
		(net "USB3_DP")
	)
	(segment
		(start 164.644832 -108.666026)
		(end 164.273992 -108.666026)
		(width 0.10668)
		(layer "B.Cu")
		(net "USB3_DP")
	)
	(segment
		(start 166.984172 -61.347858)
		(end 167.090852 -61.454538)
		(width 0.10668)
		(layer "B.Cu")
		(net "USB3_DP")
	)
	(segment
		(start 166.1541 -62.487048)
		(end 166.1541 -61.656976)
		(width 0.10668)
		(layer "B.Cu")
		(net "USB3_DP")
	)
	(segment
		(start 164.167312 -107.98302)
		(end 164.945314 -107.205018)
		(width 0.10668)
		(layer "B.Cu")
		(net "USB3_DP")
	)
	(segment
		(start 167.090852 -61.454538)
		(end 167.090852 -61.825378)
		(width 0.10668)
		(layer "B.Cu")
		(net "USB3_DP")
	)
	(segment
		(start 164.945314 -107.205018)
		(end 175.034956 -107.205018)
		(width 0.10668)
		(layer "B.Cu")
		(net "USB3_DP")
	)
	(segment
		(start 128.117854 -161.243772)
		(end 127.856996 -161.243772)
		(width 0.1016)
		(layer "F.Cu")
		(net "I2C_PSU3_SCL")
	)
	(segment
		(start 127.856996 -161.243772)
		(end 127.711454 -161.389314)
		(width 0.1016)
		(layer "F.Cu")
		(net "I2C_PSU3_SCL")
	)
	(segment
		(start 128.339596 -163.205922)
		(end 128.46812 -163.205922)
		(width 0.1016)
		(layer "F.Cu")
		(net "I2C_PSU3_SCL")
	)
	(segment
		(start 127.711454 -161.389314)
		(end 127.711454 -162.57778)
		(width 0.1016)
		(layer "F.Cu")
		(net "I2C_PSU3_SCL")
	)
	(segment
		(start 128.117854 -161.103564)
		(end 128.117854 -161.243772)
		(width 0.1016)
		(layer "F.Cu")
		(net "I2C_PSU3_SCL")
	)
	(segment
		(start 128.955292 -157.524196)
		(end 128.3208 -158.158688)
		(width 0.1016)
		(layer "F.Cu")
		(net "I2C_PSU3_SCL")
	)
	(segment
		(start 128.3208 -158.158688)
		(end 128.3208 -160.900618)
		(width 0.1016)
		(layer "F.Cu")
		(net "I2C_PSU3_SCL")
	)
	(segment
		(start 130.108452 -157.524196)
		(end 128.955292 -157.524196)
		(width 0.1016)
		(layer "F.Cu")
		(net "I2C_PSU3_SCL")
	)
	(segment
		(start 127.711454 -162.57778)
		(end 128.339596 -163.205922)
		(width 0.1016)
		(layer "F.Cu")
		(net "I2C_PSU3_SCL")
	)
	(segment
		(start 128.3208 -160.900618)
		(end 128.117854 -161.103564)
		(width 0.1016)
		(layer "F.Cu")
		(net "I2C_PSU3_SCL")
	)
	(via
		(at 128.46812 -163.205922)
		(size 0.508)
		(drill 0.254)
		(layers "F.Cu" "B.Cu")
		(net "I2C_PSU3_SCL")
	)
	(via
		(at 155.88742 -182.286402)
		(size 0.508)
		(drill 0.254)
		(layers "F.Cu" "B.Cu")
		(net "I2C_PSU3_SCL")
	)
	(segment
		(start 157.33776 -184.046368)
		(end 157.04566 -183.754268)
		(width 0.1016)
		(layer "B.Cu")
		(net "I2C_PSU3_SCL")
	)
	(segment
		(start 157.04566 -182.761636)
		(end 156.570426 -182.286402)
		(width 0.1016)
		(layer "B.Cu")
		(net "I2C_PSU3_SCL")
	)
	(segment
		(start 156.570426 -182.286402)
		(end 155.88742 -182.286402)
		(width 0.1016)
		(layer "B.Cu")
		(net "I2C_PSU3_SCL")
	)
	(segment
		(start 157.04566 -183.754268)
		(end 157.04566 -182.761636)
		(width 0.1016)
		(layer "B.Cu")
		(net "I2C_PSU3_SCL")
	)
	(segment
		(start 157.33776 -184.551574)
		(end 157.33776 -184.046368)
		(width 0.1016)
		(layer "B.Cu")
		(net "I2C_PSU3_SCL")
	)
	(segment
		(start 151.74468 -181.209442)
		(end 150.92172 -180.386482)
		(width 0.1143)
		(layer "In7.Cu")
		(net "I2C_PSU3_SCL")
	)
	(segment
		(start 144.285462 -164.7952)
		(end 140.9954 -164.7952)
		(width 0.1143)
		(layer "In7.Cu")
		(net "I2C_PSU3_SCL")
	)
	(segment
		(start 151.41829 -177.739548)
		(end 150.91156 -177.232818)
		(width 0.1143)
		(layer "In7.Cu")
		(net "I2C_PSU3_SCL")
	)
	(segment
		(start 133.21919 -163.682426)
		(end 132.891276 -164.01034)
		(width 0.1143)
		(layer "In7.Cu")
		(net "I2C_PSU3_SCL")
	)
	(segment
		(start 150.92172 -180.386482)
		(end 150.92172 -179.52339)
		(width 0.1143)
		(layer "In7.Cu")
		(net "I2C_PSU3_SCL")
	)
	(segment
		(start 139.882626 -163.682426)
		(end 133.21919 -163.682426)
		(width 0.1143)
		(layer "In7.Cu")
		(net "I2C_PSU3_SCL")
	)
	(segment
		(start 150.91156 -171.30395)
		(end 149.37232 -169.76471)
		(width 0.1143)
		(layer "In7.Cu")
		(net "I2C_PSU3_SCL")
	)
	(segment
		(start 154.010106 -182.286402)
		(end 152.933146 -181.209442)
		(width 0.1143)
		(layer "In7.Cu")
		(net "I2C_PSU3_SCL")
	)
	(segment
		(start 151.41829 -179.02682)
		(end 151.41829 -177.739548)
		(width 0.1143)
		(layer "In7.Cu")
		(net "I2C_PSU3_SCL")
	)
	(segment
		(start 129.897124 -164.01034)
		(end 129.240788 -163.354004)
		(width 0.1143)
		(layer "In7.Cu")
		(net "I2C_PSU3_SCL")
	)
	(segment
		(start 155.88742 -182.286402)
		(end 154.010106 -182.286402)
		(width 0.1143)
		(layer "In7.Cu")
		(net "I2C_PSU3_SCL")
	)
	(segment
		(start 149.37232 -169.76471)
		(end 149.37232 -168.278048)
		(width 0.1143)
		(layer "In7.Cu")
		(net "I2C_PSU3_SCL")
	)
	(segment
		(start 148.900134 -167.805862)
		(end 148.468588 -167.805862)
		(width 0.1143)
		(layer "In7.Cu")
		(net "I2C_PSU3_SCL")
	)
	(segment
		(start 150.92172 -179.52339)
		(end 151.41829 -179.02682)
		(width 0.1143)
		(layer "In7.Cu")
		(net "I2C_PSU3_SCL")
	)
	(segment
		(start 149.37232 -168.278048)
		(end 148.900134 -167.805862)
		(width 0.1143)
		(layer "In7.Cu")
		(net "I2C_PSU3_SCL")
	)
	(segment
		(start 132.891276 -164.01034)
		(end 129.897124 -164.01034)
		(width 0.1143)
		(layer "In7.Cu")
		(net "I2C_PSU3_SCL")
	)
	(segment
		(start 150.91156 -177.232818)
		(end 150.91156 -171.30395)
		(width 0.1143)
		(layer "In7.Cu")
		(net "I2C_PSU3_SCL")
	)
	(segment
		(start 152.933146 -181.209442)
		(end 151.74468 -181.209442)
		(width 0.1143)
		(layer "In7.Cu")
		(net "I2C_PSU3_SCL")
	)
	(segment
		(start 145.572988 -166.082726)
		(end 144.285462 -164.7952)
		(width 0.1143)
		(layer "In7.Cu")
		(net "I2C_PSU3_SCL")
	)
	(segment
		(start 140.9954 -164.7952)
		(end 139.882626 -163.682426)
		(width 0.1143)
		(layer "In7.Cu")
		(net "I2C_PSU3_SCL")
	)
	(segment
		(start 146.745452 -166.082726)
		(end 145.572988 -166.082726)
		(width 0.1143)
		(layer "In7.Cu")
		(net "I2C_PSU3_SCL")
	)
	(segment
		(start 148.468588 -167.805862)
		(end 146.745452 -166.082726)
		(width 0.1143)
		(layer "In7.Cu")
		(net "I2C_PSU3_SCL")
	)
	(segment
		(start 128.616202 -163.354004)
		(end 128.46812 -163.205922)
		(width 0.1143)
		(layer "In7.Cu")
		(net "I2C_PSU3_SCL")
	)
	(segment
		(start 129.240788 -163.354004)
		(end 128.616202 -163.354004)
		(width 0.1143)
		(layer "In7.Cu")
		(net "I2C_PSU3_SCL")
	)
	(segment
		(start 168.010586 -105.445814)
		(end 168.010586 -107.625134)
		(width 0.10668)
		(layer "F.Cu")
		(net "USB2_DP")
	)
	(segment
		(start 168.247314 -57.99709)
		(end 168.222676 -57.972452)
		(width 0.10668)
		(layer "F.Cu")
		(net "USB2_DP")
	)
	(segment
		(start 168.043352 -104.839008)
		(end 168.043352 -105.413048)
		(width 0.10668)
		(layer "F.Cu")
		(net "USB2_DP")
	)
	(segment
		(start 167.378634 -57.63006)
		(end 167.721026 -57.972452)
		(width 0.10668)
		(layer "F.Cu")
		(net "USB2_DP")
	)
	(segment
		(start 168.043352 -105.413048)
		(end 168.010586 -105.445814)
		(width 0.10668)
		(layer "F.Cu")
		(net "USB2_DP")
	)
	(segment
		(start 169.243502 -57.99709)
		(end 168.247314 -57.99709)
		(width 0.10668)
		(layer "F.Cu")
		(net "USB2_DP")
	)
	(segment
		(start 166.848536 -57.63006)
		(end 167.378634 -57.63006)
		(width 0.10668)
		(layer "F.Cu")
		(net "USB2_DP")
	)
	(segment
		(start 166.37762 -58.100976)
		(end 166.848536 -57.63006)
		(width 0.10668)
		(layer "F.Cu")
		(net "USB2_DP")
	)
	(segment
		(start 168.010586 -107.625134)
		(end 168.488106 -108.102654)
		(width 0.10668)
		(layer "F.Cu")
		(net "USB2_DP")
	)
	(segment
		(start 167.721026 -57.972452)
		(end 168.222676 -57.972452)
		(width 0.10668)
		(layer "F.Cu")
		(net "USB2_DP")
	)
	(via
		(at 168.488106 -108.102654)
		(size 0.508)
		(drill 0.254)
		(layers "F.Cu" "B.Cu")
		(net "USB2_DP")
	)
	(via
		(at 166.37762 -58.100976)
		(size 0.508)
		(drill 0.254)
		(layers "F.Cu" "B.Cu")
		(net "USB2_DP")
	)
	(segment
		(start 168.010586 -108.942632)
		(end 168.010586 -108.580174)
		(width 0.10668)
		(layer "B.Cu")
		(net "USB2_DP")
	)
	(segment
		(start 179.15128 -74.10704)
		(end 179.15128 -104.356154)
		(width 0.10668)
		(layer "B.Cu")
		(net "USB2_DP")
	)
	(segment
		(start 166.867078 -57.611518)
		(end 167.53459 -57.611518)
		(width 0.10668)
		(layer "B.Cu")
		(net "USB2_DP")
	)
	(segment
		(start 168.010586 -108.580174)
		(end 168.488106 -108.102654)
		(width 0.10668)
		(layer "B.Cu")
		(net "USB2_DP")
	)
	(segment
		(start 179.15128 -104.356154)
		(end 174.097696 -109.409738)
		(width 0.10668)
		(layer "B.Cu")
		(net "USB2_DP")
	)
	(segment
		(start 167.53459 -57.611518)
		(end 169.55008 -59.627008)
		(width 0.10668)
		(layer "B.Cu")
		(net "USB2_DP")
	)
	(segment
		(start 169.55008 -64.50584)
		(end 179.15128 -74.10704)
		(width 0.10668)
		(layer "B.Cu")
		(net "USB2_DP")
	)
	(segment
		(start 174.097696 -109.409738)
		(end 168.477692 -109.409738)
		(width 0.10668)
		(layer "B.Cu")
		(net "USB2_DP")
	)
	(segment
		(start 169.55008 -59.627008)
		(end 169.55008 -64.50584)
		(width 0.10668)
		(layer "B.Cu")
		(net "USB2_DP")
	)
	(segment
		(start 166.37762 -58.100976)
		(end 166.867078 -57.611518)
		(width 0.10668)
		(layer "B.Cu")
		(net "USB2_DP")
	)
	(segment
		(start 168.477692 -109.409738)
		(end 168.010586 -108.942632)
		(width 0.10668)
		(layer "B.Cu")
		(net "USB2_DP")
	)
	(segment
		(start 168.318942 -41.66489)
		(end 167.815514 -41.66489)
		(width 0.10668)
		(layer "F.Cu")
		(net "USB1_DP")
	)
	(segment
		(start 169.328846 -41.679114)
		(end 169.314622 -41.66489)
		(width 0.10668)
		(layer "F.Cu")
		(net "USB1_DP")
	)
	(segment
		(start 172.210222 -104.057958)
		(end 171.88815 -103.735886)
		(width 0.10668)
		(layer "F.Cu")
		(net "USB1_DP")
	)
	(segment
		(start 171.88815 -103.735886)
		(end 171.14647 -103.735886)
		(width 0.10668)
		(layer "F.Cu")
		(net "USB1_DP")
	)
	(segment
		(start 175.139858 -103.592122)
		(end 174.674022 -104.057958)
		(width 0.10668)
		(layer "F.Cu")
		(net "USB1_DP")
	)
	(segment
		(start 167.02405 -41.322498)
		(end 166.54653 -41.800018)
		(width 0.10668)
		(layer "F.Cu")
		(net "USB1_DP")
	)
	(segment
		(start 174.674022 -104.057958)
		(end 172.210222 -104.057958)
		(width 0.10668)
		(layer "F.Cu")
		(net "USB1_DP")
	)
	(segment
		(start 169.314622 -41.66489)
		(end 168.318942 -41.66489)
		(width 0.10668)
		(layer "F.Cu")
		(net "USB1_DP")
	)
	(segment
		(start 167.815514 -41.66489)
		(end 167.473122 -41.322498)
		(width 0.10668)
		(layer "F.Cu")
		(net "USB1_DP")
	)
	(segment
		(start 167.473122 -41.322498)
		(end 167.02405 -41.322498)
		(width 0.10668)
		(layer "F.Cu")
		(net "USB1_DP")
	)
	(via
		(at 175.139858 -103.592122)
		(size 0.508)
		(drill 0.254)
		(layers "F.Cu" "B.Cu")
		(net "USB1_DP")
	)
	(via
		(at 166.54653 -41.800018)
		(size 0.508)
		(drill 0.254)
		(layers "F.Cu" "B.Cu")
		(net "USB1_DP")
	)
	(segment
		(start 175.139858 -103.962962)
		(end 175.033178 -104.069642)
		(width 0.10668)
		(layer "B.Cu")
		(net "USB1_DP")
	)
	(segment
		(start 174.450248 -104.069642)
		(end 173.69028 -103.309674)
		(width 0.10668)
		(layer "B.Cu")
		(net "USB1_DP")
	)
	(segment
		(start 166.54653 -41.429178)
		(end 166.54653 -41.800018)
		(width 0.10668)
		(layer "B.Cu")
		(net "USB1_DP")
	)
	(segment
		(start 165.82517 -41.322498)
		(end 166.43985 -41.322498)
		(width 0.10668)
		(layer "B.Cu")
		(net "USB1_DP")
	)
	(segment
		(start 173.69028 -103.309674)
		(end 173.69028 -73.37044)
		(width 0.10668)
		(layer "B.Cu")
		(net "USB1_DP")
	)
	(segment
		(start 163.9316 -43.216068)
		(end 165.82517 -41.322498)
		(width 0.10668)
		(layer "B.Cu")
		(net "USB1_DP")
	)
	(segment
		(start 175.139858 -103.592122)
		(end 175.139858 -103.962962)
		(width 0.10668)
		(layer "B.Cu")
		(net "USB1_DP")
	)
	(segment
		(start 163.9316 -63.61176)
		(end 163.9316 -43.216068)
		(width 0.10668)
		(layer "B.Cu")
		(net "USB1_DP")
	)
	(segment
		(start 173.69028 -73.37044)
		(end 163.9316 -63.61176)
		(width 0.10668)
		(layer "B.Cu")
		(net "USB1_DP")
	)
	(segment
		(start 175.033178 -104.069642)
		(end 174.450248 -104.069642)
		(width 0.10668)
		(layer "B.Cu")
		(net "USB1_DP")
	)
	(segment
		(start 166.43985 -41.322498)
		(end 166.54653 -41.429178)
		(width 0.10668)
		(layer "B.Cu")
		(net "USB1_DP")
	)
	(segment
		(start 166.54653 -40.530018)
		(end 167.02405 -41.007538)
		(width 0.10668)
		(layer "F.Cu")
		(net "USB1_DN")
	)
	(segment
		(start 172.079666 -104.372918)
		(end 171.84243 -104.135682)
		(width 0.10668)
		(layer "F.Cu")
		(net "USB1_DN")
	)
	(segment
		(start 174.650654 -104.372918)
		(end 172.079666 -104.372918)
		(width 0.10668)
		(layer "F.Cu")
		(net "USB1_DN")
	)
	(segment
		(start 167.815514 -40.665146)
		(end 168.318942 -40.665146)
		(width 0.10668)
		(layer "F.Cu")
		(net "USB1_DN")
	)
	(segment
		(start 175.139858 -104.862122)
		(end 174.650654 -104.372918)
		(width 0.10668)
		(layer "F.Cu")
		(net "USB1_DN")
	)
	(segment
		(start 171.84243 -104.135682)
		(end 171.23537 -104.135682)
		(width 0.10668)
		(layer "F.Cu")
		(net "USB1_DN")
	)
	(segment
		(start 167.473122 -41.007538)
		(end 167.815514 -40.665146)
		(width 0.10668)
		(layer "F.Cu")
		(net "USB1_DN")
	)
	(segment
		(start 169.328846 -40.663114)
		(end 168.320974 -40.663114)
		(width 0.10668)
		(layer "F.Cu")
		(net "USB1_DN")
	)
	(segment
		(start 168.320974 -40.663114)
		(end 168.318942 -40.665146)
		(width 0.10668)
		(layer "F.Cu")
		(net "USB1_DN")
	)
	(segment
		(start 167.02405 -41.007538)
		(end 167.473122 -41.007538)
		(width 0.10668)
		(layer "F.Cu")
		(net "USB1_DN")
	)
	(via
		(at 166.54653 -40.530018)
		(size 0.508)
		(drill 0.254)
		(layers "F.Cu" "B.Cu")
		(net "USB1_DN")
	)
	(via
		(at 175.139858 -104.862122)
		(size 0.508)
		(drill 0.254)
		(layers "F.Cu" "B.Cu")
		(net "USB1_DN")
	)
	(segment
		(start 163.61664 -43.085512)
		(end 165.694614 -41.007538)
		(width 0.10668)
		(layer "B.Cu")
		(net "USB1_DN")
	)
	(segment
		(start 175.033178 -104.384602)
		(end 174.319692 -104.384602)
		(width 0.10668)
		(layer "B.Cu")
		(net "USB1_DN")
	)
	(segment
		(start 174.319692 -104.384602)
		(end 173.37532 -103.44023)
		(width 0.10668)
		(layer "B.Cu")
		(net "USB1_DN")
	)
	(segment
		(start 163.61664 -63.742316)
		(end 163.61664 -43.085512)
		(width 0.10668)
		(layer "B.Cu")
		(net "USB1_DN")
	)
	(segment
		(start 173.37532 -103.44023)
		(end 173.37532 -73.500996)
		(width 0.10668)
		(layer "B.Cu")
		(net "USB1_DN")
	)
	(segment
		(start 175.139858 -104.491282)
		(end 175.033178 -104.384602)
		(width 0.10668)
		(layer "B.Cu")
		(net "USB1_DN")
	)
	(segment
		(start 175.139858 -104.862122)
		(end 175.139858 -104.491282)
		(width 0.10668)
		(layer "B.Cu")
		(net "USB1_DN")
	)
	(segment
		(start 165.694614 -41.007538)
		(end 166.43985 -41.007538)
		(width 0.10668)
		(layer "B.Cu")
		(net "USB1_DN")
	)
	(segment
		(start 166.54653 -40.900858)
		(end 166.54653 -40.530018)
		(width 0.10668)
		(layer "B.Cu")
		(net "USB1_DN")
	)
	(segment
		(start 173.37532 -73.500996)
		(end 163.61664 -63.742316)
		(width 0.10668)
		(layer "B.Cu")
		(net "USB1_DN")
	)
	(segment
		(start 166.43985 -41.007538)
		(end 166.54653 -40.900858)
		(width 0.10668)
		(layer "B.Cu")
		(net "USB1_DN")
	)
	(segment
		(start 48.641 -145.596356)
		(end 48.641 -145.276824)
		(width 0.1016)
		(layer "F.Cu")
		(net "SPI_LAN1_NVM_SI")
	)
	(segment
		(start 46.317662 -150.37308)
		(end 46.317662 -149.614636)
		(width 0.1016)
		(layer "F.Cu")
		(net "SPI_LAN1_NVM_SI")
	)
	(segment
		(start 58.216546 -162.328606)
		(end 58.216546 -163.11372)
		(width 0.1016)
		(layer "F.Cu")
		(net "SPI_LAN1_NVM_SI")
	)
	(segment
		(start 46.51248 -149.419818)
		(end 46.51248 -147.724876)
		(width 0.1016)
		(layer "F.Cu")
		(net "SPI_LAN1_NVM_SI")
	)
	(segment
		(start 46.51248 -147.724876)
		(end 48.641 -145.596356)
		(width 0.1016)
		(layer "F.Cu")
		(net "SPI_LAN1_NVM_SI")
	)
	(segment
		(start 46.317662 -149.614636)
		(end 46.51248 -149.419818)
		(width 0.1016)
		(layer "F.Cu")
		(net "SPI_LAN1_NVM_SI")
	)
	(via
		(at 58.216546 -163.11372)
		(size 0.508)
		(drill 0.254)
		(layers "F.Cu" "B.Cu")
		(net "SPI_LAN1_NVM_SI")
	)
	(via
		(at 48.641 -145.276824)
		(size 0.508)
		(drill 0.254)
		(layers "F.Cu" "B.Cu")
		(net "SPI_LAN1_NVM_SI")
	)
	(segment
		(start 50.907188 -144.910048)
		(end 49.00676 -144.910048)
		(width 0.1016)
		(layer "B.Cu")
		(net "SPI_LAN1_NVM_SI")
	)
	(segment
		(start 56.426862 -158.619698)
		(end 56.2483 -158.441136)
		(width 0.1016)
		(layer "B.Cu")
		(net "SPI_LAN1_NVM_SI")
	)
	(segment
		(start 56.426862 -159.229298)
		(end 57.253378 -159.229298)
		(width 0.1016)
		(layer "B.Cu")
		(net "SPI_LAN1_NVM_SI")
	)
	(segment
		(start 53.18506 -149.278594)
		(end 52.67452 -148.768054)
		(width 0.1016)
		(layer "B.Cu")
		(net "SPI_LAN1_NVM_SI")
	)
	(segment
		(start 57.253378 -159.229298)
		(end 57.43194 -159.050736)
		(width 0.1016)
		(layer "B.Cu")
		(net "SPI_LAN1_NVM_SI")
	)
	(segment
		(start 56.2483 -157.221936)
		(end 56.2483 -156.59227)
		(width 0.1016)
		(layer "B.Cu")
		(net "SPI_LAN1_NVM_SI")
	)
	(segment
		(start 57.43194 -157.57906)
		(end 57.253378 -157.400498)
		(width 0.1016)
		(layer "B.Cu")
		(net "SPI_LAN1_NVM_SI")
	)
	(segment
		(start 48.641 -145.275808)
		(end 48.641 -145.276824)
		(width 0.1016)
		(layer "B.Cu")
		(net "SPI_LAN1_NVM_SI")
	)
	(segment
		(start 57.43194 -158.79826)
		(end 57.253378 -158.619698)
		(width 0.1016)
		(layer "B.Cu")
		(net "SPI_LAN1_NVM_SI")
	)
	(segment
		(start 56.2483 -161.145474)
		(end 56.2483 -159.40786)
		(width 0.1016)
		(layer "B.Cu")
		(net "SPI_LAN1_NVM_SI")
	)
	(segment
		(start 56.2483 -159.40786)
		(end 56.426862 -159.229298)
		(width 0.1016)
		(layer "B.Cu")
		(net "SPI_LAN1_NVM_SI")
	)
	(segment
		(start 56.426862 -158.010098)
		(end 57.253378 -158.010098)
		(width 0.1016)
		(layer "B.Cu")
		(net "SPI_LAN1_NVM_SI")
	)
	(segment
		(start 57.43194 -157.831536)
		(end 57.43194 -157.57906)
		(width 0.1016)
		(layer "B.Cu")
		(net "SPI_LAN1_NVM_SI")
	)
	(segment
		(start 52.67452 -148.768054)
		(end 52.67452 -146.67738)
		(width 0.1016)
		(layer "B.Cu")
		(net "SPI_LAN1_NVM_SI")
	)
	(segment
		(start 49.00676 -144.910048)
		(end 48.641 -145.275808)
		(width 0.1016)
		(layer "B.Cu")
		(net "SPI_LAN1_NVM_SI")
	)
	(segment
		(start 56.426862 -157.400498)
		(end 56.2483 -157.221936)
		(width 0.1016)
		(layer "B.Cu")
		(net "SPI_LAN1_NVM_SI")
	)
	(segment
		(start 56.2483 -156.59227)
		(end 53.18506 -153.52903)
		(width 0.1016)
		(layer "B.Cu")
		(net "SPI_LAN1_NVM_SI")
	)
	(segment
		(start 52.67452 -146.67738)
		(end 50.907188 -144.910048)
		(width 0.1016)
		(layer "B.Cu")
		(net "SPI_LAN1_NVM_SI")
	)
	(segment
		(start 57.253378 -158.619698)
		(end 56.426862 -158.619698)
		(width 0.1016)
		(layer "B.Cu")
		(net "SPI_LAN1_NVM_SI")
	)
	(segment
		(start 56.2483 -158.441136)
		(end 56.2483 -158.18866)
		(width 0.1016)
		(layer "B.Cu")
		(net "SPI_LAN1_NVM_SI")
	)
	(segment
		(start 58.216546 -163.11372)
		(end 56.2483 -161.145474)
		(width 0.1016)
		(layer "B.Cu")
		(net "SPI_LAN1_NVM_SI")
	)
	(segment
		(start 57.253378 -157.400498)
		(end 56.426862 -157.400498)
		(width 0.1016)
		(layer "B.Cu")
		(net "SPI_LAN1_NVM_SI")
	)
	(segment
		(start 56.2483 -158.18866)
		(end 56.426862 -158.010098)
		(width 0.1016)
		(layer "B.Cu")
		(net "SPI_LAN1_NVM_SI")
	)
	(segment
		(start 57.43194 -159.050736)
		(end 57.43194 -158.79826)
		(width 0.1016)
		(layer "B.Cu")
		(net "SPI_LAN1_NVM_SI")
	)
	(segment
		(start 57.253378 -158.010098)
		(end 57.43194 -157.831536)
		(width 0.1016)
		(layer "B.Cu")
		(net "SPI_LAN1_NVM_SI")
	)
	(segment
		(start 53.18506 -153.52903)
		(end 53.18506 -149.278594)
		(width 0.1016)
		(layer "B.Cu")
		(net "SPI_LAN1_NVM_SI")
	)
	(segment
		(start 93.826838 -165.160706)
		(end 93.84792 -165.139624)
		(width 0.1016)
		(layer "F.Cu")
		(net "FAN5_TACH")
	)
	(segment
		(start 93.84792 -165.139624)
		(end 94.051882 -165.139624)
		(width 0.1016)
		(layer "F.Cu")
		(net "FAN5_TACH")
	)
	(segment
		(start 93.43898 -165.160706)
		(end 93.826838 -165.160706)
		(width 0.1016)
		(layer "F.Cu")
		(net "FAN5_TACH")
	)
	(via
		(at 93.43898 -165.160706)
		(size 0.508)
		(drill 0.254)
		(layers "F.Cu" "B.Cu")
		(net "FAN5_TACH")
	)
	(via
		(at 161.40684 -186.72302)
		(size 0.508)
		(drill 0.254)
		(layers "F.Cu" "B.Cu")
		(net "FAN5_TACH")
	)
	(segment
		(start 161.40684 -186.735974)
		(end 161.40684 -186.72302)
		(width 0.1016)
		(layer "B.Cu")
		(net "FAN5_TACH")
	)
	(segment
		(start 160.63976 -187.472574)
		(end 160.67024 -187.472574)
		(width 0.1016)
		(layer "B.Cu")
		(net "FAN5_TACH")
	)
	(segment
		(start 160.67024 -187.472574)
		(end 161.40684 -186.735974)
		(width 0.1016)
		(layer "B.Cu")
		(net "FAN5_TACH")
	)
	(segment
		(start 160.73628 -187.39358)
		(end 161.40684 -186.72302)
		(width 0.1143)
		(layer "In7.Cu")
		(net "FAN5_TACH")
	)
	(segment
		(start 110.64875 -189.10427)
		(end 158.787084 -189.10427)
		(width 0.1143)
		(layer "In7.Cu")
		(net "FAN5_TACH")
	)
	(segment
		(start 100.28428 -172.969174)
		(end 100.457 -173.141894)
		(width 0.1143)
		(layer "In7.Cu")
		(net "FAN5_TACH")
	)
	(segment
		(start 95.293688 -165.160706)
		(end 100.28428 -170.151298)
		(width 0.1143)
		(layer "In7.Cu")
		(net "FAN5_TACH")
	)
	(segment
		(start 108.75264 -187.20816)
		(end 110.64875 -189.10427)
		(width 0.1143)
		(layer "In7.Cu")
		(net "FAN5_TACH")
	)
	(segment
		(start 107.456224 -185.70575)
		(end 107.916726 -185.70575)
		(width 0.1143)
		(layer "In7.Cu")
		(net "FAN5_TACH")
	)
	(segment
		(start 108.75264 -186.541664)
		(end 108.75264 -187.20816)
		(width 0.1143)
		(layer "In7.Cu")
		(net "FAN5_TACH")
	)
	(segment
		(start 102.68331 -180.192934)
		(end 102.68331 -181.722776)
		(width 0.1143)
		(layer "In7.Cu")
		(net "FAN5_TACH")
	)
	(segment
		(start 107.916726 -185.70575)
		(end 108.75264 -186.541664)
		(width 0.1143)
		(layer "In7.Cu")
		(net "FAN5_TACH")
	)
	(segment
		(start 100.457 -175.988472)
		(end 102.380542 -177.912014)
		(width 0.1143)
		(layer "In7.Cu")
		(net "FAN5_TACH")
	)
	(segment
		(start 158.787084 -189.10427)
		(end 159.64662 -189.963806)
		(width 0.1143)
		(layer "In7.Cu")
		(net "FAN5_TACH")
	)
	(segment
		(start 102.68331 -181.722776)
		(end 106.440224 -185.47969)
		(width 0.1143)
		(layer "In7.Cu")
		(net "FAN5_TACH")
	)
	(segment
		(start 102.380542 -179.890166)
		(end 102.68331 -180.192934)
		(width 0.1143)
		(layer "In7.Cu")
		(net "FAN5_TACH")
	)
	(segment
		(start 100.28428 -170.151298)
		(end 100.28428 -172.969174)
		(width 0.1143)
		(layer "In7.Cu")
		(net "FAN5_TACH")
	)
	(segment
		(start 107.230164 -185.47969)
		(end 107.456224 -185.70575)
		(width 0.1143)
		(layer "In7.Cu")
		(net "FAN5_TACH")
	)
	(segment
		(start 106.440224 -185.47969)
		(end 107.230164 -185.47969)
		(width 0.1143)
		(layer "In7.Cu")
		(net "FAN5_TACH")
	)
	(segment
		(start 159.64662 -189.963806)
		(end 160.32226 -189.963806)
		(width 0.1143)
		(layer "In7.Cu")
		(net "FAN5_TACH")
	)
	(segment
		(start 100.457 -173.141894)
		(end 100.457 -175.988472)
		(width 0.1143)
		(layer "In7.Cu")
		(net "FAN5_TACH")
	)
	(segment
		(start 160.32226 -189.963806)
		(end 160.73628 -189.549786)
		(width 0.1143)
		(layer "In7.Cu")
		(net "FAN5_TACH")
	)
	(segment
		(start 160.73628 -189.549786)
		(end 160.73628 -187.39358)
		(width 0.1143)
		(layer "In7.Cu")
		(net "FAN5_TACH")
	)
	(segment
		(start 93.43898 -165.160706)
		(end 95.293688 -165.160706)
		(width 0.1143)
		(layer "In7.Cu")
		(net "FAN5_TACH")
	)
	(segment
		(start 102.380542 -177.912014)
		(end 102.380542 -179.890166)
		(width 0.1143)
		(layer "In7.Cu")
		(net "FAN5_TACH")
	)
	(segment
		(start 47.817532 -148.85797)
		(end 47.865792 -148.80971)
		(width 0.1016)
		(layer "F.Cu")
		(net "SPI_LAN1_NVM_CS_N")
	)
	(segment
		(start 47.817532 -150.37308)
		(end 47.817532 -148.85797)
		(width 0.1016)
		(layer "F.Cu")
		(net "SPI_LAN1_NVM_CS_N")
	)
	(segment
		(start 47.865792 -148.80971)
		(end 47.8663 -148.80971)
		(width 0.1016)
		(layer "F.Cu")
		(net "SPI_LAN1_NVM_CS_N")
	)
	(segment
		(start 51.823112 -148.562822)
		(end 51.823112 -147.546822)
		(width 0.1016)
		(layer "F.Cu")
		(net "SPI_LAN1_NVM_CS_N")
	)
	(segment
		(start 47.8663 -148.80971)
		(end 49.04232 -147.63369)
		(width 0.1016)
		(layer "F.Cu")
		(net "SPI_LAN1_NVM_CS_N")
	)
	(segment
		(start 51.288188 -147.546822)
		(end 51.20132 -147.63369)
		(width 0.1016)
		(layer "F.Cu")
		(net "SPI_LAN1_NVM_CS_N")
	)
	(segment
		(start 51.823112 -147.546822)
		(end 51.288188 -147.546822)
		(width 0.1016)
		(layer "F.Cu")
		(net "SPI_LAN1_NVM_CS_N")
	)
	(segment
		(start 51.20132 -147.63369)
		(end 49.04232 -147.63369)
		(width 0.1016)
		(layer "F.Cu")
		(net "SPI_LAN1_NVM_CS_N")
	)
	(via
		(at 49.04232 -147.63369)
		(size 0.508)
		(drill 0.254)
		(layers "F.Cu" "B.Cu")
		(net "SPI_LAN1_NVM_CS_N")
	)
	(segment
		(start 94.051882 -169.203624)
		(end 94.051882 -169.116756)
		(width 0.1016)
		(layer "F.Cu")
		(net "FAN2_TACH")
	)
	(segment
		(start 156.48178 -183.314086)
		(end 156.48178 -183.092852)
		(width 0.1016)
		(layer "F.Cu")
		(net "FAN2_TACH")
	)
	(segment
		(start 94.051882 -169.116756)
		(end 94.91472 -168.253918)
		(width 0.1016)
		(layer "F.Cu")
		(net "FAN2_TACH")
	)
	(segment
		(start 157.33776 -184.805574)
		(end 157.33776 -184.170066)
		(width 0.1016)
		(layer "F.Cu")
		(net "FAN2_TACH")
	)
	(segment
		(start 157.33776 -184.170066)
		(end 156.48178 -183.314086)
		(width 0.1016)
		(layer "F.Cu")
		(net "FAN2_TACH")
	)
	(via
		(at 156.48178 -183.092852)
		(size 0.508)
		(drill 0.254)
		(layers "F.Cu" "B.Cu")
		(net "FAN2_TACH")
	)
	(via
		(at 94.91472 -168.253918)
		(size 0.508)
		(drill 0.254)
		(layers "F.Cu" "B.Cu")
		(net "FAN2_TACH")
	)
	(segment
		(start 147.204176 -182.219346)
		(end 146.86915 -181.88432)
		(width 0.1143)
		(layer "In6.Cu")
		(net "FAN2_TACH")
	)
	(segment
		(start 108.07827 -179.864004)
		(end 107.685078 -180.257196)
		(width 0.1143)
		(layer "In6.Cu")
		(net "FAN2_TACH")
	)
	(segment
		(start 105.055162 -178.486816)
		(end 103.15448 -176.586134)
		(width 0.1143)
		(layer "In6.Cu")
		(net "FAN2_TACH")
	)
	(segment
		(start 153.434288 -182.662068)
		(end 152.9588 -183.13781)
		(width 0.1143)
		(layer "In6.Cu")
		(net "FAN2_TACH")
	)
	(segment
		(start 138.23696 -179.032916)
		(end 136.826244 -177.6222)
		(width 0.1143)
		(layer "In6.Cu")
		(net "FAN2_TACH")
	)
	(segment
		(start 146.86915 -181.88432)
		(end 145.427192 -181.88432)
		(width 0.1143)
		(layer "In6.Cu")
		(net "FAN2_TACH")
	)
	(segment
		(start 136.826244 -177.6222)
		(end 128.365758 -177.6222)
		(width 0.1143)
		(layer "In6.Cu")
		(net "FAN2_TACH")
	)
	(segment
		(start 96.88322 -168.507156)
		(end 95.167958 -168.507156)
		(width 0.1143)
		(layer "In6.Cu")
		(net "FAN2_TACH")
	)
	(segment
		(start 125.97765 -175.234092)
		(end 124.557282 -175.234092)
		(width 0.1143)
		(layer "In6.Cu")
		(net "FAN2_TACH")
	)
	(segment
		(start 122.351038 -177.440336)
		(end 113.555018 -177.440336)
		(width 0.1143)
		(layer "In6.Cu")
		(net "FAN2_TACH")
	)
	(segment
		(start 98.645472 -168.48836)
		(end 96.902016 -168.48836)
		(width 0.1143)
		(layer "In6.Cu")
		(net "FAN2_TACH")
	)
	(segment
		(start 95.167958 -168.507156)
		(end 94.91472 -168.253918)
		(width 0.1143)
		(layer "In6.Cu")
		(net "FAN2_TACH")
	)
	(segment
		(start 124.557282 -175.234092)
		(end 122.351038 -177.440336)
		(width 0.1143)
		(layer "In6.Cu")
		(net "FAN2_TACH")
	)
	(segment
		(start 148.933154 -182.219346)
		(end 147.204176 -182.219346)
		(width 0.1143)
		(layer "In6.Cu")
		(net "FAN2_TACH")
	)
	(segment
		(start 156.48178 -183.092852)
		(end 155.5496 -183.092852)
		(width 0.1143)
		(layer "In6.Cu")
		(net "FAN2_TACH")
	)
	(segment
		(start 105.551478 -178.486816)
		(end 105.055162 -178.486816)
		(width 0.1143)
		(layer "In6.Cu")
		(net "FAN2_TACH")
	)
	(segment
		(start 145.124424 -182.187088)
		(end 143.235172 -182.187088)
		(width 0.1143)
		(layer "In6.Cu")
		(net "FAN2_TACH")
	)
	(segment
		(start 103.15448 -176.586134)
		(end 103.15448 -172.997368)
		(width 0.1143)
		(layer "In6.Cu")
		(net "FAN2_TACH")
	)
	(segment
		(start 139.502896 -179.032916)
		(end 138.23696 -179.032916)
		(width 0.1143)
		(layer "In6.Cu")
		(net "FAN2_TACH")
	)
	(segment
		(start 140.547598 -180.186076)
		(end 140.547598 -180.077618)
		(width 0.1143)
		(layer "In6.Cu")
		(net "FAN2_TACH")
	)
	(segment
		(start 108.07827 -179.492148)
		(end 108.07827 -179.864004)
		(width 0.1143)
		(layer "In6.Cu")
		(net "FAN2_TACH")
	)
	(segment
		(start 145.427192 -181.88432)
		(end 145.124424 -182.187088)
		(width 0.1143)
		(layer "In6.Cu")
		(net "FAN2_TACH")
	)
	(segment
		(start 143.235172 -182.187088)
		(end 141.4907 -180.442616)
		(width 0.1143)
		(layer "In6.Cu")
		(net "FAN2_TACH")
	)
	(segment
		(start 96.902016 -168.48836)
		(end 96.88322 -168.507156)
		(width 0.1143)
		(layer "In6.Cu")
		(net "FAN2_TACH")
	)
	(segment
		(start 128.365758 -177.6222)
		(end 125.97765 -175.234092)
		(width 0.1143)
		(layer "In6.Cu")
		(net "FAN2_TACH")
	)
	(segment
		(start 141.4907 -180.442616)
		(end 140.804138 -180.442616)
		(width 0.1143)
		(layer "In6.Cu")
		(net "FAN2_TACH")
	)
	(segment
		(start 140.547598 -180.077618)
		(end 139.502896 -179.032916)
		(width 0.1143)
		(layer "In6.Cu")
		(net "FAN2_TACH")
	)
	(segment
		(start 152.9588 -183.13781)
		(end 149.851618 -183.13781)
		(width 0.1143)
		(layer "In6.Cu")
		(net "FAN2_TACH")
	)
	(segment
		(start 111.81588 -179.179474)
		(end 108.390944 -179.179474)
		(width 0.1143)
		(layer "In6.Cu")
		(net "FAN2_TACH")
	)
	(segment
		(start 113.555018 -177.440336)
		(end 111.81588 -179.179474)
		(width 0.1143)
		(layer "In6.Cu")
		(net "FAN2_TACH")
	)
	(segment
		(start 155.5496 -183.092852)
		(end 155.118816 -182.662068)
		(width 0.1143)
		(layer "In6.Cu")
		(net "FAN2_TACH")
	)
	(segment
		(start 107.321858 -180.257196)
		(end 105.551478 -178.486816)
		(width 0.1143)
		(layer "In6.Cu")
		(net "FAN2_TACH")
	)
	(segment
		(start 140.804138 -180.442616)
		(end 140.547598 -180.186076)
		(width 0.1143)
		(layer "In6.Cu")
		(net "FAN2_TACH")
	)
	(segment
		(start 107.685078 -180.257196)
		(end 107.321858 -180.257196)
		(width 0.1143)
		(layer "In6.Cu")
		(net "FAN2_TACH")
	)
	(segment
		(start 155.118816 -182.662068)
		(end 153.434288 -182.662068)
		(width 0.1143)
		(layer "In6.Cu")
		(net "FAN2_TACH")
	)
	(segment
		(start 103.15448 -172.997368)
		(end 98.645472 -168.48836)
		(width 0.1143)
		(layer "In6.Cu")
		(net "FAN2_TACH")
	)
	(segment
		(start 108.390944 -179.179474)
		(end 108.07827 -179.492148)
		(width 0.1143)
		(layer "In6.Cu")
		(net "FAN2_TACH")
	)
	(segment
		(start 149.851618 -183.13781)
		(end 148.933154 -182.219346)
		(width 0.1143)
		(layer "In6.Cu")
		(net "FAN2_TACH")
	)
	(segment
		(start 27.81808 -41.85158)
		(end 29.18968 -43.22318)
		(width 0.1016)
		(layer "F.Cu")
		(net "UART_RTS_P2_L_N")
	)
	(segment
		(start 11.237976 -31.540704)
		(end 14.054328 -34.357056)
		(width 0.1016)
		(layer "F.Cu")
		(net "UART_RTS_P2_L_N")
	)
	(segment
		(start 27.81808 -39.80307)
		(end 27.81808 -41.85158)
		(width 0.1016)
		(layer "F.Cu")
		(net "UART_RTS_P2_L_N")
	)
	(segment
		(start 26.94305 -34.357056)
		(end 29.111702 -36.525708)
		(width 0.1016)
		(layer "F.Cu")
		(net "UART_RTS_P2_L_N")
	)
	(segment
		(start 11.237976 -26.04516)
		(end 11.237976 -31.540704)
		(width 0.1016)
		(layer "F.Cu")
		(net "UART_RTS_P2_L_N")
	)
	(segment
		(start 29.111702 -36.525708)
		(end 29.111702 -38.509448)
		(width 0.1016)
		(layer "F.Cu")
		(net "UART_RTS_P2_L_N")
	)
	(segment
		(start 29.111702 -38.509448)
		(end 27.81808 -39.80307)
		(width 0.1016)
		(layer "F.Cu")
		(net "UART_RTS_P2_L_N")
	)
	(segment
		(start 14.054328 -34.357056)
		(end 26.94305 -34.357056)
		(width 0.1016)
		(layer "F.Cu")
		(net "UART_RTS_P2_L_N")
	)
	(segment
		(start 29.18968 -43.22318)
		(end 29.18968 -45.486828)
		(width 0.1016)
		(layer "F.Cu")
		(net "UART_RTS_P2_L_N")
	)
	(via
		(at 35.47872 -199.287384)
		(size 0.508)
		(drill 0.254)
		(layers "F.Cu" "B.Cu")
		(net "UART_RTS_P2_L_N")
	)
	(via
		(at 29.18968 -45.486828)
		(size 0.508)
		(drill 0.254)
		(layers "F.Cu" "B.Cu")
		(net "UART_RTS_P2_L_N")
	)
	(segment
		(start 35.47872 -199.450452)
		(end 35.014916 -199.914256)
		(width 0.1016)
		(layer "B.Cu")
		(net "UART_RTS_P2_L_N")
	)
	(segment
		(start 35.47872 -199.287384)
		(end 35.47872 -199.450452)
		(width 0.1016)
		(layer "B.Cu")
		(net "UART_RTS_P2_L_N")
	)
	(segment
		(start 35.014916 -199.914256)
		(end 35.014916 -205.199488)
		(width 0.1016)
		(layer "B.Cu")
		(net "UART_RTS_P2_L_N")
	)
	(segment
		(start 30.286198 -46.583346)
		(end 30.286198 -80.213454)
		(width 0.1143)
		(layer "In2.Cu")
		(net "UART_RTS_P2_L_N")
	)
	(segment
		(start 10.82929 -104.883712)
		(end 10.82929 -112.647222)
		(width 0.1143)
		(layer "In2.Cu")
		(net "UART_RTS_P2_L_N")
	)
	(segment
		(start 19.46656 -168.768522)
		(end 19.46656 -182.225442)
		(width 0.1143)
		(layer "In2.Cu")
		(net "UART_RTS_P2_L_N")
	)
	(segment
		(start 29.18968 -45.486828)
		(end 30.286198 -46.583346)
		(width 0.1143)
		(layer "In2.Cu")
		(net "UART_RTS_P2_L_N")
	)
	(segment
		(start 11.742928 -150.713186)
		(end 11.742928 -155.35783)
		(width 0.1143)
		(layer "In2.Cu")
		(net "UART_RTS_P2_L_N")
	)
	(segment
		(start 22.20722 -93.74759)
		(end 17.57172 -98.38309)
		(width 0.1143)
		(layer "In2.Cu")
		(net "UART_RTS_P2_L_N")
	)
	(segment
		(start 11.641328 -150.611586)
		(end 11.742928 -150.713186)
		(width 0.1143)
		(layer "In2.Cu")
		(net "UART_RTS_P2_L_N")
	)
	(segment
		(start 11.35761 -113.175542)
		(end 11.35761 -134.40156)
		(width 0.1143)
		(layer "In2.Cu")
		(net "UART_RTS_P2_L_N")
	)
	(segment
		(start 13.1826 -162.484562)
		(end 19.46656 -168.768522)
		(width 0.1143)
		(layer "In2.Cu")
		(net "UART_RTS_P2_L_N")
	)
	(segment
		(start 10.93597 -156.164788)
		(end 10.93597 -161.019998)
		(width 0.1143)
		(layer "In2.Cu")
		(net "UART_RTS_P2_L_N")
	)
	(segment
		(start 11.35761 -134.40156)
		(end 12.79271 -135.83666)
		(width 0.1143)
		(layer "In2.Cu")
		(net "UART_RTS_P2_L_N")
	)
	(segment
		(start 11.939016 -104.329992)
		(end 11.38301 -104.329992)
		(width 0.1143)
		(layer "In2.Cu")
		(net "UART_RTS_P2_L_N")
	)
	(segment
		(start 17.57172 -98.697288)
		(end 11.939016 -104.329992)
		(width 0.1143)
		(layer "In2.Cu")
		(net "UART_RTS_P2_L_N")
	)
	(segment
		(start 12.1158 -138.717782)
		(end 12.1158 -143.364204)
		(width 0.1143)
		(layer "In2.Cu")
		(net "UART_RTS_P2_L_N")
	)
	(segment
		(start 10.82929 -112.647222)
		(end 11.35761 -113.175542)
		(width 0.1143)
		(layer "In2.Cu")
		(net "UART_RTS_P2_L_N")
	)
	(segment
		(start 31.711392 -194.470274)
		(end 32.827468 -194.470274)
		(width 0.1143)
		(layer "In2.Cu")
		(net "UART_RTS_P2_L_N")
	)
	(segment
		(start 12.79271 -135.83666)
		(end 12.79271 -138.040872)
		(width 0.1143)
		(layer "In2.Cu")
		(net "UART_RTS_P2_L_N")
	)
	(segment
		(start 17.57172 -98.38309)
		(end 17.57172 -98.697288)
		(width 0.1143)
		(layer "In2.Cu")
		(net "UART_RTS_P2_L_N")
	)
	(segment
		(start 35.89655 -198.869554)
		(end 35.47872 -199.287384)
		(width 0.1143)
		(layer "In2.Cu")
		(net "UART_RTS_P2_L_N")
	)
	(segment
		(start 12.1158 -143.364204)
		(end 11.641328 -143.838676)
		(width 0.1143)
		(layer "In2.Cu")
		(net "UART_RTS_P2_L_N")
	)
	(segment
		(start 22.20722 -88.292432)
		(end 22.20722 -93.74759)
		(width 0.1143)
		(layer "In2.Cu")
		(net "UART_RTS_P2_L_N")
	)
	(segment
		(start 10.93597 -161.019998)
		(end 12.400534 -162.484562)
		(width 0.1143)
		(layer "In2.Cu")
		(net "UART_RTS_P2_L_N")
	)
	(segment
		(start 11.641328 -143.838676)
		(end 11.641328 -150.611586)
		(width 0.1143)
		(layer "In2.Cu")
		(net "UART_RTS_P2_L_N")
	)
	(segment
		(start 19.46656 -182.225442)
		(end 31.711392 -194.470274)
		(width 0.1143)
		(layer "In2.Cu")
		(net "UART_RTS_P2_L_N")
	)
	(segment
		(start 11.742928 -155.35783)
		(end 10.93597 -156.164788)
		(width 0.1143)
		(layer "In2.Cu")
		(net "UART_RTS_P2_L_N")
	)
	(segment
		(start 12.79271 -138.040872)
		(end 12.1158 -138.717782)
		(width 0.1143)
		(layer "In2.Cu")
		(net "UART_RTS_P2_L_N")
	)
	(segment
		(start 35.89655 -197.539356)
		(end 35.89655 -198.869554)
		(width 0.1143)
		(layer "In2.Cu")
		(net "UART_RTS_P2_L_N")
	)
	(segment
		(start 30.286198 -80.213454)
		(end 22.20722 -88.292432)
		(width 0.1143)
		(layer "In2.Cu")
		(net "UART_RTS_P2_L_N")
	)
	(segment
		(start 11.38301 -104.329992)
		(end 10.82929 -104.883712)
		(width 0.1143)
		(layer "In2.Cu")
		(net "UART_RTS_P2_L_N")
	)
	(segment
		(start 12.400534 -162.484562)
		(end 13.1826 -162.484562)
		(width 0.1143)
		(layer "In2.Cu")
		(net "UART_RTS_P2_L_N")
	)
	(segment
		(start 32.827468 -194.470274)
		(end 35.89655 -197.539356)
		(width 0.1143)
		(layer "In2.Cu")
		(net "UART_RTS_P2_L_N")
	)
	(segment
		(start 26.94686 -39.810944)
		(end 26.94686 -42.57421)
		(width 0.1016)
		(layer "F.Cu")
		(net "UART_DTR_P2_L_N")
	)
	(segment
		(start 28.502102 -36.778692)
		(end 28.502102 -38.255702)
		(width 0.1016)
		(layer "F.Cu")
		(net "UART_DTR_P2_L_N")
	)
	(segment
		(start 26.812494 -35.089084)
		(end 28.502102 -36.778692)
		(width 0.1016)
		(layer "F.Cu")
		(net "UART_DTR_P2_L_N")
	)
	(segment
		(start 9.938004 -31.309564)
		(end 13.717524 -35.089084)
		(width 0.1016)
		(layer "F.Cu")
		(net "UART_DTR_P2_L_N")
	)
	(segment
		(start 28.502102 -38.255702)
		(end 26.94686 -39.810944)
		(width 0.1016)
		(layer "F.Cu")
		(net "UART_DTR_P2_L_N")
	)
	(segment
		(start 13.717524 -35.089084)
		(end 26.812494 -35.089084)
		(width 0.1016)
		(layer "F.Cu")
		(net "UART_DTR_P2_L_N")
	)
	(segment
		(start 9.938004 -26.04516)
		(end 9.938004 -31.309564)
		(width 0.1016)
		(layer "F.Cu")
		(net "UART_DTR_P2_L_N")
	)
	(via
		(at 31.17088 -199.402954)
		(size 0.508)
		(drill 0.254)
		(layers "F.Cu" "B.Cu")
		(net "UART_DTR_P2_L_N")
	)
	(via
		(at 26.94686 -42.57421)
		(size 0.508)
		(drill 0.254)
		(layers "F.Cu" "B.Cu")
		(net "UART_DTR_P2_L_N")
	)
	(segment
		(start 31.165038 -199.402954)
		(end 31.014924 -199.553068)
		(width 0.1016)
		(layer "B.Cu")
		(net "UART_DTR_P2_L_N")
	)
	(segment
		(start 31.17088 -199.402954)
		(end 31.165038 -199.402954)
		(width 0.1016)
		(layer "B.Cu")
		(net "UART_DTR_P2_L_N")
	)
	(segment
		(start 31.014924 -199.553068)
		(end 31.014924 -205.199488)
		(width 0.1016)
		(layer "B.Cu")
		(net "UART_DTR_P2_L_N")
	)
	(segment
		(start 26.55824 -57.937908)
		(end 25.54986 -58.946288)
		(width 0.1143)
		(layer "In2.Cu")
		(net "UART_DTR_P2_L_N")
	)
	(segment
		(start 10.58164 -165.673278)
		(end 11.326368 -166.418006)
		(width 0.1143)
		(layer "In2.Cu")
		(net "UART_DTR_P2_L_N")
	)
	(segment
		(start 6.630924 -150.885398)
		(end 6.630924 -151.77897)
		(width 0.1143)
		(layer "In2.Cu")
		(net "UART_DTR_P2_L_N")
	)
	(segment
		(start 7.38759 -147.09648)
		(end 6.384798 -148.099272)
		(width 0.1143)
		(layer "In2.Cu")
		(net "UART_DTR_P2_L_N")
	)
	(segment
		(start 30.755844 -197.587362)
		(end 31.17088 -198.002398)
		(width 0.1143)
		(layer "In2.Cu")
		(net "UART_DTR_P2_L_N")
	)
	(segment
		(start 6.630924 -151.77897)
		(end 6.40334 -152.006554)
		(width 0.1143)
		(layer "In2.Cu")
		(net "UART_DTR_P2_L_N")
	)
	(segment
		(start 6.384798 -150.639272)
		(end 6.630924 -150.885398)
		(width 0.1143)
		(layer "In2.Cu")
		(net "UART_DTR_P2_L_N")
	)
	(segment
		(start 26.94686 -43.278298)
		(end 26.27249 -43.952668)
		(width 0.1143)
		(layer "In2.Cu")
		(net "UART_DTR_P2_L_N")
	)
	(segment
		(start 12.41298 -99.024186)
		(end 7.96036 -103.476806)
		(width 0.1143)
		(layer "In2.Cu")
		(net "UART_DTR_P2_L_N")
	)
	(segment
		(start 23.936198 -64.82969)
		(end 25.06345 -65.956942)
		(width 0.1143)
		(layer "In2.Cu")
		(net "UART_DTR_P2_L_N")
	)
	(segment
		(start 16.88084 -170.821858)
		(end 16.88084 -184.655206)
		(width 0.1143)
		(layer "In2.Cu")
		(net "UART_DTR_P2_L_N")
	)
	(segment
		(start 25.54986 -58.946288)
		(end 25.54986 -60.153042)
		(width 0.1143)
		(layer "In2.Cu")
		(net "UART_DTR_P2_L_N")
	)
	(segment
		(start 25.06345 -65.956942)
		(end 25.06345 -81.771744)
		(width 0.1143)
		(layer "In2.Cu")
		(net "UART_DTR_P2_L_N")
	)
	(segment
		(start 26.27249 -43.952668)
		(end 26.27249 -55.384446)
		(width 0.1143)
		(layer "In2.Cu")
		(net "UART_DTR_P2_L_N")
	)
	(segment
		(start 10.58164 -165.10127)
		(end 10.58164 -165.673278)
		(width 0.1143)
		(layer "In2.Cu")
		(net "UART_DTR_P2_L_N")
	)
	(segment
		(start 29.812996 -197.587362)
		(end 30.755844 -197.587362)
		(width 0.1143)
		(layer "In2.Cu")
		(net "UART_DTR_P2_L_N")
	)
	(segment
		(start 19.61642 -92.4687)
		(end 13.83792 -98.2472)
		(width 0.1143)
		(layer "In2.Cu")
		(net "UART_DTR_P2_L_N")
	)
	(segment
		(start 12.476988 -166.418006)
		(end 16.88084 -170.821858)
		(width 0.1143)
		(layer "In2.Cu")
		(net "UART_DTR_P2_L_N")
	)
	(segment
		(start 7.96036 -103.476806)
		(end 7.96036 -120.193816)
		(width 0.1143)
		(layer "In2.Cu")
		(net "UART_DTR_P2_L_N")
	)
	(segment
		(start 19.61642 -87.218774)
		(end 19.61642 -92.4687)
		(width 0.1143)
		(layer "In2.Cu")
		(net "UART_DTR_P2_L_N")
	)
	(segment
		(start 6.384798 -148.099272)
		(end 6.384798 -150.639272)
		(width 0.1143)
		(layer "In2.Cu")
		(net "UART_DTR_P2_L_N")
	)
	(segment
		(start 26.94686 -42.57421)
		(end 26.94686 -43.278298)
		(width 0.1143)
		(layer "In2.Cu")
		(net "UART_DTR_P2_L_N")
	)
	(segment
		(start 16.88084 -184.655206)
		(end 29.812996 -197.587362)
		(width 0.1143)
		(layer "In2.Cu")
		(net "UART_DTR_P2_L_N")
	)
	(segment
		(start 26.55824 -55.670196)
		(end 26.55824 -57.937908)
		(width 0.1143)
		(layer "In2.Cu")
		(net "UART_DTR_P2_L_N")
	)
	(segment
		(start 23.936198 -61.766704)
		(end 23.936198 -64.82969)
		(width 0.1143)
		(layer "In2.Cu")
		(net "UART_DTR_P2_L_N")
	)
	(segment
		(start 25.06345 -81.771744)
		(end 19.61642 -87.218774)
		(width 0.1143)
		(layer "In2.Cu")
		(net "UART_DTR_P2_L_N")
	)
	(segment
		(start 13.83792 -98.2472)
		(end 13.3858 -98.2472)
		(width 0.1143)
		(layer "In2.Cu")
		(net "UART_DTR_P2_L_N")
	)
	(segment
		(start 7.352538 -120.801638)
		(end 7.352538 -140.199618)
		(width 0.1143)
		(layer "In2.Cu")
		(net "UART_DTR_P2_L_N")
	)
	(segment
		(start 11.326368 -166.418006)
		(end 12.476988 -166.418006)
		(width 0.1143)
		(layer "In2.Cu")
		(net "UART_DTR_P2_L_N")
	)
	(segment
		(start 7.38759 -140.23467)
		(end 7.38759 -147.09648)
		(width 0.1143)
		(layer "In2.Cu")
		(net "UART_DTR_P2_L_N")
	)
	(segment
		(start 12.608814 -99.024186)
		(end 12.41298 -99.024186)
		(width 0.1143)
		(layer "In2.Cu")
		(net "UART_DTR_P2_L_N")
	)
	(segment
		(start 6.40334 -152.006554)
		(end 6.40334 -160.92297)
		(width 0.1143)
		(layer "In2.Cu")
		(net "UART_DTR_P2_L_N")
	)
	(segment
		(start 25.54986 -60.153042)
		(end 23.936198 -61.766704)
		(width 0.1143)
		(layer "In2.Cu")
		(net "UART_DTR_P2_L_N")
	)
	(segment
		(start 26.27249 -55.384446)
		(end 26.55824 -55.670196)
		(width 0.1143)
		(layer "In2.Cu")
		(net "UART_DTR_P2_L_N")
	)
	(segment
		(start 13.3858 -98.2472)
		(end 12.608814 -99.024186)
		(width 0.1143)
		(layer "In2.Cu")
		(net "UART_DTR_P2_L_N")
	)
	(segment
		(start 6.40334 -160.92297)
		(end 10.58164 -165.10127)
		(width 0.1143)
		(layer "In2.Cu")
		(net "UART_DTR_P2_L_N")
	)
	(segment
		(start 31.17088 -198.002398)
		(end 31.17088 -199.402954)
		(width 0.1143)
		(layer "In2.Cu")
		(net "UART_DTR_P2_L_N")
	)
	(segment
		(start 7.96036 -120.193816)
		(end 7.352538 -120.801638)
		(width 0.1143)
		(layer "In2.Cu")
		(net "UART_DTR_P2_L_N")
	)
	(segment
		(start 7.352538 -140.199618)
		(end 7.38759 -140.23467)
		(width 0.1143)
		(layer "In2.Cu")
		(net "UART_DTR_P2_L_N")
	)
	(segment
		(start 46.817534 -149.591776)
		(end 46.81728 -149.591776)
		(width 0.1016)
		(layer "F.Cu")
		(net "SPI_LAN1_NVM_SK")
	)
	(segment
		(start 46.81728 -149.591776)
		(end 46.81728 -147.896072)
		(width 0.1016)
		(layer "F.Cu")
		(net "SPI_LAN1_NVM_SK")
	)
	(segment
		(start 51.823112 -145.514822)
		(end 50.22342 -145.514822)
		(width 0.1016)
		(layer "F.Cu")
		(net "SPI_LAN1_NVM_SK")
	)
	(segment
		(start 46.817534 -150.37308)
		(end 46.817534 -149.591776)
		(width 0.1016)
		(layer "F.Cu")
		(net "SPI_LAN1_NVM_SK")
	)
	(segment
		(start 46.81728 -147.896072)
		(end 49.19853 -145.514822)
		(width 0.1016)
		(layer "F.Cu")
		(net "SPI_LAN1_NVM_SK")
	)
	(segment
		(start 49.19853 -145.514822)
		(end 50.22342 -145.514822)
		(width 0.1016)
		(layer "F.Cu")
		(net "SPI_LAN1_NVM_SK")
	)
	(via
		(at 50.22342 -145.514822)
		(size 0.508)
		(drill 0.254)
		(layers "F.Cu" "B.Cu")
		(net "SPI_LAN1_NVM_SK")
	)
	(segment
		(start 27.40914 -44.25188)
		(end 27.11704 -44.54398)
		(width 0.1016)
		(layer "F.Cu")
		(net "UART_TX_P2_L")
	)
	(segment
		(start 27.40914 -39.780464)
		(end 27.40914 -44.25188)
		(width 0.1016)
		(layer "F.Cu")
		(net "UART_TX_P2_L")
	)
	(segment
		(start 26.846276 -34.691574)
		(end 28.806902 -36.6522)
		(width 0.1016)
		(layer "F.Cu")
		(net "UART_TX_P2_L")
	)
	(segment
		(start 28.806902 -36.6522)
		(end 28.806902 -38.382702)
		(width 0.1016)
		(layer "F.Cu")
		(net "UART_TX_P2_L")
	)
	(segment
		(start 10.58799 -31.462218)
		(end 13.817346 -34.691574)
		(width 0.1016)
		(layer "F.Cu")
		(net "UART_TX_P2_L")
	)
	(segment
		(start 10.58799 -26.04516)
		(end 10.58799 -31.462218)
		(width 0.1016)
		(layer "F.Cu")
		(net "UART_TX_P2_L")
	)
	(segment
		(start 13.817346 -34.691574)
		(end 26.846276 -34.691574)
		(width 0.1016)
		(layer "F.Cu")
		(net "UART_TX_P2_L")
	)
	(segment
		(start 28.806902 -38.382702)
		(end 27.40914 -39.780464)
		(width 0.1016)
		(layer "F.Cu")
		(net "UART_TX_P2_L")
	)
	(via
		(at 27.11704 -44.54398)
		(size 0.508)
		(drill 0.254)
		(layers "F.Cu" "B.Cu")
		(net "UART_TX_P2_L")
	)
	(via
		(at 32.33166 -198.623428)
		(size 0.508)
		(drill 0.254)
		(layers "F.Cu" "B.Cu")
		(net "UART_TX_P2_L")
	)
	(segment
		(start 32.33166 -198.623428)
		(end 32.54756 -198.839328)
		(width 0.1016)
		(layer "B.Cu")
		(net "UART_TX_P2_L")
	)
	(segment
		(start 32.54756 -198.839328)
		(end 32.54756 -199.770238)
		(width 0.1016)
		(layer "B.Cu")
		(net "UART_TX_P2_L")
	)
	(segment
		(start 32.54756 -199.770238)
		(end 32.014922 -200.302876)
		(width 0.1016)
		(layer "B.Cu")
		(net "UART_TX_P2_L")
	)
	(segment
		(start 32.014922 -200.302876)
		(end 32.014922 -205.199488)
		(width 0.1016)
		(layer "B.Cu")
		(net "UART_TX_P2_L")
	)
	(segment
		(start 8.23341 -139.389358)
		(end 8.23341 -120.902984)
		(width 0.1143)
		(layer "In2.Cu")
		(net "UART_TX_P2_L")
	)
	(segment
		(start 28.381198 -79.352902)
		(end 28.381198 -54.246272)
		(width 0.1143)
		(layer "In2.Cu")
		(net "UART_TX_P2_L")
	)
	(segment
		(start 20.27682 -87.458042)
		(end 20.39112 -87.343742)
		(width 0.1143)
		(layer "In2.Cu")
		(net "UART_TX_P2_L")
	)
	(segment
		(start 17.51584 -170.558206)
		(end 7.370826 -160.413192)
		(width 0.1143)
		(layer "In2.Cu")
		(net "UART_TX_P2_L")
	)
	(segment
		(start 20.39112 -87.343742)
		(end 20.39112 -87.34298)
		(width 0.1143)
		(layer "In2.Cu")
		(net "UART_TX_P2_L")
	)
	(segment
		(start 8.5979 -103.73741)
		(end 12.676124 -99.659186)
		(width 0.1143)
		(layer "In2.Cu")
		(net "UART_TX_P2_L")
	)
	(segment
		(start 12.9159 -99.659186)
		(end 13.692886 -98.8822)
		(width 0.1143)
		(layer "In2.Cu")
		(net "UART_TX_P2_L")
	)
	(segment
		(start 20.27682 -92.707968)
		(end 20.27682 -87.458042)
		(width 0.1143)
		(layer "In2.Cu")
		(net "UART_TX_P2_L")
	)
	(segment
		(start 7.62 -155.629102)
		(end 7.62 -147.76577)
		(width 0.1143)
		(layer "In2.Cu")
		(net "UART_TX_P2_L")
	)
	(segment
		(start 7.62 -147.76577)
		(end 8.878824 -146.506946)
		(width 0.1143)
		(layer "In2.Cu")
		(net "UART_TX_P2_L")
	)
	(segment
		(start 29.785564 -196.661786)
		(end 17.51584 -184.392062)
		(width 0.1143)
		(layer "In2.Cu")
		(net "UART_TX_P2_L")
	)
	(segment
		(start 17.51584 -184.392062)
		(end 17.51584 -170.558206)
		(width 0.1143)
		(layer "In2.Cu")
		(net "UART_TX_P2_L")
	)
	(segment
		(start 26.90749 -52.772564)
		(end 26.90749 -44.75353)
		(width 0.1143)
		(layer "In2.Cu")
		(net "UART_TX_P2_L")
	)
	(segment
		(start 8.5979 -120.538494)
		(end 8.5979 -103.73741)
		(width 0.1143)
		(layer "In2.Cu")
		(net "UART_TX_P2_L")
	)
	(segment
		(start 8.878824 -146.506946)
		(end 8.878824 -140.034772)
		(width 0.1143)
		(layer "In2.Cu")
		(net "UART_TX_P2_L")
	)
	(segment
		(start 20.39112 -87.34298)
		(end 28.381198 -79.352902)
		(width 0.1143)
		(layer "In2.Cu")
		(net "UART_TX_P2_L")
	)
	(segment
		(start 28.381198 -54.246272)
		(end 26.90749 -52.772564)
		(width 0.1143)
		(layer "In2.Cu")
		(net "UART_TX_P2_L")
	)
	(segment
		(start 32.33166 -198.623428)
		(end 32.33166 -197.282816)
		(width 0.1143)
		(layer "In2.Cu")
		(net "UART_TX_P2_L")
	)
	(segment
		(start 7.370826 -160.413192)
		(end 7.370826 -155.878276)
		(width 0.1143)
		(layer "In2.Cu")
		(net "UART_TX_P2_L")
	)
	(segment
		(start 31.71063 -196.661786)
		(end 29.785564 -196.661786)
		(width 0.1143)
		(layer "In2.Cu")
		(net "UART_TX_P2_L")
	)
	(segment
		(start 8.878824 -140.034772)
		(end 8.23341 -139.389358)
		(width 0.1143)
		(layer "In2.Cu")
		(net "UART_TX_P2_L")
	)
	(segment
		(start 32.33166 -197.282816)
		(end 31.71063 -196.661786)
		(width 0.1143)
		(layer "In2.Cu")
		(net "UART_TX_P2_L")
	)
	(segment
		(start 13.692886 -98.8822)
		(end 14.102588 -98.8822)
		(width 0.1143)
		(layer "In2.Cu")
		(net "UART_TX_P2_L")
	)
	(segment
		(start 7.370826 -155.878276)
		(end 7.62 -155.629102)
		(width 0.1143)
		(layer "In2.Cu")
		(net "UART_TX_P2_L")
	)
	(segment
		(start 8.23341 -120.902984)
		(end 8.5979 -120.538494)
		(width 0.1143)
		(layer "In2.Cu")
		(net "UART_TX_P2_L")
	)
	(segment
		(start 26.90749 -44.75353)
		(end 27.11704 -44.54398)
		(width 0.1143)
		(layer "In2.Cu")
		(net "UART_TX_P2_L")
	)
	(segment
		(start 14.102588 -98.8822)
		(end 20.27682 -92.707968)
		(width 0.1143)
		(layer "In2.Cu")
		(net "UART_TX_P2_L")
	)
	(segment
		(start 12.676124 -99.659186)
		(end 12.9159 -99.659186)
		(width 0.1143)
		(layer "In2.Cu")
		(net "UART_TX_P2_L")
	)
	(segment
		(start 49.442624 -146.52879)
		(end 51.18354 -146.52879)
		(width 0.1016)
		(layer "F.Cu")
		(net "SPI_LAN1_NVM_SO")
	)
	(segment
		(start 51.5493 -146.52879)
		(end 51.18354 -146.52879)
		(width 0.1016)
		(layer "F.Cu")
		(net "SPI_LAN1_NVM_SO")
	)
	(segment
		(start 47.31766 -150.37308)
		(end 47.31766 -148.653754)
		(width 0.1016)
		(layer "F.Cu")
		(net "SPI_LAN1_NVM_SO")
	)
	(segment
		(start 51.551332 -146.530822)
		(end 51.5493 -146.52879)
		(width 0.1016)
		(layer "F.Cu")
		(net "SPI_LAN1_NVM_SO")
	)
	(segment
		(start 51.823112 -146.530822)
		(end 51.551332 -146.530822)
		(width 0.1016)
		(layer "F.Cu")
		(net "SPI_LAN1_NVM_SO")
	)
	(segment
		(start 47.31766 -148.653754)
		(end 49.442624 -146.52879)
		(width 0.1016)
		(layer "F.Cu")
		(net "SPI_LAN1_NVM_SO")
	)
	(via
		(at 51.18354 -146.52879)
		(size 0.508)
		(drill 0.254)
		(layers "F.Cu" "B.Cu")
		(net "SPI_LAN1_NVM_SO")
	)
	(segment
		(start 29.721302 -36.272724)
		(end 29.721302 -46.19752)
		(width 0.1016)
		(layer "F.Cu")
		(net "UART_DSR_P2_L_N")
	)
	(segment
		(start 13.030962 -28.320492)
		(end 13.030962 -31.548324)
		(width 0.1016)
		(layer "F.Cu")
		(net "UART_DSR_P2_L_N")
	)
	(segment
		(start 13.838174 -26.04516)
		(end 13.838174 -27.51328)
		(width 0.1016)
		(layer "F.Cu")
		(net "UART_DSR_P2_L_N")
	)
	(segment
		(start 13.030962 -31.548324)
		(end 15.031212 -33.548574)
		(width 0.1016)
		(layer "F.Cu")
		(net "UART_DSR_P2_L_N")
	)
	(segment
		(start 29.721302 -46.19752)
		(end 28.58262 -47.336202)
		(width 0.1016)
		(layer "F.Cu")
		(net "UART_DSR_P2_L_N")
	)
	(segment
		(start 26.997152 -33.548574)
		(end 29.721302 -36.272724)
		(width 0.1016)
		(layer "F.Cu")
		(net "UART_DSR_P2_L_N")
	)
	(segment
		(start 15.031212 -33.548574)
		(end 26.997152 -33.548574)
		(width 0.1016)
		(layer "F.Cu")
		(net "UART_DSR_P2_L_N")
	)
	(segment
		(start 13.838174 -27.51328)
		(end 13.030962 -28.320492)
		(width 0.1016)
		(layer "F.Cu")
		(net "UART_DSR_P2_L_N")
	)
	(via
		(at 28.58262 -47.336202)
		(size 0.508)
		(drill 0.254)
		(layers "F.Cu" "B.Cu")
		(net "UART_DSR_P2_L_N")
	)
	(via
		(at 34.44494 -199.268334)
		(size 0.508)
		(drill 0.254)
		(layers "F.Cu" "B.Cu")
		(net "UART_DSR_P2_L_N")
	)
	(segment
		(start 34.014918 -205.199488)
		(end 34.014918 -199.698356)
		(width 0.1016)
		(layer "B.Cu")
		(net "UART_DSR_P2_L_N")
	)
	(segment
		(start 34.014918 -199.698356)
		(end 34.44494 -199.268334)
		(width 0.1016)
		(layer "B.Cu")
		(net "UART_DSR_P2_L_N")
	)
	(segment
		(start 34.90976 -197.621398)
		(end 32.568642 -195.28028)
		(width 0.1143)
		(layer "In2.Cu")
		(net "UART_DSR_P2_L_N")
	)
	(segment
		(start 14.845792 -165.2905)
		(end 13.551154 -163.995862)
		(width 0.1143)
		(layer "In2.Cu")
		(net "UART_DSR_P2_L_N")
	)
	(segment
		(start 32.568642 -195.28028)
		(end 30.640782 -195.28028)
		(width 0.1143)
		(layer "In2.Cu")
		(net "UART_DSR_P2_L_N")
	)
	(segment
		(start 16.93672 -98.434144)
		(end 16.93672 -98.0059)
		(width 0.1143)
		(layer "In2.Cu")
		(net "UART_DSR_P2_L_N")
	)
	(segment
		(start 10.72261 -134.91972)
		(end 10.72261 -113.96091)
		(width 0.1143)
		(layer "In2.Cu")
		(net "UART_DSR_P2_L_N")
	)
	(segment
		(start 10.19429 -104.620568)
		(end 11.521186 -103.293672)
		(width 0.1143)
		(layer "In2.Cu")
		(net "UART_DSR_P2_L_N")
	)
	(segment
		(start 10.06856 -154.258772)
		(end 9.55929 -153.749502)
		(width 0.1143)
		(layer "In2.Cu")
		(net "UART_DSR_P2_L_N")
	)
	(segment
		(start 11.521186 -103.293672)
		(end 12.077192 -103.293672)
		(width 0.1143)
		(layer "In2.Cu")
		(net "UART_DSR_P2_L_N")
	)
	(segment
		(start 11.00582 -146.333464)
		(end 11.00582 -143.132302)
		(width 0.1143)
		(layer "In2.Cu")
		(net "UART_DSR_P2_L_N")
	)
	(segment
		(start 29.651198 -79.95031)
		(end 29.651198 -53.447442)
		(width 0.1143)
		(layer "In2.Cu")
		(net "UART_DSR_P2_L_N")
	)
	(segment
		(start 21.57222 -93.3704)
		(end 21.57222 -88.029288)
		(width 0.1143)
		(layer "In2.Cu")
		(net "UART_DSR_P2_L_N")
	)
	(segment
		(start 14.845792 -166.080948)
		(end 14.845792 -165.2905)
		(width 0.1143)
		(layer "In2.Cu")
		(net "UART_DSR_P2_L_N")
	)
	(segment
		(start 12.077192 -103.293672)
		(end 16.93672 -98.434144)
		(width 0.1143)
		(layer "In2.Cu")
		(net "UART_DSR_P2_L_N")
	)
	(segment
		(start 18.83156 -183.471058)
		(end 18.83156 -170.066716)
		(width 0.1143)
		(layer "In2.Cu")
		(net "UART_DSR_P2_L_N")
	)
	(segment
		(start 12.15771 -136.35482)
		(end 10.72261 -134.91972)
		(width 0.1143)
		(layer "In2.Cu")
		(net "UART_DSR_P2_L_N")
	)
	(segment
		(start 34.90976 -198.803514)
		(end 34.90976 -197.621398)
		(width 0.1143)
		(layer "In2.Cu")
		(net "UART_DSR_P2_L_N")
	)
	(segment
		(start 11.478768 -138.4554)
		(end 12.15771 -137.776458)
		(width 0.1143)
		(layer "In2.Cu")
		(net "UART_DSR_P2_L_N")
	)
	(segment
		(start 10.19429 -113.43259)
		(end 10.19429 -104.620568)
		(width 0.1143)
		(layer "In2.Cu")
		(net "UART_DSR_P2_L_N")
	)
	(segment
		(start 30.640782 -195.28028)
		(end 18.83156 -183.471058)
		(width 0.1143)
		(layer "In2.Cu")
		(net "UART_DSR_P2_L_N")
	)
	(segment
		(start 28.58262 -52.378864)
		(end 28.58262 -47.336202)
		(width 0.1143)
		(layer "In2.Cu")
		(net "UART_DSR_P2_L_N")
	)
	(segment
		(start 18.83156 -170.066716)
		(end 14.845792 -166.080948)
		(width 0.1143)
		(layer "In2.Cu")
		(net "UART_DSR_P2_L_N")
	)
	(segment
		(start 16.93672 -98.0059)
		(end 21.57222 -93.3704)
		(width 0.1143)
		(layer "In2.Cu")
		(net "UART_DSR_P2_L_N")
	)
	(segment
		(start 9.55929 -153.749502)
		(end 9.55929 -147.779994)
		(width 0.1143)
		(layer "In2.Cu")
		(net "UART_DSR_P2_L_N")
	)
	(segment
		(start 29.651198 -53.447442)
		(end 28.58262 -52.378864)
		(width 0.1143)
		(layer "In2.Cu")
		(net "UART_DSR_P2_L_N")
	)
	(segment
		(start 10.06856 -161.28238)
		(end 10.06856 -154.258772)
		(width 0.1143)
		(layer "In2.Cu")
		(net "UART_DSR_P2_L_N")
	)
	(segment
		(start 9.55929 -147.779994)
		(end 11.00582 -146.333464)
		(width 0.1143)
		(layer "In2.Cu")
		(net "UART_DSR_P2_L_N")
	)
	(segment
		(start 10.72261 -113.96091)
		(end 10.19429 -113.43259)
		(width 0.1143)
		(layer "In2.Cu")
		(net "UART_DSR_P2_L_N")
	)
	(segment
		(start 13.551154 -163.995862)
		(end 12.782042 -163.995862)
		(width 0.1143)
		(layer "In2.Cu")
		(net "UART_DSR_P2_L_N")
	)
	(segment
		(start 21.57222 -88.029288)
		(end 29.651198 -79.95031)
		(width 0.1143)
		(layer "In2.Cu")
		(net "UART_DSR_P2_L_N")
	)
	(segment
		(start 12.15771 -137.776458)
		(end 12.15771 -136.35482)
		(width 0.1143)
		(layer "In2.Cu")
		(net "UART_DSR_P2_L_N")
	)
	(segment
		(start 11.00582 -143.132302)
		(end 11.478768 -142.659354)
		(width 0.1143)
		(layer "In2.Cu")
		(net "UART_DSR_P2_L_N")
	)
	(segment
		(start 11.478768 -142.659354)
		(end 11.478768 -138.4554)
		(width 0.1143)
		(layer "In2.Cu")
		(net "UART_DSR_P2_L_N")
	)
	(segment
		(start 34.44494 -199.268334)
		(end 34.90976 -198.803514)
		(width 0.1143)
		(layer "In2.Cu")
		(net "UART_DSR_P2_L_N")
	)
	(segment
		(start 12.782042 -163.995862)
		(end 10.06856 -161.28238)
		(width 0.1143)
		(layer "In2.Cu")
		(net "UART_DSR_P2_L_N")
	)
	(segment
		(start 27.09291 -33.21304)
		(end 30.026102 -36.146232)
		(width 0.1016)
		(layer "F.Cu")
		(net "UART_RX_P2_L")
	)
	(segment
		(start 15.12697 -33.21304)
		(end 27.09291 -33.21304)
		(width 0.1016)
		(layer "F.Cu")
		(net "UART_RX_P2_L")
	)
	(segment
		(start 13.335762 -28.538678)
		(end 13.335762 -31.421832)
		(width 0.1016)
		(layer "F.Cu")
		(net "UART_RX_P2_L")
	)
	(segment
		(start 30.026102 -36.146232)
		(end 30.026102 -46.708314)
		(width 0.1016)
		(layer "F.Cu")
		(net "UART_RX_P2_L")
	)
	(segment
		(start 13.335762 -31.421832)
		(end 15.12697 -33.21304)
		(width 0.1016)
		(layer "F.Cu")
		(net "UART_RX_P2_L")
	)
	(segment
		(start 14.48816 -26.04516)
		(end 14.48816 -27.38628)
		(width 0.1016)
		(layer "F.Cu")
		(net "UART_RX_P2_L")
	)
	(segment
		(start 30.026102 -46.708314)
		(end 27.66314 -49.071276)
		(width 0.1016)
		(layer "F.Cu")
		(net "UART_RX_P2_L")
	)
	(segment
		(start 14.48816 -27.38628)
		(end 13.335762 -28.538678)
		(width 0.1016)
		(layer "F.Cu")
		(net "UART_RX_P2_L")
	)
	(via
		(at 33.18764 -199.542654)
		(size 0.508)
		(drill 0.254)
		(layers "F.Cu" "B.Cu")
		(net "UART_RX_P2_L")
	)
	(via
		(at 27.66314 -49.071276)
		(size 0.508)
		(drill 0.254)
		(layers "F.Cu" "B.Cu")
		(net "UART_RX_P2_L")
	)
	(segment
		(start 33.01492 -199.715374)
		(end 33.18764 -199.542654)
		(width 0.1016)
		(layer "B.Cu")
		(net "UART_RX_P2_L")
	)
	(segment
		(start 33.01492 -205.199488)
		(end 33.01492 -199.715374)
		(width 0.1016)
		(layer "B.Cu")
		(net "UART_RX_P2_L")
	)
	(segment
		(start 11.575542 -102.341172)
		(end 9.55929 -104.357424)
		(width 0.1143)
		(layer "In2.Cu")
		(net "UART_RX_P2_L")
	)
	(segment
		(start 8.30961 -152.015952)
		(end 8.85571 -152.562052)
		(width 0.1143)
		(layer "In2.Cu")
		(net "UART_RX_P2_L")
	)
	(segment
		(start 14.09192 -166.22522)
		(end 18.15592 -170.28922)
		(width 0.1143)
		(layer "In2.Cu")
		(net "UART_RX_P2_L")
	)
	(segment
		(start 27.66314 -52.494434)
		(end 29.016198 -53.847492)
		(width 0.1143)
		(layer "In2.Cu")
		(net "UART_RX_P2_L")
	)
	(segment
		(start 13.065252 -165.177216)
		(end 13.834364 -165.177216)
		(width 0.1143)
		(layer "In2.Cu")
		(net "UART_RX_P2_L")
	)
	(segment
		(start 9.418828 -137.876788)
		(end 9.418828 -138.240516)
		(width 0.1143)
		(layer "In2.Cu")
		(net "UART_RX_P2_L")
	)
	(segment
		(start 9.418828 -138.240516)
		(end 10.178796 -139.000484)
		(width 0.1143)
		(layer "In2.Cu")
		(net "UART_RX_P2_L")
	)
	(segment
		(start 16.18488 -97.807272)
		(end 16.18488 -98.28784)
		(width 0.1143)
		(layer "In2.Cu")
		(net "UART_RX_P2_L")
	)
	(segment
		(start 8.30961 -148.130768)
		(end 8.30961 -152.015952)
		(width 0.1143)
		(layer "In2.Cu")
		(net "UART_RX_P2_L")
	)
	(segment
		(start 33.67405 -197.483222)
		(end 33.67405 -199.056244)
		(width 0.1143)
		(layer "In2.Cu")
		(net "UART_RX_P2_L")
	)
	(segment
		(start 13.834364 -165.177216)
		(end 14.09192 -165.434772)
		(width 0.1143)
		(layer "In2.Cu")
		(net "UART_RX_P2_L")
	)
	(segment
		(start 29.016198 -79.687166)
		(end 20.93722 -87.766144)
		(width 0.1143)
		(layer "In2.Cu")
		(net "UART_RX_P2_L")
	)
	(segment
		(start 10.08761 -114.348006)
		(end 10.08761 -134.724902)
		(width 0.1143)
		(layer "In2.Cu")
		(net "UART_RX_P2_L")
	)
	(segment
		(start 32.217614 -196.026786)
		(end 33.67405 -197.483222)
		(width 0.1143)
		(layer "In2.Cu")
		(net "UART_RX_P2_L")
	)
	(segment
		(start 9.55929 -113.819686)
		(end 10.08761 -114.348006)
		(width 0.1143)
		(layer "In2.Cu")
		(net "UART_RX_P2_L")
	)
	(segment
		(start 9.45261 -135.359902)
		(end 9.45261 -137.843006)
		(width 0.1143)
		(layer "In2.Cu")
		(net "UART_RX_P2_L")
	)
	(segment
		(start 9.55929 -104.357424)
		(end 9.55929 -113.819686)
		(width 0.1143)
		(layer "In2.Cu")
		(net "UART_RX_P2_L")
	)
	(segment
		(start 18.15592 -170.28922)
		(end 18.15592 -183.784748)
		(width 0.1143)
		(layer "In2.Cu")
		(net "UART_RX_P2_L")
	)
	(segment
		(start 9.45261 -137.843006)
		(end 9.418828 -137.876788)
		(width 0.1143)
		(layer "In2.Cu")
		(net "UART_RX_P2_L")
	)
	(segment
		(start 27.66314 -49.071276)
		(end 27.66314 -52.494434)
		(width 0.1143)
		(layer "In2.Cu")
		(net "UART_RX_P2_L")
	)
	(segment
		(start 10.08761 -134.724902)
		(end 9.45261 -135.359902)
		(width 0.1143)
		(layer "In2.Cu")
		(net "UART_RX_P2_L")
	)
	(segment
		(start 8.85571 -153.149808)
		(end 8.62457 -153.380948)
		(width 0.1143)
		(layer "In2.Cu")
		(net "UART_RX_P2_L")
	)
	(segment
		(start 12.131548 -102.341172)
		(end 11.575542 -102.341172)
		(width 0.1143)
		(layer "In2.Cu")
		(net "UART_RX_P2_L")
	)
	(segment
		(start 18.15592 -183.784748)
		(end 30.397958 -196.026786)
		(width 0.1143)
		(layer "In2.Cu")
		(net "UART_RX_P2_L")
	)
	(segment
		(start 33.67405 -199.056244)
		(end 33.18764 -199.542654)
		(width 0.1143)
		(layer "In2.Cu")
		(net "UART_RX_P2_L")
	)
	(segment
		(start 8.62457 -160.736534)
		(end 13.065252 -165.177216)
		(width 0.1143)
		(layer "In2.Cu")
		(net "UART_RX_P2_L")
	)
	(segment
		(start 20.93722 -87.766144)
		(end 20.93722 -93.054932)
		(width 0.1143)
		(layer "In2.Cu")
		(net "UART_RX_P2_L")
	)
	(segment
		(start 8.85571 -152.562052)
		(end 8.85571 -153.149808)
		(width 0.1143)
		(layer "In2.Cu")
		(net "UART_RX_P2_L")
	)
	(segment
		(start 29.016198 -53.847492)
		(end 29.016198 -79.687166)
		(width 0.1143)
		(layer "In2.Cu")
		(net "UART_RX_P2_L")
	)
	(segment
		(start 16.18488 -98.28784)
		(end 12.131548 -102.341172)
		(width 0.1143)
		(layer "In2.Cu")
		(net "UART_RX_P2_L")
	)
	(segment
		(start 20.93722 -93.054932)
		(end 16.18488 -97.807272)
		(width 0.1143)
		(layer "In2.Cu")
		(net "UART_RX_P2_L")
	)
	(segment
		(start 8.62457 -153.380948)
		(end 8.62457 -160.736534)
		(width 0.1143)
		(layer "In2.Cu")
		(net "UART_RX_P2_L")
	)
	(segment
		(start 10.178796 -146.261582)
		(end 8.30961 -148.130768)
		(width 0.1143)
		(layer "In2.Cu")
		(net "UART_RX_P2_L")
	)
	(segment
		(start 30.397958 -196.026786)
		(end 32.217614 -196.026786)
		(width 0.1143)
		(layer "In2.Cu")
		(net "UART_RX_P2_L")
	)
	(segment
		(start 10.178796 -139.000484)
		(end 10.178796 -146.261582)
		(width 0.1143)
		(layer "In2.Cu")
		(net "UART_RX_P2_L")
	)
	(segment
		(start 14.09192 -165.434772)
		(end 14.09192 -166.22522)
		(width 0.1143)
		(layer "In2.Cu")
		(net "UART_RX_P2_L")
	)
	(segment
		(start 124.727208 -49.017428)
		(end 124.205746 -49.017428)
		(width 0.1016)
		(layer "F.Cu")
		(net "SIO_LRESET_N")
	)
	(segment
		(start 124.757434 -49.675796)
		(end 124.274834 -49.675796)
		(width 0.1016)
		(layer "F.Cu")
		(net "SIO_LRESET_N")
	)
	(segment
		(start 124.274834 -49.675796)
		(end 123.911106 -49.312068)
		(width 0.1016)
		(layer "F.Cu")
		(net "SIO_LRESET_N")
	)
	(segment
		(start 125.261624 -47.199804)
		(end 125.261624 -48.483012)
		(width 0.1016)
		(layer "F.Cu")
		(net "SIO_LRESET_N")
	)
	(segment
		(start 124.205746 -49.017428)
		(end 123.911106 -49.312068)
		(width 0.1016)
		(layer "F.Cu")
		(net "SIO_LRESET_N")
	)
	(segment
		(start 125.261624 -48.483012)
		(end 124.727208 -49.017428)
		(width 0.1016)
		(layer "F.Cu")
		(net "SIO_LRESET_N")
	)
	(via
		(at 123.911106 -49.312068)
		(size 0.508)
		(drill 0.254)
		(layers "F.Cu" "B.Cu")
		(net "SIO_LRESET_N")
	)
	(segment
		(start 118.38432 -164.942774)
		(end 118.38432 -163.7792)
		(width 0.1016)
		(layer "F.Cu")
		(net "I2C_PSU1_SCL")
	)
	(segment
		(start 118.38432 -163.7792)
		(end 118.76532 -163.3982)
		(width 0.1016)
		(layer "F.Cu")
		(net "I2C_PSU1_SCL")
	)
	(segment
		(start 117.60708 -167.095678)
		(end 118.08714 -166.615618)
		(width 0.1016)
		(layer "F.Cu")
		(net "I2C_PSU1_SCL")
	)
	(segment
		(start 126.563628 -157.489144)
		(end 126.083822 -157.489144)
		(width 0.1016)
		(layer "F.Cu")
		(net "I2C_PSU1_SCL")
	)
	(segment
		(start 118.76532 -163.3982)
		(end 118.76532 -162.2806)
		(width 0.1016)
		(layer "F.Cu")
		(net "I2C_PSU1_SCL")
	)
	(segment
		(start 124.73432 -160.376616)
		(end 124.542804 -160.568132)
		(width 0.1016)
		(layer "F.Cu")
		(net "I2C_PSU1_SCL")
	)
	(segment
		(start 118.752366 -161.90722)
		(end 119.005096 -161.65449)
		(width 0.1016)
		(layer "F.Cu")
		(net "I2C_PSU1_SCL")
	)
	(segment
		(start 120.633236 -161.828988)
		(end 121.079768 -161.828988)
		(width 0.1016)
		(layer "F.Cu")
		(net "I2C_PSU1_SCL")
	)
	(segment
		(start 121.670572 -161.238184)
		(end 122.848624 -161.238184)
		(width 0.1016)
		(layer "F.Cu")
		(net "I2C_PSU1_SCL")
	)
	(segment
		(start 55.10276 -184.522364)
		(end 56.21528 -183.409844)
		(width 0.1016)
		(layer "F.Cu")
		(net "I2C_PSU1_SCL")
	)
	(segment
		(start 120.458738 -161.65449)
		(end 120.633236 -161.828988)
		(width 0.1016)
		(layer "F.Cu")
		(net "I2C_PSU1_SCL")
	)
	(segment
		(start 118.08714 -165.239954)
		(end 118.38432 -164.942774)
		(width 0.1016)
		(layer "F.Cu")
		(net "I2C_PSU1_SCL")
	)
	(segment
		(start 118.08714 -166.615618)
		(end 118.08714 -165.239954)
		(width 0.1016)
		(layer "F.Cu")
		(net "I2C_PSU1_SCL")
	)
	(segment
		(start 118.76532 -162.2806)
		(end 118.752366 -162.267646)
		(width 0.1016)
		(layer "F.Cu")
		(net "I2C_PSU1_SCL")
	)
	(segment
		(start 121.079768 -161.828988)
		(end 121.670572 -161.238184)
		(width 0.1016)
		(layer "F.Cu")
		(net "I2C_PSU1_SCL")
	)
	(segment
		(start 124.73432 -158.838646)
		(end 124.73432 -160.376616)
		(width 0.1016)
		(layer "F.Cu")
		(net "I2C_PSU1_SCL")
	)
	(segment
		(start 126.083822 -157.489144)
		(end 124.73432 -158.838646)
		(width 0.1016)
		(layer "F.Cu")
		(net "I2C_PSU1_SCL")
	)
	(segment
		(start 119.005096 -161.65449)
		(end 120.458738 -161.65449)
		(width 0.1016)
		(layer "F.Cu")
		(net "I2C_PSU1_SCL")
	)
	(segment
		(start 123.518676 -160.568132)
		(end 122.848624 -161.238184)
		(width 0.1016)
		(layer "F.Cu")
		(net "I2C_PSU1_SCL")
	)
	(segment
		(start 117.60708 -167.899842)
		(end 117.60708 -167.095678)
		(width 0.1016)
		(layer "F.Cu")
		(net "I2C_PSU1_SCL")
	)
	(segment
		(start 118.752366 -162.267646)
		(end 118.752366 -161.90722)
		(width 0.1016)
		(layer "F.Cu")
		(net "I2C_PSU1_SCL")
	)
	(segment
		(start 55.10276 -184.805574)
		(end 55.10276 -184.522364)
		(width 0.1016)
		(layer "F.Cu")
		(net "I2C_PSU1_SCL")
	)
	(segment
		(start 56.21528 -183.409844)
		(end 56.21528 -183.057292)
		(width 0.1016)
		(layer "F.Cu")
		(net "I2C_PSU1_SCL")
	)
	(segment
		(start 124.542804 -160.568132)
		(end 123.518676 -160.568132)
		(width 0.1016)
		(layer "F.Cu")
		(net "I2C_PSU1_SCL")
	)
	(via
		(at 117.60708 -167.899842)
		(size 0.508)
		(drill 0.254)
		(layers "F.Cu" "B.Cu")
		(net "I2C_PSU1_SCL")
	)
	(via
		(at 56.21528 -183.057292)
		(size 0.508)
		(drill 0.254)
		(layers "F.Cu" "B.Cu")
		(net "I2C_PSU1_SCL")
	)
	(segment
		(start 80.353662 -166.827962)
		(end 79.290164 -167.89146)
		(width 0.1143)
		(layer "In2.Cu")
		(net "I2C_PSU1_SCL")
	)
	(segment
		(start 77.35824 -168.416224)
		(end 76.4413 -169.333164)
		(width 0.1143)
		(layer "In2.Cu")
		(net "I2C_PSU1_SCL")
	)
	(segment
		(start 117.993668 -167.899842)
		(end 118.37797 -168.284144)
		(width 0.1143)
		(layer "In2.Cu")
		(net "I2C_PSU1_SCL")
	)
	(segment
		(start 77.617066 -168.003474)
		(end 77.35824 -168.2623)
		(width 0.1143)
		(layer "In2.Cu")
		(net "I2C_PSU1_SCL")
	)
	(segment
		(start 91.8083 -168.504362)
		(end 91.358212 -168.95445)
		(width 0.1143)
		(layer "In2.Cu")
		(net "I2C_PSU1_SCL")
	)
	(segment
		(start 85.29574 -165.324282)
		(end 83.691984 -165.324282)
		(width 0.1143)
		(layer "In2.Cu")
		(net "I2C_PSU1_SCL")
	)
	(segment
		(start 92.526866 -168.857676)
		(end 92.173552 -168.504362)
		(width 0.1143)
		(layer "In2.Cu")
		(net "I2C_PSU1_SCL")
	)
	(segment
		(start 70.21195 -173.562772)
		(end 69.470524 -173.562772)
		(width 0.1143)
		(layer "In2.Cu")
		(net "I2C_PSU1_SCL")
	)
	(segment
		(start 92.173552 -168.504362)
		(end 91.8083 -168.504362)
		(width 0.1143)
		(layer "In2.Cu")
		(net "I2C_PSU1_SCL")
	)
	(segment
		(start 113.073942 -170.45305)
		(end 112.710722 -170.45305)
		(width 0.1143)
		(layer "In2.Cu")
		(net "I2C_PSU1_SCL")
	)
	(segment
		(start 74.441558 -169.333164)
		(end 70.21195 -173.562772)
		(width 0.1143)
		(layer "In2.Cu")
		(net "I2C_PSU1_SCL")
	)
	(segment
		(start 116.336572 -168.863772)
		(end 116.29644 -168.903904)
		(width 0.1143)
		(layer "In2.Cu")
		(net "I2C_PSU1_SCL")
	)
	(segment
		(start 86.70163 -165.955472)
		(end 85.92693 -165.955472)
		(width 0.1143)
		(layer "In2.Cu")
		(net "I2C_PSU1_SCL")
	)
	(segment
		(start 67.78879 -176.923954)
		(end 67.041776 -176.923954)
		(width 0.1143)
		(layer "In2.Cu")
		(net "I2C_PSU1_SCL")
	)
	(segment
		(start 83.53298 -165.165278)
		(end 82.85734 -165.165278)
		(width 0.1143)
		(layer "In2.Cu")
		(net "I2C_PSU1_SCL")
	)
	(segment
		(start 89.15781 -168.95445)
		(end 88.4047 -168.20134)
		(width 0.1143)
		(layer "In2.Cu")
		(net "I2C_PSU1_SCL")
	)
	(segment
		(start 108.597446 -170.355514)
		(end 100.861114 -170.355514)
		(width 0.1143)
		(layer "In2.Cu")
		(net "I2C_PSU1_SCL")
	)
	(segment
		(start 77.729334 -167.89146)
		(end 77.617066 -168.003474)
		(width 0.1143)
		(layer "In2.Cu")
		(net "I2C_PSU1_SCL")
	)
	(segment
		(start 61.623956 -182.341774)
		(end 56.910986 -182.341774)
		(width 0.1143)
		(layer "In2.Cu")
		(net "I2C_PSU1_SCL")
	)
	(segment
		(start 117.75694 -168.903904)
		(end 117.716808 -168.863772)
		(width 0.1143)
		(layer "In2.Cu")
		(net "I2C_PSU1_SCL")
	)
	(segment
		(start 88.4047 -167.658542)
		(end 86.70163 -165.955472)
		(width 0.1143)
		(layer "In2.Cu")
		(net "I2C_PSU1_SCL")
	)
	(segment
		(start 88.4047 -168.20134)
		(end 88.4047 -167.658542)
		(width 0.1143)
		(layer "In2.Cu")
		(net "I2C_PSU1_SCL")
	)
	(segment
		(start 118.12143 -168.903904)
		(end 117.75694 -168.903904)
		(width 0.1143)
		(layer "In2.Cu")
		(net "I2C_PSU1_SCL")
	)
	(segment
		(start 100.449126 -169.943526)
		(end 96.458278 -169.943526)
		(width 0.1143)
		(layer "In2.Cu")
		(net "I2C_PSU1_SCL")
	)
	(segment
		(start 118.37797 -168.284144)
		(end 118.37797 -168.647364)
		(width 0.1143)
		(layer "In2.Cu")
		(net "I2C_PSU1_SCL")
	)
	(segment
		(start 69.470524 -173.562772)
		(end 68.04533 -174.987966)
		(width 0.1143)
		(layer "In2.Cu")
		(net "I2C_PSU1_SCL")
	)
	(segment
		(start 82.85734 -165.165278)
		(end 81.194656 -166.827962)
		(width 0.1143)
		(layer "In2.Cu")
		(net "I2C_PSU1_SCL")
	)
	(segment
		(start 56.21528 -183.03748)
		(end 56.21528 -183.057292)
		(width 0.1143)
		(layer "In2.Cu")
		(net "I2C_PSU1_SCL")
	)
	(segment
		(start 95.372428 -168.857676)
		(end 92.526866 -168.857676)
		(width 0.1143)
		(layer "In2.Cu")
		(net "I2C_PSU1_SCL")
	)
	(segment
		(start 91.358212 -168.95445)
		(end 89.15781 -168.95445)
		(width 0.1143)
		(layer "In2.Cu")
		(net "I2C_PSU1_SCL")
	)
	(segment
		(start 117.716808 -168.863772)
		(end 116.336572 -168.863772)
		(width 0.1143)
		(layer "In2.Cu")
		(net "I2C_PSU1_SCL")
	)
	(segment
		(start 112.710722 -170.45305)
		(end 112.413034 -170.155362)
		(width 0.1143)
		(layer "In2.Cu")
		(net "I2C_PSU1_SCL")
	)
	(segment
		(start 67.041776 -176.923954)
		(end 61.623956 -182.341774)
		(width 0.1143)
		(layer "In2.Cu")
		(net "I2C_PSU1_SCL")
	)
	(segment
		(start 108.797598 -170.155362)
		(end 108.597446 -170.355514)
		(width 0.1143)
		(layer "In2.Cu")
		(net "I2C_PSU1_SCL")
	)
	(segment
		(start 56.910986 -182.341774)
		(end 56.21528 -183.03748)
		(width 0.1143)
		(layer "In2.Cu")
		(net "I2C_PSU1_SCL")
	)
	(segment
		(start 76.4413 -169.333164)
		(end 74.441558 -169.333164)
		(width 0.1143)
		(layer "In2.Cu")
		(net "I2C_PSU1_SCL")
	)
	(segment
		(start 68.04533 -176.667414)
		(end 67.78879 -176.923954)
		(width 0.1143)
		(layer "In2.Cu")
		(net "I2C_PSU1_SCL")
	)
	(segment
		(start 114.623088 -168.903904)
		(end 113.073942 -170.45305)
		(width 0.1143)
		(layer "In2.Cu")
		(net "I2C_PSU1_SCL")
	)
	(segment
		(start 100.861114 -170.355514)
		(end 100.449126 -169.943526)
		(width 0.1143)
		(layer "In2.Cu")
		(net "I2C_PSU1_SCL")
	)
	(segment
		(start 116.29644 -168.903904)
		(end 114.623088 -168.903904)
		(width 0.1143)
		(layer "In2.Cu")
		(net "I2C_PSU1_SCL")
	)
	(segment
		(start 117.60708 -167.899842)
		(end 117.993668 -167.899842)
		(width 0.1143)
		(layer "In2.Cu")
		(net "I2C_PSU1_SCL")
	)
	(segment
		(start 81.194656 -166.827962)
		(end 80.353662 -166.827962)
		(width 0.1143)
		(layer "In2.Cu")
		(net "I2C_PSU1_SCL")
	)
	(segment
		(start 85.92693 -165.955472)
		(end 85.29574 -165.324282)
		(width 0.1143)
		(layer "In2.Cu")
		(net "I2C_PSU1_SCL")
	)
	(segment
		(start 96.458278 -169.943526)
		(end 95.372428 -168.857676)
		(width 0.1143)
		(layer "In2.Cu")
		(net "I2C_PSU1_SCL")
	)
	(segment
		(start 68.04533 -174.987966)
		(end 68.04533 -176.667414)
		(width 0.1143)
		(layer "In2.Cu")
		(net "I2C_PSU1_SCL")
	)
	(segment
		(start 77.35824 -168.2623)
		(end 77.35824 -168.416224)
		(width 0.1143)
		(layer "In2.Cu")
		(net "I2C_PSU1_SCL")
	)
	(segment
		(start 118.37797 -168.647364)
		(end 118.12143 -168.903904)
		(width 0.1143)
		(layer "In2.Cu")
		(net "I2C_PSU1_SCL")
	)
	(segment
		(start 79.290164 -167.89146)
		(end 77.729334 -167.89146)
		(width 0.1143)
		(layer "In2.Cu")
		(net "I2C_PSU1_SCL")
	)
	(segment
		(start 83.691984 -165.324282)
		(end 83.53298 -165.165278)
		(width 0.1143)
		(layer "In2.Cu")
		(net "I2C_PSU1_SCL")
	)
	(segment
		(start 112.413034 -170.155362)
		(end 108.797598 -170.155362)
		(width 0.1143)
		(layer "In2.Cu")
		(net "I2C_PSU1_SCL")
	)
	(segment
		(start 59.32932 -159.868616)
		(end 59.972956 -159.868616)
		(width 0.1016)
		(layer "F.Cu")
		(net "LAN1_NVM_SI_R")
	)
	(segment
		(start 60.774326 -159.067246)
		(end 60.14212 -159.699452)
		(width 0.1016)
		(layer "F.Cu")
		(net "LAN1_NVM_SI_R")
	)
	(segment
		(start 58.216546 -160.98139)
		(end 59.32932 -159.868616)
		(width 0.1016)
		(layer "F.Cu")
		(net "LAN1_NVM_SI_R")
	)
	(segment
		(start 58.216546 -161.528506)
		(end 58.216546 -160.98139)
		(width 0.1016)
		(layer "F.Cu")
		(net "LAN1_NVM_SI_R")
	)
	(segment
		(start 59.972956 -159.868616)
		(end 60.14212 -159.699452)
		(width 0.1016)
		(layer "F.Cu")
		(net "LAN1_NVM_SI_R")
	)
	(segment
		(start 60.774326 -158.351982)
		(end 60.774326 -159.067246)
		(width 0.1016)
		(layer "F.Cu")
		(net "LAN1_NVM_SI_R")
	)
	(via
		(at 60.14212 -159.699452)
		(size 0.508)
		(drill 0.254)
		(layers "F.Cu" "B.Cu")
		(net "LAN1_NVM_SI_R")
	)
	(segment
		(start 13.188188 -27.642058)
		(end 12.726162 -28.104084)
		(width 0.1016)
		(layer "F.Cu")
		(net "UART_CTS_P2_L_N")
	)
	(segment
		(start 28.24988 -40.054022)
		(end 28.24988 -40.874442)
		(width 0.1016)
		(layer "F.Cu")
		(net "UART_CTS_P2_L_N")
	)
	(segment
		(start 29.416502 -38.8874)
		(end 28.24988 -40.054022)
		(width 0.1016)
		(layer "F.Cu")
		(net "UART_CTS_P2_L_N")
	)
	(segment
		(start 29.416502 -36.399216)
		(end 29.416502 -38.8874)
		(width 0.1016)
		(layer "F.Cu")
		(net "UART_CTS_P2_L_N")
	)
	(segment
		(start 12.726162 -31.674816)
		(end 14.922754 -33.871408)
		(width 0.1016)
		(layer "F.Cu")
		(net "UART_CTS_P2_L_N")
	)
	(segment
		(start 12.726162 -28.104084)
		(end 12.726162 -31.674816)
		(width 0.1016)
		(layer "F.Cu")
		(net "UART_CTS_P2_L_N")
	)
	(segment
		(start 14.922754 -33.871408)
		(end 26.888694 -33.871408)
		(width 0.1016)
		(layer "F.Cu")
		(net "UART_CTS_P2_L_N")
	)
	(segment
		(start 13.188188 -26.04516)
		(end 13.188188 -27.642058)
		(width 0.1016)
		(layer "F.Cu")
		(net "UART_CTS_P2_L_N")
	)
	(segment
		(start 26.888694 -33.871408)
		(end 29.416502 -36.399216)
		(width 0.1016)
		(layer "F.Cu")
		(net "UART_CTS_P2_L_N")
	)
	(via
		(at 28.24988 -40.874442)
		(size 0.508)
		(drill 0.254)
		(layers "F.Cu" "B.Cu")
		(net "UART_CTS_P2_L_N")
	)
	(via
		(at 30.014926 -199.099678)
		(size 0.508)
		(drill 0.254)
		(layers "F.Cu" "B.Cu")
		(net "UART_CTS_P2_L_N")
	)
	(segment
		(start 30.014926 -205.199488)
		(end 30.014926 -199.099678)
		(width 0.1016)
		(layer "B.Cu")
		(net "UART_CTS_P2_L_N")
	)
	(segment
		(start 25.01138 -43.002708)
		(end 25.01138 -55.578502)
		(width 0.1143)
		(layer "In2.Cu")
		(net "UART_CTS_P2_L_N")
	)
	(segment
		(start 24.077168 -56.512714)
		(end 23.301198 -59.603386)
		(width 0.1143)
		(layer "In2.Cu")
		(net "UART_CTS_P2_L_N")
	)
	(segment
		(start 5.76834 -151.741378)
		(end 5.76834 -162.703764)
		(width 0.1143)
		(layer "In2.Cu")
		(net "UART_CTS_P2_L_N")
	)
	(segment
		(start 11.435588 -98.745802)
		(end 11.43508 -98.745802)
		(width 0.1143)
		(layer "In2.Cu")
		(net "UART_CTS_P2_L_N")
	)
	(segment
		(start 24.42845 -66.432176)
		(end 24.42845 -81.506314)
		(width 0.1143)
		(layer "In2.Cu")
		(net "UART_CTS_P2_L_N")
	)
	(segment
		(start 12.323572 -167.162734)
		(end 16.22298 -171.062142)
		(width 0.1143)
		(layer "In2.Cu")
		(net "UART_CTS_P2_L_N")
	)
	(segment
		(start 23.301198 -59.603386)
		(end 23.301198 -65.304924)
		(width 0.1143)
		(layer "In2.Cu")
		(net "UART_CTS_P2_L_N")
	)
	(segment
		(start 25.01138 -55.578502)
		(end 24.077168 -56.512714)
		(width 0.1143)
		(layer "In2.Cu")
		(net "UART_CTS_P2_L_N")
	)
	(segment
		(start 16.22298 -171.062142)
		(end 16.22298 -184.89549)
		(width 0.1143)
		(layer "In2.Cu")
		(net "UART_CTS_P2_L_N")
	)
	(segment
		(start 24.42845 -81.506314)
		(end 18.92554 -87.009224)
		(width 0.1143)
		(layer "In2.Cu")
		(net "UART_CTS_P2_L_N")
	)
	(segment
		(start 10.22731 -167.162734)
		(end 12.323572 -167.162734)
		(width 0.1143)
		(layer "In2.Cu")
		(net "UART_CTS_P2_L_N")
	)
	(segment
		(start 11.60018 -98.20783)
		(end 11.60018 -98.58121)
		(width 0.1143)
		(layer "In2.Cu")
		(net "UART_CTS_P2_L_N")
	)
	(segment
		(start 6.75259 -140.629386)
		(end 6.75259 -146.747738)
		(width 0.1143)
		(layer "In2.Cu")
		(net "UART_CTS_P2_L_N")
	)
	(segment
		(start 6.717538 -140.594334)
		(end 6.75259 -140.629386)
		(width 0.1143)
		(layer "In2.Cu")
		(net "UART_CTS_P2_L_N")
	)
	(segment
		(start 18.92554 -87.009224)
		(end 18.92554 -92.259912)
		(width 0.1143)
		(layer "In2.Cu")
		(net "UART_CTS_P2_L_N")
	)
	(segment
		(start 14.282674 -96.902778)
		(end 12.90574 -96.902778)
		(width 0.1143)
		(layer "In2.Cu")
		(net "UART_CTS_P2_L_N")
	)
	(segment
		(start 11.43508 -98.745802)
		(end 6.717538 -103.463344)
		(width 0.1143)
		(layer "In2.Cu")
		(net "UART_CTS_P2_L_N")
	)
	(segment
		(start 6.717538 -103.463344)
		(end 6.717538 -140.594334)
		(width 0.1143)
		(layer "In2.Cu")
		(net "UART_CTS_P2_L_N")
	)
	(segment
		(start 5.749798 -150.902416)
		(end 5.995924 -151.148542)
		(width 0.1143)
		(layer "In2.Cu")
		(net "UART_CTS_P2_L_N")
	)
	(segment
		(start 6.75259 -146.747738)
		(end 5.749798 -147.75053)
		(width 0.1143)
		(layer "In2.Cu")
		(net "UART_CTS_P2_L_N")
	)
	(segment
		(start 11.600688 -98.20783)
		(end 11.60018 -98.20783)
		(width 0.1143)
		(layer "In2.Cu")
		(net "UART_CTS_P2_L_N")
	)
	(segment
		(start 5.76834 -162.703764)
		(end 10.22731 -167.162734)
		(width 0.1143)
		(layer "In2.Cu")
		(net "UART_CTS_P2_L_N")
	)
	(segment
		(start 11.60018 -98.58121)
		(end 11.435588 -98.745802)
		(width 0.1143)
		(layer "In2.Cu")
		(net "UART_CTS_P2_L_N")
	)
	(segment
		(start 30.014926 -198.687436)
		(end 30.014926 -199.099678)
		(width 0.1143)
		(layer "In2.Cu")
		(net "UART_CTS_P2_L_N")
	)
	(segment
		(start 28.24988 -40.874442)
		(end 27.1399 -40.874442)
		(width 0.1143)
		(layer "In2.Cu")
		(net "UART_CTS_P2_L_N")
	)
	(segment
		(start 18.92554 -92.259912)
		(end 14.282674 -96.902778)
		(width 0.1143)
		(layer "In2.Cu")
		(net "UART_CTS_P2_L_N")
	)
	(segment
		(start 5.995924 -151.513794)
		(end 5.76834 -151.741378)
		(width 0.1143)
		(layer "In2.Cu")
		(net "UART_CTS_P2_L_N")
	)
	(segment
		(start 5.749798 -147.75053)
		(end 5.749798 -150.902416)
		(width 0.1143)
		(layer "In2.Cu")
		(net "UART_CTS_P2_L_N")
	)
	(segment
		(start 16.22298 -184.89549)
		(end 30.014926 -198.687436)
		(width 0.1143)
		(layer "In2.Cu")
		(net "UART_CTS_P2_L_N")
	)
	(segment
		(start 27.1399 -40.874442)
		(end 26.83256 -41.181528)
		(width 0.1143)
		(layer "In2.Cu")
		(net "UART_CTS_P2_L_N")
	)
	(segment
		(start 26.83256 -41.181528)
		(end 25.01138 -43.002708)
		(width 0.1143)
		(layer "In2.Cu")
		(net "UART_CTS_P2_L_N")
	)
	(segment
		(start 12.90574 -96.902778)
		(end 11.600688 -98.20783)
		(width 0.1143)
		(layer "In2.Cu")
		(net "UART_CTS_P2_L_N")
	)
	(segment
		(start 5.995924 -151.148542)
		(end 5.995924 -151.513794)
		(width 0.1143)
		(layer "In2.Cu")
		(net "UART_CTS_P2_L_N")
	)
	(segment
		(start 23.301198 -65.304924)
		(end 24.42845 -66.432176)
		(width 0.1143)
		(layer "In2.Cu")
		(net "UART_CTS_P2_L_N")
	)
	(segment
		(start 58.234326 -153.068782)
		(end 58.234326 -151.811228)
		(width 0.1016)
		(layer "F.Cu")
		(net "LAN1_NVM_SO_R")
	)
	(segment
		(start 52.623212 -146.530822)
		(end 53.35016 -146.530822)
		(width 0.1016)
		(layer "F.Cu")
		(net "LAN1_NVM_SO_R")
	)
	(via
		(at 53.35016 -146.530822)
		(size 0.508)
		(drill 0.254)
		(layers "F.Cu" "B.Cu")
		(net "LAN1_NVM_SO_R")
	)
	(via
		(at 58.234326 -151.811228)
		(size 0.508)
		(drill 0.254)
		(layers "F.Cu" "B.Cu")
		(net "LAN1_NVM_SO_R")
	)
	(segment
		(start 59.638184 -151.811228)
		(end 59.924188 -151.811228)
		(width 0.1016)
		(layer "B.Cu")
		(net "LAN1_NVM_SO_R")
	)
	(segment
		(start 57.50433 -151.35733)
		(end 53.74894 -147.60194)
		(width 0.1016)
		(layer "B.Cu")
		(net "LAN1_NVM_SO_R")
	)
	(segment
		(start 54.1909 -146.923252)
		(end 54.1909 -147.181316)
		(width 0.1016)
		(layer "B.Cu")
		(net "LAN1_NVM_SO_R")
	)
	(segment
		(start 59.28106 -156.757878)
		(end 59.459622 -156.579316)
		(width 0.1016)
		(layer "B.Cu")
		(net "LAN1_NVM_SO_R")
	)
	(segment
		(start 57.749186 -151.35733)
		(end 57.50433 -151.35733)
		(width 0.1016)
		(layer "B.Cu")
		(net "LAN1_NVM_SO_R")
	)
	(segment
		(start 59.459622 -151.98979)
		(end 59.638184 -151.811228)
		(width 0.1016)
		(layer "B.Cu")
		(net "LAN1_NVM_SO_R")
	)
	(segment
		(start 58.850022 -156.579316)
		(end 59.028584 -156.757878)
		(width 0.1016)
		(layer "B.Cu")
		(net "LAN1_NVM_SO_R")
	)
	(segment
		(start 60.37834 -150.135336)
		(end 59.965336 -149.722332)
		(width 0.1016)
		(layer "B.Cu")
		(net "LAN1_NVM_SO_R")
	)
	(segment
		(start 54.191662 -146.923252)
		(end 54.1909 -146.923252)
		(width 0.1016)
		(layer "B.Cu")
		(net "LAN1_NVM_SO_R")
	)
	(segment
		(start 54.616604 -146.744436)
		(end 54.370478 -146.744436)
		(width 0.1016)
		(layer "B.Cu")
		(net "LAN1_NVM_SO_R")
	)
	(segment
		(start 54.1909 -147.181316)
		(end 57.92724 -150.917656)
		(width 0.1016)
		(layer "B.Cu")
		(net "LAN1_NVM_SO_R")
	)
	(segment
		(start 59.924188 -151.811228)
		(end 60.37834 -151.357076)
		(width 0.1016)
		(layer "B.Cu")
		(net "LAN1_NVM_SO_R")
	)
	(segment
		(start 59.459622 -156.579316)
		(end 59.459622 -151.98979)
		(width 0.1016)
		(layer "B.Cu")
		(net "LAN1_NVM_SO_R")
	)
	(segment
		(start 60.37834 -151.357076)
		(end 60.37834 -150.135336)
		(width 0.1016)
		(layer "B.Cu")
		(net "LAN1_NVM_SO_R")
	)
	(segment
		(start 57.92724 -150.917656)
		(end 57.92724 -151.177752)
		(width 0.1016)
		(layer "B.Cu")
		(net "LAN1_NVM_SO_R")
	)
	(segment
		(start 59.028584 -156.757878)
		(end 59.28106 -156.757878)
		(width 0.1016)
		(layer "B.Cu")
		(net "LAN1_NVM_SO_R")
	)
	(segment
		(start 57.5945 -149.722332)
		(end 54.616604 -146.744436)
		(width 0.1016)
		(layer "B.Cu")
		(net "LAN1_NVM_SO_R")
	)
	(segment
		(start 54.370478 -146.744436)
		(end 54.191662 -146.923252)
		(width 0.1016)
		(layer "B.Cu")
		(net "LAN1_NVM_SO_R")
	)
	(segment
		(start 59.965336 -149.722332)
		(end 57.5945 -149.722332)
		(width 0.1016)
		(layer "B.Cu")
		(net "LAN1_NVM_SO_R")
	)
	(segment
		(start 58.67146 -151.811228)
		(end 58.850022 -151.98979)
		(width 0.1016)
		(layer "B.Cu")
		(net "LAN1_NVM_SO_R")
	)
	(segment
		(start 57.92724 -151.177752)
		(end 57.928002 -151.178514)
		(width 0.1016)
		(layer "B.Cu")
		(net "LAN1_NVM_SO_R")
	)
	(segment
		(start 58.234326 -151.811228)
		(end 58.67146 -151.811228)
		(width 0.1016)
		(layer "B.Cu")
		(net "LAN1_NVM_SO_R")
	)
	(segment
		(start 58.850022 -151.98979)
		(end 58.850022 -156.579316)
		(width 0.1016)
		(layer "B.Cu")
		(net "LAN1_NVM_SO_R")
	)
	(segment
		(start 57.928002 -151.178514)
		(end 57.749186 -151.35733)
		(width 0.1016)
		(layer "B.Cu")
		(net "LAN1_NVM_SO_R")
	)
	(segment
		(start 53.74894 -146.929602)
		(end 53.35016 -146.530822)
		(width 0.1016)
		(layer "B.Cu")
		(net "LAN1_NVM_SO_R")
	)
	(segment
		(start 53.74894 -147.60194)
		(end 53.74894 -146.929602)
		(width 0.1016)
		(layer "B.Cu")
		(net "LAN1_NVM_SO_R")
	)
	(segment
		(start 59.325764 -155.797758)
		(end 59.504326 -155.97632)
		(width 0.1016)
		(layer "F.Cu")
		(net "LAN1_NVM_SK_R")
	)
	(segment
		(start 59.504326 -154.534616)
		(end 59.504326 -155.008072)
		(width 0.1016)
		(layer "F.Cu")
		(net "LAN1_NVM_SK_R")
	)
	(segment
		(start 59.325764 -155.188158)
		(end 56.190642 -155.188158)
		(width 0.1016)
		(layer "F.Cu")
		(net "LAN1_NVM_SK_R")
	)
	(segment
		(start 58.84418 -151.023828)
		(end 58.84418 -153.87447)
		(width 0.1016)
		(layer "F.Cu")
		(net "LAN1_NVM_SK_R")
	)
	(segment
		(start 59.504326 -155.008072)
		(end 59.325764 -155.186634)
		(width 0.1016)
		(layer "F.Cu")
		(net "LAN1_NVM_SK_R")
	)
	(segment
		(start 55.1561 -146.746214)
		(end 55.1561 -148.634196)
		(width 0.1016)
		(layer "F.Cu")
		(net "LAN1_NVM_SK_R")
	)
	(segment
		(start 59.325764 -156.407358)
		(end 56.190642 -156.407358)
		(width 0.1016)
		(layer "F.Cu")
		(net "LAN1_NVM_SK_R")
	)
	(segment
		(start 53.65496 -145.514822)
		(end 53.924708 -145.514822)
		(width 0.1016)
		(layer "F.Cu")
		(net "LAN1_NVM_SK_R")
	)
	(segment
		(start 56.190642 -156.407358)
		(end 56.01208 -156.58592)
		(width 0.1016)
		(layer "F.Cu")
		(net "LAN1_NVM_SK_R")
	)
	(segment
		(start 59.504326 -157.387544)
		(end 59.504326 -158.351982)
		(width 0.1016)
		(layer "F.Cu")
		(net "LAN1_NVM_SK_R")
	)
	(segment
		(start 59.325764 -155.186634)
		(end 59.325764 -155.188158)
		(width 0.1016)
		(layer "F.Cu")
		(net "LAN1_NVM_SK_R")
	)
	(segment
		(start 59.504326 -156.228796)
		(end 59.325764 -156.407358)
		(width 0.1016)
		(layer "F.Cu")
		(net "LAN1_NVM_SK_R")
	)
	(segment
		(start 56.971438 -149.151086)
		(end 58.84418 -151.023828)
		(width 0.1016)
		(layer "F.Cu")
		(net "LAN1_NVM_SK_R")
	)
	(segment
		(start 56.190642 -155.797758)
		(end 59.325764 -155.797758)
		(width 0.1016)
		(layer "F.Cu")
		(net "LAN1_NVM_SK_R")
	)
	(segment
		(start 56.01208 -155.619196)
		(end 56.190642 -155.797758)
		(width 0.1016)
		(layer "F.Cu")
		(net "LAN1_NVM_SK_R")
	)
	(segment
		(start 53.924708 -145.514822)
		(end 55.1561 -146.746214)
		(width 0.1016)
		(layer "F.Cu")
		(net "LAN1_NVM_SK_R")
	)
	(segment
		(start 56.01208 -156.58592)
		(end 56.01208 -156.838396)
		(width 0.1016)
		(layer "F.Cu")
		(net "LAN1_NVM_SK_R")
	)
	(segment
		(start 55.1561 -148.634196)
		(end 55.67299 -149.151086)
		(width 0.1016)
		(layer "F.Cu")
		(net "LAN1_NVM_SK_R")
	)
	(segment
		(start 58.84418 -153.87447)
		(end 59.504326 -154.534616)
		(width 0.1016)
		(layer "F.Cu")
		(net "LAN1_NVM_SK_R")
	)
	(segment
		(start 56.190642 -157.016958)
		(end 59.13374 -157.016958)
		(width 0.1016)
		(layer "F.Cu")
		(net "LAN1_NVM_SK_R")
	)
	(segment
		(start 52.623212 -145.514822)
		(end 53.65496 -145.514822)
		(width 0.1016)
		(layer "F.Cu")
		(net "LAN1_NVM_SK_R")
	)
	(segment
		(start 59.13374 -157.016958)
		(end 59.504326 -157.387544)
		(width 0.1016)
		(layer "F.Cu")
		(net "LAN1_NVM_SK_R")
	)
	(segment
		(start 56.01208 -155.36672)
		(end 56.01208 -155.619196)
		(width 0.1016)
		(layer "F.Cu")
		(net "LAN1_NVM_SK_R")
	)
	(segment
		(start 59.504326 -155.97632)
		(end 59.504326 -156.228796)
		(width 0.1016)
		(layer "F.Cu")
		(net "LAN1_NVM_SK_R")
	)
	(segment
		(start 55.67299 -149.151086)
		(end 56.971438 -149.151086)
		(width 0.1016)
		(layer "F.Cu")
		(net "LAN1_NVM_SK_R")
	)
	(segment
		(start 56.01208 -156.838396)
		(end 56.190642 -157.016958)
		(width 0.1016)
		(layer "F.Cu")
		(net "LAN1_NVM_SK_R")
	)
	(segment
		(start 56.190642 -155.188158)
		(end 56.01208 -155.36672)
		(width 0.1016)
		(layer "F.Cu")
		(net "LAN1_NVM_SK_R")
	)
	(via
		(at 53.65496 -145.514822)
		(size 0.508)
		(drill 0.254)
		(layers "F.Cu" "B.Cu")
		(net "LAN1_NVM_SK_R")
	)
	(segment
		(start 167.368982 -37.613336)
		(end 167.711374 -37.955728)
		(width 0.10668)
		(layer "F.Cu")
		(net "USB0_DP")
	)
	(segment
		(start 169.249344 -37.954712)
		(end 168.265856 -37.954712)
		(width 0.10668)
		(layer "F.Cu")
		(net "USB0_DP")
	)
	(segment
		(start 167.711374 -37.955728)
		(end 168.26484 -37.955728)
		(width 0.10668)
		(layer "F.Cu")
		(net "USB0_DP")
	)
	(segment
		(start 168.265856 -37.954712)
		(end 168.26484 -37.955728)
		(width 0.10668)
		(layer "F.Cu")
		(net "USB0_DP")
	)
	(segment
		(start 171.910502 -100.13569)
		(end 172.00753 -100.232718)
		(width 0.1016)
		(layer "F.Cu")
		(net "USB0_DP")
	)
	(segment
		(start 166.998142 -37.613336)
		(end 167.368982 -37.613336)
		(width 0.10668)
		(layer "F.Cu")
		(net "USB0_DP")
	)
	(segment
		(start 172.00753 -100.232718)
		(end 174.316644 -100.232718)
		(width 0.1016)
		(layer "F.Cu")
		(net "USB0_DP")
	)
	(segment
		(start 174.418244 -100.131118)
		(end 174.418244 -99.700588)
		(width 0.1016)
		(layer "F.Cu")
		(net "USB0_DP")
	)
	(segment
		(start 174.316644 -100.232718)
		(end 174.418244 -100.131118)
		(width 0.1016)
		(layer "F.Cu")
		(net "USB0_DP")
	)
	(segment
		(start 166.533068 -38.07841)
		(end 166.998142 -37.613336)
		(width 0.10668)
		(layer "F.Cu")
		(net "USB0_DP")
	)
	(segment
		(start 171.14647 -100.13569)
		(end 171.910502 -100.13569)
		(width 0.1016)
		(layer "F.Cu")
		(net "USB0_DP")
	)
	(via
		(at 166.533068 -38.07841)
		(size 0.508)
		(drill 0.254)
		(layers "F.Cu" "B.Cu")
		(net "USB0_DP")
	)
	(via
		(at 174.418244 -99.700588)
		(size 0.508)
		(drill 0.254)
		(layers "F.Cu" "B.Cu")
		(net "USB0_DP")
	)
	(segment
		(start 176.19218 -99.514914)
		(end 176.19218 -74.751184)
		(width 0.10668)
		(layer "B.Cu")
		(net "USB0_DP")
	)
	(segment
		(start 168.09466 -38.217094)
		(end 167.478456 -37.60089)
		(width 0.10668)
		(layer "B.Cu")
		(net "USB0_DP")
	)
	(segment
		(start 176.19218 -74.751184)
		(end 164.72662 -63.285624)
		(width 0.10668)
		(layer "B.Cu")
		(net "USB0_DP")
	)
	(segment
		(start 166.533068 -37.70757)
		(end 166.533068 -38.07841)
		(width 0.10668)
		(layer "B.Cu")
		(net "USB0_DP")
	)
	(segment
		(start 164.72662 -45.677328)
		(end 168.09466 -42.309288)
		(width 0.10668)
		(layer "B.Cu")
		(net "USB0_DP")
	)
	(segment
		(start 164.72662 -63.285624)
		(end 164.72662 -45.677328)
		(width 0.10668)
		(layer "B.Cu")
		(net "USB0_DP")
	)
	(segment
		(start 168.09466 -42.309288)
		(end 168.09466 -38.217094)
		(width 0.10668)
		(layer "B.Cu")
		(net "USB0_DP")
	)
	(segment
		(start 166.639748 -37.60089)
		(end 166.533068 -37.70757)
		(width 0.10668)
		(layer "B.Cu")
		(net "USB0_DP")
	)
	(segment
		(start 174.418244 -100.071428)
		(end 174.524924 -100.178108)
		(width 0.10668)
		(layer "B.Cu")
		(net "USB0_DP")
	)
	(segment
		(start 174.418244 -99.700588)
		(end 174.418244 -100.071428)
		(width 0.10668)
		(layer "B.Cu")
		(net "USB0_DP")
	)
	(segment
		(start 174.524924 -100.178108)
		(end 175.528986 -100.178108)
		(width 0.10668)
		(layer "B.Cu")
		(net "USB0_DP")
	)
	(segment
		(start 175.528986 -100.178108)
		(end 176.19218 -99.514914)
		(width 0.10668)
		(layer "B.Cu")
		(net "USB0_DP")
	)
	(segment
		(start 167.478456 -37.60089)
		(end 166.639748 -37.60089)
		(width 0.10668)
		(layer "B.Cu")
		(net "USB0_DP")
	)
	(segment
		(start 57.175146 -151.753062)
		(end 57.1754 -151.753062)
		(width 0.1016)
		(layer "F.Cu")
		(net "LAN1_NVM_CS_N_R")
	)
	(segment
		(start 52.623212 -148.562822)
		(end 53.32476 -148.562822)
		(width 0.1016)
		(layer "F.Cu")
		(net "LAN1_NVM_CS_N_R")
	)
	(segment
		(start 56.964326 -151.963882)
		(end 57.175146 -151.753062)
		(width 0.1016)
		(layer "F.Cu")
		(net "LAN1_NVM_CS_N_R")
	)
	(segment
		(start 56.964326 -153.068782)
		(end 56.964326 -151.963882)
		(width 0.1016)
		(layer "F.Cu")
		(net "LAN1_NVM_CS_N_R")
	)
	(via
		(at 53.32476 -148.562822)
		(size 0.508)
		(drill 0.254)
		(layers "F.Cu" "B.Cu")
		(net "LAN1_NVM_CS_N_R")
	)
	(via
		(at 57.1754 -151.753062)
		(size 0.508)
		(drill 0.254)
		(layers "F.Cu" "B.Cu")
		(net "LAN1_NVM_CS_N_R")
	)
	(segment
		(start 56.858662 -152.366472)
		(end 57.111138 -152.366472)
		(width 0.1016)
		(layer "B.Cu")
		(net "LAN1_NVM_CS_N_R")
	)
	(segment
		(start 56.6801 -152.545034)
		(end 56.858662 -152.366472)
		(width 0.1016)
		(layer "B.Cu")
		(net "LAN1_NVM_CS_N_R")
	)
	(segment
		(start 54.31028 -149.125432)
		(end 54.563518 -149.125432)
		(width 0.1016)
		(layer "B.Cu")
		(net "LAN1_NVM_CS_N_R")
	)
	(segment
		(start 57.111138 -152.366472)
		(end 57.2897 -152.545034)
		(width 0.1016)
		(layer "B.Cu")
		(net "LAN1_NVM_CS_N_R")
	)
	(segment
		(start 53.726842 -153.394664)
		(end 53.979318 -153.394664)
		(width 0.1016)
		(layer "B.Cu")
		(net "LAN1_NVM_CS_N_R")
	)
	(segment
		(start 54.76748 -149.331172)
		(end 54.76748 -154.505152)
		(width 0.1016)
		(layer "B.Cu")
		(net "LAN1_NVM_CS_N_R")
	)
	(segment
		(start 57.468262 -156.548836)
		(end 57.71896 -156.548836)
		(width 0.1016)
		(layer "B.Cu")
		(net "LAN1_NVM_CS_N_R")
	)
	(segment
		(start 54.15788 -153.216102)
		(end 54.15788 -149.277832)
		(width 0.1016)
		(layer "B.Cu")
		(net "LAN1_NVM_CS_N_R")
	)
	(segment
		(start 55.091076 -154.828748)
		(end 56.325262 -154.828748)
		(width 0.1016)
		(layer "B.Cu")
		(net "LAN1_NVM_CS_N_R")
	)
	(segment
		(start 54.563772 -149.127464)
		(end 54.76748 -149.331172)
		(width 0.1016)
		(layer "B.Cu")
		(net "LAN1_NVM_CS_N_R")
	)
	(segment
		(start 57.71896 -156.548836)
		(end 57.8993 -156.368496)
		(width 0.1016)
		(layer "B.Cu")
		(net "LAN1_NVM_CS_N_R")
	)
	(segment
		(start 54.563518 -149.125432)
		(end 54.563772 -149.127464)
		(width 0.1016)
		(layer "B.Cu")
		(net "LAN1_NVM_CS_N_R")
	)
	(segment
		(start 53.54828 -149.109176)
		(end 53.54828 -153.216102)
		(width 0.1016)
		(layer "B.Cu")
		(net "LAN1_NVM_CS_N_R")
	)
	(segment
		(start 53.32476 -148.562822)
		(end 53.32476 -148.885656)
		(width 0.1016)
		(layer "B.Cu")
		(net "LAN1_NVM_CS_N_R")
	)
	(segment
		(start 57.8993 -152.476962)
		(end 57.1754 -151.753062)
		(width 0.1016)
		(layer "B.Cu")
		(net "LAN1_NVM_CS_N_R")
	)
	(segment
		(start 56.325262 -154.828748)
		(end 56.6801 -154.47391)
		(width 0.1016)
		(layer "B.Cu")
		(net "LAN1_NVM_CS_N_R")
	)
	(segment
		(start 57.2897 -156.371036)
		(end 57.468262 -156.549598)
		(width 0.1016)
		(layer "B.Cu")
		(net "LAN1_NVM_CS_N_R")
	)
	(segment
		(start 53.32476 -148.885656)
		(end 53.54828 -149.109176)
		(width 0.1016)
		(layer "B.Cu")
		(net "LAN1_NVM_CS_N_R")
	)
	(segment
		(start 56.6801 -154.47391)
		(end 56.6801 -152.545034)
		(width 0.1016)
		(layer "B.Cu")
		(net "LAN1_NVM_CS_N_R")
	)
	(segment
		(start 53.979318 -153.394664)
		(end 54.15788 -153.216102)
		(width 0.1016)
		(layer "B.Cu")
		(net "LAN1_NVM_CS_N_R")
	)
	(segment
		(start 54.76748 -154.505152)
		(end 55.091076 -154.828748)
		(width 0.1016)
		(layer "B.Cu")
		(net "LAN1_NVM_CS_N_R")
	)
	(segment
		(start 53.54828 -153.216102)
		(end 53.726842 -153.394664)
		(width 0.1016)
		(layer "B.Cu")
		(net "LAN1_NVM_CS_N_R")
	)
	(segment
		(start 57.8993 -156.368496)
		(end 57.8993 -152.476962)
		(width 0.1016)
		(layer "B.Cu")
		(net "LAN1_NVM_CS_N_R")
	)
	(segment
		(start 57.2897 -152.545034)
		(end 57.2897 -156.371036)
		(width 0.1016)
		(layer "B.Cu")
		(net "LAN1_NVM_CS_N_R")
	)
	(segment
		(start 54.15788 -149.277832)
		(end 54.31028 -149.125432)
		(width 0.1016)
		(layer "B.Cu")
		(net "LAN1_NVM_CS_N_R")
	)
	(segment
		(start 57.468262 -156.549598)
		(end 57.468262 -156.548836)
		(width 0.1016)
		(layer "B.Cu")
		(net "LAN1_NVM_CS_N_R")
	)
	(segment
		(start 40.122602 -159.852868)
		(end 40.122602 -160.96869)
		(width 0.1016)
		(layer "F.Cu")
		(net "LAN1_RST")
	)
	(segment
		(start 40.122602 -161.787332)
		(end 40.122602 -160.96869)
		(width 0.1016)
		(layer "F.Cu")
		(net "LAN1_RST")
	)
	(segment
		(start 40.502586 -159.472884)
		(end 40.122602 -159.852868)
		(width 0.1016)
		(layer "F.Cu")
		(net "LAN1_RST")
	)
	(segment
		(start 40.817546 -159.472884)
		(end 40.502586 -159.472884)
		(width 0.1016)
		(layer "F.Cu")
		(net "LAN1_RST")
	)
	(via
		(at 40.122602 -160.96869)
		(size 0.508)
		(drill 0.254)
		(layers "F.Cu" "B.Cu")
		(net "LAN1_RST")
	)
	(segment
		(start 167.711374 -36.955984)
		(end 168.26484 -36.955984)
		(width 0.10668)
		(layer "F.Cu")
		(net "USB0_DN")
	)
	(segment
		(start 171.883578 -100.53574)
		(end 171.98086 -100.438458)
		(width 0.1016)
		(layer "F.Cu")
		(net "USB0_DN")
	)
	(segment
		(start 171.98086 -100.438458)
		(end 174.316644 -100.438458)
		(width 0.1016)
		(layer "F.Cu")
		(net "USB0_DN")
	)
	(segment
		(start 171.14647 -100.53574)
		(end 171.883578 -100.53574)
		(width 0.1016)
		(layer "F.Cu")
		(net "USB0_DN")
	)
	(segment
		(start 174.316644 -100.438458)
		(end 174.418244 -100.540058)
		(width 0.1016)
		(layer "F.Cu")
		(net "USB0_DN")
	)
	(segment
		(start 169.019474 -36.938712)
		(end 169.002202 -36.955984)
		(width 0.10668)
		(layer "F.Cu")
		(net "USB0_DN")
	)
	(segment
		(start 169.002202 -36.955984)
		(end 168.26484 -36.955984)
		(width 0.10668)
		(layer "F.Cu")
		(net "USB0_DN")
	)
	(segment
		(start 169.249344 -36.938712)
		(end 169.019474 -36.938712)
		(width 0.10668)
		(layer "F.Cu")
		(net "USB0_DN")
	)
	(segment
		(start 167.368982 -37.298376)
		(end 167.711374 -36.955984)
		(width 0.10668)
		(layer "F.Cu")
		(net "USB0_DN")
	)
	(segment
		(start 166.533068 -36.80841)
		(end 167.023034 -37.298376)
		(width 0.10668)
		(layer "F.Cu")
		(net "USB0_DN")
	)
	(segment
		(start 174.418244 -100.540058)
		(end 174.418244 -100.970588)
		(width 0.1016)
		(layer "F.Cu")
		(net "USB0_DN")
	)
	(segment
		(start 167.023034 -37.298376)
		(end 167.368982 -37.298376)
		(width 0.10668)
		(layer "F.Cu")
		(net "USB0_DN")
	)
	(via
		(at 174.418244 -100.970588)
		(size 0.508)
		(drill 0.254)
		(layers "F.Cu" "B.Cu")
		(net "USB0_DN")
	)
	(via
		(at 166.533068 -36.80841)
		(size 0.508)
		(drill 0.254)
		(layers "F.Cu" "B.Cu")
		(net "USB0_DN")
	)
	(segment
		(start 174.418244 -100.599748)
		(end 174.418244 -100.970588)
		(width 0.10668)
		(layer "B.Cu")
		(net "USB0_DN")
	)
	(segment
		(start 176.50714 -99.64547)
		(end 175.659542 -100.493068)
		(width 0.10668)
		(layer "B.Cu")
		(net "USB0_DN")
	)
	(segment
		(start 174.524924 -100.493068)
		(end 174.418244 -100.599748)
		(width 0.10668)
		(layer "B.Cu")
		(net "USB0_DN")
	)
	(segment
		(start 175.659542 -100.493068)
		(end 174.524924 -100.493068)
		(width 0.10668)
		(layer "B.Cu")
		(net "USB0_DN")
	)
	(segment
		(start 166.533068 -37.17925)
		(end 166.639748 -37.28593)
		(width 0.10668)
		(layer "B.Cu")
		(net "USB0_DN")
	)
	(segment
		(start 167.609012 -37.28593)
		(end 168.40962 -38.086538)
		(width 0.10668)
		(layer "B.Cu")
		(net "USB0_DN")
	)
	(segment
		(start 165.04158 -63.155068)
		(end 176.50714 -74.620628)
		(width 0.10668)
		(layer "B.Cu")
		(net "USB0_DN")
	)
	(segment
		(start 165.04158 -45.807884)
		(end 165.04158 -63.155068)
		(width 0.10668)
		(layer "B.Cu")
		(net "USB0_DN")
	)
	(segment
		(start 168.40962 -42.439844)
		(end 165.04158 -45.807884)
		(width 0.10668)
		(layer "B.Cu")
		(net "USB0_DN")
	)
	(segment
		(start 176.50714 -74.620628)
		(end 176.50714 -99.64547)
		(width 0.10668)
		(layer "B.Cu")
		(net "USB0_DN")
	)
	(segment
		(start 166.639748 -37.28593)
		(end 167.609012 -37.28593)
		(width 0.10668)
		(layer "B.Cu")
		(net "USB0_DN")
	)
	(segment
		(start 166.533068 -36.80841)
		(end 166.533068 -37.17925)
		(width 0.10668)
		(layer "B.Cu")
		(net "USB0_DN")
	)
	(segment
		(start 168.40962 -38.086538)
		(end 168.40962 -42.439844)
		(width 0.10668)
		(layer "B.Cu")
		(net "USB0_DN")
	)
	(via
		(at 157.99562 -199.655938)
		(size 0.6604)
		(drill 0.3302)
		(layers "F.Cu" "B.Cu")
		(net "FAN6_TACH_R")
	)
	(segment
		(start 157.99562 -195.801742)
		(end 157.99562 -199.655938)
		(width 0.1016)
		(layer "B.Cu")
		(net "FAN6_TACH_R")
	)
	(segment
		(start 159.62376 -188.272674)
		(end 158.48076 -188.272674)
		(width 0.1016)
		(layer "B.Cu")
		(net "FAN6_TACH_R")
	)
	(segment
		(start 158.48076 -188.272674)
		(end 158.48076 -188.779404)
		(width 0.1016)
		(layer "B.Cu")
		(net "FAN6_TACH_R")
	)
	(segment
		(start 157.99562 -199.655938)
		(end 157.995874 -199.655938)
		(width 0.1016)
		(layer "B.Cu")
		(net "FAN6_TACH_R")
	)
	(segment
		(start 159.00654 -194.790822)
		(end 157.99562 -195.801742)
		(width 0.1016)
		(layer "B.Cu")
		(net "FAN6_TACH_R")
	)
	(segment
		(start 159.00654 -189.305184)
		(end 159.00654 -194.790822)
		(width 0.1016)
		(layer "B.Cu")
		(net "FAN6_TACH_R")
	)
	(segment
		(start 158.015686 -199.636126)
		(end 158.015686 -205.199488)
		(width 0.1016)
		(layer "B.Cu")
		(net "FAN6_TACH_R")
	)
	(segment
		(start 157.995874 -199.655938)
		(end 158.015686 -199.636126)
		(width 0.1016)
		(layer "B.Cu")
		(net "FAN6_TACH_R")
	)
	(segment
		(start 158.48076 -188.779404)
		(end 159.00654 -189.305184)
		(width 0.1016)
		(layer "B.Cu")
		(net "FAN6_TACH_R")
	)
	(segment
		(start 16.264128 -43.940984)
		(end 17.21739 -43.940984)
		(width 0.1016)
		(layer "F.Cu")
		(net "CRT_R")
	)
	(segment
		(start 15.545308 -44.659804)
		(end 16.264128 -43.940984)
		(width 0.1016)
		(layer "F.Cu")
		(net "CRT_R")
	)
	(segment
		(start 19.35734 -41.548558)
		(end 19.35734 -41.801034)
		(width 0.1016)
		(layer "F.Cu")
		(net "CRT_R")
	)
	(segment
		(start 19.35734 -41.801034)
		(end 17.96923 -43.189144)
		(width 0.1016)
		(layer "F.Cu")
		(net "CRT_R")
	)
	(segment
		(start 15.21968 -44.659804)
		(end 15.545308 -44.659804)
		(width 0.1016)
		(layer "F.Cu")
		(net "CRT_R")
	)
	(segment
		(start 10.65022 -46.794166)
		(end 15.21968 -44.659804)
		(width 0.1016)
		(layer "F.Cu")
		(net "CRT_R")
	)
	(segment
		(start 17.21739 -43.940984)
		(end 17.96923 -43.189144)
		(width 0.1016)
		(layer "F.Cu")
		(net "CRT_R")
	)
	(segment
		(start 161.83102 -188.48197)
		(end 161.83102 -189.38113)
		(width 0.1016)
		(layer "F.Cu")
		(net "FAN4_TACH_R")
	)
	(segment
		(start 161.83102 -189.38113)
		(end 161.77514 -189.43701)
		(width 0.1016)
		(layer "F.Cu")
		(net "FAN4_TACH_R")
	)
	(via
		(at 161.77514 -189.43701)
		(size 0.508)
		(drill 0.254)
		(layers "F.Cu" "B.Cu")
		(net "FAN4_TACH_R")
	)
	(segment
		(start 160.015682 -202.450446)
		(end 160.015682 -205.199488)
		(width 0.1016)
		(layer "B.Cu")
		(net "FAN4_TACH_R")
	)
	(segment
		(start 161.65576 -188.272674)
		(end 161.65576 -189.31763)
		(width 0.1016)
		(layer "B.Cu")
		(net "FAN4_TACH_R")
	)
	(segment
		(start 159.583882 -196.745352)
		(end 159.583882 -202.018646)
		(width 0.1016)
		(layer "B.Cu")
		(net "FAN4_TACH_R")
	)
	(segment
		(start 160.54324 -195.785994)
		(end 159.583882 -196.745352)
		(width 0.1016)
		(layer "B.Cu")
		(net "FAN4_TACH_R")
	)
	(segment
		(start 159.583882 -202.018646)
		(end 160.015682 -202.450446)
		(width 0.1016)
		(layer "B.Cu")
		(net "FAN4_TACH_R")
	)
	(segment
		(start 161.77514 -193.233294)
		(end 160.54324 -194.465194)
		(width 0.1016)
		(layer "B.Cu")
		(net "FAN4_TACH_R")
	)
	(segment
		(start 160.54324 -194.465194)
		(end 160.54324 -195.785994)
		(width 0.1016)
		(layer "B.Cu")
		(net "FAN4_TACH_R")
	)
	(segment
		(start 161.65576 -189.31763)
		(end 161.77514 -189.43701)
		(width 0.1016)
		(layer "B.Cu")
		(net "FAN4_TACH_R")
	)
	(segment
		(start 161.77514 -189.43701)
		(end 161.77514 -193.233294)
		(width 0.1016)
		(layer "B.Cu")
		(net "FAN4_TACH_R")
	)
	(segment
		(start 17.982184 -65.729866)
		(end 15.724886 -65.729866)
		(width 0.1016)
		(layer "F.Cu")
		(net "CRT_DDCCLK")
	)
	(segment
		(start 15.724886 -65.729866)
		(end 15.285466 -65.290446)
		(width 0.1016)
		(layer "F.Cu")
		(net "CRT_DDCCLK")
	)
	(segment
		(start 15.285466 -65.290446)
		(end 15.285466 -64.287908)
		(width 0.1016)
		(layer "F.Cu")
		(net "CRT_DDCCLK")
	)
	(segment
		(start 15.286228 -64.287146)
		(end 10.420858 -59.974226)
		(width 0.1016)
		(layer "F.Cu")
		(net "CRT_DDCCLK")
	)
	(segment
		(start 10.420858 -59.974226)
		(end 9.985756 -59.539124)
		(width 0.1016)
		(layer "F.Cu")
		(net "CRT_DDCCLK")
	)
	(segment
		(start 9.985756 -59.539124)
		(end 9.150096 -55.187088)
		(width 0.1016)
		(layer "F.Cu")
		(net "CRT_DDCCLK")
	)
	(segment
		(start 15.285466 -64.287908)
		(end 15.286228 -64.287146)
		(width 0.1016)
		(layer "F.Cu")
		(net "CRT_DDCCLK")
	)
	(segment
		(start 160.81502 -188.48197)
		(end 160.81502 -190.224918)
		(width 0.1016)
		(layer "F.Cu")
		(net "FAN5_TACH_R")
	)
	(segment
		(start 160.81502 -190.224918)
		(end 160.6042 -190.435738)
		(width 0.1016)
		(layer "F.Cu")
		(net "FAN5_TACH_R")
	)
	(segment
		(start 160.6042 -190.435738)
		(end 160.6042 -190.43777)
		(width 0.1016)
		(layer "F.Cu")
		(net "FAN5_TACH_R")
	)
	(via
		(at 160.6042 -190.43777)
		(size 0.508)
		(drill 0.254)
		(layers "F.Cu" "B.Cu")
		(net "FAN5_TACH_R")
	)
	(segment
		(start 159.26054 -195.27266)
		(end 159.26054 -199.140572)
		(width 0.1016)
		(layer "B.Cu")
		(net "FAN5_TACH_R")
	)
	(segment
		(start 159.015684 -199.385428)
		(end 159.015684 -205.199488)
		(width 0.1016)
		(layer "B.Cu")
		(net "FAN5_TACH_R")
	)
	(segment
		(start 160.6042 -190.059818)
		(end 160.6042 -190.43777)
		(width 0.1016)
		(layer "B.Cu")
		(net "FAN5_TACH_R")
	)
	(segment
		(start 160.63976 -190.024258)
		(end 160.6042 -190.059818)
		(width 0.1016)
		(layer "B.Cu")
		(net "FAN5_TACH_R")
	)
	(segment
		(start 159.26054 -199.140572)
		(end 159.015684 -199.385428)
		(width 0.1016)
		(layer "B.Cu")
		(net "FAN5_TACH_R")
	)
	(segment
		(start 160.63976 -188.272674)
		(end 160.63976 -190.024258)
		(width 0.1016)
		(layer "B.Cu")
		(net "FAN5_TACH_R")
	)
	(segment
		(start 160.6042 -193.929)
		(end 159.26054 -195.27266)
		(width 0.1016)
		(layer "B.Cu")
		(net "FAN5_TACH_R")
	)
	(segment
		(start 160.6042 -190.43777)
		(end 160.6042 -193.929)
		(width 0.1016)
		(layer "B.Cu")
		(net "FAN5_TACH_R")
	)
	(segment
		(start 15.514574 -46.715934)
		(end 16.552926 -46.715934)
		(width 0.1016)
		(layer "F.Cu")
		(net "CRT_DDCDATA")
	)
	(segment
		(start 15.499588 -46.700948)
		(end 14.27734 -46.700948)
		(width 0.1016)
		(layer "F.Cu")
		(net "CRT_DDCDATA")
	)
	(segment
		(start 12.65809 -48.320198)
		(end 10.65022 -48.320198)
		(width 0.1016)
		(layer "F.Cu")
		(net "CRT_DDCDATA")
	)
	(segment
		(start 16.552926 -46.715172)
		(end 16.552926 -46.715934)
		(width 0.1016)
		(layer "F.Cu")
		(net "CRT_DDCDATA")
	)
	(segment
		(start 15.499588 -46.700948)
		(end 15.514574 -46.715934)
		(width 0.1016)
		(layer "F.Cu")
		(net "CRT_DDCDATA")
	)
	(segment
		(start 19.797776 -46.219618)
		(end 18.914364 -46.219618)
		(width 0.1016)
		(layer "F.Cu")
		(net "CRT_DDCDATA")
	)
	(segment
		(start 14.27734 -46.700948)
		(end 12.65809 -48.320198)
		(width 0.1016)
		(layer "F.Cu")
		(net "CRT_DDCDATA")
	)
	(segment
		(start 18.914364 -46.219618)
		(end 18.41881 -46.715172)
		(width 0.1016)
		(layer "F.Cu")
		(net "CRT_DDCDATA")
	)
	(segment
		(start 18.41881 -46.715172)
		(end 16.552926 -46.715172)
		(width 0.1016)
		(layer "F.Cu")
		(net "CRT_DDCDATA")
	)
	(segment
		(start 158.48076 -188.901578)
		(end 158.06674 -189.315598)
		(width 0.1016)
		(layer "F.Cu")
		(net "FAN1_TACH_R")
	)
	(segment
		(start 159.03702 -186.378088)
		(end 159.03702 -187.970414)
		(width 0.1016)
		(layer "F.Cu")
		(net "FAN1_TACH_R")
	)
	(segment
		(start 158.06674 -196.09054)
		(end 158.7754 -196.7992)
		(width 0.1016)
		(layer "F.Cu")
		(net "FAN1_TACH_R")
	)
	(segment
		(start 158.48076 -185.605674)
		(end 158.48076 -185.821828)
		(width 0.1016)
		(layer "F.Cu")
		(net "FAN1_TACH_R")
	)
	(segment
		(start 158.7754 -197.683374)
		(end 158.75254 -197.683374)
		(width 0.1016)
		(layer "F.Cu")
		(net "FAN1_TACH_R")
	)
	(segment
		(start 158.48076 -188.526674)
		(end 158.48076 -188.901578)
		(width 0.1016)
		(layer "F.Cu")
		(net "FAN1_TACH_R")
	)
	(segment
		(start 159.015684 -197.946518)
		(end 158.75254 -197.683374)
		(width 0.1016)
		(layer "F.Cu")
		(net "FAN1_TACH_R")
	)
	(segment
		(start 159.03702 -187.970414)
		(end 158.48076 -188.526674)
		(width 0.1016)
		(layer "F.Cu")
		(net "FAN1_TACH_R")
	)
	(segment
		(start 159.015684 -205.199488)
		(end 159.015684 -197.946518)
		(width 0.1016)
		(layer "F.Cu")
		(net "FAN1_TACH_R")
	)
	(segment
		(start 158.48076 -185.821828)
		(end 159.03702 -186.378088)
		(width 0.1016)
		(layer "F.Cu")
		(net "FAN1_TACH_R")
	)
	(segment
		(start 158.06674 -189.315598)
		(end 158.06674 -196.09054)
		(width 0.1016)
		(layer "F.Cu")
		(net "FAN1_TACH_R")
	)
	(segment
		(start 158.7754 -196.7992)
		(end 158.7754 -197.683374)
		(width 0.1016)
		(layer "F.Cu")
		(net "FAN1_TACH_R")
	)
	(via
		(at 158.75254 -197.683374)
		(size 0.508)
		(drill 0.254)
		(layers "F.Cu" "B.Cu")
		(net "FAN1_TACH_R")
	)
	(segment
		(start 19.797776 -49.716182)
		(end 19.79676 -49.715166)
		(width 0.1016)
		(layer "F.Cu")
		(net "CRT_G")
	)
	(segment
		(start 13.582904 -49.083214)
		(end 13.716 -49.21631)
		(width 0.1016)
		(layer "F.Cu")
		(net "CRT_G")
	)
	(segment
		(start 15.40764 -48.052228)
		(end 15.408402 -48.052228)
		(width 0.1016)
		(layer "F.Cu")
		(net "CRT_G")
	)
	(segment
		(start 15.194534 -49.21631)
		(end 15.194534 -48.912018)
		(width 0.1016)
		(layer "F.Cu")
		(net "CRT_G")
	)
	(segment
		(start 15.63878 -47.350426)
		(end 15.408402 -47.580804)
		(width 0.1016)
		(layer "F.Cu")
		(net "CRT_G")
	)
	(segment
		(start 15.194534 -48.912018)
		(end 15.40764 -48.698912)
		(width 0.1016)
		(layer "F.Cu")
		(net "CRT_G")
	)
	(segment
		(start 19.412204 -47.350426)
		(end 15.63878 -47.350426)
		(width 0.1016)
		(layer "F.Cu")
		(net "CRT_G")
	)
	(segment
		(start 13.716 -49.21631)
		(end 15.194534 -49.21631)
		(width 0.1016)
		(layer "F.Cu")
		(net "CRT_G")
	)
	(segment
		(start 15.40764 -48.698912)
		(end 15.40764 -48.052228)
		(width 0.1016)
		(layer "F.Cu")
		(net "CRT_G")
	)
	(segment
		(start 15.408402 -47.580804)
		(end 15.408402 -48.052228)
		(width 0.1016)
		(layer "F.Cu")
		(net "CRT_G")
	)
	(segment
		(start 19.79676 -49.715166)
		(end 19.79676 -47.734982)
		(width 0.1016)
		(layer "F.Cu")
		(net "CRT_G")
	)
	(segment
		(start 9.150096 -49.083214)
		(end 13.582904 -49.083214)
		(width 0.1016)
		(layer "F.Cu")
		(net "CRT_G")
	)
	(segment
		(start 19.79676 -47.734982)
		(end 19.412204 -47.350426)
		(width 0.1016)
		(layer "F.Cu")
		(net "CRT_G")
	)
	(segment
		(start 156.65196 -186.313572)
		(end 156.65196 -188.252608)
		(width 0.1016)
		(layer "F.Cu")
		(net "FAN3_TACH_R")
	)
	(segment
		(start 157.447488 -201.786744)
		(end 157.015688 -202.218544)
		(width 0.1016)
		(layer "F.Cu")
		(net "FAN3_TACH_R")
	)
	(segment
		(start 156.19476 -196.746368)
		(end 157.23362 -197.785228)
		(width 0.1016)
		(layer "F.Cu")
		(net "FAN3_TACH_R")
	)
	(segment
		(start 157.23362 -197.785228)
		(end 157.447488 -197.999096)
		(width 0.1016)
		(layer "F.Cu")
		(net "FAN3_TACH_R")
	)
	(segment
		(start 156.65196 -188.252608)
		(end 156.377894 -188.526674)
		(width 0.1016)
		(layer "F.Cu")
		(net "FAN3_TACH_R")
	)
	(segment
		(start 156.19476 -185.856372)
		(end 156.65196 -186.313572)
		(width 0.1016)
		(layer "F.Cu")
		(net "FAN3_TACH_R")
	)
	(segment
		(start 157.015688 -202.218544)
		(end 157.015688 -205.199488)
		(width 0.1016)
		(layer "F.Cu")
		(net "FAN3_TACH_R")
	)
	(segment
		(start 156.19476 -188.526674)
		(end 156.19476 -196.746368)
		(width 0.1016)
		(layer "F.Cu")
		(net "FAN3_TACH_R")
	)
	(segment
		(start 157.447488 -197.999096)
		(end 157.447488 -201.786744)
		(width 0.1016)
		(layer "F.Cu")
		(net "FAN3_TACH_R")
	)
	(segment
		(start 156.377894 -188.526674)
		(end 156.19476 -188.526674)
		(width 0.1016)
		(layer "F.Cu")
		(net "FAN3_TACH_R")
	)
	(segment
		(start 156.19476 -185.605674)
		(end 156.19476 -185.856372)
		(width 0.1016)
		(layer "F.Cu")
		(net "FAN3_TACH_R")
	)
	(via
		(at 157.23362 -197.785228)
		(size 0.508)
		(drill 0.254)
		(layers "F.Cu" "B.Cu")
		(net "FAN3_TACH_R")
	)
	(segment
		(start 106.570526 -169.932858)
		(end 106.570526 -169.533824)
		(width 0.1016)
		(layer "F.Cu")
		(net "FAN4_TACH")
	)
	(segment
		(start 106.570526 -169.533824)
		(end 106.95432 -169.15003)
		(width 0.1016)
		(layer "F.Cu")
		(net "FAN4_TACH")
	)
	(via
		(at 106.95432 -169.15003)
		(size 0.508)
		(drill 0.254)
		(layers "F.Cu" "B.Cu")
		(net "FAN4_TACH")
	)
	(via
		(at 160.44926 -186.370976)
		(size 0.508)
		(drill 0.254)
		(layers "F.Cu" "B.Cu")
		(net "FAN4_TACH")
	)
	(segment
		(start 161.84626 -187.282074)
		(end 161.84626 -186.55157)
		(width 0.1016)
		(layer "B.Cu")
		(net "FAN4_TACH")
	)
	(segment
		(start 161.65576 -187.472574)
		(end 161.84626 -187.282074)
		(width 0.1016)
		(layer "B.Cu")
		(net "FAN4_TACH")
	)
	(segment
		(start 161.58591 -186.29122)
		(end 160.610296 -186.29122)
		(width 0.1016)
		(layer "B.Cu")
		(net "FAN4_TACH")
	)
	(segment
		(start 160.53054 -186.370976)
		(end 160.44926 -186.370976)
		(width 0.1016)
		(layer "B.Cu")
		(net "FAN4_TACH")
	)
	(segment
		(start 160.610296 -186.29122)
		(end 160.53054 -186.370976)
		(width 0.1016)
		(layer "B.Cu")
		(net "FAN4_TACH")
	)
	(segment
		(start 161.84626 -186.55157)
		(end 161.58591 -186.29122)
		(width 0.1016)
		(layer "B.Cu")
		(net "FAN4_TACH")
	)
	(segment
		(start 102.695502 -176.783746)
		(end 102.695502 -169.757598)
		(width 0.1143)
		(layer "In7.Cu")
		(net "FAN4_TACH")
	)
	(segment
		(start 106.339894 -183.182514)
		(end 105.12044 -181.96306)
		(width 0.1143)
		(layer "In7.Cu")
		(net "FAN4_TACH")
	)
	(segment
		(start 104.7115 -169.15003)
		(end 106.95432 -169.15003)
		(width 0.1143)
		(layer "In7.Cu")
		(net "FAN4_TACH")
	)
	(segment
		(start 102.695502 -169.757598)
		(end 103.40467 -169.04843)
		(width 0.1143)
		(layer "In7.Cu")
		(net "FAN4_TACH")
	)
	(segment
		(start 108.553504 -184.814464)
		(end 107.86618 -184.12714)
		(width 0.1143)
		(layer "In7.Cu")
		(net "FAN4_TACH")
	)
	(segment
		(start 107.86618 -183.665368)
		(end 107.383326 -183.182514)
		(width 0.1143)
		(layer "In7.Cu")
		(net "FAN4_TACH")
	)
	(segment
		(start 112.449864 -188.154056)
		(end 109.110272 -184.814464)
		(width 0.1143)
		(layer "In7.Cu")
		(net "FAN4_TACH")
	)
	(segment
		(start 109.110272 -184.814464)
		(end 108.553504 -184.814464)
		(width 0.1143)
		(layer "In7.Cu")
		(net "FAN4_TACH")
	)
	(segment
		(start 158.885128 -188.154056)
		(end 112.449864 -188.154056)
		(width 0.1143)
		(layer "In7.Cu")
		(net "FAN4_TACH")
	)
	(segment
		(start 103.40467 -169.04843)
		(end 104.6099 -169.04843)
		(width 0.1143)
		(layer "In7.Cu")
		(net "FAN4_TACH")
	)
	(segment
		(start 160.44926 -186.370976)
		(end 160.44926 -186.589924)
		(width 0.1143)
		(layer "In7.Cu")
		(net "FAN4_TACH")
	)
	(segment
		(start 105.12044 -180.846222)
		(end 103.3272 -179.052982)
		(width 0.1143)
		(layer "In7.Cu")
		(net "FAN4_TACH")
	)
	(segment
		(start 160.44926 -186.589924)
		(end 158.885128 -188.154056)
		(width 0.1143)
		(layer "In7.Cu")
		(net "FAN4_TACH")
	)
	(segment
		(start 105.12044 -181.96306)
		(end 105.12044 -180.846222)
		(width 0.1143)
		(layer "In7.Cu")
		(net "FAN4_TACH")
	)
	(segment
		(start 103.3272 -177.415444)
		(end 102.695502 -176.783746)
		(width 0.1143)
		(layer "In7.Cu")
		(net "FAN4_TACH")
	)
	(segment
		(start 103.3272 -179.052982)
		(end 103.3272 -177.415444)
		(width 0.1143)
		(layer "In7.Cu")
		(net "FAN4_TACH")
	)
	(segment
		(start 104.6099 -169.04843)
		(end 104.7115 -169.15003)
		(width 0.1143)
		(layer "In7.Cu")
		(net "FAN4_TACH")
	)
	(segment
		(start 107.383326 -183.182514)
		(end 106.339894 -183.182514)
		(width 0.1143)
		(layer "In7.Cu")
		(net "FAN4_TACH")
	)
	(segment
		(start 107.86618 -184.12714)
		(end 107.86618 -183.665368)
		(width 0.1143)
		(layer "In7.Cu")
		(net "FAN4_TACH")
	)
	(segment
		(start 22.032976 -47.235618)
		(end 21.104606 -47.235618)
		(width 0.508)
		(layer "F.Cu")
		(net "P5V_CRT")
	)
	(segment
		(start 15.284958 -61.689488)
		(end 14.296898 -61.689488)
		(width 0.508)
		(layer "F.Cu")
		(net "P5V_CRT")
	)
	(segment
		(start 18.918936 -60.43168)
		(end 20.102068 -60.43168)
		(width 0.508)
		(layer "F.Cu")
		(net "P5V_CRT")
	)
	(segment
		(start 23.030942 -54.318408)
		(end 21.887688 -54.318408)
		(width 0.508)
		(layer "F.Cu")
		(net "P5V_CRT")
	)
	(segment
		(start 21.44649 -59.85891)
		(end 21.18106 -59.85891)
		(width 0.508)
		(layer "F.Cu")
		(net "P5V_CRT")
	)
	(segment
		(start 22.493224 -57.844436)
		(end 21.70684 -58.63082)
		(width 0.508)
		(layer "F.Cu")
		(net "P5V_CRT")
	)
	(segment
		(start 23.046182 -57.844436)
		(end 22.493224 -57.844436)
		(width 0.508)
		(layer "F.Cu")
		(net "P5V_CRT")
	)
	(segment
		(start 21.70684 -59.59856)
		(end 21.44649 -59.85891)
		(width 0.508)
		(layer "F.Cu")
		(net "P5V_CRT")
	)
	(segment
		(start 21.59254 -42.564558)
		(end 21.59254 -43.606466)
		(width 0.508)
		(layer "F.Cu")
		(net "P5V_CRT")
	)
	(segment
		(start 22.032976 -50.732182)
		(end 23.08987 -50.732182)
		(width 0.508)
		(layer "F.Cu")
		(net "P5V_CRT")
	)
	(segment
		(start 18.21942 -45.090334)
		(end 18.21942 -45.108876)
		(width 0.381)
		(layer "F.Cu")
		(net "P5V_CRT")
	)
	(segment
		(start 21.70684 -59.146694)
		(end 21.70684 -59.59856)
		(width 0.508)
		(layer "F.Cu")
		(net "P5V_CRT")
	)
	(segment
		(start 21.70684 -58.63082)
		(end 21.70684 -59.146694)
		(width 0.508)
		(layer "F.Cu")
		(net "P5V_CRT")
	)
	(segment
		(start 18.69059 -44.619164)
		(end 18.21942 -45.090334)
		(width 0.381)
		(layer "F.Cu")
		(net "P5V_CRT")
	)
	(segment
		(start 18.91538 -44.619164)
		(end 18.69059 -44.619164)
		(width 0.381)
		(layer "F.Cu")
		(net "P5V_CRT")
	)
	(segment
		(start 21.104606 -47.235618)
		(end 20.968462 -47.099474)
		(width 0.508)
		(layer "F.Cu")
		(net "P5V_CRT")
	)
	(via
		(at 19.864578 -70.889368)
		(size 0.508)
		(drill 0.254)
		(layers "F.Cu" "B.Cu")
		(net "P5V_CRT")
	)
	(via
		(at 15.73403 -67.965066)
		(size 0.508)
		(drill 0.254)
		(layers "F.Cu" "B.Cu")
		(net "P5V_CRT")
	)
	(via
		(at 14.296898 -61.689488)
		(size 0.508)
		(drill 0.254)
		(layers "F.Cu" "B.Cu")
		(net "P5V_CRT")
	)
	(via
		(at 20.968462 -47.099474)
		(size 0.508)
		(drill 0.254)
		(layers "F.Cu" "B.Cu")
		(net "P5V_CRT")
	)
	(via
		(at 21.18106 -59.85891)
		(size 0.508)
		(drill 0.254)
		(layers "F.Cu" "B.Cu")
		(net "P5V_CRT")
	)
	(via
		(at 21.59254 -43.606466)
		(size 0.508)
		(drill 0.254)
		(layers "F.Cu" "B.Cu")
		(net "P5V_CRT")
	)
	(via
		(at 19.86788 -71.56323)
		(size 0.508)
		(drill 0.254)
		(layers "F.Cu" "B.Cu")
		(net "P5V_CRT")
	)
	(via
		(at 20.102068 -60.43168)
		(size 0.508)
		(drill 0.254)
		(layers "F.Cu" "B.Cu")
		(net "P5V_CRT")
	)
	(via
		(at 19.906742 -70.111366)
		(size 0.508)
		(drill 0.254)
		(layers "F.Cu" "B.Cu")
		(net "P5V_CRT")
	)
	(via
		(at 18.91538 -44.619164)
		(size 0.508)
		(drill 0.254)
		(layers "F.Cu" "B.Cu")
		(net "P5V_CRT")
	)
	(via
		(at 21.887688 -54.318408)
		(size 0.508)
		(drill 0.254)
		(layers "F.Cu" "B.Cu")
		(net "P5V_CRT")
	)
	(via
		(at 23.08987 -50.732182)
		(size 0.508)
		(drill 0.254)
		(layers "F.Cu" "B.Cu")
		(net "P5V_CRT")
	)
	(segment
		(start 55.25262 -181.68747)
		(end 55.05958 -181.49443)
		(width 0.1016)
		(layer "F.Cu")
		(net "PSU_ALERT_N")
	)
	(segment
		(start 54.445662 -178.805586)
		(end 53.222144 -177.582068)
		(width 0.1016)
		(layer "F.Cu")
		(net "PSU_ALERT_N")
	)
	(segment
		(start 53.222144 -177.582068)
		(end 53.222144 -176.162716)
		(width 0.1016)
		(layer "F.Cu")
		(net "PSU_ALERT_N")
	)
	(segment
		(start 55.05958 -181.059328)
		(end 54.445662 -180.44541)
		(width 0.1016)
		(layer "F.Cu")
		(net "PSU_ALERT_N")
	)
	(segment
		(start 55.05958 -181.49443)
		(end 55.05958 -181.059328)
		(width 0.1016)
		(layer "F.Cu")
		(net "PSU_ALERT_N")
	)
	(segment
		(start 54.445662 -180.44541)
		(end 54.445662 -178.805586)
		(width 0.1016)
		(layer "F.Cu")
		(net "PSU_ALERT_N")
	)
	(segment
		(start 53.222144 -176.162716)
		(end 53.549296 -175.835564)
		(width 0.1016)
		(layer "F.Cu")
		(net "PSU_ALERT_N")
	)
	(via
		(at 53.549296 -175.835564)
		(size 0.508)
		(drill 0.254)
		(layers "F.Cu" "B.Cu")
		(net "PSU_ALERT_N")
	)
	(via
		(at 55.25262 -181.68747)
		(size 0.508)
		(drill 0.254)
		(layers "F.Cu" "B.Cu")
		(net "PSU_ALERT_N")
	)
	(via
		(at 106.75366 -186.370214)
		(size 0.508)
		(drill 0.254)
		(layers "F.Cu" "B.Cu")
		(net "PSU_ALERT_N")
	)
	(segment
		(start 107.42676 -187.726574)
		(end 107.09402 -187.393834)
		(width 0.1016)
		(layer "B.Cu")
		(net "PSU_ALERT_N")
	)
	(segment
		(start 107.09402 -186.710574)
		(end 106.75366 -186.370214)
		(width 0.1016)
		(layer "B.Cu")
		(net "PSU_ALERT_N")
	)
	(segment
		(start 107.42676 -185.697114)
		(end 106.75366 -186.370214)
		(width 0.1016)
		(layer "B.Cu")
		(net "PSU_ALERT_N")
	)
	(segment
		(start 53.05425 -175.340518)
		(end 53.549296 -175.835564)
		(width 0.1016)
		(layer "B.Cu")
		(net "PSU_ALERT_N")
	)
	(segment
		(start 52.30876 -175.340518)
		(end 53.05425 -175.340518)
		(width 0.1016)
		(layer "B.Cu")
		(net "PSU_ALERT_N")
	)
	(segment
		(start 107.42676 -185.605674)
		(end 107.42676 -185.697114)
		(width 0.1016)
		(layer "B.Cu")
		(net "PSU_ALERT_N")
	)
	(segment
		(start 107.09402 -187.393834)
		(end 107.09402 -186.710574)
		(width 0.1016)
		(layer "B.Cu")
		(net "PSU_ALERT_N")
	)
	(segment
		(start 101.60254 -182.938166)
		(end 101.059234 -183.481472)
		(width 0.1143)
		(layer "In2.Cu")
		(net "PSU_ALERT_N")
	)
	(segment
		(start 101.059234 -183.481472)
		(end 97.340928 -183.481472)
		(width 0.1143)
		(layer "In2.Cu")
		(net "PSU_ALERT_N")
	)
	(segment
		(start 55.65902 -182.09387)
		(end 55.25262 -181.68747)
		(width 0.1143)
		(layer "In2.Cu")
		(net "PSU_ALERT_N")
	)
	(segment
		(start 103.321612 -182.938166)
		(end 101.60254 -182.938166)
		(width 0.1143)
		(layer "In2.Cu")
		(net "PSU_ALERT_N")
	)
	(segment
		(start 58.066432 -185.528204)
		(end 55.65902 -183.120792)
		(width 0.1143)
		(layer "In2.Cu")
		(net "PSU_ALERT_N")
	)
	(segment
		(start 97.340928 -183.481472)
		(end 96.2406 -184.5818)
		(width 0.1143)
		(layer "In2.Cu")
		(net "PSU_ALERT_N")
	)
	(segment
		(start 91.32062 -185.189876)
		(end 90.982292 -185.528204)
		(width 0.1143)
		(layer "In2.Cu")
		(net "PSU_ALERT_N")
	)
	(segment
		(start 95.88119 -187.102242)
		(end 93.763846 -187.102242)
		(width 0.1143)
		(layer "In2.Cu")
		(net "PSU_ALERT_N")
	)
	(segment
		(start 96.2406 -184.5818)
		(end 96.2406 -186.479942)
		(width 0.1143)
		(layer "In2.Cu")
		(net "PSU_ALERT_N")
	)
	(segment
		(start 90.982292 -185.528204)
		(end 58.066432 -185.528204)
		(width 0.1143)
		(layer "In2.Cu")
		(net "PSU_ALERT_N")
	)
	(segment
		(start 96.24314 -186.479942)
		(end 96.24314 -186.740292)
		(width 0.1143)
		(layer "In2.Cu")
		(net "PSU_ALERT_N")
	)
	(segment
		(start 55.65902 -183.120792)
		(end 55.65902 -182.09387)
		(width 0.1143)
		(layer "In2.Cu")
		(net "PSU_ALERT_N")
	)
	(segment
		(start 91.85148 -185.189876)
		(end 91.32062 -185.189876)
		(width 0.1143)
		(layer "In2.Cu")
		(net "PSU_ALERT_N")
	)
	(segment
		(start 106.75366 -186.370214)
		(end 103.321612 -182.938166)
		(width 0.1143)
		(layer "In2.Cu")
		(net "PSU_ALERT_N")
	)
	(segment
		(start 93.763846 -187.102242)
		(end 91.85148 -185.189876)
		(width 0.1143)
		(layer "In2.Cu")
		(net "PSU_ALERT_N")
	)
	(segment
		(start 96.2406 -186.479942)
		(end 96.24314 -186.479942)
		(width 0.1143)
		(layer "In2.Cu")
		(net "PSU_ALERT_N")
	)
	(segment
		(start 96.24314 -186.740292)
		(end 95.88119 -187.102242)
		(width 0.1143)
		(layer "In2.Cu")
		(net "PSU_ALERT_N")
	)
	(segment
		(start 158.015686 -205.199488)
		(end 158.015686 -197.012306)
		(width 0.1016)
		(layer "F.Cu")
		(net "FAN2_TACH_R")
	)
	(segment
		(start 157.85338 -188.011054)
		(end 157.33776 -188.526674)
		(width 0.1016)
		(layer "F.Cu")
		(net "FAN2_TACH_R")
	)
	(segment
		(start 157.85338 -186.030108)
		(end 157.85338 -188.011054)
		(width 0.1016)
		(layer "F.Cu")
		(net "FAN2_TACH_R")
	)
	(segment
		(start 157.428946 -185.605674)
		(end 157.85338 -186.030108)
		(width 0.1016)
		(layer "F.Cu")
		(net "FAN2_TACH_R")
	)
	(segment
		(start 157.226 -190.559182)
		(end 157.3276 -190.457582)
		(width 0.1016)
		(layer "F.Cu")
		(net "FAN2_TACH_R")
	)
	(segment
		(start 157.3276 -190.457582)
		(end 157.33776 -190.457582)
		(width 0.1016)
		(layer "F.Cu")
		(net "FAN2_TACH_R")
	)
	(segment
		(start 157.33776 -185.605674)
		(end 157.428946 -185.605674)
		(width 0.1016)
		(layer "F.Cu")
		(net "FAN2_TACH_R")
	)
	(segment
		(start 157.24632 -196.24294)
		(end 157.226 -196.24294)
		(width 0.1016)
		(layer "F.Cu")
		(net "FAN2_TACH_R")
	)
	(segment
		(start 157.226 -196.24294)
		(end 157.226 -190.559182)
		(width 0.1016)
		(layer "F.Cu")
		(net "FAN2_TACH_R")
	)
	(segment
		(start 158.015686 -197.012306)
		(end 157.24632 -196.24294)
		(width 0.1016)
		(layer "F.Cu")
		(net "FAN2_TACH_R")
	)
	(segment
		(start 157.33776 -190.457582)
		(end 157.33776 -188.526674)
		(width 0.1016)
		(layer "F.Cu")
		(net "FAN2_TACH_R")
	)
	(via
		(at 157.24632 -196.24294)
		(size 0.508)
		(drill 0.254)
		(layers "F.Cu" "B.Cu")
		(net "FAN2_TACH_R")
	)
	(segment
		(start 10.65022 -52.89804)
		(end 14.50975 -58.244232)
		(width 0.1016)
		(layer "F.Cu")
		(net "CRT_VSYNC")
	)
	(segment
		(start 15.248128 -58.885582)
		(end 15.247366 -58.886344)
		(width 0.1016)
		(layer "F.Cu")
		(net "CRT_VSYNC")
	)
	(segment
		(start 14.50975 -58.244232)
		(end 15.248128 -58.885582)
		(width 0.1016)
		(layer "F.Cu")
		(net "CRT_VSYNC")
	)
	(segment
		(start 16.223742 -59.41568)
		(end 16.683736 -59.41568)
		(width 0.1016)
		(layer "F.Cu")
		(net "CRT_VSYNC")
	)
	(segment
		(start 15.247366 -58.886344)
		(end 15.247366 -59.91352)
		(width 0.1016)
		(layer "F.Cu")
		(net "CRT_VSYNC")
	)
	(segment
		(start 15.725902 -59.91352)
		(end 16.223742 -59.41568)
		(width 0.1016)
		(layer "F.Cu")
		(net "CRT_VSYNC")
	)
	(segment
		(start 15.247366 -59.91352)
		(end 15.725902 -59.91352)
		(width 0.1016)
		(layer "F.Cu")
		(net "CRT_VSYNC")
	)
	(segment
		(start 131.260342 -54.55031)
		(end 131.203954 -54.606698)
		(width 0.1016)
		(layer "F.Cu")
		(net "UART_RTS_P4_N")
	)
	(segment
		(start 77.494638 -181.10327)
		(end 77.134974 -181.462934)
		(width 0.1016)
		(layer "F.Cu")
		(net "UART_RTS_P4_N")
	)
	(segment
		(start 77.494638 -179.874672)
		(end 77.494638 -181.10327)
		(width 0.1016)
		(layer "F.Cu")
		(net "UART_RTS_P4_N")
	)
	(segment
		(start 131.260342 -51.881024)
		(end 131.260342 -54.55031)
		(width 0.1016)
		(layer "F.Cu")
		(net "UART_RTS_P4_N")
	)
	(segment
		(start 131.230878 -51.85156)
		(end 131.260342 -51.881024)
		(width 0.1016)
		(layer "F.Cu")
		(net "UART_RTS_P4_N")
	)
	(via
		(at 134.623048 -179.988972)
		(size 0.508)
		(drill 0.254)
		(layers "F.Cu" "B.Cu")
		(net "UART_RTS_P4_N")
	)
	(via
		(at 77.134974 -181.462934)
		(size 0.508)
		(drill 0.254)
		(layers "F.Cu" "B.Cu")
		(net "UART_RTS_P4_N")
	)
	(via
		(at 157.60954 -162.414458)
		(size 0.508)
		(drill 0.254)
		(layers "F.Cu" "B.Cu")
		(net "UART_RTS_P4_N")
	)
	(via
		(at 131.203954 -54.606698)
		(size 0.508)
		(drill 0.254)
		(layers "F.Cu" "B.Cu")
		(net "UART_RTS_P4_N")
	)
	(segment
		(start 136.551162 -171.277788)
		(end 140.643102 -167.185848)
		(width 0.1016)
		(layer "B.Cu")
		(net "UART_RTS_P4_N")
	)
	(segment
		(start 141.262862 -167.185848)
		(end 146.26082 -162.18789)
		(width 0.1016)
		(layer "B.Cu")
		(net "UART_RTS_P4_N")
	)
	(segment
		(start 136.551162 -178.060858)
		(end 136.551162 -171.277788)
		(width 0.1016)
		(layer "B.Cu")
		(net "UART_RTS_P4_N")
	)
	(segment
		(start 76.392024 -181.462934)
		(end 77.134974 -181.462934)
		(width 0.1016)
		(layer "B.Cu")
		(net "UART_RTS_P4_N")
	)
	(segment
		(start 76.108052 -180.390292)
		(end 76.108052 -181.178962)
		(width 0.1016)
		(layer "B.Cu")
		(net "UART_RTS_P4_N")
	)
	(segment
		(start 140.643102 -167.185848)
		(end 141.262862 -167.185848)
		(width 0.1016)
		(layer "B.Cu")
		(net "UART_RTS_P4_N")
	)
	(segment
		(start 156.33954 -162.414458)
		(end 157.60954 -162.414458)
		(width 0.1016)
		(layer "B.Cu")
		(net "UART_RTS_P4_N")
	)
	(segment
		(start 76.108052 -181.178962)
		(end 76.392024 -181.462934)
		(width 0.1016)
		(layer "B.Cu")
		(net "UART_RTS_P4_N")
	)
	(segment
		(start 156.112972 -162.18789)
		(end 156.33954 -162.414458)
		(width 0.1016)
		(layer "B.Cu")
		(net "UART_RTS_P4_N")
	)
	(segment
		(start 134.623048 -179.988972)
		(end 136.551162 -178.060858)
		(width 0.1016)
		(layer "B.Cu")
		(net "UART_RTS_P4_N")
	)
	(segment
		(start 146.26082 -162.18789)
		(end 156.112972 -162.18789)
		(width 0.1016)
		(layer "B.Cu")
		(net "UART_RTS_P4_N")
	)
	(segment
		(start 171.854368 -159.241998)
		(end 176.338738 -159.241998)
		(width 0.1143)
		(layer "In2.Cu")
		(net "UART_RTS_P4_N")
	)
	(segment
		(start 176.338738 -159.241998)
		(end 187.949586 -147.63115)
		(width 0.1143)
		(layer "In2.Cu")
		(net "UART_RTS_P4_N")
	)
	(segment
		(start 131.203954 -54.695344)
		(end 131.203954 -54.606698)
		(width 0.1143)
		(layer "In2.Cu")
		(net "UART_RTS_P4_N")
	)
	(segment
		(start 189.252606 -124.183394)
		(end 189.252606 -98.082608)
		(width 0.1143)
		(layer "In2.Cu")
		(net "UART_RTS_P4_N")
	)
	(segment
		(start 189.252606 -141.653514)
		(end 189.252606 -125.625606)
		(width 0.1143)
		(layer "In2.Cu")
		(net "UART_RTS_P4_N")
	)
	(segment
		(start 130.2258 -66.847212)
		(end 130.2258 -55.673498)
		(width 0.1143)
		(layer "In2.Cu")
		(net "UART_RTS_P4_N")
	)
	(segment
		(start 188.849 -125.222)
		(end 188.849 -124.587)
		(width 0.1143)
		(layer "In2.Cu")
		(net "UART_RTS_P4_N")
	)
	(segment
		(start 136.16178 -74.721974)
		(end 136.16178 -73.953624)
		(width 0.1143)
		(layer "In2.Cu")
		(net "UART_RTS_P4_N")
	)
	(segment
		(start 188.849 -124.587)
		(end 189.252606 -124.183394)
		(width 0.1143)
		(layer "In2.Cu")
		(net "UART_RTS_P4_N")
	)
	(segment
		(start 133.79958 -71.591424)
		(end 133.79958 -70.420992)
		(width 0.1143)
		(layer "In2.Cu")
		(net "UART_RTS_P4_N")
	)
	(segment
		(start 157.680406 -162.343592)
		(end 158.507684 -162.343592)
		(width 0.1143)
		(layer "In2.Cu")
		(net "UART_RTS_P4_N")
	)
	(segment
		(start 189.252606 -98.082608)
		(end 178.31562 -87.145622)
		(width 0.1143)
		(layer "In2.Cu")
		(net "UART_RTS_P4_N")
	)
	(segment
		(start 136.16178 -73.953624)
		(end 133.79958 -71.591424)
		(width 0.1143)
		(layer "In2.Cu")
		(net "UART_RTS_P4_N")
	)
	(segment
		(start 158.507684 -162.343592)
		(end 159.04464 -161.806636)
		(width 0.1143)
		(layer "In2.Cu")
		(net "UART_RTS_P4_N")
	)
	(segment
		(start 169.28973 -161.806636)
		(end 171.854368 -159.241998)
		(width 0.1143)
		(layer "In2.Cu")
		(net "UART_RTS_P4_N")
	)
	(segment
		(start 148.585428 -87.145622)
		(end 136.16178 -74.721974)
		(width 0.1143)
		(layer "In2.Cu")
		(net "UART_RTS_P4_N")
	)
	(segment
		(start 187.949586 -147.63115)
		(end 187.949586 -142.956534)
		(width 0.1143)
		(layer "In2.Cu")
		(net "UART_RTS_P4_N")
	)
	(segment
		(start 187.949586 -142.956534)
		(end 189.252606 -141.653514)
		(width 0.1143)
		(layer "In2.Cu")
		(net "UART_RTS_P4_N")
	)
	(segment
		(start 130.2258 -55.673498)
		(end 131.203954 -54.695344)
		(width 0.1143)
		(layer "In2.Cu")
		(net "UART_RTS_P4_N")
	)
	(segment
		(start 159.04464 -161.806636)
		(end 169.28973 -161.806636)
		(width 0.1143)
		(layer "In2.Cu")
		(net "UART_RTS_P4_N")
	)
	(segment
		(start 133.79958 -70.420992)
		(end 130.2258 -66.847212)
		(width 0.1143)
		(layer "In2.Cu")
		(net "UART_RTS_P4_N")
	)
	(segment
		(start 189.252606 -125.625606)
		(end 188.849 -125.222)
		(width 0.1143)
		(layer "In2.Cu")
		(net "UART_RTS_P4_N")
	)
	(segment
		(start 178.31562 -87.145622)
		(end 148.585428 -87.145622)
		(width 0.1143)
		(layer "In2.Cu")
		(net "UART_RTS_P4_N")
	)
	(segment
		(start 157.60954 -162.414458)
		(end 157.680406 -162.343592)
		(width 0.1143)
		(layer "In2.Cu")
		(net "UART_RTS_P4_N")
	)
	(segment
		(start 111.589058 -182.973472)
		(end 112.25149 -182.31104)
		(width 0.1143)
		(layer "In6.Cu")
		(net "UART_RTS_P4_N")
	)
	(segment
		(start 102.865428 -181.680866)
		(end 103.383334 -182.198772)
		(width 0.1143)
		(layer "In6.Cu")
		(net "UART_RTS_P4_N")
	)
	(segment
		(start 112.25149 -182.31104)
		(end 120.73636 -182.31104)
		(width 0.1143)
		(layer "In6.Cu")
		(net "UART_RTS_P4_N")
	)
	(segment
		(start 91.80322 -182.343044)
		(end 96.939608 -182.343044)
		(width 0.1143)
		(layer "In6.Cu")
		(net "UART_RTS_P4_N")
	)
	(segment
		(start 105.608628 -183.407558)
		(end 108.387388 -183.407558)
		(width 0.1143)
		(layer "In6.Cu")
		(net "UART_RTS_P4_N")
	)
	(segment
		(start 105.3592 -183.656986)
		(end 105.608628 -183.407558)
		(width 0.1143)
		(layer "In6.Cu")
		(net "UART_RTS_P4_N")
	)
	(segment
		(start 120.73636 -182.31104)
		(end 120.991122 -182.056278)
		(width 0.1143)
		(layer "In6.Cu")
		(net "UART_RTS_P4_N")
	)
	(segment
		(start 104.99471 -183.656986)
		(end 105.3592 -183.656986)
		(width 0.1143)
		(layer "In6.Cu")
		(net "UART_RTS_P4_N")
	)
	(segment
		(start 120.991122 -182.056278)
		(end 126.928118 -182.056278)
		(width 0.1143)
		(layer "In6.Cu")
		(net "UART_RTS_P4_N")
	)
	(segment
		(start 87.773256 -184.536842)
		(end 89.32672 -182.983378)
		(width 0.1143)
		(layer "In6.Cu")
		(net "UART_RTS_P4_N")
	)
	(segment
		(start 89.32672 -182.983378)
		(end 91.162886 -182.983378)
		(width 0.1143)
		(layer "In6.Cu")
		(net "UART_RTS_P4_N")
	)
	(segment
		(start 85.241638 -184.536842)
		(end 87.773256 -184.536842)
		(width 0.1143)
		(layer "In6.Cu")
		(net "UART_RTS_P4_N")
	)
	(segment
		(start 103.568754 -182.198772)
		(end 104.7369 -183.366918)
		(width 0.1143)
		(layer "In6.Cu")
		(net "UART_RTS_P4_N")
	)
	(segment
		(start 128.995424 -179.988972)
		(end 134.623048 -179.988972)
		(width 0.1143)
		(layer "In6.Cu")
		(net "UART_RTS_P4_N")
	)
	(segment
		(start 80.045052 -183.437784)
		(end 81.204308 -184.59704)
		(width 0.1143)
		(layer "In6.Cu")
		(net "UART_RTS_P4_N")
	)
	(segment
		(start 77.134974 -181.462934)
		(end 79.109824 -183.437784)
		(width 0.1143)
		(layer "In6.Cu")
		(net "UART_RTS_P4_N")
	)
	(segment
		(start 97.137728 -182.144924)
		(end 100.369624 -182.144924)
		(width 0.1143)
		(layer "In6.Cu")
		(net "UART_RTS_P4_N")
	)
	(segment
		(start 104.7369 -183.399176)
		(end 104.99471 -183.656986)
		(width 0.1143)
		(layer "In6.Cu")
		(net "UART_RTS_P4_N")
	)
	(segment
		(start 109.875828 -182.973472)
		(end 111.589058 -182.973472)
		(width 0.1143)
		(layer "In6.Cu")
		(net "UART_RTS_P4_N")
	)
	(segment
		(start 100.369624 -182.144924)
		(end 100.833682 -181.680866)
		(width 0.1143)
		(layer "In6.Cu")
		(net "UART_RTS_P4_N")
	)
	(segment
		(start 79.109824 -183.437784)
		(end 80.045052 -183.437784)
		(width 0.1143)
		(layer "In6.Cu")
		(net "UART_RTS_P4_N")
	)
	(segment
		(start 103.383334 -182.198772)
		(end 103.568754 -182.198772)
		(width 0.1143)
		(layer "In6.Cu")
		(net "UART_RTS_P4_N")
	)
	(segment
		(start 96.939608 -182.343044)
		(end 97.137728 -182.144924)
		(width 0.1143)
		(layer "In6.Cu")
		(net "UART_RTS_P4_N")
	)
	(segment
		(start 100.833682 -181.680866)
		(end 102.865428 -181.680866)
		(width 0.1143)
		(layer "In6.Cu")
		(net "UART_RTS_P4_N")
	)
	(segment
		(start 85.18144 -184.59704)
		(end 85.241638 -184.536842)
		(width 0.1143)
		(layer "In6.Cu")
		(net "UART_RTS_P4_N")
	)
	(segment
		(start 91.162886 -182.983378)
		(end 91.80322 -182.343044)
		(width 0.1143)
		(layer "In6.Cu")
		(net "UART_RTS_P4_N")
	)
	(segment
		(start 109.273594 -183.575706)
		(end 109.875828 -182.973472)
		(width 0.1143)
		(layer "In6.Cu")
		(net "UART_RTS_P4_N")
	)
	(segment
		(start 108.387388 -183.407558)
		(end 108.555536 -183.575706)
		(width 0.1143)
		(layer "In6.Cu")
		(net "UART_RTS_P4_N")
	)
	(segment
		(start 126.928118 -182.056278)
		(end 128.995424 -179.988972)
		(width 0.1143)
		(layer "In6.Cu")
		(net "UART_RTS_P4_N")
	)
	(segment
		(start 108.555536 -183.575706)
		(end 109.273594 -183.575706)
		(width 0.1143)
		(layer "In6.Cu")
		(net "UART_RTS_P4_N")
	)
	(segment
		(start 104.7369 -183.366918)
		(end 104.7369 -183.399176)
		(width 0.1143)
		(layer "In6.Cu")
		(net "UART_RTS_P4_N")
	)
	(segment
		(start 81.204308 -184.59704)
		(end 85.18144 -184.59704)
		(width 0.1143)
		(layer "In6.Cu")
		(net "UART_RTS_P4_N")
	)
	(segment
		(start 13.260832 -52.698904)
		(end 15.425166 -52.698904)
		(width 0.1016)
		(layer "F.Cu")
		(net "CRT_HSYNC")
	)
	(segment
		(start 16.486124 -52.728622)
		(end 16.486124 -52.72913)
		(width 0.1016)
		(layer "F.Cu")
		(net "CRT_HSYNC")
	)
	(segment
		(start 15.425166 -52.698904)
		(end 15.455392 -52.72913)
		(width 0.1016)
		(layer "F.Cu")
		(net "CRT_HSYNC")
	)
	(segment
		(start 16.633444 -52.581302)
		(end 16.486124 -52.728622)
		(width 0.1016)
		(layer "F.Cu")
		(net "CRT_HSYNC")
	)
	(segment
		(start 12.7762 -52.214272)
		(end 13.260832 -52.698904)
		(width 0.1016)
		(layer "F.Cu")
		(net "CRT_HSYNC")
	)
	(segment
		(start 19.031712 -53.302408)
		(end 18.310606 -52.581302)
		(width 0.1016)
		(layer "F.Cu")
		(net "CRT_HSYNC")
	)
	(segment
		(start 9.150096 -50.609246)
		(end 11.984482 -50.609246)
		(width 0.1016)
		(layer "F.Cu")
		(net "CRT_HSYNC")
	)
	(segment
		(start 18.310606 -52.581302)
		(end 16.633444 -52.581302)
		(width 0.1016)
		(layer "F.Cu")
		(net "CRT_HSYNC")
	)
	(segment
		(start 12.7762 -51.400964)
		(end 12.7762 -52.214272)
		(width 0.1016)
		(layer "F.Cu")
		(net "CRT_HSYNC")
	)
	(segment
		(start 11.984482 -50.609246)
		(end 12.7762 -51.400964)
		(width 0.1016)
		(layer "F.Cu")
		(net "CRT_HSYNC")
	)
	(segment
		(start 20.795742 -53.302408)
		(end 19.031712 -53.302408)
		(width 0.1016)
		(layer "F.Cu")
		(net "CRT_HSYNC")
	)
	(segment
		(start 15.455392 -52.72913)
		(end 16.486124 -52.72913)
		(width 0.1016)
		(layer "F.Cu")
		(net "CRT_HSYNC")
	)
	(segment
		(start 16.060166 -53.408834)
		(end 15.432278 -54.036722)
		(width 0.1016)
		(layer "F.Cu")
		(net "CRT_B")
	)
	(segment
		(start 20.81022 -56.827674)
		(end 20.810982 -56.828436)
		(width 0.1016)
		(layer "F.Cu")
		(net "CRT_B")
	)
	(segment
		(start 13.31468 -54.036722)
		(end 10.65022 -51.372262)
		(width 0.1016)
		(layer "F.Cu")
		(net "CRT_B")
	)
	(segment
		(start 18.231612 -53.854604)
		(end 17.785842 -53.408834)
		(width 0.1016)
		(layer "F.Cu")
		(net "CRT_B")
	)
	(segment
		(start 18.231612 -53.854604)
		(end 18.443702 -53.854604)
		(width 0.1016)
		(layer "F.Cu")
		(net "CRT_B")
	)
	(segment
		(start 15.432278 -54.036722)
		(end 15.301468 -54.036722)
		(width 0.1016)
		(layer "F.Cu")
		(net "CRT_B")
	)
	(segment
		(start 15.301468 -54.036722)
		(end 13.31468 -54.036722)
		(width 0.1016)
		(layer "F.Cu")
		(net "CRT_B")
	)
	(segment
		(start 18.443702 -53.854604)
		(end 20.81022 -56.221122)
		(width 0.1016)
		(layer "F.Cu")
		(net "CRT_B")
	)
	(segment
		(start 17.785842 -53.408834)
		(end 16.060166 -53.408834)
		(width 0.1016)
		(layer "F.Cu")
		(net "CRT_B")
	)
	(segment
		(start 20.81022 -56.221122)
		(end 20.81022 -56.827674)
		(width 0.1016)
		(layer "F.Cu")
		(net "CRT_B")
	)
	(segment
		(start 104.23017 -167.975026)
		(end 104.380792 -167.975026)
		(width 0.1016)
		(layer "F.Cu")
		(net "I2C_SDA_FANCTRL2_R")
	)
	(segment
		(start 103.86949 -168.335706)
		(end 104.23017 -167.975026)
		(width 0.1016)
		(layer "F.Cu")
		(net "I2C_SDA_FANCTRL2_R")
	)
	(segment
		(start 104.380792 -167.975026)
		(end 104.643428 -167.71239)
		(width 0.1016)
		(layer "F.Cu")
		(net "I2C_SDA_FANCTRL2_R")
	)
	(segment
		(start 103.214932 -168.335706)
		(end 103.86949 -168.335706)
		(width 0.1016)
		(layer "F.Cu")
		(net "I2C_SDA_FANCTRL2_R")
	)
	(via
		(at 104.643428 -167.71239)
		(size 0.508)
		(drill 0.254)
		(layers "F.Cu" "B.Cu")
		(net "I2C_SDA_FANCTRL2_R")
	)
	(segment
		(start 111.955072 -165.362128)
		(end 106.99369 -165.362128)
		(width 0.1016)
		(layer "B.Cu")
		(net "I2C_SDA_FANCTRL2_R")
	)
	(segment
		(start 112.4712 -164.846)
		(end 111.955072 -165.362128)
		(width 0.1016)
		(layer "B.Cu")
		(net "I2C_SDA_FANCTRL2_R")
	)
	(segment
		(start 106.99369 -165.362128)
		(end 104.643428 -167.71239)
		(width 0.1016)
		(layer "B.Cu")
		(net "I2C_SDA_FANCTRL2_R")
	)
	(segment
		(start 114.092482 -165.291516)
		(end 113.646966 -164.846)
		(width 0.1016)
		(layer "B.Cu")
		(net "I2C_SDA_FANCTRL2_R")
	)
	(segment
		(start 113.646966 -164.846)
		(end 112.4712 -164.846)
		(width 0.1016)
		(layer "B.Cu")
		(net "I2C_SDA_FANCTRL2_R")
	)
	(segment
		(start 94.051882 -164.123624)
		(end 93.18498 -164.123624)
		(width 0.1016)
		(layer "F.Cu")
		(net "FAN6_TACH")
	)
	(segment
		(start 92.96146 -163.900104)
		(end 92.96146 -163.899088)
		(width 0.1016)
		(layer "F.Cu")
		(net "FAN6_TACH")
	)
	(segment
		(start 93.18498 -164.123624)
		(end 92.96146 -163.900104)
		(width 0.1016)
		(layer "F.Cu")
		(net "FAN6_TACH")
	)
	(via
		(at 160.03016 -189.258956)
		(size 0.508)
		(drill 0.254)
		(layers "F.Cu" "B.Cu")
		(net "FAN6_TACH")
	)
	(via
		(at 92.96146 -163.899088)
		(size 0.508)
		(drill 0.254)
		(layers "F.Cu" "B.Cu")
		(net "FAN6_TACH")
	)
	(segment
		(start 160.05556 -187.592716)
		(end 159.935418 -187.472574)
		(width 0.1016)
		(layer "B.Cu")
		(net "FAN6_TACH")
	)
	(segment
		(start 160.03016 -189.258956)
		(end 160.05556 -189.233556)
		(width 0.1016)
		(layer "B.Cu")
		(net "FAN6_TACH")
	)
	(segment
		(start 160.05556 -189.233556)
		(end 160.05556 -187.592716)
		(width 0.1016)
		(layer "B.Cu")
		(net "FAN6_TACH")
	)
	(segment
		(start 159.935418 -187.472574)
		(end 159.62376 -187.472574)
		(width 0.1016)
		(layer "B.Cu")
		(net "FAN6_TACH")
	)
	(segment
		(start 107.941872 -184.780682)
		(end 110.16234 -187.00115)
		(width 0.1143)
		(layer "In7.Cu")
		(net "FAN6_TACH")
	)
	(segment
		(start 92.96146 -163.899088)
		(end 93.185996 -164.123624)
		(width 0.1143)
		(layer "In7.Cu")
		(net "FAN6_TACH")
	)
	(segment
		(start 111.54791 -188.491622)
		(end 159.262826 -188.491622)
		(width 0.1143)
		(layer "In7.Cu")
		(net "FAN6_TACH")
	)
	(segment
		(start 110.16234 -187.106052)
		(end 111.54791 -188.491622)
		(width 0.1143)
		(layer "In7.Cu")
		(net "FAN6_TACH")
	)
	(segment
		(start 94.633796 -164.123624)
		(end 101.16185 -170.651678)
		(width 0.1143)
		(layer "In7.Cu")
		(net "FAN6_TACH")
	)
	(segment
		(start 101.16185 -170.651678)
		(end 101.16185 -175.082454)
		(width 0.1143)
		(layer "In7.Cu")
		(net "FAN6_TACH")
	)
	(segment
		(start 101.16185 -175.082454)
		(end 101.118416 -175.125888)
		(width 0.1143)
		(layer "In7.Cu")
		(net "FAN6_TACH")
	)
	(segment
		(start 103.0605 -177.531268)
		(end 103.0605 -179.164488)
		(width 0.1143)
		(layer "In7.Cu")
		(net "FAN6_TACH")
	)
	(segment
		(start 105.61447 -183.488076)
		(end 106.907076 -184.780682)
		(width 0.1143)
		(layer "In7.Cu")
		(net "FAN6_TACH")
	)
	(segment
		(start 104.471724 -181.81828)
		(end 105.61447 -182.961026)
		(width 0.1143)
		(layer "In7.Cu")
		(net "FAN6_TACH")
	)
	(segment
		(start 103.0605 -179.164488)
		(end 104.471724 -180.575712)
		(width 0.1143)
		(layer "In7.Cu")
		(net "FAN6_TACH")
	)
	(segment
		(start 101.118416 -175.125888)
		(end 101.118416 -175.589184)
		(width 0.1143)
		(layer "In7.Cu")
		(net "FAN6_TACH")
	)
	(segment
		(start 101.118416 -175.589184)
		(end 103.0605 -177.531268)
		(width 0.1143)
		(layer "In7.Cu")
		(net "FAN6_TACH")
	)
	(segment
		(start 105.61447 -182.961026)
		(end 105.61447 -183.488076)
		(width 0.1143)
		(layer "In7.Cu")
		(net "FAN6_TACH")
	)
	(segment
		(start 110.16234 -187.00115)
		(end 110.16234 -187.106052)
		(width 0.1143)
		(layer "In7.Cu")
		(net "FAN6_TACH")
	)
	(segment
		(start 104.471724 -180.575712)
		(end 104.471724 -181.81828)
		(width 0.1143)
		(layer "In7.Cu")
		(net "FAN6_TACH")
	)
	(segment
		(start 93.185996 -164.123624)
		(end 94.633796 -164.123624)
		(width 0.1143)
		(layer "In7.Cu")
		(net "FAN6_TACH")
	)
	(segment
		(start 106.907076 -184.780682)
		(end 107.941872 -184.780682)
		(width 0.1143)
		(layer "In7.Cu")
		(net "FAN6_TACH")
	)
	(segment
		(start 159.262826 -188.491622)
		(end 160.03016 -189.258956)
		(width 0.1143)
		(layer "In7.Cu")
		(net "FAN6_TACH")
	)
	(segment
		(start 52.17414 -166.8399)
		(end 52.17414 -167.9448)
		(width 0.1016)
		(layer "F.Cu")
		(net "SMB_PCH_SCL")
	)
	(segment
		(start 150.478998 -141.532864)
		(end 150.478998 -142.48638)
		(width 0.1016)
		(layer "F.Cu")
		(net "SMB_PCH_SCL")
	)
	(segment
		(start 151.843486 -140.168376)
		(end 150.478998 -141.532864)
		(width 0.1016)
		(layer "F.Cu")
		(net "SMB_PCH_SCL")
	)
	(segment
		(start 154.0002 -140.168376)
		(end 151.843486 -140.168376)
		(width 0.1016)
		(layer "F.Cu")
		(net "SMB_PCH_SCL")
	)
	(via
		(at 52.17414 -167.9448)
		(size 0.508)
		(drill 0.254)
		(layers "F.Cu" "B.Cu")
		(net "SMB_PCH_SCL")
	)
	(via
		(at 154.0002 -140.168376)
		(size 0.508)
		(drill 0.254)
		(layers "F.Cu" "B.Cu")
		(net "SMB_PCH_SCL")
	)
	(segment
		(start 75.03414 -166.684706)
		(end 74.032364 -167.686482)
		(width 0.1143)
		(layer "In2.Cu")
		(net "SMB_PCH_SCL")
	)
	(segment
		(start 59.80938 -168.411144)
		(end 59.343036 -167.9448)
		(width 0.1143)
		(layer "In2.Cu")
		(net "SMB_PCH_SCL")
	)
	(segment
		(start 146.933158 -162.239452)
		(end 144.42694 -162.239452)
		(width 0.1143)
		(layer "In2.Cu")
		(net "SMB_PCH_SCL")
	)
	(segment
		(start 118.215156 -167.067738)
		(end 116.141246 -167.067738)
		(width 0.1143)
		(layer "In2.Cu")
		(net "SMB_PCH_SCL")
	)
	(segment
		(start 66.773806 -168.48201)
		(end 66.70294 -168.411144)
		(width 0.1143)
		(layer "In2.Cu")
		(net "SMB_PCH_SCL")
	)
	(segment
		(start 154.254454 -150.632414)
		(end 154.295094 -150.673054)
		(width 0.1143)
		(layer "In2.Cu")
		(net "SMB_PCH_SCL")
	)
	(segment
		(start 101.061012 -168.461944)
		(end 101.05644 -168.466516)
		(width 0.1143)
		(layer "In2.Cu")
		(net "SMB_PCH_SCL")
	)
	(segment
		(start 111.70158 -168.035224)
		(end 105.479342 -168.035224)
		(width 0.1143)
		(layer "In2.Cu")
		(net "SMB_PCH_SCL")
	)
	(segment
		(start 100.523802 -168.466516)
		(end 98.684842 -166.627556)
		(width 0.1143)
		(layer "In2.Cu")
		(net "SMB_PCH_SCL")
	)
	(segment
		(start 87.23122 -164.592508)
		(end 86.19236 -164.592508)
		(width 0.1143)
		(layer "In2.Cu")
		(net "SMB_PCH_SCL")
	)
	(segment
		(start 125.74397 -163.525454)
		(end 125.07722 -162.858704)
		(width 0.1143)
		(layer "In2.Cu")
		(net "SMB_PCH_SCL")
	)
	(segment
		(start 91.978734 -166.51859)
		(end 89.157302 -166.51859)
		(width 0.1143)
		(layer "In2.Cu")
		(net "SMB_PCH_SCL")
	)
	(segment
		(start 120.81002 -166.00551)
		(end 119.329454 -167.486076)
		(width 0.1143)
		(layer "In2.Cu")
		(net "SMB_PCH_SCL")
	)
	(segment
		(start 89.157302 -166.51859)
		(end 87.23122 -164.592508)
		(width 0.1143)
		(layer "In2.Cu")
		(net "SMB_PCH_SCL")
	)
	(segment
		(start 127.118364 -164.194998)
		(end 126.44882 -163.525454)
		(width 0.1143)
		(layer "In2.Cu")
		(net "SMB_PCH_SCL")
	)
	(segment
		(start 154.635708 -143.8148)
		(end 154.635708 -144.180052)
		(width 0.1143)
		(layer "In2.Cu")
		(net "SMB_PCH_SCL")
	)
	(segment
		(start 154.635708 -144.180052)
		(end 154.254454 -144.561306)
		(width 0.1143)
		(layer "In2.Cu")
		(net "SMB_PCH_SCL")
	)
	(segment
		(start 143.829278 -162.837114)
		(end 141.250924 -162.837114)
		(width 0.1143)
		(layer "In2.Cu")
		(net "SMB_PCH_SCL")
	)
	(segment
		(start 76.838556 -164.741606)
		(end 75.03414 -166.546022)
		(width 0.1143)
		(layer "In2.Cu")
		(net "SMB_PCH_SCL")
	)
	(segment
		(start 154.19832 -141.208252)
		(end 154.373072 -141.383004)
		(width 0.1143)
		(layer "In2.Cu")
		(net "SMB_PCH_SCL")
	)
	(segment
		(start 154.254454 -144.561306)
		(end 154.254454 -150.632414)
		(width 0.1143)
		(layer "In2.Cu")
		(net "SMB_PCH_SCL")
	)
	(segment
		(start 92.49791 -165.999414)
		(end 91.978734 -166.51859)
		(width 0.1143)
		(layer "In2.Cu")
		(net "SMB_PCH_SCL")
	)
	(segment
		(start 128.694434 -164.194998)
		(end 127.118364 -164.194998)
		(width 0.1143)
		(layer "In2.Cu")
		(net "SMB_PCH_SCL")
	)
	(segment
		(start 84.175346 -164.103304)
		(end 84.13242 -164.060378)
		(width 0.1143)
		(layer "In2.Cu")
		(net "SMB_PCH_SCL")
	)
	(segment
		(start 121.664476 -162.318446)
		(end 120.81002 -163.172902)
		(width 0.1143)
		(layer "In2.Cu")
		(net "SMB_PCH_SCL")
	)
	(segment
		(start 74.032364 -167.686482)
		(end 73.2663 -167.686482)
		(width 0.1143)
		(layer "In2.Cu")
		(net "SMB_PCH_SCL")
	)
	(segment
		(start 134.982966 -164.27704)
		(end 129.318004 -164.27704)
		(width 0.1143)
		(layer "In2.Cu")
		(net "SMB_PCH_SCL")
	)
	(segment
		(start 101.05644 -168.466516)
		(end 100.523802 -168.466516)
		(width 0.1143)
		(layer "In2.Cu")
		(net "SMB_PCH_SCL")
	)
	(segment
		(start 129.318004 -164.27704)
		(end 129.23012 -164.364924)
		(width 0.1143)
		(layer "In2.Cu")
		(net "SMB_PCH_SCL")
	)
	(segment
		(start 154.295094 -154.877516)
		(end 146.933158 -162.239452)
		(width 0.1143)
		(layer "In2.Cu")
		(net "SMB_PCH_SCL")
	)
	(segment
		(start 81.711292 -164.741606)
		(end 76.838556 -164.741606)
		(width 0.1143)
		(layer "In2.Cu")
		(net "SMB_PCH_SCL")
	)
	(segment
		(start 75.03414 -166.546022)
		(end 75.03414 -166.684706)
		(width 0.1143)
		(layer "In2.Cu")
		(net "SMB_PCH_SCL")
	)
	(segment
		(start 154.19832 -140.366496)
		(end 154.19832 -141.208252)
		(width 0.1143)
		(layer "In2.Cu")
		(net "SMB_PCH_SCL")
	)
	(segment
		(start 105.479342 -168.035224)
		(end 105.052622 -168.461944)
		(width 0.1143)
		(layer "In2.Cu")
		(net "SMB_PCH_SCL")
	)
	(segment
		(start 115.646962 -166.573454)
		(end 113.16335 -166.573454)
		(width 0.1143)
		(layer "In2.Cu")
		(net "SMB_PCH_SCL")
	)
	(segment
		(start 120.81002 -163.172902)
		(end 120.81002 -166.00551)
		(width 0.1143)
		(layer "In2.Cu")
		(net "SMB_PCH_SCL")
	)
	(segment
		(start 71.888604 -169.062654)
		(end 70.03669 -169.062654)
		(width 0.1143)
		(layer "In2.Cu")
		(net "SMB_PCH_SCL")
	)
	(segment
		(start 66.70294 -168.411144)
		(end 59.80938 -168.411144)
		(width 0.1143)
		(layer "In2.Cu")
		(net "SMB_PCH_SCL")
	)
	(segment
		(start 123.765564 -162.318446)
		(end 121.664476 -162.318446)
		(width 0.1143)
		(layer "In2.Cu")
		(net "SMB_PCH_SCL")
	)
	(segment
		(start 95.08617 -166.627556)
		(end 94.458028 -165.999414)
		(width 0.1143)
		(layer "In2.Cu")
		(net "SMB_PCH_SCL")
	)
	(segment
		(start 126.44882 -163.525454)
		(end 125.74397 -163.525454)
		(width 0.1143)
		(layer "In2.Cu")
		(net "SMB_PCH_SCL")
	)
	(segment
		(start 124.305822 -162.858704)
		(end 123.765564 -162.318446)
		(width 0.1143)
		(layer "In2.Cu")
		(net "SMB_PCH_SCL")
	)
	(segment
		(start 85.703156 -164.103304)
		(end 84.175346 -164.103304)
		(width 0.1143)
		(layer "In2.Cu")
		(net "SMB_PCH_SCL")
	)
	(segment
		(start 105.052622 -168.461944)
		(end 101.061012 -168.461944)
		(width 0.1143)
		(layer "In2.Cu")
		(net "SMB_PCH_SCL")
	)
	(segment
		(start 84.13242 -164.060378)
		(end 82.39252 -164.060378)
		(width 0.1143)
		(layer "In2.Cu")
		(net "SMB_PCH_SCL")
	)
	(segment
		(start 94.458028 -165.999414)
		(end 92.49791 -165.999414)
		(width 0.1143)
		(layer "In2.Cu")
		(net "SMB_PCH_SCL")
	)
	(segment
		(start 82.39252 -164.060378)
		(end 81.711292 -164.741606)
		(width 0.1143)
		(layer "In2.Cu")
		(net "SMB_PCH_SCL")
	)
	(segment
		(start 86.19236 -164.592508)
		(end 85.703156 -164.103304)
		(width 0.1143)
		(layer "In2.Cu")
		(net "SMB_PCH_SCL")
	)
	(segment
		(start 73.2663 -167.686482)
		(end 71.888604 -169.062654)
		(width 0.1143)
		(layer "In2.Cu")
		(net "SMB_PCH_SCL")
	)
	(segment
		(start 154.0002 -140.168376)
		(end 154.19832 -140.366496)
		(width 0.1143)
		(layer "In2.Cu")
		(net "SMB_PCH_SCL")
	)
	(segment
		(start 118.633494 -167.486076)
		(end 118.215156 -167.067738)
		(width 0.1143)
		(layer "In2.Cu")
		(net "SMB_PCH_SCL")
	)
	(segment
		(start 154.373072 -141.383004)
		(end 154.373072 -143.552164)
		(width 0.1143)
		(layer "In2.Cu")
		(net "SMB_PCH_SCL")
	)
	(segment
		(start 69.456046 -168.48201)
		(end 66.773806 -168.48201)
		(width 0.1143)
		(layer "In2.Cu")
		(net "SMB_PCH_SCL")
	)
	(segment
		(start 140.58138 -163.506658)
		(end 135.753348 -163.506658)
		(width 0.1143)
		(layer "In2.Cu")
		(net "SMB_PCH_SCL")
	)
	(segment
		(start 116.141246 -167.067738)
		(end 115.646962 -166.573454)
		(width 0.1143)
		(layer "In2.Cu")
		(net "SMB_PCH_SCL")
	)
	(segment
		(start 141.250924 -162.837114)
		(end 140.58138 -163.506658)
		(width 0.1143)
		(layer "In2.Cu")
		(net "SMB_PCH_SCL")
	)
	(segment
		(start 113.16335 -166.573454)
		(end 111.70158 -168.035224)
		(width 0.1143)
		(layer "In2.Cu")
		(net "SMB_PCH_SCL")
	)
	(segment
		(start 59.343036 -167.9448)
		(end 52.17414 -167.9448)
		(width 0.1143)
		(layer "In2.Cu")
		(net "SMB_PCH_SCL")
	)
	(segment
		(start 70.03669 -169.062654)
		(end 69.456046 -168.48201)
		(width 0.1143)
		(layer "In2.Cu")
		(net "SMB_PCH_SCL")
	)
	(segment
		(start 129.23012 -164.364924)
		(end 128.86436 -164.364924)
		(width 0.1143)
		(layer "In2.Cu")
		(net "SMB_PCH_SCL")
	)
	(segment
		(start 154.373072 -143.552164)
		(end 154.635708 -143.8148)
		(width 0.1143)
		(layer "In2.Cu")
		(net "SMB_PCH_SCL")
	)
	(segment
		(start 125.07722 -162.858704)
		(end 124.305822 -162.858704)
		(width 0.1143)
		(layer "In2.Cu")
		(net "SMB_PCH_SCL")
	)
	(segment
		(start 119.329454 -167.486076)
		(end 118.633494 -167.486076)
		(width 0.1143)
		(layer "In2.Cu")
		(net "SMB_PCH_SCL")
	)
	(segment
		(start 98.684842 -166.627556)
		(end 95.08617 -166.627556)
		(width 0.1143)
		(layer "In2.Cu")
		(net "SMB_PCH_SCL")
	)
	(segment
		(start 154.295094 -150.673054)
		(end 154.295094 -154.877516)
		(width 0.1143)
		(layer "In2.Cu")
		(net "SMB_PCH_SCL")
	)
	(segment
		(start 144.42694 -162.239452)
		(end 143.829278 -162.837114)
		(width 0.1143)
		(layer "In2.Cu")
		(net "SMB_PCH_SCL")
	)
	(segment
		(start 135.753348 -163.506658)
		(end 134.982966 -164.27704)
		(width 0.1143)
		(layer "In2.Cu")
		(net "SMB_PCH_SCL")
	)
	(segment
		(start 128.86436 -164.364924)
		(end 128.694434 -164.194998)
		(width 0.1143)
		(layer "In2.Cu")
		(net "SMB_PCH_SCL")
	)
	(segment
		(start 99.21621 -168.335706)
		(end 99.584764 -168.70426)
		(width 0.1016)
		(layer "F.Cu")
		(net "I2C_SCL_FANCTRL2_R")
	)
	(segment
		(start 103.943912 -169.004996)
		(end 105.177336 -169.004996)
		(width 0.1016)
		(layer "F.Cu")
		(net "I2C_SCL_FANCTRL2_R")
	)
	(segment
		(start 97.728532 -168.335706)
		(end 99.21621 -168.335706)
		(width 0.1016)
		(layer "F.Cu")
		(net "I2C_SCL_FANCTRL2_R")
	)
	(segment
		(start 105.177336 -169.004996)
		(end 105.458006 -168.724326)
		(width 0.1016)
		(layer "F.Cu")
		(net "I2C_SCL_FANCTRL2_R")
	)
	(segment
		(start 99.584764 -168.70426)
		(end 103.643176 -168.70426)
		(width 0.1016)
		(layer "F.Cu")
		(net "I2C_SCL_FANCTRL2_R")
	)
	(segment
		(start 105.458006 -168.724326)
		(end 105.458006 -168.707562)
		(width 0.1016)
		(layer "F.Cu")
		(net "I2C_SCL_FANCTRL2_R")
	)
	(segment
		(start 105.458006 -168.707562)
		(end 105.465372 -168.707562)
		(width 0.1016)
		(layer "F.Cu")
		(net "I2C_SCL_FANCTRL2_R")
	)
	(segment
		(start 103.643176 -168.70426)
		(end 103.943912 -169.004996)
		(width 0.1016)
		(layer "F.Cu")
		(net "I2C_SCL_FANCTRL2_R")
	)
	(via
		(at 105.465372 -168.707562)
		(size 0.508)
		(drill 0.254)
		(layers "F.Cu" "B.Cu")
		(net "I2C_SCL_FANCTRL2_R")
	)
	(segment
		(start 107.368848 -166.225728)
		(end 107.206288 -166.225728)
		(width 0.1016)
		(layer "B.Cu")
		(net "I2C_SCL_FANCTRL2_R")
	)
	(segment
		(start 111.397034 -166.08933)
		(end 107.505246 -166.08933)
		(width 0.1016)
		(layer "B.Cu")
		(net "I2C_SCL_FANCTRL2_R")
	)
	(segment
		(start 115.12169 -165.779704)
		(end 114.796824 -166.10457)
		(width 0.1016)
		(layer "B.Cu")
		(net "I2C_SCL_FANCTRL2_R")
	)
	(segment
		(start 111.412274 -166.10457)
		(end 111.397034 -166.08933)
		(width 0.1016)
		(layer "B.Cu")
		(net "I2C_SCL_FANCTRL2_R")
	)
	(segment
		(start 107.505246 -166.08933)
		(end 107.368848 -166.225728)
		(width 0.1016)
		(layer "B.Cu")
		(net "I2C_SCL_FANCTRL2_R")
	)
	(segment
		(start 105.46334 -168.707562)
		(end 105.465372 -168.707562)
		(width 0.1016)
		(layer "B.Cu")
		(net "I2C_SCL_FANCTRL2_R")
	)
	(segment
		(start 115.12169 -165.28542)
		(end 115.12169 -165.779704)
		(width 0.1016)
		(layer "B.Cu")
		(net "I2C_SCL_FANCTRL2_R")
	)
	(segment
		(start 107.206288 -166.225728)
		(end 105.46334 -167.968676)
		(width 0.1016)
		(layer "B.Cu")
		(net "I2C_SCL_FANCTRL2_R")
	)
	(segment
		(start 105.46334 -167.968676)
		(end 105.46334 -168.707562)
		(width 0.1016)
		(layer "B.Cu")
		(net "I2C_SCL_FANCTRL2_R")
	)
	(segment
		(start 114.796824 -166.10457)
		(end 111.412274 -166.10457)
		(width 0.1016)
		(layer "B.Cu")
		(net "I2C_SCL_FANCTRL2_R")
	)
	(segment
		(start 49.88814 -166.8399)
		(end 49.88814 -167.654732)
		(width 0.1016)
		(layer "F.Cu")
		(net "SMB_PCH_SDA")
	)
	(segment
		(start 154.542998 -142.48638)
		(end 154.542998 -142.042134)
		(width 0.1016)
		(layer "F.Cu")
		(net "SMB_PCH_SDA")
	)
	(segment
		(start 154.542998 -142.042134)
		(end 154.95778 -141.627352)
		(width 0.1016)
		(layer "F.Cu")
		(net "SMB_PCH_SDA")
	)
	(segment
		(start 49.88814 -167.654732)
		(end 50.67554 -168.442132)
		(width 0.1016)
		(layer "F.Cu")
		(net "SMB_PCH_SDA")
	)
	(via
		(at 50.67554 -168.442132)
		(size 0.508)
		(drill 0.254)
		(layers "F.Cu" "B.Cu")
		(net "SMB_PCH_SDA")
	)
	(via
		(at 154.95778 -141.627352)
		(size 0.508)
		(drill 0.254)
		(layers "F.Cu" "B.Cu")
		(net "SMB_PCH_SDA")
	)
	(segment
		(start 154.68346 -155.010104)
		(end 154.68346 -147.730718)
		(width 0.1143)
		(layer "In2.Cu")
		(net "SMB_PCH_SDA")
	)
	(segment
		(start 85.584284 -164.507672)
		(end 86.03742 -164.960808)
		(width 0.1143)
		(layer "In2.Cu")
		(net "SMB_PCH_SDA")
	)
	(segment
		(start 99.153472 -168.12006)
		(end 99.868228 -168.834816)
		(width 0.1143)
		(layer "In2.Cu")
		(net "SMB_PCH_SDA")
	)
	(segment
		(start 154.68346 -147.730718)
		(end 155.586684 -146.827494)
		(width 0.1143)
		(layer "In2.Cu")
		(net "SMB_PCH_SDA")
	)
	(segment
		(start 76.99248 -166.70274)
		(end 76.99248 -165.740842)
		(width 0.1143)
		(layer "In2.Cu")
		(net "SMB_PCH_SDA")
	)
	(segment
		(start 73.74636 -168.638474)
		(end 74.754994 -167.62984)
		(width 0.1143)
		(layer "In2.Cu")
		(net "SMB_PCH_SDA")
	)
	(segment
		(start 112.91697 -167.413178)
		(end 113.28146 -167.413178)
		(width 0.1143)
		(layer "In2.Cu")
		(net "SMB_PCH_SDA")
	)
	(segment
		(start 113.318036 -167.449754)
		(end 118.075456 -167.449754)
		(width 0.1143)
		(layer "In2.Cu")
		(net "SMB_PCH_SDA")
	)
	(segment
		(start 119.482108 -167.854376)
		(end 121.329958 -166.006526)
		(width 0.1143)
		(layer "In2.Cu")
		(net "SMB_PCH_SDA")
	)
	(segment
		(start 155.586684 -143.707866)
		(end 154.95778 -143.078962)
		(width 0.1143)
		(layer "In2.Cu")
		(net "SMB_PCH_SDA")
	)
	(segment
		(start 90.856562 -166.88689)
		(end 91.67622 -167.706548)
		(width 0.1143)
		(layer "In2.Cu")
		(net "SMB_PCH_SDA")
	)
	(segment
		(start 118.075456 -167.449754)
		(end 118.480078 -167.854376)
		(width 0.1143)
		(layer "In2.Cu")
		(net "SMB_PCH_SDA")
	)
	(segment
		(start 97.74936 -168.12006)
		(end 99.153472 -168.12006)
		(width 0.1143)
		(layer "In2.Cu")
		(net "SMB_PCH_SDA")
	)
	(segment
		(start 50.67554 -168.442132)
		(end 50.99304 -168.124632)
		(width 0.1143)
		(layer "In2.Cu")
		(net "SMB_PCH_SDA")
	)
	(segment
		(start 58.725816 -168.442132)
		(end 59.622944 -169.33926)
		(width 0.1143)
		(layer "In2.Cu")
		(net "SMB_PCH_SDA")
	)
	(segment
		(start 93.633544 -167.447468)
		(end 95.672656 -167.447468)
		(width 0.1143)
		(layer "In2.Cu")
		(net "SMB_PCH_SDA")
	)
	(segment
		(start 101.38156 -168.834816)
		(end 101.386132 -168.830244)
		(width 0.1143)
		(layer "In2.Cu")
		(net "SMB_PCH_SDA")
	)
	(segment
		(start 135.184388 -164.64534)
		(end 135.95477 -163.874958)
		(width 0.1143)
		(layer "In2.Cu")
		(net "SMB_PCH_SDA")
	)
	(segment
		(start 97.730564 -168.138856)
		(end 97.74936 -168.12006)
		(width 0.1143)
		(layer "In2.Cu")
		(net "SMB_PCH_SDA")
	)
	(segment
		(start 74.754994 -167.62984)
		(end 76.06538 -167.62984)
		(width 0.1143)
		(layer "In2.Cu")
		(net "SMB_PCH_SDA")
	)
	(segment
		(start 50.99304 -168.124632)
		(end 51.623214 -168.124632)
		(width 0.1143)
		(layer "In2.Cu")
		(net "SMB_PCH_SDA")
	)
	(segment
		(start 51.623214 -168.124632)
		(end 51.940714 -168.442132)
		(width 0.1143)
		(layer "In2.Cu")
		(net "SMB_PCH_SDA")
	)
	(segment
		(start 76.06538 -167.62984)
		(end 76.99248 -166.70274)
		(width 0.1143)
		(layer "In2.Cu")
		(net "SMB_PCH_SDA")
	)
	(segment
		(start 77.56144 -165.171882)
		(end 81.804256 -165.171882)
		(width 0.1143)
		(layer "In2.Cu")
		(net "SMB_PCH_SDA")
	)
	(segment
		(start 84.056474 -164.507672)
		(end 85.584284 -164.507672)
		(width 0.1143)
		(layer "In2.Cu")
		(net "SMB_PCH_SDA")
	)
	(segment
		(start 59.622944 -169.33926)
		(end 67.63258 -169.33926)
		(width 0.1143)
		(layer "In2.Cu")
		(net "SMB_PCH_SDA")
	)
	(segment
		(start 87.076026 -164.960808)
		(end 89.002108 -166.88689)
		(width 0.1143)
		(layer "In2.Cu")
		(net "SMB_PCH_SDA")
	)
	(segment
		(start 101.386132 -168.830244)
		(end 104.31145 -168.830244)
		(width 0.1143)
		(layer "In2.Cu")
		(net "SMB_PCH_SDA")
	)
	(segment
		(start 147.085812 -162.607752)
		(end 154.68346 -155.010104)
		(width 0.1143)
		(layer "In2.Cu")
		(net "SMB_PCH_SDA")
	)
	(segment
		(start 144.58188 -162.607752)
		(end 147.085812 -162.607752)
		(width 0.1143)
		(layer "In2.Cu")
		(net "SMB_PCH_SDA")
	)
	(segment
		(start 123.308618 -162.686746)
		(end 123.848876 -163.227004)
		(width 0.1143)
		(layer "In2.Cu")
		(net "SMB_PCH_SDA")
	)
	(segment
		(start 96.364044 -168.138856)
		(end 97.730564 -168.138856)
		(width 0.1143)
		(layer "In2.Cu")
		(net "SMB_PCH_SDA")
	)
	(segment
		(start 86.03742 -164.960808)
		(end 87.076026 -164.960808)
		(width 0.1143)
		(layer "In2.Cu")
		(net "SMB_PCH_SDA")
	)
	(segment
		(start 121.81713 -162.686746)
		(end 123.308618 -162.686746)
		(width 0.1143)
		(layer "In2.Cu")
		(net "SMB_PCH_SDA")
	)
	(segment
		(start 128.27254 -164.563298)
		(end 128.442466 -164.733224)
		(width 0.1143)
		(layer "In2.Cu")
		(net "SMB_PCH_SDA")
	)
	(segment
		(start 113.28146 -167.413178)
		(end 113.318036 -167.449754)
		(width 0.1143)
		(layer "In2.Cu")
		(net "SMB_PCH_SDA")
	)
	(segment
		(start 68.531486 -170.238166)
		(end 71.245222 -170.238166)
		(width 0.1143)
		(layer "In2.Cu")
		(net "SMB_PCH_SDA")
	)
	(segment
		(start 106.8451 -168.63949)
		(end 111.690404 -168.63949)
		(width 0.1143)
		(layer "In2.Cu")
		(net "SMB_PCH_SDA")
	)
	(segment
		(start 104.626918 -169.145712)
		(end 106.338878 -169.145712)
		(width 0.1143)
		(layer "In2.Cu")
		(net "SMB_PCH_SDA")
	)
	(segment
		(start 155.586684 -146.827494)
		(end 155.586684 -143.707866)
		(width 0.1143)
		(layer "In2.Cu")
		(net "SMB_PCH_SDA")
	)
	(segment
		(start 125.58903 -163.893754)
		(end 126.26086 -163.893754)
		(width 0.1143)
		(layer "In2.Cu")
		(net "SMB_PCH_SDA")
	)
	(segment
		(start 89.002108 -166.88689)
		(end 90.856562 -166.88689)
		(width 0.1143)
		(layer "In2.Cu")
		(net "SMB_PCH_SDA")
	)
	(segment
		(start 111.690404 -168.63949)
		(end 112.91697 -167.413178)
		(width 0.1143)
		(layer "In2.Cu")
		(net "SMB_PCH_SDA")
	)
	(segment
		(start 51.940714 -168.442132)
		(end 58.725816 -168.442132)
		(width 0.1143)
		(layer "In2.Cu")
		(net "SMB_PCH_SDA")
	)
	(segment
		(start 83.97748 -164.428678)
		(end 84.056474 -164.507672)
		(width 0.1143)
		(layer "In2.Cu")
		(net "SMB_PCH_SDA")
	)
	(segment
		(start 121.329958 -163.173918)
		(end 121.81713 -162.686746)
		(width 0.1143)
		(layer "In2.Cu")
		(net "SMB_PCH_SDA")
	)
	(segment
		(start 126.930404 -164.563298)
		(end 128.27254 -164.563298)
		(width 0.1143)
		(layer "In2.Cu")
		(net "SMB_PCH_SDA")
	)
	(segment
		(start 76.99248 -165.740842)
		(end 77.56144 -165.171882)
		(width 0.1143)
		(layer "In2.Cu")
		(net "SMB_PCH_SDA")
	)
	(segment
		(start 135.95477 -163.874958)
		(end 140.734796 -163.874958)
		(width 0.1143)
		(layer "In2.Cu")
		(net "SMB_PCH_SDA")
	)
	(segment
		(start 93.494352 -167.58666)
		(end 93.633544 -167.447468)
		(width 0.1143)
		(layer "In2.Cu")
		(net "SMB_PCH_SDA")
	)
	(segment
		(start 128.442466 -164.733224)
		(end 129.38506 -164.733224)
		(width 0.1143)
		(layer "In2.Cu")
		(net "SMB_PCH_SDA")
	)
	(segment
		(start 154.95778 -143.078962)
		(end 154.95778 -141.627352)
		(width 0.1143)
		(layer "In2.Cu")
		(net "SMB_PCH_SDA")
	)
	(segment
		(start 129.38506 -164.733224)
		(end 129.472944 -164.64534)
		(width 0.1143)
		(layer "In2.Cu")
		(net "SMB_PCH_SDA")
	)
	(segment
		(start 81.804256 -165.171882)
		(end 82.54746 -164.428678)
		(width 0.1143)
		(layer "In2.Cu")
		(net "SMB_PCH_SDA")
	)
	(segment
		(start 104.31145 -168.830244)
		(end 104.626918 -169.145712)
		(width 0.1143)
		(layer "In2.Cu")
		(net "SMB_PCH_SDA")
	)
	(segment
		(start 126.26086 -163.893754)
		(end 126.930404 -164.563298)
		(width 0.1143)
		(layer "In2.Cu")
		(net "SMB_PCH_SDA")
	)
	(segment
		(start 143.984218 -163.205414)
		(end 144.58188 -162.607752)
		(width 0.1143)
		(layer "In2.Cu")
		(net "SMB_PCH_SDA")
	)
	(segment
		(start 92.161868 -167.58666)
		(end 93.494352 -167.58666)
		(width 0.1143)
		(layer "In2.Cu")
		(net "SMB_PCH_SDA")
	)
	(segment
		(start 82.54746 -164.428678)
		(end 83.97748 -164.428678)
		(width 0.1143)
		(layer "In2.Cu")
		(net "SMB_PCH_SDA")
	)
	(segment
		(start 106.338878 -169.145712)
		(end 106.8451 -168.63949)
		(width 0.1143)
		(layer "In2.Cu")
		(net "SMB_PCH_SDA")
	)
	(segment
		(start 71.245222 -170.238166)
		(end 72.844914 -168.638474)
		(width 0.1143)
		(layer "In2.Cu")
		(net "SMB_PCH_SDA")
	)
	(segment
		(start 118.480078 -167.854376)
		(end 119.482108 -167.854376)
		(width 0.1143)
		(layer "In2.Cu")
		(net "SMB_PCH_SDA")
	)
	(segment
		(start 129.472944 -164.64534)
		(end 135.184388 -164.64534)
		(width 0.1143)
		(layer "In2.Cu")
		(net "SMB_PCH_SDA")
	)
	(segment
		(start 124.92228 -163.227004)
		(end 125.58903 -163.893754)
		(width 0.1143)
		(layer "In2.Cu")
		(net "SMB_PCH_SDA")
	)
	(segment
		(start 141.40434 -163.205414)
		(end 143.984218 -163.205414)
		(width 0.1143)
		(layer "In2.Cu")
		(net "SMB_PCH_SDA")
	)
	(segment
		(start 140.734796 -163.874958)
		(end 141.40434 -163.205414)
		(width 0.1143)
		(layer "In2.Cu")
		(net "SMB_PCH_SDA")
	)
	(segment
		(start 91.67622 -167.706548)
		(end 92.04198 -167.706548)
		(width 0.1143)
		(layer "In2.Cu")
		(net "SMB_PCH_SDA")
	)
	(segment
		(start 99.868228 -168.834816)
		(end 101.38156 -168.834816)
		(width 0.1143)
		(layer "In2.Cu")
		(net "SMB_PCH_SDA")
	)
	(segment
		(start 67.63258 -169.33926)
		(end 68.531486 -170.238166)
		(width 0.1143)
		(layer "In2.Cu")
		(net "SMB_PCH_SDA")
	)
	(segment
		(start 123.848876 -163.227004)
		(end 124.92228 -163.227004)
		(width 0.1143)
		(layer "In2.Cu")
		(net "SMB_PCH_SDA")
	)
	(segment
		(start 72.844914 -168.638474)
		(end 73.74636 -168.638474)
		(width 0.1143)
		(layer "In2.Cu")
		(net "SMB_PCH_SDA")
	)
	(segment
		(start 121.329958 -166.006526)
		(end 121.329958 -163.173918)
		(width 0.1143)
		(layer "In2.Cu")
		(net "SMB_PCH_SDA")
	)
	(segment
		(start 95.672656 -167.447468)
		(end 96.364044 -168.138856)
		(width 0.1143)
		(layer "In2.Cu")
		(net "SMB_PCH_SDA")
	)
	(segment
		(start 92.04198 -167.706548)
		(end 92.161868 -167.58666)
		(width 0.1143)
		(layer "In2.Cu")
		(net "SMB_PCH_SDA")
	)
	(segment
		(start 161.5694 -21.14423)
		(end 156.243528 -15.818358)
		(width 0.1016)
		(layer "F.Cu")
		(net "UART_DSR_P1_L_N")
	)
	(segment
		(start 158.271972 -31.834836)
		(end 159.756602 -31.834836)
		(width 0.1016)
		(layer "F.Cu")
		(net "UART_DSR_P1_L_N")
	)
	(segment
		(start 124.549154 -16.185134)
		(end 121.7803 -16.185134)
		(width 0.1016)
		(layer "F.Cu")
		(net "UART_DSR_P1_L_N")
	)
	(segment
		(start 33.88868 -199.071738)
		(end 33.88868 -199.677274)
		(width 0.1016)
		(layer "F.Cu")
		(net "UART_DSR_P1_L_N")
	)
	(segment
		(start 156.243528 -15.818358)
		(end 138.82624 -15.818358)
		(width 0.1016)
		(layer "F.Cu")
		(net "UART_DSR_P1_L_N")
	)
	(segment
		(start 34.40938 -198.551038)
		(end 33.88868 -199.071738)
		(width 0.1016)
		(layer "F.Cu")
		(net "UART_DSR_P1_L_N")
	)
	(segment
		(start 33.88868 -199.677274)
		(end 34.014918 -199.803512)
		(width 0.1016)
		(layer "F.Cu")
		(net "UART_DSR_P1_L_N")
	)
	(segment
		(start 126.873508 -13.86078)
		(end 124.549154 -16.185134)
		(width 0.1016)
		(layer "F.Cu")
		(net "UART_DSR_P1_L_N")
	)
	(segment
		(start 138.82624 -15.818358)
		(end 136.868662 -13.86078)
		(width 0.1016)
		(layer "F.Cu")
		(net "UART_DSR_P1_L_N")
	)
	(segment
		(start 159.756602 -31.834836)
		(end 161.5694 -30.022038)
		(width 0.1016)
		(layer "F.Cu")
		(net "UART_DSR_P1_L_N")
	)
	(segment
		(start 136.868662 -13.86078)
		(end 126.873508 -13.86078)
		(width 0.1016)
		(layer "F.Cu")
		(net "UART_DSR_P1_L_N")
	)
	(segment
		(start 34.014918 -199.803512)
		(end 34.014918 -205.199488)
		(width 0.1016)
		(layer "F.Cu")
		(net "UART_DSR_P1_L_N")
	)
	(segment
		(start 161.5694 -30.022038)
		(end 161.5694 -21.14423)
		(width 0.1016)
		(layer "F.Cu")
		(net "UART_DSR_P1_L_N")
	)
	(via
		(at 121.7803 -16.185134)
		(size 0.508)
		(drill 0.254)
		(layers "F.Cu" "B.Cu")
		(net "UART_DSR_P1_L_N")
	)
	(via
		(at 34.40938 -198.551038)
		(size 0.508)
		(drill 0.254)
		(layers "F.Cu" "B.Cu")
		(net "UART_DSR_P1_L_N")
	)
	(segment
		(start 106.80827 -14.297406)
		(end 89.914476 -14.297406)
		(width 0.1143)
		(layer "In2.Cu")
		(net "UART_DSR_P1_L_N")
	)
	(segment
		(start 18.47342 -170.157648)
		(end 18.47342 -183.56199)
		(width 0.1143)
		(layer "In2.Cu")
		(net "UART_DSR_P1_L_N")
	)
	(segment
		(start 37.76218 -27.74061)
		(end 37.76218 -28.191968)
		(width 0.1143)
		(layer "In2.Cu")
		(net "UART_DSR_P1_L_N")
	)
	(segment
		(start 11.389614 -102.976172)
		(end 9.87679 -104.488996)
		(width 0.1143)
		(layer "In2.Cu")
		(net "UART_DSR_P1_L_N")
	)
	(segment
		(start 16.61922 -98.302572)
		(end 11.94562 -102.976172)
		(width 0.1143)
		(layer "In2.Cu")
		(net "UART_DSR_P1_L_N")
	)
	(segment
		(start 33.007808 -33.55975)
		(end 29.77388 -36.793678)
		(width 0.1143)
		(layer "In2.Cu")
		(net "UART_DSR_P1_L_N")
	)
	(segment
		(start 29.333698 -53.698648)
		(end 29.333698 -79.818738)
		(width 0.1143)
		(layer "In2.Cu")
		(net "UART_DSR_P1_L_N")
	)
	(segment
		(start 9.87679 -104.488996)
		(end 9.87679 -113.564416)
		(width 0.1143)
		(layer "In2.Cu")
		(net "UART_DSR_P1_L_N")
	)
	(segment
		(start 33.54705 -33.30321)
		(end 33.29051 -33.55975)
		(width 0.1143)
		(layer "In2.Cu")
		(net "UART_DSR_P1_L_N")
	)
	(segment
		(start 34.153856 -198.295514)
		(end 34.40938 -198.551038)
		(width 0.1143)
		(layer "In2.Cu")
		(net "UART_DSR_P1_L_N")
	)
	(segment
		(start 29.333698 -79.818738)
		(end 21.25472 -87.897716)
		(width 0.1143)
		(layer "In2.Cu")
		(net "UART_DSR_P1_L_N")
	)
	(segment
		(start 33.54705 -32.407098)
		(end 33.54705 -33.30321)
		(width 0.1143)
		(layer "In2.Cu")
		(net "UART_DSR_P1_L_N")
	)
	(segment
		(start 11.095228 -135.743442)
		(end 11.095228 -138.187176)
		(width 0.1143)
		(layer "In2.Cu")
		(net "UART_DSR_P1_L_N")
	)
	(segment
		(start 16.61922 -97.874328)
		(end 16.61922 -98.302572)
		(width 0.1143)
		(layer "In2.Cu")
		(net "UART_DSR_P1_L_N")
	)
	(segment
		(start 34.153856 -197.513956)
		(end 34.153856 -198.295514)
		(width 0.1143)
		(layer "In2.Cu")
		(net "UART_DSR_P1_L_N")
	)
	(segment
		(start 9.65454 -156.65704)
		(end 9.65454 -161.317432)
		(width 0.1143)
		(layer "In2.Cu")
		(net "UART_DSR_P1_L_N")
	)
	(segment
		(start 118.986046 -16.189198)
		(end 108.700062 -16.189198)
		(width 0.1143)
		(layer "In2.Cu")
		(net "UART_DSR_P1_L_N")
	)
	(segment
		(start 9.18591 -147.70354)
		(end 9.18591 -154.299158)
		(width 0.1143)
		(layer "In2.Cu")
		(net "UART_DSR_P1_L_N")
	)
	(segment
		(start 37.76218 -28.191968)
		(end 33.54705 -32.407098)
		(width 0.1143)
		(layer "In2.Cu")
		(net "UART_DSR_P1_L_N")
	)
	(segment
		(start 67.8307 -17.666716)
		(end 67.107562 -18.389854)
		(width 0.1143)
		(layer "In2.Cu")
		(net "UART_DSR_P1_L_N")
	)
	(segment
		(start 89.318846 -13.701776)
		(end 88.66886 -13.701776)
		(width 0.1143)
		(layer "In2.Cu")
		(net "UART_DSR_P1_L_N")
	)
	(segment
		(start 88.52154 -13.84808)
		(end 87.73414 -14.1478)
		(width 0.1143)
		(layer "In2.Cu")
		(net "UART_DSR_P1_L_N")
	)
	(segment
		(start 56.302656 -21.593048)
		(end 42.29608 -21.593048)
		(width 0.1143)
		(layer "In2.Cu")
		(net "UART_DSR_P1_L_N")
	)
	(segment
		(start 39.981632 -22.516338)
		(end 39.981632 -25.520396)
		(width 0.1143)
		(layer "In2.Cu")
		(net "UART_DSR_P1_L_N")
	)
	(segment
		(start 11.095228 -138.187176)
		(end 10.496296 -138.786108)
		(width 0.1143)
		(layer "In2.Cu")
		(net "UART_DSR_P1_L_N")
	)
	(segment
		(start 18.47342 -183.56199)
		(end 30.50921 -195.59778)
		(width 0.1143)
		(layer "In2.Cu")
		(net "UART_DSR_P1_L_N")
	)
	(segment
		(start 9.87679 -113.564416)
		(end 10.40511 -114.092736)
		(width 0.1143)
		(layer "In2.Cu")
		(net "UART_DSR_P1_L_N")
	)
	(segment
		(start 121.276872 -16.688562)
		(end 119.48541 -16.688562)
		(width 0.1143)
		(layer "In2.Cu")
		(net "UART_DSR_P1_L_N")
	)
	(segment
		(start 87.465662 -14.249908)
		(end 84.0486 -17.666716)
		(width 0.1143)
		(layer "In2.Cu")
		(net "UART_DSR_P1_L_N")
	)
	(segment
		(start 21.25472 -87.897716)
		(end 21.25472 -93.238828)
		(width 0.1143)
		(layer "In2.Cu")
		(net "UART_DSR_P1_L_N")
	)
	(segment
		(start 13.196824 -164.859716)
		(end 13.965936 -164.859716)
		(width 0.1143)
		(layer "In2.Cu")
		(net "UART_DSR_P1_L_N")
	)
	(segment
		(start 10.496296 -146.393154)
		(end 9.18591 -147.70354)
		(width 0.1143)
		(layer "In2.Cu")
		(net "UART_DSR_P1_L_N")
	)
	(segment
		(start 13.965936 -164.859716)
		(end 14.40942 -165.3032)
		(width 0.1143)
		(layer "In2.Cu")
		(net "UART_DSR_P1_L_N")
	)
	(segment
		(start 121.7803 -16.185134)
		(end 121.276872 -16.688562)
		(width 0.1143)
		(layer "In2.Cu")
		(net "UART_DSR_P1_L_N")
	)
	(segment
		(start 89.914476 -14.297406)
		(end 89.318846 -13.701776)
		(width 0.1143)
		(layer "In2.Cu")
		(net "UART_DSR_P1_L_N")
	)
	(segment
		(start 8.94207 -155.94457)
		(end 9.65454 -156.65704)
		(width 0.1143)
		(layer "In2.Cu")
		(net "UART_DSR_P1_L_N")
	)
	(segment
		(start 108.700062 -16.189198)
		(end 106.80827 -14.297406)
		(width 0.1143)
		(layer "In2.Cu")
		(net "UART_DSR_P1_L_N")
	)
	(segment
		(start 9.65454 -161.317432)
		(end 13.196824 -164.859716)
		(width 0.1143)
		(layer "In2.Cu")
		(net "UART_DSR_P1_L_N")
	)
	(segment
		(start 10.40511 -114.092736)
		(end 10.40511 -135.053324)
		(width 0.1143)
		(layer "In2.Cu")
		(net "UART_DSR_P1_L_N")
	)
	(segment
		(start 28.14447 -45.400468)
		(end 28.14447 -52.50942)
		(width 0.1143)
		(layer "In2.Cu")
		(net "UART_DSR_P1_L_N")
	)
	(segment
		(start 66.16954 -18.389854)
		(end 65.134236 -19.425158)
		(width 0.1143)
		(layer "In2.Cu")
		(net "UART_DSR_P1_L_N")
	)
	(segment
		(start 33.29051 -33.55975)
		(end 33.007808 -33.55975)
		(width 0.1143)
		(layer "In2.Cu")
		(net "UART_DSR_P1_L_N")
	)
	(segment
		(start 10.40511 -135.053324)
		(end 11.095228 -135.743442)
		(width 0.1143)
		(layer "In2.Cu")
		(net "UART_DSR_P1_L_N")
	)
	(segment
		(start 11.94562 -102.976172)
		(end 11.389614 -102.976172)
		(width 0.1143)
		(layer "In2.Cu")
		(net "UART_DSR_P1_L_N")
	)
	(segment
		(start 39.981632 -25.520396)
		(end 38.50132 -27.000708)
		(width 0.1143)
		(layer "In2.Cu")
		(net "UART_DSR_P1_L_N")
	)
	(segment
		(start 40.597328 -21.900642)
		(end 39.981632 -22.516338)
		(width 0.1143)
		(layer "In2.Cu")
		(net "UART_DSR_P1_L_N")
	)
	(segment
		(start 8.94207 -154.542998)
		(end 8.94207 -155.94457)
		(width 0.1143)
		(layer "In2.Cu")
		(net "UART_DSR_P1_L_N")
	)
	(segment
		(start 29.77388 -36.793678)
		(end 29.77388 -43.771058)
		(width 0.1143)
		(layer "In2.Cu")
		(net "UART_DSR_P1_L_N")
	)
	(segment
		(start 14.40942 -165.3032)
		(end 14.40942 -166.093648)
		(width 0.1143)
		(layer "In2.Cu")
		(net "UART_DSR_P1_L_N")
	)
	(segment
		(start 29.77388 -43.771058)
		(end 28.14447 -45.400468)
		(width 0.1143)
		(layer "In2.Cu")
		(net "UART_DSR_P1_L_N")
	)
	(segment
		(start 14.40942 -166.093648)
		(end 18.47342 -170.157648)
		(width 0.1143)
		(layer "In2.Cu")
		(net "UART_DSR_P1_L_N")
	)
	(segment
		(start 28.14447 -52.50942)
		(end 29.333698 -53.698648)
		(width 0.1143)
		(layer "In2.Cu")
		(net "UART_DSR_P1_L_N")
	)
	(segment
		(start 32.23768 -195.59778)
		(end 34.153856 -197.513956)
		(width 0.1143)
		(layer "In2.Cu")
		(net "UART_DSR_P1_L_N")
	)
	(segment
		(start 84.0486 -17.666716)
		(end 67.8307 -17.666716)
		(width 0.1143)
		(layer "In2.Cu")
		(net "UART_DSR_P1_L_N")
	)
	(segment
		(start 67.107562 -18.389854)
		(end 66.16954 -18.389854)
		(width 0.1143)
		(layer "In2.Cu")
		(net "UART_DSR_P1_L_N")
	)
	(segment
		(start 119.48541 -16.688562)
		(end 118.986046 -16.189198)
		(width 0.1143)
		(layer "In2.Cu")
		(net "UART_DSR_P1_L_N")
	)
	(segment
		(start 10.496296 -138.786108)
		(end 10.496296 -146.393154)
		(width 0.1143)
		(layer "In2.Cu")
		(net "UART_DSR_P1_L_N")
	)
	(segment
		(start 41.988486 -21.900642)
		(end 40.597328 -21.900642)
		(width 0.1143)
		(layer "In2.Cu")
		(net "UART_DSR_P1_L_N")
	)
	(segment
		(start 65.134236 -19.425158)
		(end 58.470546 -19.425158)
		(width 0.1143)
		(layer "In2.Cu")
		(net "UART_DSR_P1_L_N")
	)
	(segment
		(start 42.29608 -21.593048)
		(end 41.988486 -21.900642)
		(width 0.1143)
		(layer "In2.Cu")
		(net "UART_DSR_P1_L_N")
	)
	(segment
		(start 58.470546 -19.425158)
		(end 56.302656 -21.593048)
		(width 0.1143)
		(layer "In2.Cu")
		(net "UART_DSR_P1_L_N")
	)
	(segment
		(start 30.50921 -195.59778)
		(end 32.23768 -195.59778)
		(width 0.1143)
		(layer "In2.Cu")
		(net "UART_DSR_P1_L_N")
	)
	(segment
		(start 38.50132 -27.000708)
		(end 37.76218 -27.74061)
		(width 0.1143)
		(layer "In2.Cu")
		(net "UART_DSR_P1_L_N")
	)
	(segment
		(start 88.66886 -13.701776)
		(end 88.52154 -13.84808)
		(width 0.1143)
		(layer "In2.Cu")
		(net "UART_DSR_P1_L_N")
	)
	(segment
		(start 9.18591 -154.299158)
		(end 8.94207 -154.542998)
		(width 0.1143)
		(layer "In2.Cu")
		(net "UART_DSR_P1_L_N")
	)
	(segment
		(start 87.73414 -14.1478)
		(end 87.465662 -14.249908)
		(width 0.1143)
		(layer "In2.Cu")
		(net "UART_DSR_P1_L_N")
	)
	(segment
		(start 21.25472 -93.238828)
		(end 16.61922 -97.874328)
		(width 0.1143)
		(layer "In2.Cu")
		(net "UART_DSR_P1_L_N")
	)
	(segment
		(start 161.8742 -30.312614)
		(end 161.8742 -21.017738)
		(width 0.1016)
		(layer "F.Cu")
		(net "UART_CTS_P1_L_N")
	)
	(segment
		(start 139.133072 -15.495778)
		(end 137.193274 -13.55598)
		(width 0.1016)
		(layer "F.Cu")
		(net "UART_CTS_P1_L_N")
	)
	(segment
		(start 30.014926 -205.199488)
		(end 30.014926 -200.08596)
		(width 0.1016)
		(layer "F.Cu")
		(net "UART_CTS_P1_L_N")
	)
	(segment
		(start 126.746254 -13.55598)
		(end 124.431044 -15.87119)
		(width 0.1016)
		(layer "F.Cu")
		(net "UART_CTS_P1_L_N")
	)
	(segment
		(start 156.35224 -15.495778)
		(end 139.133072 -15.495778)
		(width 0.1016)
		(layer "F.Cu")
		(net "UART_CTS_P1_L_N")
	)
	(segment
		(start 30.014926 -200.08596)
		(end 29.55798 -199.629014)
		(width 0.1016)
		(layer "F.Cu")
		(net "UART_CTS_P1_L_N")
	)
	(segment
		(start 121.96064 -15.753334)
		(end 119.31777 -15.753334)
		(width 0.1016)
		(layer "F.Cu")
		(net "UART_CTS_P1_L_N")
	)
	(segment
		(start 158.271972 -32.484822)
		(end 159.701992 -32.484822)
		(width 0.1016)
		(layer "F.Cu")
		(net "UART_CTS_P1_L_N")
	)
	(segment
		(start 159.701992 -32.484822)
		(end 161.8742 -30.312614)
		(width 0.1016)
		(layer "F.Cu")
		(net "UART_CTS_P1_L_N")
	)
	(segment
		(start 161.8742 -21.017738)
		(end 156.35224 -15.495778)
		(width 0.1016)
		(layer "F.Cu")
		(net "UART_CTS_P1_L_N")
	)
	(segment
		(start 122.078496 -15.87119)
		(end 121.96064 -15.753334)
		(width 0.1016)
		(layer "F.Cu")
		(net "UART_CTS_P1_L_N")
	)
	(segment
		(start 119.31777 -15.753334)
		(end 117.89918 -14.334744)
		(width 0.1016)
		(layer "F.Cu")
		(net "UART_CTS_P1_L_N")
	)
	(segment
		(start 124.431044 -15.87119)
		(end 122.078496 -15.87119)
		(width 0.1016)
		(layer "F.Cu")
		(net "UART_CTS_P1_L_N")
	)
	(segment
		(start 137.193274 -13.55598)
		(end 126.746254 -13.55598)
		(width 0.1016)
		(layer "F.Cu")
		(net "UART_CTS_P1_L_N")
	)
	(via
		(at 117.89918 -14.334744)
		(size 0.508)
		(drill 0.254)
		(layers "F.Cu" "B.Cu")
		(net "UART_CTS_P1_L_N")
	)
	(via
		(at 29.55798 -199.629014)
		(size 0.508)
		(drill 0.254)
		(layers "F.Cu" "B.Cu")
		(net "UART_CTS_P1_L_N")
	)
	(segment
		(start 6.43509 -146.615404)
		(end 6.43509 -140.760958)
		(width 0.1143)
		(layer "In2.Cu")
		(net "UART_CTS_P1_L_N")
	)
	(segment
		(start 24.11095 -81.37398)
		(end 24.11095 -66.819272)
		(width 0.1143)
		(layer "In2.Cu")
		(net "UART_CTS_P1_L_N")
	)
	(segment
		(start 23.78964 -56.350154)
		(end 23.801578 -56.338216)
		(width 0.1143)
		(layer "In2.Cu")
		(net "UART_CTS_P1_L_N")
	)
	(segment
		(start 11.28268 -98.076258)
		(end 12.77366 -96.585278)
		(width 0.1143)
		(layer "In2.Cu")
		(net "UART_CTS_P1_L_N")
	)
	(segment
		(start 10.095738 -167.480234)
		(end 5.119624 -162.50412)
		(width 0.1143)
		(layer "In2.Cu")
		(net "UART_CTS_P1_L_N")
	)
	(segment
		(start 22.983698 -59.555634)
		(end 22.983698 -59.52236)
		(width 0.1143)
		(layer "In2.Cu")
		(net "UART_CTS_P1_L_N")
	)
	(segment
		(start 23.802594 -56.334152)
		(end 24.69388 -55.442866)
		(width 0.1143)
		(layer "In2.Cu")
		(net "UART_CTS_P1_L_N")
	)
	(segment
		(start 22.95906 -59.653678)
		(end 22.983698 -59.555634)
		(width 0.1143)
		(layer "In2.Cu")
		(net "UART_CTS_P1_L_N")
	)
	(segment
		(start 12.192 -167.480234)
		(end 10.095738 -167.480234)
		(width 0.1143)
		(layer "In2.Cu")
		(net "UART_CTS_P1_L_N")
	)
	(segment
		(start 29.55798 -199.629014)
		(end 29.4132 -199.484234)
		(width 0.1143)
		(layer "In2.Cu")
		(net "UART_CTS_P1_L_N")
	)
	(segment
		(start 5.119624 -147.93087)
		(end 6.43509 -146.615404)
		(width 0.1143)
		(layer "In2.Cu")
		(net "UART_CTS_P1_L_N")
	)
	(segment
		(start 64.586612 -18.099278)
		(end 65.566036 -17.119854)
		(width 0.1143)
		(layer "In2.Cu")
		(net "UART_CTS_P1_L_N")
	)
	(segment
		(start 36.19246 -27.555698)
		(end 36.19246 -24.147018)
		(width 0.1143)
		(layer "In2.Cu")
		(net "UART_CTS_P1_L_N")
	)
	(segment
		(start 15.86738 -171.155614)
		(end 12.192 -167.480234)
		(width 0.1143)
		(layer "In2.Cu")
		(net "UART_CTS_P1_L_N")
	)
	(segment
		(start 22.983698 -59.69508)
		(end 22.95906 -59.653678)
		(width 0.1143)
		(layer "In2.Cu")
		(net "UART_CTS_P1_L_N")
	)
	(segment
		(start 88.14054 -12.431776)
		(end 89.98966 -12.431776)
		(width 0.1143)
		(layer "In2.Cu")
		(net "UART_CTS_P1_L_N")
	)
	(segment
		(start 24.69388 -55.442866)
		(end 24.69388 -42.833798)
		(width 0.1143)
		(layer "In2.Cu")
		(net "UART_CTS_P1_L_N")
	)
	(segment
		(start 6.400038 -140.725906)
		(end 6.400038 -103.331518)
		(width 0.1143)
		(layer "In2.Cu")
		(net "UART_CTS_P1_L_N")
	)
	(segment
		(start 22.983698 -65.69202)
		(end 22.983698 -59.69508)
		(width 0.1143)
		(layer "In2.Cu")
		(net "UART_CTS_P1_L_N")
	)
	(segment
		(start 87.812626 -12.756388)
		(end 88.14054 -12.431776)
		(width 0.1143)
		(layer "In2.Cu")
		(net "UART_CTS_P1_L_N")
	)
	(segment
		(start 80.446626 -15.555976)
		(end 80.51546 -15.529814)
		(width 0.1143)
		(layer "In2.Cu")
		(net "UART_CTS_P1_L_N")
	)
	(segment
		(start 36.01212 -27.736292)
		(end 36.19246 -27.555698)
		(width 0.1143)
		(layer "In2.Cu")
		(net "UART_CTS_P1_L_N")
	)
	(segment
		(start 89.98966 -12.431776)
		(end 90.36304 -12.805156)
		(width 0.1143)
		(layer "In2.Cu")
		(net "UART_CTS_P1_L_N")
	)
	(segment
		(start 108.78693 -14.334744)
		(end 117.89918 -14.334744)
		(width 0.1143)
		(layer "In2.Cu")
		(net "UART_CTS_P1_L_N")
	)
	(segment
		(start 39.74592 -20.593558)
		(end 41.275 -20.593558)
		(width 0.1143)
		(layer "In2.Cu")
		(net "UART_CTS_P1_L_N")
	)
	(segment
		(start 11.28268 -98.448876)
		(end 11.28268 -98.076258)
		(width 0.1143)
		(layer "In2.Cu")
		(net "UART_CTS_P1_L_N")
	)
	(segment
		(start 107.296458 -12.844272)
		(end 108.78693 -14.334744)
		(width 0.1143)
		(layer "In2.Cu")
		(net "UART_CTS_P1_L_N")
	)
	(segment
		(start 41.710356 -20.158202)
		(end 55.624476 -20.158202)
		(width 0.1143)
		(layer "In2.Cu")
		(net "UART_CTS_P1_L_N")
	)
	(segment
		(start 5.119624 -162.50412)
		(end 5.119624 -147.93087)
		(width 0.1143)
		(layer "In2.Cu")
		(net "UART_CTS_P1_L_N")
	)
	(segment
		(start 23.801578 -56.338216)
		(end 23.802594 -56.334152)
		(width 0.1143)
		(layer "In2.Cu")
		(net "UART_CTS_P1_L_N")
	)
	(segment
		(start 23.379938 -57.979056)
		(end 23.78964 -56.350154)
		(width 0.1143)
		(layer "In2.Cu")
		(net "UART_CTS_P1_L_N")
	)
	(segment
		(start 28.0543 -39.473378)
		(end 28.0543 -35.694112)
		(width 0.1143)
		(layer "In2.Cu")
		(net "UART_CTS_P1_L_N")
	)
	(segment
		(start 29.4132 -199.484234)
		(end 29.4132 -198.534782)
		(width 0.1143)
		(layer "In2.Cu")
		(net "UART_CTS_P1_L_N")
	)
	(segment
		(start 66.4845 -17.119854)
		(end 68.048378 -15.555976)
		(width 0.1143)
		(layer "In2.Cu")
		(net "UART_CTS_P1_L_N")
	)
	(segment
		(start 29.4132 -198.534782)
		(end 15.86738 -184.988962)
		(width 0.1143)
		(layer "In2.Cu")
		(net "UART_CTS_P1_L_N")
	)
	(segment
		(start 6.43509 -140.760958)
		(end 6.400038 -140.725906)
		(width 0.1143)
		(layer "In2.Cu")
		(net "UART_CTS_P1_L_N")
	)
	(segment
		(start 107.14482 -12.805156)
		(end 107.296458 -12.844272)
		(width 0.1143)
		(layer "In2.Cu")
		(net "UART_CTS_P1_L_N")
	)
	(segment
		(start 55.624476 -20.158202)
		(end 57.6834 -18.099278)
		(width 0.1143)
		(layer "In2.Cu")
		(net "UART_CTS_P1_L_N")
	)
	(segment
		(start 12.77366 -96.585278)
		(end 14.149578 -96.585278)
		(width 0.1143)
		(layer "In2.Cu")
		(net "UART_CTS_P1_L_N")
	)
	(segment
		(start 65.566036 -17.119854)
		(end 66.4845 -17.119854)
		(width 0.1143)
		(layer "In2.Cu")
		(net "UART_CTS_P1_L_N")
	)
	(segment
		(start 15.86738 -184.988962)
		(end 15.86738 -171.155614)
		(width 0.1143)
		(layer "In2.Cu")
		(net "UART_CTS_P1_L_N")
	)
	(segment
		(start 18.5166 -86.96833)
		(end 24.11095 -81.37398)
		(width 0.1143)
		(layer "In2.Cu")
		(net "UART_CTS_P1_L_N")
	)
	(segment
		(start 57.6834 -18.099278)
		(end 64.586612 -18.099278)
		(width 0.1143)
		(layer "In2.Cu")
		(net "UART_CTS_P1_L_N")
	)
	(segment
		(start 14.149578 -96.585278)
		(end 18.5166 -92.218256)
		(width 0.1143)
		(layer "In2.Cu")
		(net "UART_CTS_P1_L_N")
	)
	(segment
		(start 24.11095 -66.819272)
		(end 22.983698 -65.69202)
		(width 0.1143)
		(layer "In2.Cu")
		(net "UART_CTS_P1_L_N")
	)
	(segment
		(start 18.5166 -92.218256)
		(end 18.5166 -86.96833)
		(width 0.1143)
		(layer "In2.Cu")
		(net "UART_CTS_P1_L_N")
	)
	(segment
		(start 24.69388 -42.833798)
		(end 28.0543 -39.473378)
		(width 0.1143)
		(layer "In2.Cu")
		(net "UART_CTS_P1_L_N")
	)
	(segment
		(start 41.275 -20.593558)
		(end 41.710356 -20.158202)
		(width 0.1143)
		(layer "In2.Cu")
		(net "UART_CTS_P1_L_N")
	)
	(segment
		(start 6.400038 -103.331518)
		(end 11.28268 -98.448876)
		(width 0.1143)
		(layer "In2.Cu")
		(net "UART_CTS_P1_L_N")
	)
	(segment
		(start 68.048378 -15.555976)
		(end 80.446626 -15.555976)
		(width 0.1143)
		(layer "In2.Cu")
		(net "UART_CTS_P1_L_N")
	)
	(segment
		(start 28.0543 -35.694112)
		(end 36.01212 -27.736292)
		(width 0.1143)
		(layer "In2.Cu")
		(net "UART_CTS_P1_L_N")
	)
	(segment
		(start 90.36304 -12.805156)
		(end 107.14482 -12.805156)
		(width 0.1143)
		(layer "In2.Cu")
		(net "UART_CTS_P1_L_N")
	)
	(segment
		(start 22.983698 -59.52236)
		(end 23.379938 -57.979056)
		(width 0.1143)
		(layer "In2.Cu")
		(net "UART_CTS_P1_L_N")
	)
	(segment
		(start 80.51546 -15.529814)
		(end 87.812626 -12.756388)
		(width 0.1143)
		(layer "In2.Cu")
		(net "UART_CTS_P1_L_N")
	)
	(segment
		(start 36.19246 -24.147018)
		(end 39.74592 -20.593558)
		(width 0.1143)
		(layer "In2.Cu")
		(net "UART_CTS_P1_L_N")
	)
	(segment
		(start 127.274828 -14.16558)
		(end 124.823474 -16.616934)
		(width 0.1016)
		(layer "F.Cu")
		(net "UART_RX_P1_L")
	)
	(segment
		(start 136.645396 -14.16558)
		(end 127.274828 -14.16558)
		(width 0.1016)
		(layer "F.Cu")
		(net "UART_RX_P1_L")
	)
	(segment
		(start 156.185616 -16.191738)
		(end 138.671554 -16.191738)
		(width 0.1016)
		(layer "F.Cu")
		(net "UART_RX_P1_L")
	)
	(segment
		(start 158.271972 -31.18485)
		(end 159.97428 -31.18485)
		(width 0.1016)
		(layer "F.Cu")
		(net "UART_RX_P1_L")
	)
	(segment
		(start 121.049288 -16.616934)
		(end 120.65762 -16.225266)
		(width 0.1016)
		(layer "F.Cu")
		(net "UART_RX_P1_L")
	)
	(segment
		(start 161.2646 -21.270722)
		(end 156.185616 -16.191738)
		(width 0.1016)
		(layer "F.Cu")
		(net "UART_RX_P1_L")
	)
	(segment
		(start 161.2646 -29.89453)
		(end 161.2646 -21.270722)
		(width 0.1016)
		(layer "F.Cu")
		(net "UART_RX_P1_L")
	)
	(segment
		(start 33.01492 -200.226676)
		(end 33.01492 -205.199488)
		(width 0.1016)
		(layer "F.Cu")
		(net "UART_RX_P1_L")
	)
	(segment
		(start 138.671554 -16.191738)
		(end 136.645396 -14.16558)
		(width 0.1016)
		(layer "F.Cu")
		(net "UART_RX_P1_L")
	)
	(segment
		(start 33.2359 -198.743824)
		(end 32.62376 -199.355964)
		(width 0.1016)
		(layer "F.Cu")
		(net "UART_RX_P1_L")
	)
	(segment
		(start 32.62376 -199.835516)
		(end 33.01492 -200.226676)
		(width 0.1016)
		(layer "F.Cu")
		(net "UART_RX_P1_L")
	)
	(segment
		(start 124.823474 -16.616934)
		(end 121.049288 -16.616934)
		(width 0.1016)
		(layer "F.Cu")
		(net "UART_RX_P1_L")
	)
	(segment
		(start 32.62376 -199.355964)
		(end 32.62376 -199.835516)
		(width 0.1016)
		(layer "F.Cu")
		(net "UART_RX_P1_L")
	)
	(segment
		(start 159.97428 -31.18485)
		(end 161.2646 -29.89453)
		(width 0.1016)
		(layer "F.Cu")
		(net "UART_RX_P1_L")
	)
	(via
		(at 120.65762 -16.225266)
		(size 0.508)
		(drill 0.254)
		(layers "F.Cu" "B.Cu")
		(net "UART_RX_P1_L")
	)
	(via
		(at 33.2359 -198.743824)
		(size 0.508)
		(drill 0.254)
		(layers "F.Cu" "B.Cu")
		(net "UART_RX_P1_L")
	)
	(segment
		(start 8.247126 -156.764482)
		(end 8.247126 -160.829498)
		(width 0.1143)
		(layer "In2.Cu")
		(net "UART_RX_P1_L")
	)
	(segment
		(start 89.515696 -13.448538)
		(end 89.45118 -13.384276)
		(width 0.1143)
		(layer "In2.Cu")
		(net "UART_RX_P1_L")
	)
	(segment
		(start 90.01506 -13.947394)
		(end 89.515696 -13.448538)
		(width 0.1143)
		(layer "In2.Cu")
		(net "UART_RX_P1_L")
	)
	(segment
		(start 17.83842 -183.91632)
		(end 30.266386 -196.344286)
		(width 0.1143)
		(layer "In2.Cu")
		(net "UART_RX_P1_L")
	)
	(segment
		(start 27.22499 -52.640992)
		(end 28.698698 -54.1147)
		(width 0.1143)
		(layer "In2.Cu")
		(net "UART_RX_P1_L")
	)
	(segment
		(start 89.45118 -13.384276)
		(end 88.53678 -13.384276)
		(width 0.1143)
		(layer "In2.Cu")
		(net "UART_RX_P1_L")
	)
	(segment
		(start 20.61972 -87.564214)
		(end 20.61972 -92.871798)
		(width 0.1143)
		(layer "In2.Cu")
		(net "UART_RX_P1_L")
	)
	(segment
		(start 108.97108 -15.871698)
		(end 107.046776 -13.947394)
		(width 0.1143)
		(layer "In2.Cu")
		(net "UART_RX_P1_L")
	)
	(segment
		(start 28.698698 -54.1147)
		(end 28.698698 -79.485236)
		(width 0.1143)
		(layer "In2.Cu")
		(net "UART_RX_P1_L")
	)
	(segment
		(start 87.885778 -13.750036)
		(end 87.803228 -13.781278)
		(width 0.1143)
		(layer "In2.Cu")
		(net "UART_RX_P1_L")
	)
	(segment
		(start 42.051478 -21.207476)
		(end 41.67886 -21.580094)
		(width 0.1143)
		(layer "In2.Cu")
		(net "UART_RX_P1_L")
	)
	(segment
		(start 65.002156 -19.107658)
		(end 58.335418 -19.107658)
		(width 0.1143)
		(layer "In2.Cu")
		(net "UART_RX_P1_L")
	)
	(segment
		(start 41.67886 -21.580094)
		(end 40.246554 -21.580094)
		(width 0.1143)
		(layer "In2.Cu")
		(net "UART_RX_P1_L")
	)
	(segment
		(start 7.97941 -156.496766)
		(end 8.247126 -156.764482)
		(width 0.1143)
		(layer "In2.Cu")
		(net "UART_RX_P1_L")
	)
	(segment
		(start 88.385142 -13.53439)
		(end 88.34374 -13.575792)
		(width 0.1143)
		(layer "In2.Cu")
		(net "UART_RX_P1_L")
	)
	(segment
		(start 119.288306 -15.871698)
		(end 108.97108 -15.871698)
		(width 0.1143)
		(layer "In2.Cu")
		(net "UART_RX_P1_L")
	)
	(segment
		(start 56.2356 -21.207476)
		(end 42.051478 -21.207476)
		(width 0.1143)
		(layer "In2.Cu")
		(net "UART_RX_P1_L")
	)
	(segment
		(start 29.42082 -36.084256)
		(end 29.42082 -43.311318)
		(width 0.1143)
		(layer "In2.Cu")
		(net "UART_RX_P1_L")
	)
	(segment
		(start 31.842202 -196.344286)
		(end 32.94634 -197.448424)
		(width 0.1143)
		(layer "In2.Cu")
		(net "UART_RX_P1_L")
	)
	(segment
		(start 9.13511 -103.681784)
		(end 9.13511 -137.711434)
		(width 0.1143)
		(layer "In2.Cu")
		(net "UART_RX_P1_L")
	)
	(segment
		(start 88.53678 -13.384276)
		(end 88.385142 -13.53439)
		(width 0.1143)
		(layer "In2.Cu")
		(net "UART_RX_P1_L")
	)
	(segment
		(start 120.65762 -16.225266)
		(end 119.641874 -16.225266)
		(width 0.1143)
		(layer "In2.Cu")
		(net "UART_RX_P1_L")
	)
	(segment
		(start 32.94634 -197.448424)
		(end 32.94634 -198.454264)
		(width 0.1143)
		(layer "In2.Cu")
		(net "UART_RX_P1_L")
	)
	(segment
		(start 66.03746 -18.072354)
		(end 65.002156 -19.107658)
		(width 0.1143)
		(layer "In2.Cu")
		(net "UART_RX_P1_L")
	)
	(segment
		(start 66.882518 -18.072354)
		(end 66.03746 -18.072354)
		(width 0.1143)
		(layer "In2.Cu")
		(net "UART_RX_P1_L")
	)
	(segment
		(start 37.14496 -28.3591)
		(end 37.00018 -28.504388)
		(width 0.1143)
		(layer "In2.Cu")
		(net "UART_RX_P1_L")
	)
	(segment
		(start 33.22828 -32.276542)
		(end 29.42082 -36.084256)
		(width 0.1143)
		(layer "In2.Cu")
		(net "UART_RX_P1_L")
	)
	(segment
		(start 37.14496 -24.681688)
		(end 37.14496 -28.3591)
		(width 0.1143)
		(layer "In2.Cu")
		(net "UART_RX_P1_L")
	)
	(segment
		(start 28.698698 -79.485236)
		(end 20.61972 -87.564214)
		(width 0.1143)
		(layer "In2.Cu")
		(net "UART_RX_P1_L")
	)
	(segment
		(start 13.09624 -100.085144)
		(end 12.73175 -100.085144)
		(width 0.1143)
		(layer "In2.Cu")
		(net "UART_RX_P1_L")
	)
	(segment
		(start 83.829144 -17.254474)
		(end 67.700398 -17.254474)
		(width 0.1143)
		(layer "In2.Cu")
		(net "UART_RX_P1_L")
	)
	(segment
		(start 29.42082 -43.311318)
		(end 27.22499 -45.507148)
		(width 0.1143)
		(layer "In2.Cu")
		(net "UART_RX_P1_L")
	)
	(segment
		(start 20.61972 -92.871798)
		(end 15.81912 -97.672398)
		(width 0.1143)
		(layer "In2.Cu")
		(net "UART_RX_P1_L")
	)
	(segment
		(start 9.13511 -137.711434)
		(end 9.101328 -137.745216)
		(width 0.1143)
		(layer "In2.Cu")
		(net "UART_RX_P1_L")
	)
	(segment
		(start 15.81912 -97.672398)
		(end 15.81912 -98.204528)
		(width 0.1143)
		(layer "In2.Cu")
		(net "UART_RX_P1_L")
	)
	(segment
		(start 86.995 -14.088618)
		(end 83.829144 -17.254474)
		(width 0.1143)
		(layer "In2.Cu")
		(net "UART_RX_P1_L")
	)
	(segment
		(start 17.83842 -170.420792)
		(end 17.83842 -183.91632)
		(width 0.1143)
		(layer "In2.Cu")
		(net "UART_RX_P1_L")
	)
	(segment
		(start 9.196324 -138.467592)
		(end 9.196324 -146.638518)
		(width 0.1143)
		(layer "In2.Cu")
		(net "UART_RX_P1_L")
	)
	(segment
		(start 37.00018 -28.504388)
		(end 36.9951 -28.509722)
		(width 0.1143)
		(layer "In2.Cu")
		(net "UART_RX_P1_L")
	)
	(segment
		(start 13.72997 -100.293678)
		(end 13.304774 -100.293678)
		(width 0.1143)
		(layer "In2.Cu")
		(net "UART_RX_P1_L")
	)
	(segment
		(start 13.304774 -100.293678)
		(end 13.09624 -100.085144)
		(width 0.1143)
		(layer "In2.Cu")
		(net "UART_RX_P1_L")
	)
	(segment
		(start 27.22499 -45.507148)
		(end 27.22499 -52.640992)
		(width 0.1143)
		(layer "In2.Cu")
		(net "UART_RX_P1_L")
	)
	(segment
		(start 67.700398 -17.254474)
		(end 66.882518 -18.072354)
		(width 0.1143)
		(layer "In2.Cu")
		(net "UART_RX_P1_L")
	)
	(segment
		(start 8.247126 -160.829498)
		(end 17.83842 -170.420792)
		(width 0.1143)
		(layer "In2.Cu")
		(net "UART_RX_P1_L")
	)
	(segment
		(start 12.73175 -100.085144)
		(end 9.13511 -103.681784)
		(width 0.1143)
		(layer "In2.Cu")
		(net "UART_RX_P1_L")
	)
	(segment
		(start 119.641874 -16.225266)
		(end 119.288306 -15.871698)
		(width 0.1143)
		(layer "In2.Cu")
		(net "UART_RX_P1_L")
	)
	(segment
		(start 7.97941 -147.855432)
		(end 7.97941 -156.496766)
		(width 0.1143)
		(layer "In2.Cu")
		(net "UART_RX_P1_L")
	)
	(segment
		(start 9.101328 -138.372596)
		(end 9.196324 -138.467592)
		(width 0.1143)
		(layer "In2.Cu")
		(net "UART_RX_P1_L")
	)
	(segment
		(start 15.81912 -98.204528)
		(end 13.72997 -100.293678)
		(width 0.1143)
		(layer "In2.Cu")
		(net "UART_RX_P1_L")
	)
	(segment
		(start 88.34374 -13.575792)
		(end 87.885778 -13.750036)
		(width 0.1143)
		(layer "In2.Cu")
		(net "UART_RX_P1_L")
	)
	(segment
		(start 87.803228 -13.781278)
		(end 86.995 -14.088618)
		(width 0.1143)
		(layer "In2.Cu")
		(net "UART_RX_P1_L")
	)
	(segment
		(start 36.9951 -28.509722)
		(end 33.22828 -32.276542)
		(width 0.1143)
		(layer "In2.Cu")
		(net "UART_RX_P1_L")
	)
	(segment
		(start 9.101328 -137.745216)
		(end 9.101328 -138.372596)
		(width 0.1143)
		(layer "In2.Cu")
		(net "UART_RX_P1_L")
	)
	(segment
		(start 40.246554 -21.580094)
		(end 37.14496 -24.681688)
		(width 0.1143)
		(layer "In2.Cu")
		(net "UART_RX_P1_L")
	)
	(segment
		(start 9.196324 -146.638518)
		(end 7.97941 -147.855432)
		(width 0.1143)
		(layer "In2.Cu")
		(net "UART_RX_P1_L")
	)
	(segment
		(start 107.046776 -13.947394)
		(end 90.01506 -13.947394)
		(width 0.1143)
		(layer "In2.Cu")
		(net "UART_RX_P1_L")
	)
	(segment
		(start 58.335418 -19.107658)
		(end 56.2356 -21.207476)
		(width 0.1143)
		(layer "In2.Cu")
		(net "UART_RX_P1_L")
	)
	(segment
		(start 30.266386 -196.344286)
		(end 31.842202 -196.344286)
		(width 0.1143)
		(layer "In2.Cu")
		(net "UART_RX_P1_L")
	)
	(segment
		(start 32.94634 -198.454264)
		(end 33.2359 -198.743824)
		(width 0.1143)
		(layer "In2.Cu")
		(net "UART_RX_P1_L")
	)
	(segment
		(start 132.207 -51.83505)
		(end 132.207 -52.50434)
		(width 0.1016)
		(layer "F.Cu")
		(net "UART_DTR_P4_N")
	)
	(segment
		(start 132.207 -52.50434)
		(end 132.097272 -52.614068)
		(width 0.1016)
		(layer "F.Cu")
		(net "UART_DTR_P4_N")
	)
	(segment
		(start 77.994764 -181.090824)
		(end 77.994764 -179.874672)
		(width 0.1016)
		(layer "F.Cu")
		(net "UART_DTR_P4_N")
	)
	(segment
		(start 78.006702 -181.102762)
		(end 77.994764 -181.090824)
		(width 0.1016)
		(layer "F.Cu")
		(net "UART_DTR_P4_N")
	)
	(via
		(at 158.31566 -162.870388)
		(size 0.508)
		(drill 0.254)
		(layers "F.Cu" "B.Cu")
		(net "UART_DTR_P4_N")
	)
	(via
		(at 132.097272 -52.614068)
		(size 0.508)
		(drill 0.254)
		(layers "F.Cu" "B.Cu")
		(net "UART_DTR_P4_N")
	)
	(via
		(at 135.905748 -180.004466)
		(size 0.508)
		(drill 0.254)
		(layers "F.Cu" "B.Cu")
		(net "UART_DTR_P4_N")
	)
	(via
		(at 78.006702 -181.102762)
		(size 0.508)
		(drill 0.254)
		(layers "F.Cu" "B.Cu")
		(net "UART_DTR_P4_N")
	)
	(segment
		(start 77.098652 -180.390292)
		(end 77.098652 -180.815742)
		(width 0.1016)
		(layer "B.Cu")
		(net "UART_DTR_P4_N")
	)
	(segment
		(start 137.096754 -172.859954)
		(end 138.095736 -171.860972)
		(width 0.1016)
		(layer "B.Cu")
		(net "UART_DTR_P4_N")
	)
	(segment
		(start 137.096754 -178.81346)
		(end 137.096754 -172.859954)
		(width 0.1016)
		(layer "B.Cu")
		(net "UART_DTR_P4_N")
	)
	(segment
		(start 142.260066 -166.62019)
		(end 143.248634 -166.62019)
		(width 0.1016)
		(layer "B.Cu")
		(net "UART_DTR_P4_N")
	)
	(segment
		(start 145.4277 -165.573456)
		(end 148.508466 -162.49269)
		(width 0.1016)
		(layer "B.Cu")
		(net "UART_DTR_P4_N")
	)
	(segment
		(start 148.508466 -162.49269)
		(end 154.673808 -162.49269)
		(width 0.1016)
		(layer "B.Cu")
		(net "UART_DTR_P4_N")
	)
	(segment
		(start 141.379702 -167.500554)
		(end 142.260066 -166.62019)
		(width 0.1016)
		(layer "B.Cu")
		(net "UART_DTR_P4_N")
	)
	(segment
		(start 154.673808 -162.49269)
		(end 155.051506 -162.870388)
		(width 0.1016)
		(layer "B.Cu")
		(net "UART_DTR_P4_N")
	)
	(segment
		(start 144.295368 -165.573456)
		(end 145.4277 -165.573456)
		(width 0.1016)
		(layer "B.Cu")
		(net "UART_DTR_P4_N")
	)
	(segment
		(start 155.051506 -162.870388)
		(end 158.31566 -162.870388)
		(width 0.1016)
		(layer "B.Cu")
		(net "UART_DTR_P4_N")
	)
	(segment
		(start 138.095736 -170.261534)
		(end 140.856716 -167.500554)
		(width 0.1016)
		(layer "B.Cu")
		(net "UART_DTR_P4_N")
	)
	(segment
		(start 77.098652 -180.815742)
		(end 77.385672 -181.102762)
		(width 0.1016)
		(layer "B.Cu")
		(net "UART_DTR_P4_N")
	)
	(segment
		(start 143.248634 -166.62019)
		(end 144.295368 -165.573456)
		(width 0.1016)
		(layer "B.Cu")
		(net "UART_DTR_P4_N")
	)
	(segment
		(start 140.856716 -167.500554)
		(end 141.379702 -167.500554)
		(width 0.1016)
		(layer "B.Cu")
		(net "UART_DTR_P4_N")
	)
	(segment
		(start 138.095736 -171.860972)
		(end 138.095736 -170.261534)
		(width 0.1016)
		(layer "B.Cu")
		(net "UART_DTR_P4_N")
	)
	(segment
		(start 77.385672 -181.102762)
		(end 78.006702 -181.102762)
		(width 0.1016)
		(layer "B.Cu")
		(net "UART_DTR_P4_N")
	)
	(segment
		(start 135.905748 -180.004466)
		(end 137.096754 -178.81346)
		(width 0.1016)
		(layer "B.Cu")
		(net "UART_DTR_P4_N")
	)
	(segment
		(start 131.856226 -55.38089)
		(end 131.856226 -52.855114)
		(width 0.1143)
		(layer "In2.Cu")
		(net "UART_DTR_P4_N")
	)
	(segment
		(start 130.5433 -66.71564)
		(end 130.5433 -56.693816)
		(width 0.1143)
		(layer "In2.Cu")
		(net "UART_DTR_P4_N")
	)
	(segment
		(start 172.516038 -159.715708)
		(end 176.3141 -159.715708)
		(width 0.1143)
		(layer "In2.Cu")
		(net "UART_DTR_P4_N")
	)
	(segment
		(start 189.570106 -142.509494)
		(end 189.570106 -125.897894)
		(width 0.1143)
		(layer "In2.Cu")
		(net "UART_DTR_P4_N")
	)
	(segment
		(start 176.3141 -159.715708)
		(end 188.3537 -147.676108)
		(width 0.1143)
		(layer "In2.Cu")
		(net "UART_DTR_P4_N")
	)
	(segment
		(start 169.361358 -162.870388)
		(end 172.516038 -159.715708)
		(width 0.1143)
		(layer "In2.Cu")
		(net "UART_DTR_P4_N")
	)
	(segment
		(start 134.11708 -70.28942)
		(end 130.5433 -66.71564)
		(width 0.1143)
		(layer "In2.Cu")
		(net "UART_DTR_P4_N")
	)
	(segment
		(start 178.447192 -86.828122)
		(end 148.717 -86.828122)
		(width 0.1143)
		(layer "In2.Cu")
		(net "UART_DTR_P4_N")
	)
	(segment
		(start 158.31566 -162.870388)
		(end 169.361358 -162.870388)
		(width 0.1143)
		(layer "In2.Cu")
		(net "UART_DTR_P4_N")
	)
	(segment
		(start 189.570106 -97.951036)
		(end 178.447192 -86.828122)
		(width 0.1143)
		(layer "In2.Cu")
		(net "UART_DTR_P4_N")
	)
	(segment
		(start 189.570106 -123.276106)
		(end 189.570106 -97.951036)
		(width 0.1143)
		(layer "In2.Cu")
		(net "UART_DTR_P4_N")
	)
	(segment
		(start 188.3537 -143.7259)
		(end 189.570106 -142.509494)
		(width 0.1143)
		(layer "In2.Cu")
		(net "UART_DTR_P4_N")
	)
	(segment
		(start 130.5433 -56.693816)
		(end 131.856226 -55.38089)
		(width 0.1143)
		(layer "In2.Cu")
		(net "UART_DTR_P4_N")
	)
	(segment
		(start 189.570106 -125.897894)
		(end 189.992 -125.476)
		(width 0.1143)
		(layer "In2.Cu")
		(net "UART_DTR_P4_N")
	)
	(segment
		(start 136.47928 -73.822052)
		(end 134.11708 -71.459852)
		(width 0.1143)
		(layer "In2.Cu")
		(net "UART_DTR_P4_N")
	)
	(segment
		(start 131.856226 -52.855114)
		(end 132.097272 -52.614068)
		(width 0.1143)
		(layer "In2.Cu")
		(net "UART_DTR_P4_N")
	)
	(segment
		(start 148.717 -86.828122)
		(end 136.47928 -74.590402)
		(width 0.1143)
		(layer "In2.Cu")
		(net "UART_DTR_P4_N")
	)
	(segment
		(start 136.47928 -74.590402)
		(end 136.47928 -73.822052)
		(width 0.1143)
		(layer "In2.Cu")
		(net "UART_DTR_P4_N")
	)
	(segment
		(start 134.11708 -71.459852)
		(end 134.11708 -70.28942)
		(width 0.1143)
		(layer "In2.Cu")
		(net "UART_DTR_P4_N")
	)
	(segment
		(start 189.992 -125.476)
		(end 189.992 -123.698)
		(width 0.1143)
		(layer "In2.Cu")
		(net "UART_DTR_P4_N")
	)
	(segment
		(start 189.992 -123.698)
		(end 189.570106 -123.276106)
		(width 0.1143)
		(layer "In2.Cu")
		(net "UART_DTR_P4_N")
	)
	(segment
		(start 188.3537 -147.676108)
		(end 188.3537 -143.7259)
		(width 0.1143)
		(layer "In2.Cu")
		(net "UART_DTR_P4_N")
	)
	(segment
		(start 85.53323 -183.555894)
		(end 85.29447 -183.317134)
		(width 0.1143)
		(layer "In6.Cu")
		(net "UART_DTR_P4_N")
	)
	(segment
		(start 111.57204 -182.290974)
		(end 109.252512 -182.290974)
		(width 0.1143)
		(layer "In6.Cu")
		(net "UART_DTR_P4_N")
	)
	(segment
		(start 120.555258 -181.972458)
		(end 111.890556 -181.972458)
		(width 0.1143)
		(layer "In6.Cu")
		(net "UART_DTR_P4_N")
	)
	(segment
		(start 105.57256 -182.919116)
		(end 104.84993 -182.196486)
		(width 0.1143)
		(layer "In6.Cu")
		(net "UART_DTR_P4_N")
	)
	(segment
		(start 127.14224 -180.925978)
		(end 126.77648 -180.925978)
		(width 0.1143)
		(layer "In6.Cu")
		(net "UART_DTR_P4_N")
	)
	(segment
		(start 103.514906 -181.881272)
		(end 102.997 -181.363366)
		(width 0.1143)
		(layer "In6.Cu")
		(net "UART_DTR_P4_N")
	)
	(segment
		(start 121.611136 -180.91658)
		(end 120.555258 -181.972458)
		(width 0.1143)
		(layer "In6.Cu")
		(net "UART_DTR_P4_N")
	)
	(segment
		(start 108.62437 -182.919116)
		(end 105.57256 -182.919116)
		(width 0.1143)
		(layer "In6.Cu")
		(net "UART_DTR_P4_N")
	)
	(segment
		(start 128.517396 -179.550822)
		(end 127.14224 -180.925978)
		(width 0.1143)
		(layer "In6.Cu")
		(net "UART_DTR_P4_N")
	)
	(segment
		(start 104.486456 -181.881272)
		(end 103.514906 -181.881272)
		(width 0.1143)
		(layer "In6.Cu")
		(net "UART_DTR_P4_N")
	)
	(segment
		(start 88.624156 -182.471822)
		(end 87.540084 -183.555894)
		(width 0.1143)
		(layer "In6.Cu")
		(net "UART_DTR_P4_N")
	)
	(segment
		(start 89.88044 -182.471822)
		(end 88.624156 -182.471822)
		(width 0.1143)
		(layer "In6.Cu")
		(net "UART_DTR_P4_N")
	)
	(segment
		(start 80.400652 -183.317134)
		(end 79.792322 -182.708804)
		(width 0.1143)
		(layer "In6.Cu")
		(net "UART_DTR_P4_N")
	)
	(segment
		(start 102.997 -181.363366)
		(end 100.701602 -181.363366)
		(width 0.1143)
		(layer "In6.Cu")
		(net "UART_DTR_P4_N")
	)
	(segment
		(start 126.767082 -180.91658)
		(end 121.611136 -180.91658)
		(width 0.1143)
		(layer "In6.Cu")
		(net "UART_DTR_P4_N")
	)
	(segment
		(start 109.252512 -182.290974)
		(end 108.62437 -182.919116)
		(width 0.1143)
		(layer "In6.Cu")
		(net "UART_DTR_P4_N")
	)
	(segment
		(start 100.701602 -181.363366)
		(end 100.237544 -181.827424)
		(width 0.1143)
		(layer "In6.Cu")
		(net "UART_DTR_P4_N")
	)
	(segment
		(start 87.540084 -183.555894)
		(end 85.53323 -183.555894)
		(width 0.1143)
		(layer "In6.Cu")
		(net "UART_DTR_P4_N")
	)
	(segment
		(start 104.80167 -182.196486)
		(end 104.486456 -181.881272)
		(width 0.1143)
		(layer "In6.Cu")
		(net "UART_DTR_P4_N")
	)
	(segment
		(start 111.890556 -181.972458)
		(end 111.57204 -182.290974)
		(width 0.1143)
		(layer "In6.Cu")
		(net "UART_DTR_P4_N")
	)
	(segment
		(start 135.452104 -179.550822)
		(end 128.517396 -179.550822)
		(width 0.1143)
		(layer "In6.Cu")
		(net "UART_DTR_P4_N")
	)
	(segment
		(start 79.06385 -182.708804)
		(end 78.006702 -181.651656)
		(width 0.1143)
		(layer "In6.Cu")
		(net "UART_DTR_P4_N")
	)
	(segment
		(start 94.585282 -182.025544)
		(end 90.326718 -182.025544)
		(width 0.1143)
		(layer "In6.Cu")
		(net "UART_DTR_P4_N")
	)
	(segment
		(start 78.006702 -181.651656)
		(end 78.006702 -181.102762)
		(width 0.1143)
		(layer "In6.Cu")
		(net "UART_DTR_P4_N")
	)
	(segment
		(start 85.29447 -183.317134)
		(end 80.400652 -183.317134)
		(width 0.1143)
		(layer "In6.Cu")
		(net "UART_DTR_P4_N")
	)
	(segment
		(start 90.326718 -182.025544)
		(end 89.88044 -182.471822)
		(width 0.1143)
		(layer "In6.Cu")
		(net "UART_DTR_P4_N")
	)
	(segment
		(start 135.905748 -180.004466)
		(end 135.452104 -179.550822)
		(width 0.1143)
		(layer "In6.Cu")
		(net "UART_DTR_P4_N")
	)
	(segment
		(start 79.792322 -182.708804)
		(end 79.06385 -182.708804)
		(width 0.1143)
		(layer "In6.Cu")
		(net "UART_DTR_P4_N")
	)
	(segment
		(start 100.237544 -181.827424)
		(end 94.783402 -181.827424)
		(width 0.1143)
		(layer "In6.Cu")
		(net "UART_DTR_P4_N")
	)
	(segment
		(start 126.77648 -180.925978)
		(end 126.767082 -180.91658)
		(width 0.1143)
		(layer "In6.Cu")
		(net "UART_DTR_P4_N")
	)
	(segment
		(start 104.84993 -182.196486)
		(end 104.80167 -182.196486)
		(width 0.1143)
		(layer "In6.Cu")
		(net "UART_DTR_P4_N")
	)
	(segment
		(start 94.783402 -181.827424)
		(end 94.585282 -182.025544)
		(width 0.1143)
		(layer "In6.Cu")
		(net "UART_DTR_P4_N")
	)
	(segment
		(start 156.564076 -14.413738)
		(end 163.46678 -21.316442)
		(width 0.1016)
		(layer "F.Cu")
		(net "UART_DTR_P1_L_N")
	)
	(segment
		(start 30.66034 -198.434452)
		(end 30.66034 -199.651366)
		(width 0.1016)
		(layer "F.Cu")
		(net "UART_DTR_P1_L_N")
	)
	(segment
		(start 163.46678 -34.716212)
		(end 162.447986 -35.735006)
		(width 0.1016)
		(layer "F.Cu")
		(net "UART_DTR_P1_L_N")
	)
	(segment
		(start 30.66034 -199.651366)
		(end 31.014924 -200.00595)
		(width 0.1016)
		(layer "F.Cu")
		(net "UART_DTR_P1_L_N")
	)
	(segment
		(start 124.213112 -14.569694)
		(end 126.141226 -12.64158)
		(width 0.1016)
		(layer "F.Cu")
		(net "UART_DTR_P1_L_N")
	)
	(segment
		(start 122.82932 -14.569694)
		(end 124.213112 -14.569694)
		(width 0.1016)
		(layer "F.Cu")
		(net "UART_DTR_P1_L_N")
	)
	(segment
		(start 31.014924 -200.00595)
		(end 31.014924 -205.199488)
		(width 0.1016)
		(layer "F.Cu")
		(net "UART_DTR_P1_L_N")
	)
	(segment
		(start 139.582398 -14.413738)
		(end 156.564076 -14.413738)
		(width 0.1016)
		(layer "F.Cu")
		(net "UART_DTR_P1_L_N")
	)
	(segment
		(start 30.50286 -198.276972)
		(end 30.66034 -198.434452)
		(width 0.1016)
		(layer "F.Cu")
		(net "UART_DTR_P1_L_N")
	)
	(segment
		(start 163.46678 -21.316442)
		(end 163.46678 -34.716212)
		(width 0.1016)
		(layer "F.Cu")
		(net "UART_DTR_P1_L_N")
	)
	(segment
		(start 120.72874 -15.175484)
		(end 122.22353 -15.175484)
		(width 0.1016)
		(layer "F.Cu")
		(net "UART_DTR_P1_L_N")
	)
	(segment
		(start 122.22353 -15.175484)
		(end 122.82932 -14.569694)
		(width 0.1016)
		(layer "F.Cu")
		(net "UART_DTR_P1_L_N")
	)
	(segment
		(start 126.141226 -12.64158)
		(end 137.81024 -12.64158)
		(width 0.1016)
		(layer "F.Cu")
		(net "UART_DTR_P1_L_N")
	)
	(segment
		(start 137.81024 -12.64158)
		(end 139.582398 -14.413738)
		(width 0.1016)
		(layer "F.Cu")
		(net "UART_DTR_P1_L_N")
	)
	(segment
		(start 162.447986 -35.735006)
		(end 158.271972 -35.735006)
		(width 0.1016)
		(layer "F.Cu")
		(net "UART_DTR_P1_L_N")
	)
	(via
		(at 30.50286 -198.276972)
		(size 0.508)
		(drill 0.254)
		(layers "F.Cu" "B.Cu")
		(net "UART_DTR_P1_L_N")
	)
	(via
		(at 120.72874 -15.175484)
		(size 0.508)
		(drill 0.254)
		(layers "F.Cu" "B.Cu")
		(net "UART_DTR_P1_L_N")
	)
	(segment
		(start 7.61365 -103.018336)
		(end 7.61365 -120.088914)
		(width 0.1143)
		(layer "In2.Cu")
		(net "UART_DTR_P1_L_N")
	)
	(segment
		(start 87.991188 -13.02893)
		(end 86.41842 -13.626846)
		(width 0.1143)
		(layer "In2.Cu")
		(net "UART_DTR_P1_L_N")
	)
	(segment
		(start 90.117422 -13.122656)
		(end 89.744042 -12.749276)
		(width 0.1143)
		(layer "In2.Cu")
		(net "UART_DTR_P1_L_N")
	)
	(segment
		(start 36.36518 -27.832558)
		(end 28.71724 -35.480498)
		(width 0.1143)
		(layer "In2.Cu")
		(net "UART_DTR_P1_L_N")
	)
	(segment
		(start 10.0711 -165.61181)
		(end 11.194796 -166.735506)
		(width 0.1143)
		(layer "In2.Cu")
		(net "UART_DTR_P1_L_N")
	)
	(segment
		(start 24.74595 -81.640172)
		(end 19.29892 -87.087202)
		(width 0.1143)
		(layer "In2.Cu")
		(net "UART_DTR_P1_L_N")
	)
	(segment
		(start 7.61365 -120.088914)
		(end 7.035038 -120.667526)
		(width 0.1143)
		(layer "In2.Cu")
		(net "UART_DTR_P1_L_N")
	)
	(segment
		(start 36.50996 -24.27859)
		(end 36.50996 -27.68727)
		(width 0.1143)
		(layer "In2.Cu")
		(net "UART_DTR_P1_L_N")
	)
	(segment
		(start 25.086818 -56.082184)
		(end 25.086818 -56.857138)
		(width 0.1143)
		(layer "In2.Cu")
		(net "UART_DTR_P1_L_N")
	)
	(segment
		(start 7.07009 -146.964908)
		(end 6.067298 -147.9677)
		(width 0.1143)
		(layer "In2.Cu")
		(net "UART_DTR_P1_L_N")
	)
	(segment
		(start 19.29892 -92.336366)
		(end 14.415008 -97.220278)
		(width 0.1143)
		(layer "In2.Cu")
		(net "UART_DTR_P1_L_N")
	)
	(segment
		(start 57.8993 -18.458942)
		(end 55.88254 -20.475702)
		(width 0.1143)
		(layer "In2.Cu")
		(net "UART_DTR_P1_L_N")
	)
	(segment
		(start 67.44335 -16.610584)
		(end 66.61658 -17.437354)
		(width 0.1143)
		(layer "In2.Cu")
		(net "UART_DTR_P1_L_N")
	)
	(segment
		(start 25.329896 -44.44619)
		(end 25.329896 -55.839106)
		(width 0.1143)
		(layer "In2.Cu")
		(net "UART_DTR_P1_L_N")
	)
	(segment
		(start 28.71724 -35.480498)
		(end 28.71724 -41.026842)
		(width 0.1143)
		(layer "In2.Cu")
		(net "UART_DTR_P1_L_N")
	)
	(segment
		(start 24.183086 -57.76087)
		(end 23.618698 -59.711844)
		(width 0.1143)
		(layer "In2.Cu")
		(net "UART_DTR_P1_L_N")
	)
	(segment
		(start 13.038074 -97.220278)
		(end 11.91895 -98.339402)
		(width 0.1143)
		(layer "In2.Cu")
		(net "UART_DTR_P1_L_N")
	)
	(segment
		(start 11.91895 -98.339402)
		(end 11.91895 -98.713036)
		(width 0.1143)
		(layer "In2.Cu")
		(net "UART_DTR_P1_L_N")
	)
	(segment
		(start 107.10418 -13.122656)
		(end 90.117422 -13.122656)
		(width 0.1143)
		(layer "In2.Cu")
		(net "UART_DTR_P1_L_N")
	)
	(segment
		(start 27.186382 -41.714928)
		(end 26.48712 -42.41419)
		(width 0.1143)
		(layer "In2.Cu")
		(net "UART_DTR_P1_L_N")
	)
	(segment
		(start 6.08584 -151.874982)
		(end 6.08584 -161.397442)
		(width 0.1143)
		(layer "In2.Cu")
		(net "UART_DTR_P1_L_N")
	)
	(segment
		(start 39.843456 -20.945094)
		(end 36.50996 -24.27859)
		(width 0.1143)
		(layer "In2.Cu")
		(net "UART_DTR_P1_L_N")
	)
	(segment
		(start 11.194796 -166.735506)
		(end 12.345416 -166.735506)
		(width 0.1143)
		(layer "In2.Cu")
		(net "UART_DTR_P1_L_N")
	)
	(segment
		(start 108.919772 -14.918944)
		(end 107.130342 -13.129514)
		(width 0.1143)
		(layer "In2.Cu")
		(net "UART_DTR_P1_L_N")
	)
	(segment
		(start 14.415008 -97.220278)
		(end 13.038074 -97.220278)
		(width 0.1143)
		(layer "In2.Cu")
		(net "UART_DTR_P1_L_N")
	)
	(segment
		(start 25.329896 -55.839106)
		(end 25.086818 -56.082184)
		(width 0.1143)
		(layer "In2.Cu")
		(net "UART_DTR_P1_L_N")
	)
	(segment
		(start 89.744042 -12.749276)
		(end 88.27262 -12.749276)
		(width 0.1143)
		(layer "In2.Cu")
		(net "UART_DTR_P1_L_N")
	)
	(segment
		(start 6.313424 -151.647398)
		(end 6.08584 -151.874982)
		(width 0.1143)
		(layer "In2.Cu")
		(net "UART_DTR_P1_L_N")
	)
	(segment
		(start 28.71724 -41.026842)
		(end 28.029154 -41.714928)
		(width 0.1143)
		(layer "In2.Cu")
		(net "UART_DTR_P1_L_N")
	)
	(segment
		(start 86.41842 -13.626846)
		(end 83.434682 -16.610584)
		(width 0.1143)
		(layer "In2.Cu")
		(net "UART_DTR_P1_L_N")
	)
	(segment
		(start 10.0711 -165.382702)
		(end 10.0711 -165.61181)
		(width 0.1143)
		(layer "In2.Cu")
		(net "UART_DTR_P1_L_N")
	)
	(segment
		(start 55.88254 -20.475702)
		(end 41.8846 -20.475702)
		(width 0.1143)
		(layer "In2.Cu")
		(net "UART_DTR_P1_L_N")
	)
	(segment
		(start 41.8846 -20.475702)
		(end 41.415208 -20.945094)
		(width 0.1143)
		(layer "In2.Cu")
		(net "UART_DTR_P1_L_N")
	)
	(segment
		(start 65.7733 -17.437354)
		(end 64.751712 -18.458942)
		(width 0.1143)
		(layer "In2.Cu")
		(net "UART_DTR_P1_L_N")
	)
	(segment
		(start 6.313424 -151.01697)
		(end 6.313424 -151.647398)
		(width 0.1143)
		(layer "In2.Cu")
		(net "UART_DTR_P1_L_N")
	)
	(segment
		(start 83.434682 -16.610584)
		(end 67.44335 -16.610584)
		(width 0.1143)
		(layer "In2.Cu")
		(net "UART_DTR_P1_L_N")
	)
	(segment
		(start 11.91895 -98.713036)
		(end 7.61365 -103.018336)
		(width 0.1143)
		(layer "In2.Cu")
		(net "UART_DTR_P1_L_N")
	)
	(segment
		(start 23.618698 -59.711844)
		(end 23.618698 -65.074546)
		(width 0.1143)
		(layer "In2.Cu")
		(net "UART_DTR_P1_L_N")
	)
	(segment
		(start 7.07009 -140.366242)
		(end 7.07009 -146.964908)
		(width 0.1143)
		(layer "In2.Cu")
		(net "UART_DTR_P1_L_N")
	)
	(segment
		(start 66.61658 -17.437354)
		(end 65.7733 -17.437354)
		(width 0.1143)
		(layer "In2.Cu")
		(net "UART_DTR_P1_L_N")
	)
	(segment
		(start 23.618698 -65.074546)
		(end 24.74595 -66.201798)
		(width 0.1143)
		(layer "In2.Cu")
		(net "UART_DTR_P1_L_N")
	)
	(segment
		(start 88.27262 -12.749276)
		(end 88.02116 -12.999212)
		(width 0.1143)
		(layer "In2.Cu")
		(net "UART_DTR_P1_L_N")
	)
	(segment
		(start 24.74595 -66.201798)
		(end 24.74595 -81.640172)
		(width 0.1143)
		(layer "In2.Cu")
		(net "UART_DTR_P1_L_N")
	)
	(segment
		(start 36.50996 -27.68727)
		(end 36.36518 -27.832558)
		(width 0.1143)
		(layer "In2.Cu")
		(net "UART_DTR_P1_L_N")
	)
	(segment
		(start 64.751712 -18.458942)
		(end 57.8993 -18.458942)
		(width 0.1143)
		(layer "In2.Cu")
		(net "UART_DTR_P1_L_N")
	)
	(segment
		(start 19.29892 -87.087202)
		(end 19.29892 -92.336366)
		(width 0.1143)
		(layer "In2.Cu")
		(net "UART_DTR_P1_L_N")
	)
	(segment
		(start 26.48712 -43.288966)
		(end 25.329896 -44.44619)
		(width 0.1143)
		(layer "In2.Cu")
		(net "UART_DTR_P1_L_N")
	)
	(segment
		(start 107.130342 -13.129514)
		(end 107.10418 -13.122656)
		(width 0.1143)
		(layer "In2.Cu")
		(net "UART_DTR_P1_L_N")
	)
	(segment
		(start 26.48712 -42.41419)
		(end 26.48712 -43.288966)
		(width 0.1143)
		(layer "In2.Cu")
		(net "UART_DTR_P1_L_N")
	)
	(segment
		(start 6.067298 -150.770844)
		(end 6.313424 -151.01697)
		(width 0.1143)
		(layer "In2.Cu")
		(net "UART_DTR_P1_L_N")
	)
	(segment
		(start 16.56334 -170.95343)
		(end 16.56334 -184.786778)
		(width 0.1143)
		(layer "In2.Cu")
		(net "UART_DTR_P1_L_N")
	)
	(segment
		(start 30.053534 -198.276972)
		(end 30.50286 -198.276972)
		(width 0.1143)
		(layer "In2.Cu")
		(net "UART_DTR_P1_L_N")
	)
	(segment
		(start 88.02116 -12.999212)
		(end 87.991188 -13.02893)
		(width 0.1143)
		(layer "In2.Cu")
		(net "UART_DTR_P1_L_N")
	)
	(segment
		(start 7.035038 -120.667526)
		(end 7.035038 -140.33119)
		(width 0.1143)
		(layer "In2.Cu")
		(net "UART_DTR_P1_L_N")
	)
	(segment
		(start 28.029154 -41.714928)
		(end 27.186382 -41.714928)
		(width 0.1143)
		(layer "In2.Cu")
		(net "UART_DTR_P1_L_N")
	)
	(segment
		(start 41.415208 -20.945094)
		(end 39.843456 -20.945094)
		(width 0.1143)
		(layer "In2.Cu")
		(net "UART_DTR_P1_L_N")
	)
	(segment
		(start 120.72874 -15.175484)
		(end 120.4722 -14.918944)
		(width 0.1143)
		(layer "In2.Cu")
		(net "UART_DTR_P1_L_N")
	)
	(segment
		(start 120.4722 -14.918944)
		(end 108.919772 -14.918944)
		(width 0.1143)
		(layer "In2.Cu")
		(net "UART_DTR_P1_L_N")
	)
	(segment
		(start 16.56334 -184.786778)
		(end 30.053534 -198.276972)
		(width 0.1143)
		(layer "In2.Cu")
		(net "UART_DTR_P1_L_N")
	)
	(segment
		(start 7.035038 -140.33119)
		(end 7.07009 -140.366242)
		(width 0.1143)
		(layer "In2.Cu")
		(net "UART_DTR_P1_L_N")
	)
	(segment
		(start 6.067298 -147.9677)
		(end 6.067298 -150.770844)
		(width 0.1143)
		(layer "In2.Cu")
		(net "UART_DTR_P1_L_N")
	)
	(segment
		(start 25.086818 -56.857138)
		(end 24.183086 -57.76087)
		(width 0.1143)
		(layer "In2.Cu")
		(net "UART_DTR_P1_L_N")
	)
	(segment
		(start 6.08584 -161.397442)
		(end 10.0711 -165.382702)
		(width 0.1143)
		(layer "In2.Cu")
		(net "UART_DTR_P1_L_N")
	)
	(segment
		(start 12.345416 -166.735506)
		(end 16.56334 -170.95343)
		(width 0.1143)
		(layer "In2.Cu")
		(net "UART_DTR_P1_L_N")
	)
	(segment
		(start 32.020002 -205.194408)
		(end 32.014922 -205.199488)
		(width 0.1016)
		(layer "F.Cu")
		(net "UART_TX_P1_L")
	)
	(segment
		(start 126.268226 -12.94638)
		(end 137.579354 -12.94638)
		(width 0.1016)
		(layer "F.Cu")
		(net "UART_TX_P1_L")
	)
	(segment
		(start 163.16198 -21.442934)
		(end 163.16198 -34.325052)
		(width 0.1016)
		(layer "F.Cu")
		(net "UART_TX_P1_L")
	)
	(segment
		(start 32.020002 -199.593708)
		(end 32.020002 -205.194408)
		(width 0.1016)
		(layer "F.Cu")
		(net "UART_TX_P1_L")
	)
	(segment
		(start 123.20016 -14.921484)
		(end 124.293122 -14.921484)
		(width 0.1016)
		(layer "F.Cu")
		(net "UART_TX_P1_L")
	)
	(segment
		(start 139.425172 -14.792198)
		(end 156.511244 -14.792198)
		(width 0.1016)
		(layer "F.Cu")
		(net "UART_TX_P1_L")
	)
	(segment
		(start 31.99384 -199.567546)
		(end 32.020002 -199.593708)
		(width 0.1016)
		(layer "F.Cu")
		(net "UART_TX_P1_L")
	)
	(segment
		(start 163.16198 -34.325052)
		(end 162.402012 -35.08502)
		(width 0.1016)
		(layer "F.Cu")
		(net "UART_TX_P1_L")
	)
	(segment
		(start 137.579354 -12.94638)
		(end 139.425172 -14.792198)
		(width 0.1016)
		(layer "F.Cu")
		(net "UART_TX_P1_L")
	)
	(segment
		(start 162.402012 -35.08502)
		(end 158.271972 -35.08502)
		(width 0.1016)
		(layer "F.Cu")
		(net "UART_TX_P1_L")
	)
	(segment
		(start 124.293122 -14.921484)
		(end 126.268226 -12.94638)
		(width 0.1016)
		(layer "F.Cu")
		(net "UART_TX_P1_L")
	)
	(segment
		(start 156.511244 -14.792198)
		(end 163.16198 -21.442934)
		(width 0.1016)
		(layer "F.Cu")
		(net "UART_TX_P1_L")
	)
	(segment
		(start 122.74296 -15.378684)
		(end 123.20016 -14.921484)
		(width 0.1016)
		(layer "F.Cu")
		(net "UART_TX_P1_L")
	)
	(via
		(at 122.74296 -15.378684)
		(size 0.508)
		(drill 0.254)
		(layers "F.Cu" "B.Cu")
		(net "UART_TX_P1_L")
	)
	(via
		(at 31.99384 -199.567546)
		(size 0.508)
		(drill 0.254)
		(layers "F.Cu" "B.Cu")
		(net "UART_TX_P1_L")
	)
	(segment
		(start 41.54678 -21.262594)
		(end 41.953688 -20.855686)
		(width 0.1143)
		(layer "In2.Cu")
		(net "UART_TX_P1_L")
	)
	(segment
		(start 19.93392 -91.881452)
		(end 19.93392 -87.350346)
		(width 0.1143)
		(layer "In2.Cu")
		(net "UART_TX_P1_L")
	)
	(segment
		(start 17.19834 -184.523634)
		(end 17.19834 -170.690286)
		(width 0.1143)
		(layer "In2.Cu")
		(net "UART_TX_P1_L")
	)
	(segment
		(start 13.970254 -98.5647)
		(end 19.93392 -92.601034)
		(width 0.1143)
		(layer "In2.Cu")
		(net "UART_TX_P1_L")
	)
	(segment
		(start 26.58999 -53.697124)
		(end 26.58999 -44.08424)
		(width 0.1143)
		(layer "In2.Cu")
		(net "UART_TX_P1_L")
	)
	(segment
		(start 19.93646 -92.146628)
		(end 19.93646 -91.883992)
		(width 0.1143)
		(layer "In2.Cu")
		(net "UART_TX_P1_L")
	)
	(segment
		(start 19.93392 -92.601034)
		(end 19.93392 -92.148406)
		(width 0.1143)
		(layer "In2.Cu")
		(net "UART_TX_P1_L")
	)
	(segment
		(start 30.59684 -196.979286)
		(end 29.653992 -196.979286)
		(width 0.1143)
		(layer "In2.Cu")
		(net "UART_TX_P1_L")
	)
	(segment
		(start 19.93646 -91.883992)
		(end 19.93392 -91.881452)
		(width 0.1143)
		(layer "In2.Cu")
		(net "UART_TX_P1_L")
	)
	(segment
		(start 6.72084 -160.791398)
		(end 6.72084 -152.795986)
		(width 0.1143)
		(layer "In2.Cu")
		(net "UART_TX_P1_L")
	)
	(segment
		(start 17.19834 -170.690286)
		(end 12.60856 -166.100506)
		(width 0.1143)
		(layer "In2.Cu")
		(net "UART_TX_P1_L")
	)
	(segment
		(start 28.063698 -55.170832)
		(end 26.58999 -53.697124)
		(width 0.1143)
		(layer "In2.Cu")
		(net "UART_TX_P1_L")
	)
	(segment
		(start 89.957656 -13.440156)
		(end 106.990642 -13.440156)
		(width 0.1143)
		(layer "In2.Cu")
		(net "UART_TX_P1_L")
	)
	(segment
		(start 19.93392 -87.350346)
		(end 28.063698 -79.220568)
		(width 0.1143)
		(layer "In2.Cu")
		(net "UART_TX_P1_L")
	)
	(segment
		(start 29.653992 -196.979286)
		(end 17.19834 -184.523634)
		(width 0.1143)
		(layer "In2.Cu")
		(net "UART_TX_P1_L")
	)
	(segment
		(start 108.92917 -15.378684)
		(end 119.732552 -15.378684)
		(width 0.1143)
		(layer "In2.Cu")
		(net "UART_TX_P1_L")
	)
	(segment
		(start 88.166956 -13.302996)
		(end 88.168226 -13.301726)
		(width 0.1143)
		(layer "In2.Cu")
		(net "UART_TX_P1_L")
	)
	(segment
		(start 67.57543 -16.928084)
		(end 83.70443 -16.928084)
		(width 0.1143)
		(layer "In2.Cu")
		(net "UART_TX_P1_L")
	)
	(segment
		(start 7.91591 -139.521692)
		(end 7.91591 -120.76557)
		(width 0.1143)
		(layer "In2.Cu")
		(net "UART_TX_P1_L")
	)
	(segment
		(start 89.58326 -13.066776)
		(end 89.64803 -13.131292)
		(width 0.1143)
		(layer "In2.Cu")
		(net "UART_TX_P1_L")
	)
	(segment
		(start 119.967502 -15.613634)
		(end 122.50801 -15.613634)
		(width 0.1143)
		(layer "In2.Cu")
		(net "UART_TX_P1_L")
	)
	(segment
		(start 31.83128 -199.404986)
		(end 31.83128 -198.213726)
		(width 0.1143)
		(layer "In2.Cu")
		(net "UART_TX_P1_L")
	)
	(segment
		(start 88.168226 -13.301726)
		(end 88.24595 -13.22451)
		(width 0.1143)
		(layer "In2.Cu")
		(net "UART_TX_P1_L")
	)
	(segment
		(start 83.70443 -16.928084)
		(end 86.816946 -13.815822)
		(width 0.1143)
		(layer "In2.Cu")
		(net "UART_TX_P1_L")
	)
	(segment
		(start 6.948424 -150.753826)
		(end 6.702298 -150.5077)
		(width 0.1143)
		(layer "In2.Cu")
		(net "UART_TX_P1_L")
	)
	(segment
		(start 7.9121 -147.021804)
		(end 7.9121 -140.514578)
		(width 0.1143)
		(layer "In2.Cu")
		(net "UART_TX_P1_L")
	)
	(segment
		(start 26.58999 -44.08424)
		(end 29.05506 -41.61917)
		(width 0.1143)
		(layer "In2.Cu")
		(net "UART_TX_P1_L")
	)
	(segment
		(start 56.086248 -20.855686)
		(end 58.151776 -18.790158)
		(width 0.1143)
		(layer "In2.Cu")
		(net "UART_TX_P1_L")
	)
	(segment
		(start 66.74866 -17.754854)
		(end 67.57543 -16.928084)
		(width 0.1143)
		(layer "In2.Cu")
		(net "UART_TX_P1_L")
	)
	(segment
		(start 6.702298 -150.5077)
		(end 6.702298 -148.231606)
		(width 0.1143)
		(layer "In2.Cu")
		(net "UART_TX_P1_L")
	)
	(segment
		(start 39.975028 -21.262594)
		(end 41.54678 -21.262594)
		(width 0.1143)
		(layer "In2.Cu")
		(net "UART_TX_P1_L")
	)
	(segment
		(start 88.24595 -13.22451)
		(end 88.4047 -13.066776)
		(width 0.1143)
		(layer "In2.Cu")
		(net "UART_TX_P1_L")
	)
	(segment
		(start 36.82746 -24.410162)
		(end 39.975028 -21.262594)
		(width 0.1143)
		(layer "In2.Cu")
		(net "UART_TX_P1_L")
	)
	(segment
		(start 8.228838 -140.19784)
		(end 8.228838 -139.83462)
		(width 0.1143)
		(layer "In2.Cu")
		(net "UART_TX_P1_L")
	)
	(segment
		(start 11.45794 -166.100506)
		(end 10.90041 -165.542976)
		(width 0.1143)
		(layer "In2.Cu")
		(net "UART_TX_P1_L")
	)
	(segment
		(start 8.2804 -103.605838)
		(end 12.544552 -99.341686)
		(width 0.1143)
		(layer "In2.Cu")
		(net "UART_TX_P1_L")
	)
	(segment
		(start 12.74064 -99.341686)
		(end 13.517626 -98.5647)
		(width 0.1143)
		(layer "In2.Cu")
		(net "UART_TX_P1_L")
	)
	(segment
		(start 12.544552 -99.341686)
		(end 12.74064 -99.341686)
		(width 0.1143)
		(layer "In2.Cu")
		(net "UART_TX_P1_L")
	)
	(segment
		(start 6.702298 -148.231606)
		(end 7.9121 -147.021804)
		(width 0.1143)
		(layer "In2.Cu")
		(net "UART_TX_P1_L")
	)
	(segment
		(start 86.816946 -13.815822)
		(end 88.166956 -13.302996)
		(width 0.1143)
		(layer "In2.Cu")
		(net "UART_TX_P1_L")
	)
	(segment
		(start 10.90041 -165.542976)
		(end 10.90041 -164.970968)
		(width 0.1143)
		(layer "In2.Cu")
		(net "UART_TX_P1_L")
	)
	(segment
		(start 36.6776 -27.96921)
		(end 36.68268 -27.963876)
		(width 0.1143)
		(layer "In2.Cu")
		(net "UART_TX_P1_L")
	)
	(segment
		(start 31.83128 -198.213726)
		(end 30.59684 -196.979286)
		(width 0.1143)
		(layer "In2.Cu")
		(net "UART_TX_P1_L")
	)
	(segment
		(start 122.50801 -15.613634)
		(end 122.74296 -15.378684)
		(width 0.1143)
		(layer "In2.Cu")
		(net "UART_TX_P1_L")
	)
	(segment
		(start 6.948424 -152.568402)
		(end 6.948424 -150.753826)
		(width 0.1143)
		(layer "In2.Cu")
		(net "UART_TX_P1_L")
	)
	(segment
		(start 58.151776 -18.790158)
		(end 64.870076 -18.790158)
		(width 0.1143)
		(layer "In2.Cu")
		(net "UART_TX_P1_L")
	)
	(segment
		(start 36.68268 -27.963876)
		(end 36.82746 -27.818588)
		(width 0.1143)
		(layer "In2.Cu")
		(net "UART_TX_P1_L")
	)
	(segment
		(start 8.228838 -139.83462)
		(end 7.91591 -139.521692)
		(width 0.1143)
		(layer "In2.Cu")
		(net "UART_TX_P1_L")
	)
	(segment
		(start 10.90041 -164.970968)
		(end 6.72084 -160.791398)
		(width 0.1143)
		(layer "In2.Cu")
		(net "UART_TX_P1_L")
	)
	(segment
		(start 7.91591 -120.76557)
		(end 8.2804 -120.40108)
		(width 0.1143)
		(layer "In2.Cu")
		(net "UART_TX_P1_L")
	)
	(segment
		(start 6.72084 -152.795986)
		(end 6.948424 -152.568402)
		(width 0.1143)
		(layer "In2.Cu")
		(net "UART_TX_P1_L")
	)
	(segment
		(start 36.82746 -27.818588)
		(end 36.82746 -24.410162)
		(width 0.1143)
		(layer "In2.Cu")
		(net "UART_TX_P1_L")
	)
	(segment
		(start 12.60856 -166.100506)
		(end 11.45794 -166.100506)
		(width 0.1143)
		(layer "In2.Cu")
		(net "UART_TX_P1_L")
	)
	(segment
		(start 8.2804 -120.40108)
		(end 8.2804 -103.605838)
		(width 0.1143)
		(layer "In2.Cu")
		(net "UART_TX_P1_L")
	)
	(segment
		(start 41.953688 -20.855686)
		(end 56.086248 -20.855686)
		(width 0.1143)
		(layer "In2.Cu")
		(net "UART_TX_P1_L")
	)
	(segment
		(start 19.93392 -92.148406)
		(end 19.935698 -92.146628)
		(width 0.1143)
		(layer "In2.Cu")
		(net "UART_TX_P1_L")
	)
	(segment
		(start 29.05506 -41.61917)
		(end 29.05506 -35.59175)
		(width 0.1143)
		(layer "In2.Cu")
		(net "UART_TX_P1_L")
	)
	(segment
		(start 119.732552 -15.378684)
		(end 119.967502 -15.613634)
		(width 0.1143)
		(layer "In2.Cu")
		(net "UART_TX_P1_L")
	)
	(segment
		(start 64.870076 -18.790158)
		(end 65.90538 -17.754854)
		(width 0.1143)
		(layer "In2.Cu")
		(net "UART_TX_P1_L")
	)
	(segment
		(start 89.64803 -13.131292)
		(end 89.957656 -13.440156)
		(width 0.1143)
		(layer "In2.Cu")
		(net "UART_TX_P1_L")
	)
	(segment
		(start 31.99384 -199.567546)
		(end 31.83128 -199.404986)
		(width 0.1143)
		(layer "In2.Cu")
		(net "UART_TX_P1_L")
	)
	(segment
		(start 88.4047 -13.066776)
		(end 89.58326 -13.066776)
		(width 0.1143)
		(layer "In2.Cu")
		(net "UART_TX_P1_L")
	)
	(segment
		(start 19.935698 -92.146628)
		(end 19.93646 -92.146628)
		(width 0.1143)
		(layer "In2.Cu")
		(net "UART_TX_P1_L")
	)
	(segment
		(start 13.517626 -98.5647)
		(end 13.970254 -98.5647)
		(width 0.1143)
		(layer "In2.Cu")
		(net "UART_TX_P1_L")
	)
	(segment
		(start 28.063698 -79.220568)
		(end 28.063698 -55.170832)
		(width 0.1143)
		(layer "In2.Cu")
		(net "UART_TX_P1_L")
	)
	(segment
		(start 106.990642 -13.440156)
		(end 108.92917 -15.378684)
		(width 0.1143)
		(layer "In2.Cu")
		(net "UART_TX_P1_L")
	)
	(segment
		(start 65.90538 -17.754854)
		(end 66.74866 -17.754854)
		(width 0.1143)
		(layer "In2.Cu")
		(net "UART_TX_P1_L")
	)
	(segment
		(start 29.05506 -35.59175)
		(end 36.6776 -27.96921)
		(width 0.1143)
		(layer "In2.Cu")
		(net "UART_TX_P1_L")
	)
	(segment
		(start 7.9121 -140.514578)
		(end 8.228838 -140.19784)
		(width 0.1143)
		(layer "In2.Cu")
		(net "UART_TX_P1_L")
	)
	(segment
		(start 162.85718 -33.9471)
		(end 162.85718 -21.569426)
		(width 0.1016)
		(layer "F.Cu")
		(net "UART_RTS_P1_L_N")
	)
	(segment
		(start 35.0139 -199.511158)
		(end 35.014916 -199.511158)
		(width 0.1016)
		(layer "F.Cu")
		(net "UART_RTS_P1_L_N")
	)
	(segment
		(start 139.290552 -15.117318)
		(end 137.424414 -13.25118)
		(width 0.1016)
		(layer "F.Cu")
		(net "UART_RTS_P1_L_N")
	)
	(segment
		(start 35.4584 -198.445374)
		(end 35.0139 -198.889874)
		(width 0.1016)
		(layer "F.Cu")
		(net "UART_RTS_P1_L_N")
	)
	(segment
		(start 156.405072 -15.117318)
		(end 139.290552 -15.117318)
		(width 0.1016)
		(layer "F.Cu")
		(net "UART_RTS_P1_L_N")
	)
	(segment
		(start 158.271972 -34.435034)
		(end 162.369246 -34.435034)
		(width 0.1016)
		(layer "F.Cu")
		(net "UART_RTS_P1_L_N")
	)
	(segment
		(start 35.014916 -199.511158)
		(end 35.014916 -205.199488)
		(width 0.1016)
		(layer "F.Cu")
		(net "UART_RTS_P1_L_N")
	)
	(segment
		(start 162.369246 -34.435034)
		(end 162.85718 -33.9471)
		(width 0.1016)
		(layer "F.Cu")
		(net "UART_RTS_P1_L_N")
	)
	(segment
		(start 124.208286 -15.43939)
		(end 123.64974 -15.43939)
		(width 0.1016)
		(layer "F.Cu")
		(net "UART_RTS_P1_L_N")
	)
	(segment
		(start 126.396496 -13.25118)
		(end 124.208286 -15.43939)
		(width 0.1016)
		(layer "F.Cu")
		(net "UART_RTS_P1_L_N")
	)
	(segment
		(start 35.0139 -198.889874)
		(end 35.0139 -199.511158)
		(width 0.1016)
		(layer "F.Cu")
		(net "UART_RTS_P1_L_N")
	)
	(segment
		(start 162.85718 -21.569426)
		(end 156.405072 -15.117318)
		(width 0.1016)
		(layer "F.Cu")
		(net "UART_RTS_P1_L_N")
	)
	(segment
		(start 137.424414 -13.25118)
		(end 126.396496 -13.25118)
		(width 0.1016)
		(layer "F.Cu")
		(net "UART_RTS_P1_L_N")
	)
	(via
		(at 35.4584 -198.445374)
		(size 0.508)
		(drill 0.254)
		(layers "F.Cu" "B.Cu")
		(net "UART_RTS_P1_L_N")
	)
	(via
		(at 123.64974 -15.43939)
		(size 0.508)
		(drill 0.254)
		(layers "F.Cu" "B.Cu")
		(net "UART_RTS_P1_L_N")
	)
	(segment
		(start 11.04011 -113.494312)
		(end 10.51179 -112.965992)
		(width 0.1143)
		(layer "In2.Cu")
		(net "UART_RTS_P1_L_N")
	)
	(segment
		(start 38.6334 -27.318208)
		(end 40.37584 -25.575768)
		(width 0.1143)
		(layer "In2.Cu")
		(net "UART_RTS_P1_L_N")
	)
	(segment
		(start 56.434228 -21.933408)
		(end 58.582814 -19.784822)
		(width 0.1143)
		(layer "In2.Cu")
		(net "UART_RTS_P1_L_N")
	)
	(segment
		(start 66.301112 -18.707354)
		(end 67.239388 -18.707354)
		(width 0.1143)
		(layer "In2.Cu")
		(net "UART_RTS_P1_L_N")
	)
	(segment
		(start 12.268962 -162.802062)
		(end 10.47115 -161.00425)
		(width 0.1143)
		(layer "In2.Cu")
		(net "UART_RTS_P1_L_N")
	)
	(segment
		(start 107.25912 -16.506698)
		(end 115.251484 -16.506698)
		(width 0.1143)
		(layer "In2.Cu")
		(net "UART_RTS_P1_L_N")
	)
	(segment
		(start 33.86582 -32.539432)
		(end 38.07968 -28.325572)
		(width 0.1143)
		(layer "In2.Cu")
		(net "UART_RTS_P1_L_N")
	)
	(segment
		(start 30.31236 -37.496242)
		(end 33.86582 -33.942782)
		(width 0.1143)
		(layer "In2.Cu")
		(net "UART_RTS_P1_L_N")
	)
	(segment
		(start 31.57982 -194.787774)
		(end 19.14906 -182.357014)
		(width 0.1143)
		(layer "In2.Cu")
		(net "UART_RTS_P1_L_N")
	)
	(segment
		(start 105.367328 -14.614906)
		(end 107.25912 -16.506698)
		(width 0.1143)
		(layer "In2.Cu")
		(net "UART_RTS_P1_L_N")
	)
	(segment
		(start 28.75153 -45.24375)
		(end 30.31236 -43.68292)
		(width 0.1143)
		(layer "In2.Cu")
		(net "UART_RTS_P1_L_N")
	)
	(segment
		(start 33.86582 -33.942782)
		(end 33.86582 -32.539432)
		(width 0.1143)
		(layer "In2.Cu")
		(net "UART_RTS_P1_L_N")
	)
	(segment
		(start 21.88972 -88.16086)
		(end 29.968698 -80.081882)
		(width 0.1143)
		(layer "In2.Cu")
		(net "UART_RTS_P1_L_N")
	)
	(segment
		(start 11.7983 -143.010636)
		(end 11.7983 -138.58494)
		(width 0.1143)
		(layer "In2.Cu")
		(net "UART_RTS_P1_L_N")
	)
	(segment
		(start 12.47521 -136.081262)
		(end 11.04011 -134.646162)
		(width 0.1143)
		(layer "In2.Cu")
		(net "UART_RTS_P1_L_N")
	)
	(segment
		(start 42.689526 -21.933408)
		(end 56.434228 -21.933408)
		(width 0.1143)
		(layer "In2.Cu")
		(net "UART_RTS_P1_L_N")
	)
	(segment
		(start 17.25422 -98.565716)
		(end 17.25422 -98.251518)
		(width 0.1143)
		(layer "In2.Cu")
		(net "UART_RTS_P1_L_N")
	)
	(segment
		(start 11.7983 -138.58494)
		(end 12.47521 -137.90803)
		(width 0.1143)
		(layer "In2.Cu")
		(net "UART_RTS_P1_L_N")
	)
	(segment
		(start 28.75153 -46.090078)
		(end 28.75153 -45.24375)
		(width 0.1143)
		(layer "In2.Cu")
		(net "UART_RTS_P1_L_N")
	)
	(segment
		(start 38.07968 -28.325572)
		(end 38.07968 -27.872182)
		(width 0.1143)
		(layer "In2.Cu")
		(net "UART_RTS_P1_L_N")
	)
	(segment
		(start 13.051028 -162.802062)
		(end 12.268962 -162.802062)
		(width 0.1143)
		(layer "In2.Cu")
		(net "UART_RTS_P1_L_N")
	)
	(segment
		(start 35.4584 -197.720966)
		(end 32.525208 -194.787774)
		(width 0.1143)
		(layer "In2.Cu")
		(net "UART_RTS_P1_L_N")
	)
	(segment
		(start 10.51179 -104.75214)
		(end 11.652758 -103.611172)
		(width 0.1143)
		(layer "In2.Cu")
		(net "UART_RTS_P1_L_N")
	)
	(segment
		(start 115.251484 -16.506698)
		(end 116.044472 -17.299686)
		(width 0.1143)
		(layer "In2.Cu")
		(net "UART_RTS_P1_L_N")
	)
	(segment
		(start 10.51179 -112.965992)
		(end 10.51179 -104.75214)
		(width 0.1143)
		(layer "In2.Cu")
		(net "UART_RTS_P1_L_N")
	)
	(segment
		(start 19.14906 -182.357014)
		(end 19.14906 -168.900094)
		(width 0.1143)
		(layer "In2.Cu")
		(net "UART_RTS_P1_L_N")
	)
	(segment
		(start 67.239388 -18.707354)
		(end 67.962526 -17.984216)
		(width 0.1143)
		(layer "In2.Cu")
		(net "UART_RTS_P1_L_N")
	)
	(segment
		(start 30.31236 -43.68292)
		(end 30.31236 -37.496242)
		(width 0.1143)
		(layer "In2.Cu")
		(net "UART_RTS_P1_L_N")
	)
	(segment
		(start 12.47521 -137.90803)
		(end 12.47521 -136.081262)
		(width 0.1143)
		(layer "In2.Cu")
		(net "UART_RTS_P1_L_N")
	)
	(segment
		(start 12.208764 -103.611172)
		(end 17.25422 -98.565716)
		(width 0.1143)
		(layer "In2.Cu")
		(net "UART_RTS_P1_L_N")
	)
	(segment
		(start 67.962526 -17.984216)
		(end 84.38388 -17.984216)
		(width 0.1143)
		(layer "In2.Cu")
		(net "UART_RTS_P1_L_N")
	)
	(segment
		(start 21.88972 -93.616018)
		(end 21.88972 -88.16086)
		(width 0.1143)
		(layer "In2.Cu")
		(net "UART_RTS_P1_L_N")
	)
	(segment
		(start 10.47115 -161.00425)
		(end 10.47115 -150.320756)
		(width 0.1143)
		(layer "In2.Cu")
		(net "UART_RTS_P1_L_N")
	)
	(segment
		(start 65.223644 -19.784822)
		(end 66.301112 -18.707354)
		(width 0.1143)
		(layer "In2.Cu")
		(net "UART_RTS_P1_L_N")
	)
	(segment
		(start 29.968698 -80.081882)
		(end 29.968698 -47.307246)
		(width 0.1143)
		(layer "In2.Cu")
		(net "UART_RTS_P1_L_N")
	)
	(segment
		(start 35.4584 -198.445374)
		(end 35.4584 -197.720966)
		(width 0.1143)
		(layer "In2.Cu")
		(net "UART_RTS_P1_L_N")
	)
	(segment
		(start 89.780364 -14.614906)
		(end 105.367328 -14.614906)
		(width 0.1143)
		(layer "In2.Cu")
		(net "UART_RTS_P1_L_N")
	)
	(segment
		(start 40.37584 -25.575768)
		(end 40.37584 -24.247094)
		(width 0.1143)
		(layer "In2.Cu")
		(net "UART_RTS_P1_L_N")
	)
	(segment
		(start 11.32332 -149.468586)
		(end 11.32332 -143.485616)
		(width 0.1143)
		(layer "In2.Cu")
		(net "UART_RTS_P1_L_N")
	)
	(segment
		(start 11.04011 -134.646162)
		(end 11.04011 -113.494312)
		(width 0.1143)
		(layer "In2.Cu")
		(net "UART_RTS_P1_L_N")
	)
	(segment
		(start 84.38388 -17.984216)
		(end 87.970106 -14.39799)
		(width 0.1143)
		(layer "In2.Cu")
		(net "UART_RTS_P1_L_N")
	)
	(segment
		(start 11.32332 -143.485616)
		(end 11.7983 -143.010636)
		(width 0.1143)
		(layer "In2.Cu")
		(net "UART_RTS_P1_L_N")
	)
	(segment
		(start 87.970106 -14.39799)
		(end 88.445848 -14.217142)
		(width 0.1143)
		(layer "In2.Cu")
		(net "UART_RTS_P1_L_N")
	)
	(segment
		(start 17.25422 -98.251518)
		(end 21.88972 -93.616018)
		(width 0.1143)
		(layer "In2.Cu")
		(net "UART_RTS_P1_L_N")
	)
	(segment
		(start 121.789444 -17.299686)
		(end 123.64974 -15.43939)
		(width 0.1143)
		(layer "In2.Cu")
		(net "UART_RTS_P1_L_N")
	)
	(segment
		(start 89.3826 -14.217142)
		(end 89.780364 -14.614906)
		(width 0.1143)
		(layer "In2.Cu")
		(net "UART_RTS_P1_L_N")
	)
	(segment
		(start 29.968698 -47.307246)
		(end 28.75153 -46.090078)
		(width 0.1143)
		(layer "In2.Cu")
		(net "UART_RTS_P1_L_N")
	)
	(segment
		(start 10.47115 -150.320756)
		(end 11.32332 -149.468586)
		(width 0.1143)
		(layer "In2.Cu")
		(net "UART_RTS_P1_L_N")
	)
	(segment
		(start 19.14906 -168.900094)
		(end 13.051028 -162.802062)
		(width 0.1143)
		(layer "In2.Cu")
		(net "UART_RTS_P1_L_N")
	)
	(segment
		(start 40.37584 -24.247094)
		(end 42.689526 -21.933408)
		(width 0.1143)
		(layer "In2.Cu")
		(net "UART_RTS_P1_L_N")
	)
	(segment
		(start 38.07968 -27.872182)
		(end 38.6334 -27.318208)
		(width 0.1143)
		(layer "In2.Cu")
		(net "UART_RTS_P1_L_N")
	)
	(segment
		(start 116.044472 -17.299686)
		(end 121.789444 -17.299686)
		(width 0.1143)
		(layer "In2.Cu")
		(net "UART_RTS_P1_L_N")
	)
	(segment
		(start 58.582814 -19.784822)
		(end 65.223644 -19.784822)
		(width 0.1143)
		(layer "In2.Cu")
		(net "UART_RTS_P1_L_N")
	)
	(segment
		(start 11.652758 -103.611172)
		(end 12.208764 -103.611172)
		(width 0.1143)
		(layer "In2.Cu")
		(net "UART_RTS_P1_L_N")
	)
	(segment
		(start 88.445848 -14.217142)
		(end 89.3826 -14.217142)
		(width 0.1143)
		(layer "In2.Cu")
		(net "UART_RTS_P1_L_N")
	)
	(segment
		(start 32.525208 -194.787774)
		(end 31.57982 -194.787774)
		(width 0.1143)
		(layer "In2.Cu")
		(net "UART_RTS_P1_L_N")
	)
	(segment
		(start 105.202482 -174.282354)
		(end 105.205276 -174.27956)
		(width 0.1016)
		(layer "F.Cu")
		(net "I2C_SDA_FANCTRL1_R")
	)
	(segment
		(start 103.214932 -174.102268)
		(end 105.022396 -174.102268)
		(width 0.1016)
		(layer "F.Cu")
		(net "I2C_SDA_FANCTRL1_R")
	)
	(segment
		(start 105.022396 -174.102268)
		(end 105.202482 -174.282354)
		(width 0.1016)
		(layer "F.Cu")
		(net "I2C_SDA_FANCTRL1_R")
	)
	(segment
		(start 105.205276 -174.27956)
		(end 106.116374 -174.27956)
		(width 0.1016)
		(layer "F.Cu")
		(net "I2C_SDA_FANCTRL1_R")
	)
	(via
		(at 105.202482 -174.282354)
		(size 0.508)
		(drill 0.254)
		(layers "F.Cu" "B.Cu")
		(net "I2C_SDA_FANCTRL1_R")
	)
	(segment
		(start 177.743612 -155.464256)
		(end 177.743612 -155.703524)
		(width 0.10414)
		(layer "F.Cu")
		(net "LAN2_MDI2_DP")
	)
	(segment
		(start 178.20386 -155.924504)
		(end 178.42484 -156.145484)
		(width 0.10414)
		(layer "F.Cu")
		(net "LAN2_MDI2_DP")
	)
	(segment
		(start 177.283364 -155.243276)
		(end 177.522632 -155.243276)
		(width 0.10414)
		(layer "F.Cu")
		(net "LAN2_MDI2_DP")
	)
	(segment
		(start 179.077874 -157.91053)
		(end 178.660044 -158.32836)
		(width 0.10414)
		(layer "F.Cu")
		(net "LAN2_MDI2_DP")
	)
	(segment
		(start 177.743612 -155.703524)
		(end 177.964592 -155.924504)
		(width 0.10414)
		(layer "F.Cu")
		(net "LAN2_MDI2_DP")
	)
	(segment
		(start 179.077874 -156.798518)
		(end 179.077874 -157.91053)
		(width 0.10414)
		(layer "F.Cu")
		(net "LAN2_MDI2_DP")
	)
	(segment
		(start 169.28338 -150.722838)
		(end 172.474636 -150.722838)
		(width 0.10414)
		(layer "F.Cu")
		(net "LAN2_MDI2_DP")
	)
	(segment
		(start 166.107872 -151.312118)
		(end 166.992046 -151.312118)
		(width 0.10414)
		(layer "F.Cu")
		(net "LAN2_MDI2_DP")
	)
	(segment
		(start 172.474636 -150.722838)
		(end 174.184818 -152.43302)
		(width 0.10414)
		(layer "F.Cu")
		(net "LAN2_MDI2_DP")
	)
	(segment
		(start 166.992046 -151.312118)
		(end 167.581326 -150.722838)
		(width 0.10414)
		(layer "F.Cu")
		(net "LAN2_MDI2_DP")
	)
	(segment
		(start 177.964592 -155.924504)
		(end 178.20386 -155.924504)
		(width 0.10414)
		(layer "F.Cu")
		(net "LAN2_MDI2_DP")
	)
	(segment
		(start 174.405544 -152.907238)
		(end 174.659036 -152.907238)
		(width 0.10414)
		(layer "F.Cu")
		(net "LAN2_MDI2_DP")
	)
	(segment
		(start 177.522632 -155.243276)
		(end 177.743612 -155.464256)
		(width 0.10414)
		(layer "F.Cu")
		(net "LAN2_MDI2_DP")
	)
	(segment
		(start 174.184818 -152.686512)
		(end 174.405544 -152.907238)
		(width 0.10414)
		(layer "F.Cu")
		(net "LAN2_MDI2_DP")
	)
	(segment
		(start 178.42484 -156.145484)
		(end 178.42484 -156.384752)
		(width 0.10414)
		(layer "F.Cu")
		(net "LAN2_MDI2_DP")
	)
	(segment
		(start 175.44923 -153.169874)
		(end 176.381156 -154.1018)
		(width 0.10414)
		(layer "F.Cu")
		(net "LAN2_MDI2_DP")
	)
	(segment
		(start 174.921672 -153.169874)
		(end 175.44923 -153.169874)
		(width 0.10414)
		(layer "F.Cu")
		(net "LAN2_MDI2_DP")
	)
	(segment
		(start 178.660044 -158.32836)
		(end 178.660044 -159.0421)
		(width 0.10414)
		(layer "F.Cu")
		(net "LAN2_MDI2_DP")
	)
	(segment
		(start 167.581326 -150.722838)
		(end 169.28338 -150.722838)
		(width 0.10414)
		(layer "F.Cu")
		(net "LAN2_MDI2_DP")
	)
	(segment
		(start 176.602136 -154.562048)
		(end 176.841404 -154.562048)
		(width 0.10414)
		(layer "F.Cu")
		(net "LAN2_MDI2_DP")
	)
	(segment
		(start 174.184818 -152.43302)
		(end 174.184818 -152.686512)
		(width 0.10414)
		(layer "F.Cu")
		(net "LAN2_MDI2_DP")
	)
	(segment
		(start 178.885088 -156.605732)
		(end 179.077874 -156.798518)
		(width 0.10414)
		(layer "F.Cu")
		(net "LAN2_MDI2_DP")
	)
	(segment
		(start 176.381156 -154.341068)
		(end 176.602136 -154.562048)
		(width 0.10414)
		(layer "F.Cu")
		(net "LAN2_MDI2_DP")
	)
	(segment
		(start 178.64582 -156.605732)
		(end 178.885088 -156.605732)
		(width 0.10414)
		(layer "F.Cu")
		(net "LAN2_MDI2_DP")
	)
	(segment
		(start 177.062384 -154.783028)
		(end 177.062384 -155.022296)
		(width 0.10414)
		(layer "F.Cu")
		(net "LAN2_MDI2_DP")
	)
	(segment
		(start 174.659036 -152.907238)
		(end 174.921672 -153.169874)
		(width 0.10414)
		(layer "F.Cu")
		(net "LAN2_MDI2_DP")
	)
	(segment
		(start 176.381156 -154.1018)
		(end 176.381156 -154.341068)
		(width 0.10414)
		(layer "F.Cu")
		(net "LAN2_MDI2_DP")
	)
	(segment
		(start 177.062384 -155.022296)
		(end 177.283364 -155.243276)
		(width 0.10414)
		(layer "F.Cu")
		(net "LAN2_MDI2_DP")
	)
	(segment
		(start 166.07282 -151.34717)
		(end 166.107872 -151.312118)
		(width 0.10414)
		(layer "F.Cu")
		(net "LAN2_MDI2_DP")
	)
	(segment
		(start 165.5699 -151.34717)
		(end 166.07282 -151.34717)
		(width 0.10414)
		(layer "F.Cu")
		(net "LAN2_MDI2_DP")
	)
	(segment
		(start 178.42484 -156.384752)
		(end 178.64582 -156.605732)
		(width 0.10414)
		(layer "F.Cu")
		(net "LAN2_MDI2_DP")
	)
	(segment
		(start 176.841404 -154.562048)
		(end 177.062384 -154.783028)
		(width 0.10414)
		(layer "F.Cu")
		(net "LAN2_MDI2_DP")
	)
	(via
		(at 169.28338 -150.722838)
		(size 0.4064)
		(drill 0.2032)
		(layers "F.Cu" "B.Cu")
		(net "LAN2_MDI2_DP")
	)
	(segment
		(start 145.23466 -164.286946)
		(end 144.54124 -163.593526)
		(width 0.1016)
		(layer "F.Cu")
		(net "I2C_PSU3_SDA")
	)
	(segment
		(start 144.54124 -163.593526)
		(end 144.54124 -158.6103)
		(width 0.1016)
		(layer "F.Cu")
		(net "I2C_PSU3_SDA")
	)
	(segment
		(start 137.9347 -158.553658)
		(end 136.850374 -158.553658)
		(width 0.1016)
		(layer "F.Cu")
		(net "I2C_PSU3_SDA")
	)
	(segment
		(start 138.776456 -157.711902)
		(end 137.9347 -158.553658)
		(width 0.1016)
		(layer "F.Cu")
		(net "I2C_PSU3_SDA")
	)
	(segment
		(start 133.674612 -159.91713)
		(end 134.469378 -159.91713)
		(width 0.1016)
		(layer "F.Cu")
		(net "I2C_PSU3_SDA")
	)
	(segment
		(start 143.642842 -157.711902)
		(end 138.776456 -157.711902)
		(width 0.1016)
		(layer "F.Cu")
		(net "I2C_PSU3_SDA")
	)
	(segment
		(start 134.469378 -159.91713)
		(end 135.203184 -159.183324)
		(width 0.1016)
		(layer "F.Cu")
		(net "I2C_PSU3_SDA")
	)
	(segment
		(start 136.598406 -159.183324)
		(end 136.850374 -158.931356)
		(width 0.1016)
		(layer "F.Cu")
		(net "I2C_PSU3_SDA")
	)
	(segment
		(start 144.54124 -158.6103)
		(end 143.642842 -157.711902)
		(width 0.1016)
		(layer "F.Cu")
		(net "I2C_PSU3_SDA")
	)
	(segment
		(start 135.203184 -159.183324)
		(end 136.598406 -159.183324)
		(width 0.1016)
		(layer "F.Cu")
		(net "I2C_PSU3_SDA")
	)
	(segment
		(start 136.850374 -158.931356)
		(end 136.850374 -158.553658)
		(width 0.1016)
		(layer "F.Cu")
		(net "I2C_PSU3_SDA")
	)
	(via
		(at 145.23466 -164.286946)
		(size 0.508)
		(drill 0.254)
		(layers "F.Cu" "B.Cu")
		(net "I2C_PSU3_SDA")
	)
	(via
		(at 158.06166 -179.963064)
		(size 0.508)
		(drill 0.254)
		(layers "F.Cu" "B.Cu")
		(net "I2C_PSU3_SDA")
	)
	(segment
		(start 156.19476 -184.147968)
		(end 156.19476 -184.551574)
		(width 0.1016)
		(layer "B.Cu")
		(net "I2C_PSU3_SDA")
	)
	(segment
		(start 155.37942 -182.075836)
		(end 155.37942 -183.332628)
		(width 0.1016)
		(layer "B.Cu")
		(net "I2C_PSU3_SDA")
	)
	(segment
		(start 158.06166 -179.963064)
		(end 157.517846 -179.963064)
		(width 0.1016)
		(layer "B.Cu")
		(net "I2C_PSU3_SDA")
	)
	(segment
		(start 156.920692 -180.560218)
		(end 156.895038 -180.560218)
		(width 0.1016)
		(layer "B.Cu")
		(net "I2C_PSU3_SDA")
	)
	(segment
		(start 157.517846 -179.963064)
		(end 156.920692 -180.560218)
		(width 0.1016)
		(layer "B.Cu")
		(net "I2C_PSU3_SDA")
	)
	(segment
		(start 155.37942 -183.332628)
		(end 156.19476 -184.147968)
		(width 0.1016)
		(layer "B.Cu")
		(net "I2C_PSU3_SDA")
	)
	(segment
		(start 156.895038 -180.560218)
		(end 155.37942 -182.075836)
		(width 0.1016)
		(layer "B.Cu")
		(net "I2C_PSU3_SDA")
	)
	(segment
		(start 156.092144 -177.534824)
		(end 156.092144 -171.718224)
		(width 0.1143)
		(layer "In7.Cu")
		(net "I2C_PSU3_SDA")
	)
	(segment
		(start 154.72918 -169.325036)
		(end 154.72918 -169.007028)
		(width 0.1143)
		(layer "In7.Cu")
		(net "I2C_PSU3_SDA")
	)
	(segment
		(start 158.06166 -179.963064)
		(end 158.06166 -179.18176)
		(width 0.1143)
		(layer "In7.Cu")
		(net "I2C_PSU3_SDA")
	)
	(segment
		(start 156.79547 -178.23815)
		(end 156.092144 -177.534824)
		(width 0.1143)
		(layer "In7.Cu")
		(net "I2C_PSU3_SDA")
	)
	(segment
		(start 150.009098 -164.286946)
		(end 145.23466 -164.286946)
		(width 0.1143)
		(layer "In7.Cu")
		(net "I2C_PSU3_SDA")
	)
	(segment
		(start 154.72918 -169.007028)
		(end 150.009098 -164.286946)
		(width 0.1143)
		(layer "In7.Cu")
		(net "I2C_PSU3_SDA")
	)
	(segment
		(start 157.11805 -178.23815)
		(end 156.79547 -178.23815)
		(width 0.1143)
		(layer "In7.Cu")
		(net "I2C_PSU3_SDA")
	)
	(segment
		(start 158.06166 -179.18176)
		(end 157.11805 -178.23815)
		(width 0.1143)
		(layer "In7.Cu")
		(net "I2C_PSU3_SDA")
	)
	(segment
		(start 155.33116 -170.95724)
		(end 155.33116 -169.927016)
		(width 0.1143)
		(layer "In7.Cu")
		(net "I2C_PSU3_SDA")
	)
	(segment
		(start 155.33116 -169.927016)
		(end 154.72918 -169.325036)
		(width 0.1143)
		(layer "In7.Cu")
		(net "I2C_PSU3_SDA")
	)
	(segment
		(start 156.092144 -171.718224)
		(end 155.33116 -170.95724)
		(width 0.1143)
		(layer "In7.Cu")
		(net "I2C_PSU3_SDA")
	)
	(segment
		(start 148.029168 -43.193208)
		(end 148.500084 -43.664124)
		(width 0.1016)
		(layer "F.Cu")
		(net "UART_TX_P1")
	)
	(segment
		(start 149.011894 -43.664124)
		(end 149.011894 -44.680124)
		(width 0.1016)
		(layer "F.Cu")
		(net "UART_TX_P1")
	)
	(segment
		(start 148.500084 -43.664124)
		(end 149.011894 -43.664124)
		(width 0.1016)
		(layer "F.Cu")
		(net "UART_TX_P1")
	)
	(segment
		(start 148.408644 -42.578528)
		(end 148.51761 -42.687494)
		(width 0.1016)
		(layer "F.Cu")
		(net "UART_TX_P1")
	)
	(segment
		(start 153.372312 -40.389302)
		(end 157.886654 -40.389302)
		(width 0.1016)
		(layer "F.Cu")
		(net "UART_TX_P1")
	)
	(segment
		(start 159.55518 -37.385498)
		(end 159.20466 -37.034978)
		(width 0.1016)
		(layer "F.Cu")
		(net "UART_TX_P1")
	)
	(segment
		(start 147.012406 -42.578528)
		(end 148.029168 -42.578528)
		(width 0.1016)
		(layer "F.Cu")
		(net "UART_TX_P1")
	)
	(segment
		(start 148.029168 -42.578528)
		(end 148.029168 -43.193208)
		(width 0.1016)
		(layer "F.Cu")
		(net "UART_TX_P1")
	)
	(segment
		(start 151.07412 -42.687494)
		(end 153.372312 -40.389302)
		(width 0.1016)
		(layer "F.Cu")
		(net "UART_TX_P1")
	)
	(segment
		(start 148.51761 -42.687494)
		(end 151.07412 -42.687494)
		(width 0.1016)
		(layer "F.Cu")
		(net "UART_TX_P1")
	)
	(segment
		(start 159.20466 -37.034978)
		(end 158.271972 -37.034978)
		(width 0.1016)
		(layer "F.Cu")
		(net "UART_TX_P1")
	)
	(segment
		(start 159.55518 -38.720776)
		(end 159.55518 -37.385498)
		(width 0.1016)
		(layer "F.Cu")
		(net "UART_TX_P1")
	)
	(segment
		(start 148.029168 -42.578528)
		(end 148.408644 -42.578528)
		(width 0.1016)
		(layer "F.Cu")
		(net "UART_TX_P1")
	)
	(segment
		(start 157.886654 -40.389302)
		(end 159.55518 -38.720776)
		(width 0.1016)
		(layer "F.Cu")
		(net "UART_TX_P1")
	)
	(segment
		(start 145.571718 -42.889678)
		(end 146.701256 -42.889678)
		(width 0.1016)
		(layer "F.Cu")
		(net "UART_TX_P1")
	)
	(segment
		(start 146.701256 -42.889678)
		(end 147.012406 -42.578528)
		(width 0.1016)
		(layer "F.Cu")
		(net "UART_TX_P1")
	)
	(via
		(at 148.029168 -42.578528)
		(size 0.508)
		(drill 0.254)
		(layers "F.Cu" "B.Cu")
		(net "UART_TX_P1")
	)
	(segment
		(start 164.306758 -166.388288)
		(end 164.23132 -166.31285)
		(width 0.1016)
		(layer "F.Cu")
		(net "LAN2_NVM_HOLD_N")
	)
	(segment
		(start 164.155882 -166.388288)
		(end 164.23132 -166.31285)
		(width 0.1016)
		(layer "F.Cu")
		(net "LAN2_NVM_HOLD_N")
	)
	(segment
		(start 165.411404 -166.388288)
		(end 164.306758 -166.388288)
		(width 0.1016)
		(layer "F.Cu")
		(net "LAN2_NVM_HOLD_N")
	)
	(segment
		(start 162.796474 -166.388288)
		(end 164.155882 -166.388288)
		(width 0.1016)
		(layer "F.Cu")
		(net "LAN2_NVM_HOLD_N")
	)
	(via
		(at 164.23132 -166.31285)
		(size 0.508)
		(drill 0.254)
		(layers "F.Cu" "B.Cu")
		(net "LAN2_NVM_HOLD_N")
	)
	(segment
		(start 156.470096 -154.347164)
		(end 155.573222 -154.347164)
		(width 0.254)
		(layer "F.Cu")
		(net "P1V9_LAN2")
	)
	(segment
		(start 165.5699 -156.34716)
		(end 166.591742 -156.34716)
		(width 0.254)
		(layer "F.Cu")
		(net "P1V9_LAN2")
	)
	(segment
		(start 165.5699 -155.347162)
		(end 166.35222 -155.347162)
		(width 0.254)
		(layer "F.Cu")
		(net "P1V9_LAN2")
	)
	(segment
		(start 156.470096 -155.847288)
		(end 155.687014 -155.847288)
		(width 0.254)
		(layer "F.Cu")
		(net "P1V9_LAN2")
	)
	(segment
		(start 165.5699 -150.347172)
		(end 166.48303 -150.347172)
		(width 0.254)
		(layer "F.Cu")
		(net "P1V9_LAN2")
	)
	(segment
		(start 162.770058 -148.547328)
		(end 162.770058 -147.773644)
		(width 0.254)
		(layer "F.Cu")
		(net "P1V9_LAN2")
	)
	(segment
		(start 155.687014 -155.847288)
		(end 155.54198 -155.992322)
		(width 0.254)
		(layer "F.Cu")
		(net "P1V9_LAN2")
	)
	(segment
		(start 166.35222 -155.347162)
		(end 166.64178 -155.636722)
		(width 0.254)
		(layer "F.Cu")
		(net "P1V9_LAN2")
	)
	(segment
		(start 165.5699 -152.847294)
		(end 166.544752 -152.847294)
		(width 0.254)
		(layer "F.Cu")
		(net "P1V9_LAN2")
	)
	(segment
		(start 162.770058 -147.773644)
		(end 163.03498 -147.508722)
		(width 0.254)
		(layer "F.Cu")
		(net "P1V9_LAN2")
	)
	(segment
		(start 164.269928 -148.547328)
		(end 164.269928 -147.518374)
		(width 0.254)
		(layer "F.Cu")
		(net "P1V9_LAN2")
	)
	(via
		(at 165.938454 -148.763482)
		(size 0.6604)
		(drill 0.3302)
		(layers "F.Cu" "B.Cu")
		(net "P1V9_LAN2")
	)
	(via
		(at 188.99886 -146.066764)
		(size 0.508)
		(drill 0.254)
		(layers "F.Cu" "B.Cu")
		(net "P1V9_LAN2")
	)
	(via
		(at 163.03498 -147.508722)
		(size 0.508)
		(drill 0.254)
		(layers "F.Cu" "B.Cu")
		(net "P1V9_LAN2")
	)
	(via
		(at 188.963554 -147.023582)
		(size 0.508)
		(drill 0.254)
		(layers "F.Cu" "B.Cu")
		(net "P1V9_LAN2")
	)
	(via
		(at 166.591742 -156.34716)
		(size 0.508)
		(drill 0.254)
		(layers "F.Cu" "B.Cu")
		(net "P1V9_LAN2")
	)
	(via
		(at 181.290468 -161.130742)
		(size 0.508)
		(drill 0.254)
		(layers "F.Cu" "B.Cu")
		(net "P1V9_LAN2")
	)
	(via
		(at 181.880256 -160.464246)
		(size 0.508)
		(drill 0.254)
		(layers "F.Cu" "B.Cu")
		(net "P1V9_LAN2")
	)
	(via
		(at 174.15256 -161.075116)
		(size 0.508)
		(drill 0.254)
		(layers "F.Cu" "B.Cu")
		(net "P1V9_LAN2")
	)
	(via
		(at 174.66564 -160.476946)
		(size 0.508)
		(drill 0.254)
		(layers "F.Cu" "B.Cu")
		(net "P1V9_LAN2")
	)
	(via
		(at 164.269928 -147.518374)
		(size 0.508)
		(drill 0.254)
		(layers "F.Cu" "B.Cu")
		(net "P1V9_LAN2")
	)
	(via
		(at 181.033928 -160.464246)
		(size 0.508)
		(drill 0.254)
		(layers "F.Cu" "B.Cu")
		(net "P1V9_LAN2")
	)
	(via
		(at 155.54198 -155.992322)
		(size 0.508)
		(drill 0.254)
		(layers "F.Cu" "B.Cu")
		(net "P1V9_LAN2")
	)
	(via
		(at 166.544752 -152.847294)
		(size 0.508)
		(drill 0.254)
		(layers "F.Cu" "B.Cu")
		(net "P1V9_LAN2")
	)
	(via
		(at 166.48303 -150.347172)
		(size 0.508)
		(drill 0.254)
		(layers "F.Cu" "B.Cu")
		(net "P1V9_LAN2")
	)
	(via
		(at 173.66488 -160.459928)
		(size 0.508)
		(drill 0.254)
		(layers "F.Cu" "B.Cu")
		(net "P1V9_LAN2")
	)
	(via
		(at 188.98108 -143.800322)
		(size 0.508)
		(drill 0.254)
		(layers "F.Cu" "B.Cu")
		(net "P1V9_LAN2")
	)
	(via
		(at 182.649368 -160.447228)
		(size 0.508)
		(drill 0.254)
		(layers "F.Cu" "B.Cu")
		(net "P1V9_LAN2")
	)
	(via
		(at 155.573222 -154.347164)
		(size 0.508)
		(drill 0.254)
		(layers "F.Cu" "B.Cu")
		(net "P1V9_LAN2")
	)
	(via
		(at 190.93942 -148.093938)
		(size 0.508)
		(drill 0.254)
		(layers "F.Cu" "B.Cu")
		(net "P1V9_LAN2")
	)
	(via
		(at 166.64178 -155.636722)
		(size 0.508)
		(drill 0.254)
		(layers "F.Cu" "B.Cu")
		(net "P1V9_LAN2")
	)
	(via
		(at 189.85484 -147.908772)
		(size 0.508)
		(drill 0.254)
		(layers "F.Cu" "B.Cu")
		(net "P1V9_LAN2")
	)
	(via
		(at 188.9887 -145.245836)
		(size 0.508)
		(drill 0.254)
		(layers "F.Cu" "B.Cu")
		(net "P1V9_LAN2")
	)
	(via
		(at 182.212488 -161.156396)
		(size 0.508)
		(drill 0.254)
		(layers "F.Cu" "B.Cu")
		(net "P1V9_LAN2")
	)
	(via
		(at 189.85738 -148.727668)
		(size 0.508)
		(drill 0.254)
		(layers "F.Cu" "B.Cu")
		(net "P1V9_LAN2")
	)
	(via
		(at 188.06922 -156.567886)
		(size 0.6604)
		(drill 0.3302)
		(layers "F.Cu" "B.Cu")
		(net "P1V9_LAN2")
	)
	(segment
		(start 155.643072 -155.89123)
		(end 155.54198 -155.992322)
		(width 0.508)
		(layer "B.Cu")
		(net "P1V9_LAN2")
	)
	(segment
		(start 163.890198 -147.898104)
		(end 164.269928 -147.518374)
		(width 0.508)
		(layer "B.Cu")
		(net "P1V9_LAN2")
	)
	(segment
		(start 156.428948 -155.89123)
		(end 155.643072 -155.89123)
		(width 0.508)
		(layer "B.Cu")
		(net "P1V9_LAN2")
	)
	(segment
		(start 162.80638 -148.480272)
		(end 162.78098 -148.454872)
		(width 0.508)
		(layer "B.Cu")
		(net "P1V9_LAN2")
	)
	(segment
		(start 165.59403 -150.320248)
		(end 165.59403 -151.369522)
		(width 0.508)
		(layer "B.Cu")
		(net "P1V9_LAN2")
	)
	(segment
		(start 165.611048 -150.30323)
		(end 166.439088 -150.30323)
		(width 0.508)
		(layer "B.Cu")
		(net "P1V9_LAN2")
	)
	(segment
		(start 167.258238 -152.901904)
		(end 166.599362 -152.901904)
		(width 0.508)
		(layer "B.Cu")
		(net "P1V9_LAN2")
	)
	(segment
		(start 166.439088 -150.30323)
		(end 166.48303 -150.347172)
		(width 0.508)
		(layer "B.Cu")
		(net "P1V9_LAN2")
	)
	(segment
		(start 164.949886 -148.434552)
		(end 163.911026 -148.434552)
		(width 0.508)
		(layer "B.Cu")
		(net "P1V9_LAN2")
	)
	(segment
		(start 163.911026 -148.434552)
		(end 163.890198 -148.45538)
		(width 0.508)
		(layer "B.Cu")
		(net "P1V9_LAN2")
	)
	(segment
		(start 156.428948 -154.64663)
		(end 155.872688 -154.64663)
		(width 0.508)
		(layer "B.Cu")
		(net "P1V9_LAN2")
	)
	(segment
		(start 162.80638 -147.737322)
		(end 163.03498 -147.508722)
		(width 0.508)
		(layer "B.Cu")
		(net "P1V9_LAN2")
	)
	(segment
		(start 165.611048 -152.84323)
		(end 166.540688 -152.84323)
		(width 0.508)
		(layer "B.Cu")
		(net "P1V9_LAN2")
	)
	(segment
		(start 155.872688 -154.64663)
		(end 155.573222 -154.347164)
		(width 0.508)
		(layer "B.Cu")
		(net "P1V9_LAN2")
	)
	(segment
		(start 166.54018 -150.404322)
		(end 166.48303 -150.347172)
		(width 0.508)
		(layer "B.Cu")
		(net "P1V9_LAN2")
	)
	(segment
		(start 166.599362 -152.901904)
		(end 166.544752 -152.847294)
		(width 0.508)
		(layer "B.Cu")
		(net "P1V9_LAN2")
	)
	(segment
		(start 167.23233 -151.496522)
		(end 167.23233 -150.404322)
		(width 0.508)
		(layer "B.Cu")
		(net "P1V9_LAN2")
	)
	(segment
		(start 167.23233 -150.404322)
		(end 166.54018 -150.404322)
		(width 0.508)
		(layer "B.Cu")
		(net "P1V9_LAN2")
	)
	(segment
		(start 165.611048 -150.30323)
		(end 165.59403 -150.320248)
		(width 0.508)
		(layer "B.Cu")
		(net "P1V9_LAN2")
	)
	(segment
		(start 163.890198 -148.45538)
		(end 163.890198 -147.898104)
		(width 0.508)
		(layer "B.Cu")
		(net "P1V9_LAN2")
	)
	(segment
		(start 162.78098 -148.454872)
		(end 161.76498 -148.454872)
		(width 0.508)
		(layer "B.Cu")
		(net "P1V9_LAN2")
	)
	(segment
		(start 162.80638 -148.480272)
		(end 162.80638 -147.737322)
		(width 0.508)
		(layer "B.Cu")
		(net "P1V9_LAN2")
	)
	(segment
		(start 166.540688 -152.84323)
		(end 166.544752 -152.847294)
		(width 0.508)
		(layer "B.Cu")
		(net "P1V9_LAN2")
	)
	(segment
		(start 159.29356 -162.288728)
		(end 159.295084 -162.288728)
		(width 0.1016)
		(layer "F.Cu")
		(net "SPI_LAN2_NVM_SI")
	)
	(segment
		(start 166.211504 -163.848288)
		(end 165.748208 -164.311584)
		(width 0.1016)
		(layer "F.Cu")
		(net "SPI_LAN2_NVM_SI")
	)
	(segment
		(start 159.29356 -162.517328)
		(end 159.29356 -162.288728)
		(width 0.1016)
		(layer "F.Cu")
		(net "SPI_LAN2_NVM_SI")
	)
	(segment
		(start 159.076644 -159.361124)
		(end 159.076644 -158.505144)
		(width 0.1016)
		(layer "F.Cu")
		(net "SPI_LAN2_NVM_SI")
	)
	(segment
		(start 165.748208 -164.311584)
		(end 161.087816 -164.311584)
		(width 0.1016)
		(layer "F.Cu")
		(net "SPI_LAN2_NVM_SI")
	)
	(segment
		(start 161.087816 -164.311584)
		(end 159.29356 -162.517328)
		(width 0.1016)
		(layer "F.Cu")
		(net "SPI_LAN2_NVM_SI")
	)
	(segment
		(start 159.295084 -162.288728)
		(end 159.236664 -162.230308)
		(width 0.1016)
		(layer "F.Cu")
		(net "SPI_LAN2_NVM_SI")
	)
	(segment
		(start 159.076644 -158.505144)
		(end 159.269938 -158.31185)
		(width 0.1016)
		(layer "F.Cu")
		(net "SPI_LAN2_NVM_SI")
	)
	(segment
		(start 159.236664 -159.521144)
		(end 159.076644 -159.361124)
		(width 0.1016)
		(layer "F.Cu")
		(net "SPI_LAN2_NVM_SI")
	)
	(segment
		(start 159.236664 -162.230308)
		(end 159.236664 -159.521144)
		(width 0.1016)
		(layer "F.Cu")
		(net "SPI_LAN2_NVM_SI")
	)
	(segment
		(start 159.269938 -158.31185)
		(end 159.269938 -157.647132)
		(width 0.1016)
		(layer "F.Cu")
		(net "SPI_LAN2_NVM_SI")
	)
	(via
		(at 159.295084 -162.288728)
		(size 0.508)
		(drill 0.254)
		(layers "F.Cu" "B.Cu")
		(net "SPI_LAN2_NVM_SI")
	)
	(segment
		(start 94.851982 -173.290992)
		(end 95.275146 -173.290992)
		(width 0.1016)
		(layer "F.Cu")
		(net "I2C_SCL_FANCTRL1_R")
	)
	(segment
		(start 95.698564 -173.71441)
		(end 96.035368 -173.71441)
		(width 0.1016)
		(layer "F.Cu")
		(net "I2C_SCL_FANCTRL1_R")
	)
	(segment
		(start 96.55937 -174.102268)
		(end 96.171512 -173.71441)
		(width 0.1016)
		(layer "F.Cu")
		(net "I2C_SCL_FANCTRL1_R")
	)
	(segment
		(start 96.171512 -173.71441)
		(end 96.035368 -173.71441)
		(width 0.1016)
		(layer "F.Cu")
		(net "I2C_SCL_FANCTRL1_R")
	)
	(segment
		(start 95.275146 -173.290992)
		(end 95.698564 -173.71441)
		(width 0.1016)
		(layer "F.Cu")
		(net "I2C_SCL_FANCTRL1_R")
	)
	(segment
		(start 97.728532 -174.102268)
		(end 96.55937 -174.102268)
		(width 0.1016)
		(layer "F.Cu")
		(net "I2C_SCL_FANCTRL1_R")
	)
	(via
		(at 96.035368 -173.71441)
		(size 0.762)
		(drill 0.381)
		(layers "F.Cu" "B.Cu")
		(net "I2C_SCL_FANCTRL1_R")
	)
	(segment
		(start 157.269942 -148.547328)
		(end 157.269942 -147.915884)
		(width 0.1016)
		(layer "F.Cu")
		(net "LAN2_LED_LINK_1000_N")
	)
	(segment
		(start 157.269942 -147.915884)
		(end 156.78658 -147.432522)
		(width 0.1016)
		(layer "F.Cu")
		(net "LAN2_LED_LINK_1000_N")
	)
	(segment
		(start 156.074872 -147.432522)
		(end 154.667712 -146.025362)
		(width 0.1016)
		(layer "F.Cu")
		(net "LAN2_LED_LINK_1000_N")
	)
	(segment
		(start 154.667712 -146.025362)
		(end 153.07056 -146.025362)
		(width 0.1016)
		(layer "F.Cu")
		(net "LAN2_LED_LINK_1000_N")
	)
	(segment
		(start 156.78658 -147.432522)
		(end 156.074872 -147.432522)
		(width 0.1016)
		(layer "F.Cu")
		(net "LAN2_LED_LINK_1000_N")
	)
	(via
		(at 156.78658 -147.432522)
		(size 0.508)
		(drill 0.254)
		(layers "F.Cu" "B.Cu")
		(net "LAN2_LED_LINK_1000_N")
	)
	(segment
		(start 149.5933 -165.11778)
		(end 149.547072 -165.164008)
		(width 0.1016)
		(layer "F.Cu")
		(net "UART_RTS_P3_N")
	)
	(segment
		(start 147.251166 -166.3954)
		(end 148.253196 -166.3954)
		(width 0.1016)
		(layer "F.Cu")
		(net "UART_RTS_P3_N")
	)
	(segment
		(start 146.12366 -166.108634)
		(end 146.17446 -166.057834)
		(width 0.1016)
		(layer "F.Cu")
		(net "UART_RTS_P3_N")
	)
	(segment
		(start 149.547072 -165.164008)
		(end 149.547072 -165.95979)
		(width 0.1016)
		(layer "F.Cu")
		(net "UART_RTS_P3_N")
	)
	(segment
		(start 136.310878 -51.85156)
		(end 136.310878 -52.103782)
		(width 0.1016)
		(layer "F.Cu")
		(net "UART_RTS_P3_N")
	)
	(segment
		(start 136.310878 -52.103782)
		(end 135.20928 -53.20538)
		(width 0.1016)
		(layer "F.Cu")
		(net "UART_RTS_P3_N")
	)
	(segment
		(start 148.253196 -166.3954)
		(end 148.688806 -165.95979)
		(width 0.1016)
		(layer "F.Cu")
		(net "UART_RTS_P3_N")
	)
	(segment
		(start 146.9136 -166.057834)
		(end 147.251166 -166.3954)
		(width 0.1016)
		(layer "F.Cu")
		(net "UART_RTS_P3_N")
	)
	(segment
		(start 145.275808 -166.108634)
		(end 146.12366 -166.108634)
		(width 0.1016)
		(layer "F.Cu")
		(net "UART_RTS_P3_N")
	)
	(segment
		(start 146.17446 -166.057834)
		(end 146.9136 -166.057834)
		(width 0.1016)
		(layer "F.Cu")
		(net "UART_RTS_P3_N")
	)
	(segment
		(start 148.688806 -165.95979)
		(end 149.547072 -165.95979)
		(width 0.1016)
		(layer "F.Cu")
		(net "UART_RTS_P3_N")
	)
	(via
		(at 149.5933 -165.11778)
		(size 0.508)
		(drill 0.254)
		(layers "F.Cu" "B.Cu")
		(net "UART_RTS_P3_N")
	)
	(via
		(at 135.20928 -53.20538)
		(size 0.508)
		(drill 0.254)
		(layers "F.Cu" "B.Cu")
		(net "UART_RTS_P3_N")
	)
	(segment
		(start 134.579106 -68.237354)
		(end 134.579106 -69.273166)
		(width 0.1143)
		(layer "In2.Cu")
		(net "UART_RTS_P3_N")
	)
	(segment
		(start 149.67966 -165.20414)
		(end 149.5933 -165.11778)
		(width 0.1143)
		(layer "In2.Cu")
		(net "UART_RTS_P3_N")
	)
	(segment
		(start 157.258512 -164.581332)
		(end 156.630624 -165.20922)
		(width 0.1143)
		(layer "In2.Cu")
		(net "UART_RTS_P3_N")
	)
	(segment
		(start 191.516 -128.651)
		(end 191.37757 -128.78943)
		(width 0.1143)
		(layer "In2.Cu")
		(net "UART_RTS_P3_N")
	)
	(segment
		(start 152.69337 -85.156294)
		(end 175.825912 -85.156294)
		(width 0.1143)
		(layer "In2.Cu")
		(net "UART_RTS_P3_N")
	)
	(segment
		(start 133.76656 -67.424808)
		(end 134.579106 -68.237354)
		(width 0.1143)
		(layer "In2.Cu")
		(net "UART_RTS_P3_N")
	)
	(segment
		(start 176.10582 -85.436202)
		(end 178.402488 -85.436202)
		(width 0.1143)
		(layer "In2.Cu")
		(net "UART_RTS_P3_N")
	)
	(segment
		(start 191.37757 -153.060146)
		(end 181.749446 -162.68827)
		(width 0.1143)
		(layer "In2.Cu")
		(net "UART_RTS_P3_N")
	)
	(segment
		(start 137.43178 -72.12584)
		(end 137.43178 -74.195686)
		(width 0.1143)
		(layer "In2.Cu")
		(net "UART_RTS_P3_N")
	)
	(segment
		(start 191.37757 -128.78943)
		(end 191.37757 -153.060146)
		(width 0.1143)
		(layer "In2.Cu")
		(net "UART_RTS_P3_N")
	)
	(segment
		(start 152.13076 -165.20922)
		(end 152.12568 -165.20414)
		(width 0.1143)
		(layer "In2.Cu")
		(net "UART_RTS_P3_N")
	)
	(segment
		(start 135.20928 -55.438294)
		(end 133.70052 -56.947054)
		(width 0.1143)
		(layer "In2.Cu")
		(net "UART_RTS_P3_N")
	)
	(segment
		(start 175.825912 -85.156294)
		(end 176.10582 -85.436202)
		(width 0.1143)
		(layer "In2.Cu")
		(net "UART_RTS_P3_N")
	)
	(segment
		(start 156.630624 -165.20922)
		(end 152.13076 -165.20922)
		(width 0.1143)
		(layer "In2.Cu")
		(net "UART_RTS_P3_N")
	)
	(segment
		(start 178.402488 -85.436202)
		(end 191.2493 -98.283014)
		(width 0.1143)
		(layer "In2.Cu")
		(net "UART_RTS_P3_N")
	)
	(segment
		(start 152.12568 -165.20414)
		(end 149.67966 -165.20414)
		(width 0.1143)
		(layer "In2.Cu")
		(net "UART_RTS_P3_N")
	)
	(segment
		(start 191.2493 -121.7803)
		(end 191.516 -122.047)
		(width 0.1143)
		(layer "In2.Cu")
		(net "UART_RTS_P3_N")
	)
	(segment
		(start 171.564554 -162.68827)
		(end 169.671492 -164.581332)
		(width 0.1143)
		(layer "In2.Cu")
		(net "UART_RTS_P3_N")
	)
	(segment
		(start 191.2493 -98.283014)
		(end 191.2493 -121.7803)
		(width 0.1143)
		(layer "In2.Cu")
		(net "UART_RTS_P3_N")
	)
	(segment
		(start 169.671492 -164.581332)
		(end 157.258512 -164.581332)
		(width 0.1143)
		(layer "In2.Cu")
		(net "UART_RTS_P3_N")
	)
	(segment
		(start 133.70052 -59.098434)
		(end 133.76656 -59.164474)
		(width 0.1143)
		(layer "In2.Cu")
		(net "UART_RTS_P3_N")
	)
	(segment
		(start 191.516 -122.047)
		(end 191.516 -128.651)
		(width 0.1143)
		(layer "In2.Cu")
		(net "UART_RTS_P3_N")
	)
	(segment
		(start 133.76656 -59.164474)
		(end 133.76656 -67.424808)
		(width 0.1143)
		(layer "In2.Cu")
		(net "UART_RTS_P3_N")
	)
	(segment
		(start 152.654 -85.195664)
		(end 152.69337 -85.156294)
		(width 0.1143)
		(layer "In2.Cu")
		(net "UART_RTS_P3_N")
	)
	(segment
		(start 133.70052 -56.947054)
		(end 133.70052 -59.098434)
		(width 0.1143)
		(layer "In2.Cu")
		(net "UART_RTS_P3_N")
	)
	(segment
		(start 148.431758 -85.195664)
		(end 152.654 -85.195664)
		(width 0.1143)
		(layer "In2.Cu")
		(net "UART_RTS_P3_N")
	)
	(segment
		(start 181.749446 -162.68827)
		(end 171.564554 -162.68827)
		(width 0.1143)
		(layer "In2.Cu")
		(net "UART_RTS_P3_N")
	)
	(segment
		(start 134.579106 -69.273166)
		(end 137.43178 -72.12584)
		(width 0.1143)
		(layer "In2.Cu")
		(net "UART_RTS_P3_N")
	)
	(segment
		(start 135.20928 -53.20538)
		(end 135.20928 -55.438294)
		(width 0.1143)
		(layer "In2.Cu")
		(net "UART_RTS_P3_N")
	)
	(segment
		(start 137.43178 -74.195686)
		(end 148.431758 -85.195664)
		(width 0.1143)
		(layer "In2.Cu")
		(net "UART_RTS_P3_N")
	)
	(segment
		(start 154.634438 -147.041362)
		(end 153.07056 -147.041362)
		(width 0.1016)
		(layer "F.Cu")
		(net "LAN2_LED_LINK_100_N")
	)
	(segment
		(start 154.69108 -147.101052)
		(end 154.69108 -148.842222)
		(width 0.1016)
		(layer "F.Cu")
		(net "LAN2_LED_LINK_100_N")
	)
	(segment
		(start 155.696158 -149.8473)
		(end 156.470096 -149.8473)
		(width 0.1016)
		(layer "F.Cu")
		(net "LAN2_LED_LINK_100_N")
	)
	(segment
		(start 154.692604 -147.099528)
		(end 154.634438 -147.041362)
		(width 0.1016)
		(layer "F.Cu")
		(net "LAN2_LED_LINK_100_N")
	)
	(segment
		(start 154.692604 -147.099528)
		(end 154.69108 -147.101052)
		(width 0.1016)
		(layer "F.Cu")
		(net "LAN2_LED_LINK_100_N")
	)
	(segment
		(start 154.69108 -148.842222)
		(end 155.696158 -149.8473)
		(width 0.1016)
		(layer "F.Cu")
		(net "LAN2_LED_LINK_100_N")
	)
	(via
		(at 154.692604 -147.099528)
		(size 0.508)
		(drill 0.254)
		(layers "F.Cu" "B.Cu")
		(net "LAN2_LED_LINK_100_N")
	)
	(segment
		(start 156.19476 -184.773062)
		(end 156.109924 -184.773062)
		(width 0.1016)
		(layer "F.Cu")
		(net "FAN3_TACH")
	)
	(segment
		(start 156.109924 -184.773062)
		(end 154.70378 -183.366918)
		(width 0.1016)
		(layer "F.Cu")
		(net "FAN3_TACH")
	)
	(segment
		(start 94.051882 -171.250356)
		(end 94.051628 -171.250356)
		(width 0.1016)
		(layer "F.Cu")
		(net "FAN3_TACH")
	)
	(segment
		(start 156.19476 -184.805574)
		(end 156.19476 -184.773062)
		(width 0.1016)
		(layer "F.Cu")
		(net "FAN3_TACH")
	)
	(segment
		(start 94.051628 -171.250356)
		(end 93.5228 -170.721528)
		(width 0.1016)
		(layer "F.Cu")
		(net "FAN3_TACH")
	)
	(via
		(at 154.70378 -183.366918)
		(size 0.508)
		(drill 0.254)
		(layers "F.Cu" "B.Cu")
		(net "FAN3_TACH")
	)
	(via
		(at 93.5228 -170.721528)
		(size 0.508)
		(drill 0.254)
		(layers "F.Cu" "B.Cu")
		(net "FAN3_TACH")
	)
	(segment
		(start 109.225842 -181.071774)
		(end 108.944664 -180.790596)
		(width 0.1143)
		(layer "In6.Cu")
		(net "FAN3_TACH")
	)
	(segment
		(start 102.5525 -176.738534)
		(end 102.5525 -173.149768)
		(width 0.1143)
		(layer "In6.Cu")
		(net "FAN3_TACH")
	)
	(segment
		(start 137.762742 -179.566316)
		(end 136.497314 -178.300888)
		(width 0.1143)
		(layer "In6.Cu")
		(net "FAN3_TACH")
	)
	(segment
		(start 94.462854 -169.781474)
		(end 93.5228 -170.721528)
		(width 0.1143)
		(layer "In6.Cu")
		(net "FAN3_TACH")
	)
	(segment
		(start 125.240796 -177.274474)
		(end 124.39396 -177.274474)
		(width 0.1143)
		(layer "In6.Cu")
		(net "FAN3_TACH")
	)
	(segment
		(start 148.049742 -184.6072)
		(end 147.91817 -184.475628)
		(width 0.1143)
		(layer "In6.Cu")
		(net "FAN3_TACH")
	)
	(segment
		(start 142.66672 -184.475628)
		(end 142.41018 -184.219088)
		(width 0.1143)
		(layer "In6.Cu")
		(net "FAN3_TACH")
	)
	(segment
		(start 124.39396 -177.274474)
		(end 123.579382 -178.089052)
		(width 0.1143)
		(layer "In6.Cu")
		(net "FAN3_TACH")
	)
	(segment
		(start 123.579382 -178.089052)
		(end 113.663476 -178.089052)
		(width 0.1143)
		(layer "In6.Cu")
		(net "FAN3_TACH")
	)
	(segment
		(start 95.711264 -169.781474)
		(end 94.462854 -169.781474)
		(width 0.1143)
		(layer "In6.Cu")
		(net "FAN3_TACH")
	)
	(segment
		(start 140.34897 -182.619904)
		(end 138.637518 -180.908452)
		(width 0.1143)
		(layer "In6.Cu")
		(net "FAN3_TACH")
	)
	(segment
		(start 138.637518 -180.908452)
		(end 138.637518 -180.543454)
		(width 0.1143)
		(layer "In6.Cu")
		(net "FAN3_TACH")
	)
	(segment
		(start 110.836202 -179.878228)
		(end 109.642656 -181.071774)
		(width 0.1143)
		(layer "In6.Cu")
		(net "FAN3_TACH")
	)
	(segment
		(start 113.663476 -178.089052)
		(end 111.8743 -179.878228)
		(width 0.1143)
		(layer "In6.Cu")
		(net "FAN3_TACH")
	)
	(segment
		(start 142.41018 -184.155334)
		(end 140.87475 -182.619904)
		(width 0.1143)
		(layer "In6.Cu")
		(net "FAN3_TACH")
	)
	(segment
		(start 108.944664 -180.790596)
		(end 107.0102 -180.790596)
		(width 0.1143)
		(layer "In6.Cu")
		(net "FAN3_TACH")
	)
	(segment
		(start 126.26721 -178.300888)
		(end 125.240796 -177.274474)
		(width 0.1143)
		(layer "In6.Cu")
		(net "FAN3_TACH")
	)
	(segment
		(start 96.044258 -170.114468)
		(end 95.711264 -169.781474)
		(width 0.1143)
		(layer "In6.Cu")
		(net "FAN3_TACH")
	)
	(segment
		(start 140.87475 -182.619904)
		(end 140.34897 -182.619904)
		(width 0.1143)
		(layer "In6.Cu")
		(net "FAN3_TACH")
	)
	(segment
		(start 142.41018 -184.219088)
		(end 142.41018 -184.155334)
		(width 0.1143)
		(layer "In6.Cu")
		(net "FAN3_TACH")
	)
	(segment
		(start 102.5525 -173.149768)
		(end 99.5172 -170.114468)
		(width 0.1143)
		(layer "In6.Cu")
		(net "FAN3_TACH")
	)
	(segment
		(start 136.497314 -178.300888)
		(end 126.26721 -178.300888)
		(width 0.1143)
		(layer "In6.Cu")
		(net "FAN3_TACH")
	)
	(segment
		(start 104.834182 -179.020216)
		(end 102.5525 -176.738534)
		(width 0.1143)
		(layer "In6.Cu")
		(net "FAN3_TACH")
	)
	(segment
		(start 107.0102 -180.790596)
		(end 105.23982 -179.020216)
		(width 0.1143)
		(layer "In6.Cu")
		(net "FAN3_TACH")
	)
	(segment
		(start 138.637518 -180.543454)
		(end 138.883898 -180.297074)
		(width 0.1143)
		(layer "In6.Cu")
		(net "FAN3_TACH")
	)
	(segment
		(start 109.642656 -181.071774)
		(end 109.225842 -181.071774)
		(width 0.1143)
		(layer "In6.Cu")
		(net "FAN3_TACH")
	)
	(segment
		(start 99.5172 -170.114468)
		(end 96.044258 -170.114468)
		(width 0.1143)
		(layer "In6.Cu")
		(net "FAN3_TACH")
	)
	(segment
		(start 138.627358 -179.566316)
		(end 137.762742 -179.566316)
		(width 0.1143)
		(layer "In6.Cu")
		(net "FAN3_TACH")
	)
	(segment
		(start 105.23982 -179.020216)
		(end 104.834182 -179.020216)
		(width 0.1143)
		(layer "In6.Cu")
		(net "FAN3_TACH")
	)
	(segment
		(start 111.8743 -179.878228)
		(end 110.836202 -179.878228)
		(width 0.1143)
		(layer "In6.Cu")
		(net "FAN3_TACH")
	)
	(segment
		(start 138.883898 -179.822856)
		(end 138.627358 -179.566316)
		(width 0.1143)
		(layer "In6.Cu")
		(net "FAN3_TACH")
	)
	(segment
		(start 154.70378 -183.366918)
		(end 153.463498 -184.6072)
		(width 0.1143)
		(layer "In6.Cu")
		(net "FAN3_TACH")
	)
	(segment
		(start 147.91817 -184.475628)
		(end 142.66672 -184.475628)
		(width 0.1143)
		(layer "In6.Cu")
		(net "FAN3_TACH")
	)
	(segment
		(start 153.463498 -184.6072)
		(end 148.049742 -184.6072)
		(width 0.1143)
		(layer "In6.Cu")
		(net "FAN3_TACH")
	)
	(segment
		(start 138.883898 -180.297074)
		(end 138.883898 -179.822856)
		(width 0.1143)
		(layer "In6.Cu")
		(net "FAN3_TACH")
	)
	(segment
		(start 135.473948 -179.825396)
		(end 135.473948 -180.183536)
		(width 0.1016)
		(layer "F.Cu")
		(net "UART_DTR_P3_N")
	)
	(segment
		(start 135.473948 -180.183536)
		(end 135.93953 -180.649118)
		(width 0.1016)
		(layer "F.Cu")
		(net "UART_DTR_P3_N")
	)
	(segment
		(start 135.93953 -180.649118)
		(end 135.959088 -180.649118)
		(width 0.1016)
		(layer "F.Cu")
		(net "UART_DTR_P3_N")
	)
	(segment
		(start 137.58164 -52.742592)
		(end 137.580878 -52.74183)
		(width 0.1016)
		(layer "F.Cu")
		(net "UART_DTR_P3_N")
	)
	(segment
		(start 137.287 -51.83505)
		(end 137.287 -52.447952)
		(width 0.1016)
		(layer "F.Cu")
		(net "UART_DTR_P3_N")
	)
	(segment
		(start 137.58164 -53.754528)
		(end 137.58164 -52.742592)
		(width 0.1016)
		(layer "F.Cu")
		(net "UART_DTR_P3_N")
	)
	(segment
		(start 135.525764 -179.77358)
		(end 135.473948 -179.825396)
		(width 0.1016)
		(layer "F.Cu")
		(net "UART_DTR_P3_N")
	)
	(segment
		(start 135.525764 -178.858672)
		(end 135.525764 -179.77358)
		(width 0.1016)
		(layer "F.Cu")
		(net "UART_DTR_P3_N")
	)
	(segment
		(start 137.287 -52.447952)
		(end 137.580878 -52.74183)
		(width 0.1016)
		(layer "F.Cu")
		(net "UART_DTR_P3_N")
	)
	(via
		(at 137.580878 -52.74183)
		(size 0.508)
		(drill 0.254)
		(layers "F.Cu" "B.Cu")
		(net "UART_DTR_P3_N")
	)
	(via
		(at 135.959088 -180.649118)
		(size 0.508)
		(drill 0.254)
		(layers "F.Cu" "B.Cu")
		(net "UART_DTR_P3_N")
	)
	(via
		(at 140.511022 -184.111138)
		(size 0.508)
		(drill 0.254)
		(layers "F.Cu" "B.Cu")
		(net "UART_DTR_P3_N")
	)
	(segment
		(start 166.96309 -179.20589)
		(end 166.96309 -179.584096)
		(width 0.1143)
		(layer "In2.Cu")
		(net "UART_DTR_P3_N")
	)
	(segment
		(start 149.61235 -184.276238)
		(end 146.536156 -187.352432)
		(width 0.1143)
		(layer "In2.Cu")
		(net "UART_DTR_P3_N")
	)
	(segment
		(start 142.929102 -186.529218)
		(end 140.511022 -184.111138)
		(width 0.1143)
		(layer "In2.Cu")
		(net "UART_DTR_P3_N")
	)
	(segment
		(start 146.536156 -187.352432)
		(end 143.193262 -187.352432)
		(width 0.1143)
		(layer "In2.Cu")
		(net "UART_DTR_P3_N")
	)
	(segment
		(start 136.434068 -66.661538)
		(end 136.434068 -68.963286)
		(width 0.1143)
		(layer "In2.Cu")
		(net "UART_DTR_P3_N")
	)
	(segment
		(start 172.162216 -164.933122)
		(end 170.4467 -166.648638)
		(width 0.1143)
		(layer "In2.Cu")
		(net "UART_DTR_P3_N")
	)
	(segment
		(start 193.548 -153.711656)
		(end 182.326534 -164.933122)
		(width 0.1143)
		(layer "In2.Cu")
		(net "UART_DTR_P3_N")
	)
	(segment
		(start 170.4467 -166.648638)
		(end 169.59961 -166.648638)
		(width 0.1143)
		(layer "In2.Cu")
		(net "UART_DTR_P3_N")
	)
	(segment
		(start 140.53058 -75.803506)
		(end 148.868638 -84.141564)
		(width 0.1143)
		(layer "In2.Cu")
		(net "UART_DTR_P3_N")
	)
	(segment
		(start 193.548 -117.348)
		(end 193.929 -117.729)
		(width 0.1143)
		(layer "In2.Cu")
		(net "UART_DTR_P3_N")
	)
	(segment
		(start 152.21204 -84.141564)
		(end 152.25141 -84.102194)
		(width 0.1143)
		(layer "In2.Cu")
		(net "UART_DTR_P3_N")
	)
	(segment
		(start 136.434068 -68.963286)
		(end 140.53058 -73.059798)
		(width 0.1143)
		(layer "In2.Cu")
		(net "UART_DTR_P3_N")
	)
	(segment
		(start 143.193262 -187.352432)
		(end 142.929102 -187.088272)
		(width 0.1143)
		(layer "In2.Cu")
		(net "UART_DTR_P3_N")
	)
	(segment
		(start 165.7858 -178.0286)
		(end 166.96309 -179.20589)
		(width 0.1143)
		(layer "In2.Cu")
		(net "UART_DTR_P3_N")
	)
	(segment
		(start 193.929 -117.729)
		(end 193.929 -139.7)
		(width 0.1143)
		(layer "In2.Cu")
		(net "UART_DTR_P3_N")
	)
	(segment
		(start 169.59961 -166.648638)
		(end 166.250366 -169.997882)
		(width 0.1143)
		(layer "In2.Cu")
		(net "UART_DTR_P3_N")
	)
	(segment
		(start 159.773112 -184.276238)
		(end 149.61235 -184.276238)
		(width 0.1143)
		(layer "In2.Cu")
		(net "UART_DTR_P3_N")
	)
	(segment
		(start 177.838608 -84.102194)
		(end 178.0667 -83.874102)
		(width 0.1143)
		(layer "In2.Cu")
		(net "UART_DTR_P3_N")
	)
	(segment
		(start 140.53058 -73.059798)
		(end 140.53058 -75.803506)
		(width 0.1143)
		(layer "In2.Cu")
		(net "UART_DTR_P3_N")
	)
	(segment
		(start 178.0667 -83.874102)
		(end 178.78044 -83.874102)
		(width 0.1143)
		(layer "In2.Cu")
		(net "UART_DTR_P3_N")
	)
	(segment
		(start 178.78044 -83.874102)
		(end 193.548 -98.641662)
		(width 0.1143)
		(layer "In2.Cu")
		(net "UART_DTR_P3_N")
	)
	(segment
		(start 165.7858 -173.101)
		(end 165.7858 -178.0286)
		(width 0.1143)
		(layer "In2.Cu")
		(net "UART_DTR_P3_N")
	)
	(segment
		(start 193.548 -98.641662)
		(end 193.548 -117.348)
		(width 0.1143)
		(layer "In2.Cu")
		(net "UART_DTR_P3_N")
	)
	(segment
		(start 166.250366 -169.997882)
		(end 166.250366 -172.636434)
		(width 0.1143)
		(layer "In2.Cu")
		(net "UART_DTR_P3_N")
	)
	(segment
		(start 193.548 -140.081)
		(end 193.548 -153.711656)
		(width 0.1143)
		(layer "In2.Cu")
		(net "UART_DTR_P3_N")
	)
	(segment
		(start 166.96309 -179.584096)
		(end 166.70655 -179.840636)
		(width 0.1143)
		(layer "In2.Cu")
		(net "UART_DTR_P3_N")
	)
	(segment
		(start 152.25141 -84.102194)
		(end 177.838608 -84.102194)
		(width 0.1143)
		(layer "In2.Cu")
		(net "UART_DTR_P3_N")
	)
	(segment
		(start 182.326534 -164.933122)
		(end 172.162216 -164.933122)
		(width 0.1143)
		(layer "In2.Cu")
		(net "UART_DTR_P3_N")
	)
	(segment
		(start 137.580878 -52.74183)
		(end 137.580878 -65.514728)
		(width 0.1143)
		(layer "In2.Cu")
		(net "UART_DTR_P3_N")
	)
	(segment
		(start 166.250366 -172.636434)
		(end 165.7858 -173.101)
		(width 0.1143)
		(layer "In2.Cu")
		(net "UART_DTR_P3_N")
	)
	(segment
		(start 164.208714 -179.840636)
		(end 159.773112 -184.276238)
		(width 0.1143)
		(layer "In2.Cu")
		(net "UART_DTR_P3_N")
	)
	(segment
		(start 137.580878 -65.514728)
		(end 136.434068 -66.661538)
		(width 0.1143)
		(layer "In2.Cu")
		(net "UART_DTR_P3_N")
	)
	(segment
		(start 148.868638 -84.141564)
		(end 152.21204 -84.141564)
		(width 0.1143)
		(layer "In2.Cu")
		(net "UART_DTR_P3_N")
	)
	(segment
		(start 166.70655 -179.840636)
		(end 164.208714 -179.840636)
		(width 0.1143)
		(layer "In2.Cu")
		(net "UART_DTR_P3_N")
	)
	(segment
		(start 193.929 -139.7)
		(end 193.548 -140.081)
		(width 0.1143)
		(layer "In2.Cu")
		(net "UART_DTR_P3_N")
	)
	(segment
		(start 142.929102 -187.088272)
		(end 142.929102 -186.529218)
		(width 0.1143)
		(layer "In2.Cu")
		(net "UART_DTR_P3_N")
	)
	(segment
		(start 139.742418 -182.65013)
		(end 138.040364 -182.65013)
		(width 0.1143)
		(layer "In6.Cu")
		(net "UART_DTR_P3_N")
	)
	(segment
		(start 140.295884 -183.896)
		(end 140.295884 -183.203596)
		(width 0.1143)
		(layer "In6.Cu")
		(net "UART_DTR_P3_N")
	)
	(segment
		(start 138.040364 -182.65013)
		(end 136.039352 -180.649118)
		(width 0.1143)
		(layer "In6.Cu")
		(net "UART_DTR_P3_N")
	)
	(segment
		(start 136.039352 -180.649118)
		(end 135.959088 -180.649118)
		(width 0.1143)
		(layer "In6.Cu")
		(net "UART_DTR_P3_N")
	)
	(segment
		(start 140.295884 -183.203596)
		(end 139.742418 -182.65013)
		(width 0.1143)
		(layer "In6.Cu")
		(net "UART_DTR_P3_N")
	)
	(segment
		(start 140.511022 -184.111138)
		(end 140.295884 -183.896)
		(width 0.1143)
		(layer "In6.Cu")
		(net "UART_DTR_P3_N")
	)
	(segment
		(start 155.715208 -150.347172)
		(end 153.742644 -148.374608)
		(width 0.1016)
		(layer "F.Cu")
		(net "LAN2_LED_ACT_N")
	)
	(segment
		(start 153.425398 -148.057362)
		(end 153.742644 -148.374608)
		(width 0.1016)
		(layer "F.Cu")
		(net "LAN2_LED_ACT_N")
	)
	(segment
		(start 153.07056 -148.057362)
		(end 153.425398 -148.057362)
		(width 0.1016)
		(layer "F.Cu")
		(net "LAN2_LED_ACT_N")
	)
	(segment
		(start 156.470096 -150.347172)
		(end 155.715208 -150.347172)
		(width 0.1016)
		(layer "F.Cu")
		(net "LAN2_LED_ACT_N")
	)
	(via
		(at 153.742644 -148.374608)
		(size 0.508)
		(drill 0.254)
		(layers "F.Cu" "B.Cu")
		(net "LAN2_LED_ACT_N")
	)
	(segment
		(start 156.470096 -156.34716)
		(end 155.976066 -156.34716)
		(width 0.254)
		(layer "F.Cu")
		(net "P1V05_LAN2")
	)
	(segment
		(start 163.26993 -157.647132)
		(end 163.26993 -158.703772)
		(width 0.254)
		(layer "F.Cu")
		(net "P1V05_LAN2")
	)
	(segment
		(start 159.50692 -158.751016)
		(end 159.770064 -158.487872)
		(width 0.254)
		(layer "F.Cu")
		(net "P1V05_LAN2")
	)
	(segment
		(start 159.508444 -158.97733)
		(end 159.50692 -158.97733)
		(width 0.254)
		(layer "F.Cu")
		(net "P1V05_LAN2")
	)
	(segment
		(start 155.976066 -156.34716)
		(end 155.518104 -156.805122)
		(width 0.254)
		(layer "F.Cu")
		(net "P1V05_LAN2")
	)
	(segment
		(start 159.269938 -148.547328)
		(end 159.269938 -147.590764)
		(width 0.254)
		(layer "F.Cu")
		(net "P1V05_LAN2")
	)
	(segment
		(start 165.5699 -154.84729)
		(end 166.618412 -154.84729)
		(width 0.254)
		(layer "F.Cu")
		(net "P1V05_LAN2")
	)
	(segment
		(start 159.770064 -158.487872)
		(end 159.770064 -157.647132)
		(width 0.254)
		(layer "F.Cu")
		(net "P1V05_LAN2")
	)
	(segment
		(start 159.50692 -158.97733)
		(end 159.50692 -158.751016)
		(width 0.254)
		(layer "F.Cu")
		(net "P1V05_LAN2")
	)
	(segment
		(start 156.470096 -151.847296)
		(end 155.6385 -151.847296)
		(width 0.254)
		(layer "F.Cu")
		(net "P1V05_LAN2")
	)
	(segment
		(start 155.6385 -151.847296)
		(end 155.32608 -151.534876)
		(width 0.254)
		(layer "F.Cu")
		(net "P1V05_LAN2")
	)
	(segment
		(start 161.269934 -148.547328)
		(end 161.269934 -147.361402)
		(width 0.254)
		(layer "F.Cu")
		(net "P1V05_LAN2")
	)
	(segment
		(start 155.518104 -156.805122)
		(end 155.410916 -156.805122)
		(width 0.254)
		(layer "F.Cu")
		(net "P1V05_LAN2")
	)
	(segment
		(start 155.410916 -156.805122)
		(end 155.258516 -156.957522)
		(width 0.254)
		(layer "F.Cu")
		(net "P1V05_LAN2")
	)
	(via
		(at 153.77922 -158.171134)
		(size 0.6604)
		(drill 0.3302)
		(layers "F.Cu" "B.Cu")
		(net "P1V05_LAN2")
	)
	(via
		(at 155.32608 -151.534876)
		(size 0.508)
		(drill 0.254)
		(layers "F.Cu" "B.Cu")
		(net "P1V05_LAN2")
	)
	(via
		(at 161.269934 -147.361402)
		(size 0.508)
		(drill 0.254)
		(layers "F.Cu" "B.Cu")
		(net "P1V05_LAN2")
	)
	(via
		(at 166.618412 -154.84729)
		(size 0.508)
		(drill 0.254)
		(layers "F.Cu" "B.Cu")
		(net "P1V05_LAN2")
	)
	(via
		(at 155.258516 -156.957522)
		(size 0.508)
		(drill 0.254)
		(layers "F.Cu" "B.Cu")
		(net "P1V05_LAN2")
	)
	(via
		(at 159.269938 -147.590764)
		(size 0.508)
		(drill 0.254)
		(layers "F.Cu" "B.Cu")
		(net "P1V05_LAN2")
	)
	(via
		(at 159.508444 -158.97733)
		(size 0.508)
		(drill 0.254)
		(layers "F.Cu" "B.Cu")
		(net "P1V05_LAN2")
	)
	(via
		(at 163.26993 -158.703772)
		(size 0.508)
		(drill 0.254)
		(layers "F.Cu" "B.Cu")
		(net "P1V05_LAN2")
	)
	(segment
		(start 161.269934 -147.361402)
		(end 160.763712 -147.361402)
		(width 0.508)
		(layer "B.Cu")
		(net "P1V05_LAN2")
	)
	(segment
		(start 165.61943 -154.315922)
		(end 166.087044 -154.315922)
		(width 0.508)
		(layer "B.Cu")
		(net "P1V05_LAN2")
	)
	(segment
		(start 155.32608 -151.534876)
		(end 155.668726 -151.877522)
		(width 0.508)
		(layer "B.Cu")
		(net "P1V05_LAN2")
	)
	(segment
		(start 160.763712 -147.361402)
		(end 160.67278 -147.452334)
		(width 0.508)
		(layer "B.Cu")
		(net "P1V05_LAN2")
	)
	(segment
		(start 159.269938 -147.590764)
		(end 159.25038 -147.610322)
		(width 0.508)
		(layer "B.Cu")
		(net "P1V05_LAN2")
	)
	(segment
		(start 155.668726 -151.877522)
		(end 156.43733 -151.877522)
		(width 0.508)
		(layer "B.Cu")
		(net "P1V05_LAN2")
	)
	(segment
		(start 155.258516 -156.957522)
		(end 156.43733 -156.957522)
		(width 0.508)
		(layer "B.Cu")
		(net "P1V05_LAN2")
	)
	(segment
		(start 160.67278 -147.452334)
		(end 160.67278 -148.454872)
		(width 0.508)
		(layer "B.Cu")
		(net "P1V05_LAN2")
	)
	(segment
		(start 166.087044 -154.315922)
		(end 166.618412 -154.84729)
		(width 0.508)
		(layer "B.Cu")
		(net "P1V05_LAN2")
	)
	(segment
		(start 159.25038 -147.610322)
		(end 159.25038 -148.404072)
		(width 0.508)
		(layer "B.Cu")
		(net "P1V05_LAN2")
	)
	(segment
		(start 165.5699 -154.347164)
		(end 166.777162 -154.347164)
		(width 0.1016)
		(layer "F.Cu")
		(net "LAN2_DIS_REG10")
	)
	(segment
		(start 168.108376 -156.668216)
		(end 168.108376 -156.826458)
		(width 0.1016)
		(layer "F.Cu")
		(net "LAN2_DIS_REG10")
	)
	(segment
		(start 168.108376 -156.826458)
		(end 168.109392 -156.827474)
		(width 0.1016)
		(layer "F.Cu")
		(net "LAN2_DIS_REG10")
	)
	(segment
		(start 166.777162 -154.347164)
		(end 167.38092 -154.950922)
		(width 0.1016)
		(layer "F.Cu")
		(net "LAN2_DIS_REG10")
	)
	(segment
		(start 167.38092 -154.950922)
		(end 167.38092 -155.94076)
		(width 0.1016)
		(layer "F.Cu")
		(net "LAN2_DIS_REG10")
	)
	(segment
		(start 167.38092 -155.94076)
		(end 168.108376 -156.668216)
		(width 0.1016)
		(layer "F.Cu")
		(net "LAN2_DIS_REG10")
	)
	(via
		(at 167.38092 -154.950922)
		(size 0.508)
		(drill 0.254)
		(layers "F.Cu" "B.Cu")
		(net "LAN2_DIS_REG10")
	)
	(segment
		(start 168.733978 -154.804872)
		(end 167.52697 -154.804872)
		(width 0.1016)
		(layer "B.Cu")
		(net "LAN2_DIS_REG10")
	)
	(segment
		(start 167.52697 -154.804872)
		(end 167.38092 -154.950922)
		(width 0.1016)
		(layer "B.Cu")
		(net "LAN2_DIS_REG10")
	)
	(segment
		(start 173.209204 -154.398218)
		(end 173.349412 -154.538426)
		(width 0.10414)
		(layer "F.Cu")
		(net "LAN2_MDI1_DP")
	)
	(segment
		(start 174.254668 -154.538426)
		(end 174.567088 -154.538426)
		(width 0.10414)
		(layer "F.Cu")
		(net "LAN2_MDI1_DP")
	)
	(segment
		(start 171.854876 -151.841962)
		(end 172.3009 -152.287986)
		(width 0.10414)
		(layer "F.Cu")
		(net "LAN2_MDI1_DP")
	)
	(segment
		(start 170.071288 -152.318974)
		(end 170.5483 -151.841962)
		(width 0.10414)
		(layer "F.Cu")
		(net "LAN2_MDI1_DP")
	)
	(segment
		(start 174.567088 -154.538426)
		(end 174.707296 -154.398218)
		(width 0.10414)
		(layer "F.Cu")
		(net "LAN2_MDI1_DP")
	)
	(segment
		(start 175.07966 -156.732732)
		(end 175.601122 -157.254194)
		(width 0.10414)
		(layer "F.Cu")
		(net "LAN2_MDI1_DP")
	)
	(segment
		(start 167.435276 -152.470104)
		(end 167.122856 -152.470104)
		(width 0.10414)
		(layer "F.Cu")
		(net "LAN2_MDI1_DP")
	)
	(segment
		(start 167.898572 -152.318974)
		(end 167.586152 -152.318974)
		(width 0.10414)
		(layer "F.Cu")
		(net "LAN2_MDI1_DP")
	)
	(segment
		(start 175.33112 -154.780742)
		(end 175.33112 -155.325064)
		(width 0.10414)
		(layer "F.Cu")
		(net "LAN2_MDI1_DP")
	)
	(segment
		(start 174.707296 -154.398218)
		(end 174.948596 -154.398218)
		(width 0.10414)
		(layer "F.Cu")
		(net "LAN2_MDI1_DP")
	)
	(segment
		(start 172.3009 -153.832814)
		(end 172.866304 -154.398218)
		(width 0.10414)
		(layer "F.Cu")
		(net "LAN2_MDI1_DP")
	)
	(segment
		(start 172.3009 -152.530048)
		(end 172.13072 -152.700228)
		(width 0.10414)
		(layer "F.Cu")
		(net "LAN2_MDI1_DP")
	)
	(segment
		(start 175.601122 -157.254194)
		(end 176.346358 -157.254194)
		(width 0.10414)
		(layer "F.Cu")
		(net "LAN2_MDI1_DP")
	)
	(segment
		(start 172.3009 -153.182828)
		(end 172.3009 -153.832814)
		(width 0.10414)
		(layer "F.Cu")
		(net "LAN2_MDI1_DP")
	)
	(segment
		(start 170.891962 -151.841962)
		(end 171.056554 -152.006808)
		(width 0.10414)
		(layer "F.Cu")
		(net "LAN2_MDI1_DP")
	)
	(segment
		(start 176.120044 -158.32836)
		(end 176.120044 -159.0421)
		(width 0.10414)
		(layer "F.Cu")
		(net "LAN2_MDI1_DP")
	)
	(segment
		(start 176.53762 -157.881574)
		(end 176.537874 -157.881828)
		(width 0.10414)
		(layer "F.Cu")
		(net "LAN2_MDI1_DP")
	)
	(segment
		(start 167.122856 -152.470104)
		(end 166.97198 -152.318974)
		(width 0.10414)
		(layer "F.Cu")
		(net "LAN2_MDI1_DP")
	)
	(segment
		(start 172.866304 -154.398218)
		(end 173.209204 -154.398218)
		(width 0.10414)
		(layer "F.Cu")
		(net "LAN2_MDI1_DP")
	)
	(segment
		(start 176.537874 -157.91053)
		(end 176.120044 -158.32836)
		(width 0.10414)
		(layer "F.Cu")
		(net "LAN2_MDI1_DP")
	)
	(segment
		(start 173.661832 -154.538426)
		(end 173.80204 -154.398218)
		(width 0.10414)
		(layer "F.Cu")
		(net "LAN2_MDI1_DP")
	)
	(segment
		(start 168.512744 -152.318974)
		(end 168.361868 -152.470104)
		(width 0.10414)
		(layer "F.Cu")
		(net "LAN2_MDI1_DP")
	)
	(segment
		(start 175.33112 -155.325064)
		(end 175.07966 -155.576524)
		(width 0.10414)
		(layer "F.Cu")
		(net "LAN2_MDI1_DP")
	)
	(segment
		(start 171.056554 -152.006808)
		(end 171.368974 -152.006808)
		(width 0.10414)
		(layer "F.Cu")
		(net "LAN2_MDI1_DP")
	)
	(segment
		(start 170.5483 -151.841962)
		(end 170.891962 -151.841962)
		(width 0.10414)
		(layer "F.Cu")
		(net "LAN2_MDI1_DP")
	)
	(segment
		(start 171.533566 -151.841962)
		(end 171.854876 -151.841962)
		(width 0.10414)
		(layer "F.Cu")
		(net "LAN2_MDI1_DP")
	)
	(segment
		(start 172.13072 -152.700228)
		(end 172.13072 -153.012648)
		(width 0.10414)
		(layer "F.Cu")
		(net "LAN2_MDI1_DP")
	)
	(segment
		(start 166.97198 -152.318974)
		(end 166.07536 -152.318974)
		(width 0.10414)
		(layer "F.Cu")
		(net "LAN2_MDI1_DP")
	)
	(segment
		(start 176.53762 -157.445456)
		(end 176.53762 -157.881574)
		(width 0.10414)
		(layer "F.Cu")
		(net "LAN2_MDI1_DP")
	)
	(segment
		(start 176.346358 -157.254194)
		(end 176.53762 -157.445456)
		(width 0.10414)
		(layer "F.Cu")
		(net "LAN2_MDI1_DP")
	)
	(segment
		(start 171.368974 -152.006808)
		(end 171.533566 -151.841962)
		(width 0.10414)
		(layer "F.Cu")
		(net "LAN2_MDI1_DP")
	)
	(segment
		(start 169.65422 -152.318974)
		(end 168.512744 -152.318974)
		(width 0.10414)
		(layer "F.Cu")
		(net "LAN2_MDI1_DP")
	)
	(segment
		(start 176.537874 -157.881828)
		(end 176.537874 -157.91053)
		(width 0.10414)
		(layer "F.Cu")
		(net "LAN2_MDI1_DP")
	)
	(segment
		(start 172.3009 -152.287986)
		(end 172.3009 -152.530048)
		(width 0.10414)
		(layer "F.Cu")
		(net "LAN2_MDI1_DP")
	)
	(segment
		(start 168.361868 -152.470104)
		(end 168.049448 -152.470104)
		(width 0.10414)
		(layer "F.Cu")
		(net "LAN2_MDI1_DP")
	)
	(segment
		(start 167.586152 -152.318974)
		(end 167.435276 -152.470104)
		(width 0.10414)
		(layer "F.Cu")
		(net "LAN2_MDI1_DP")
	)
	(segment
		(start 172.13072 -153.012648)
		(end 172.3009 -153.182828)
		(width 0.10414)
		(layer "F.Cu")
		(net "LAN2_MDI1_DP")
	)
	(segment
		(start 166.047166 -152.347168)
		(end 165.5699 -152.347168)
		(width 0.10414)
		(layer "F.Cu")
		(net "LAN2_MDI1_DP")
	)
	(segment
		(start 174.11446 -154.398218)
		(end 174.254668 -154.538426)
		(width 0.10414)
		(layer "F.Cu")
		(net "LAN2_MDI1_DP")
	)
	(segment
		(start 169.65422 -152.318974)
		(end 170.071288 -152.318974)
		(width 0.10414)
		(layer "F.Cu")
		(net "LAN2_MDI1_DP")
	)
	(segment
		(start 174.948596 -154.398218)
		(end 175.33112 -154.780742)
		(width 0.10414)
		(layer "F.Cu")
		(net "LAN2_MDI1_DP")
	)
	(segment
		(start 175.07966 -155.576524)
		(end 175.07966 -156.732732)
		(width 0.10414)
		(layer "F.Cu")
		(net "LAN2_MDI1_DP")
	)
	(segment
		(start 168.049448 -152.470104)
		(end 167.898572 -152.318974)
		(width 0.10414)
		(layer "F.Cu")
		(net "LAN2_MDI1_DP")
	)
	(segment
		(start 166.07536 -152.318974)
		(end 166.047166 -152.347168)
		(width 0.10414)
		(layer "F.Cu")
		(net "LAN2_MDI1_DP")
	)
	(segment
		(start 173.80204 -154.398218)
		(end 174.11446 -154.398218)
		(width 0.10414)
		(layer "F.Cu")
		(net "LAN2_MDI1_DP")
	)
	(segment
		(start 173.349412 -154.538426)
		(end 173.661832 -154.538426)
		(width 0.10414)
		(layer "F.Cu")
		(net "LAN2_MDI1_DP")
	)
	(via
		(at 169.65422 -152.318974)
		(size 0.4064)
		(drill 0.2032)
		(layers "F.Cu" "B.Cu")
		(net "LAN2_MDI1_DP")
	)
	(segment
		(start 176.97196 -157.26537)
		(end 176.97196 -157.701488)
		(width 0.10414)
		(layer "F.Cu")
		(net "LAN2_MDI1_DN")
	)
	(segment
		(start 169.891202 -151.884634)
		(end 166.102538 -151.884634)
		(width 0.10414)
		(layer "F.Cu")
		(net "LAN2_MDI1_DN")
	)
	(segment
		(start 175.76546 -155.097988)
		(end 175.76546 -155.50515)
		(width 0.10414)
		(layer "F.Cu")
		(net "LAN2_MDI1_DN")
	)
	(segment
		(start 175.781208 -156.819854)
		(end 176.526444 -156.819854)
		(width 0.10414)
		(layer "F.Cu")
		(net "LAN2_MDI1_DN")
	)
	(segment
		(start 175.76546 -155.097988)
		(end 175.76546 -154.600656)
		(width 0.10414)
		(layer "F.Cu")
		(net "LAN2_MDI1_DN")
	)
	(segment
		(start 172.73524 -152.1079)
		(end 172.034962 -151.407622)
		(width 0.10414)
		(layer "F.Cu")
		(net "LAN2_MDI1_DN")
	)
	(segment
		(start 176.97196 -157.701488)
		(end 176.972214 -157.701742)
		(width 0.10414)
		(layer "F.Cu")
		(net "LAN2_MDI1_DN")
	)
	(segment
		(start 166.102538 -151.884634)
		(end 166.0652 -151.847296)
		(width 0.10414)
		(layer "F.Cu")
		(net "LAN2_MDI1_DN")
	)
	(segment
		(start 173.04639 -153.963878)
		(end 172.73524 -153.652728)
		(width 0.10414)
		(layer "F.Cu")
		(net "LAN2_MDI1_DN")
	)
	(segment
		(start 175.128682 -153.963878)
		(end 173.04639 -153.963878)
		(width 0.10414)
		(layer "F.Cu")
		(net "LAN2_MDI1_DN")
	)
	(segment
		(start 172.034962 -151.407622)
		(end 170.368214 -151.407622)
		(width 0.10414)
		(layer "F.Cu")
		(net "LAN2_MDI1_DN")
	)
	(segment
		(start 172.73524 -153.652728)
		(end 172.73524 -152.1079)
		(width 0.10414)
		(layer "F.Cu")
		(net "LAN2_MDI1_DN")
	)
	(segment
		(start 175.76546 -154.600656)
		(end 175.128682 -153.963878)
		(width 0.10414)
		(layer "F.Cu")
		(net "LAN2_MDI1_DN")
	)
	(segment
		(start 175.514 -155.75661)
		(end 175.514 -156.552646)
		(width 0.10414)
		(layer "F.Cu")
		(net "LAN2_MDI1_DN")
	)
	(segment
		(start 175.76546 -155.50515)
		(end 175.514 -155.75661)
		(width 0.10414)
		(layer "F.Cu")
		(net "LAN2_MDI1_DN")
	)
	(segment
		(start 176.972214 -157.91053)
		(end 177.390044 -158.32836)
		(width 0.10414)
		(layer "F.Cu")
		(net "LAN2_MDI1_DN")
	)
	(segment
		(start 176.972214 -157.701742)
		(end 176.972214 -157.91053)
		(width 0.10414)
		(layer "F.Cu")
		(net "LAN2_MDI1_DN")
	)
	(segment
		(start 175.514 -156.552646)
		(end 175.781208 -156.819854)
		(width 0.10414)
		(layer "F.Cu")
		(net "LAN2_MDI1_DN")
	)
	(segment
		(start 177.390044 -158.32836)
		(end 177.390044 -159.0421)
		(width 0.10414)
		(layer "F.Cu")
		(net "LAN2_MDI1_DN")
	)
	(segment
		(start 170.368214 -151.407622)
		(end 169.891202 -151.884634)
		(width 0.10414)
		(layer "F.Cu")
		(net "LAN2_MDI1_DN")
	)
	(segment
		(start 176.526444 -156.819854)
		(end 176.97196 -157.26537)
		(width 0.10414)
		(layer "F.Cu")
		(net "LAN2_MDI1_DN")
	)
	(segment
		(start 166.0652 -151.847296)
		(end 165.5699 -151.847296)
		(width 0.10414)
		(layer "F.Cu")
		(net "LAN2_MDI1_DN")
	)
	(via
		(at 175.76546 -155.097988)
		(size 0.4064)
		(drill 0.2032)
		(layers "F.Cu" "B.Cu")
		(net "LAN2_MDI1_DN")
	)
	(segment
		(start 164.770054 -148.008848)
		(end 165.464998 -147.313904)
		(width 0.1016)
		(layer "F.Cu")
		(net "LAN2_RST")
	)
	(segment
		(start 165.464998 -146.23288)
		(end 165.464998 -147.051522)
		(width 0.1016)
		(layer "F.Cu")
		(net "LAN2_RST")
	)
	(segment
		(start 165.464998 -147.313904)
		(end 165.464998 -147.051522)
		(width 0.1016)
		(layer "F.Cu")
		(net "LAN2_RST")
	)
	(segment
		(start 164.770054 -148.547328)
		(end 164.770054 -148.008848)
		(width 0.1016)
		(layer "F.Cu")
		(net "LAN2_RST")
	)
	(via
		(at 165.464998 -147.051522)
		(size 0.508)
		(drill 0.254)
		(layers "F.Cu" "B.Cu")
		(net "LAN2_RST")
	)
	(segment
		(start 160.054798 -159.74441)
		(end 159.964374 -159.653986)
		(width 0.1016)
		(layer "F.Cu")
		(net "LAN2_NC_SI_TDX0")
	)
	(segment
		(start 160.054798 -160.970468)
		(end 160.054798 -159.74441)
		(width 0.1016)
		(layer "F.Cu")
		(net "LAN2_NC_SI_TDX0")
	)
	(segment
		(start 160.770062 -158.848298)
		(end 159.964374 -159.653986)
		(width 0.1016)
		(layer "F.Cu")
		(net "LAN2_NC_SI_TDX0")
	)
	(segment
		(start 160.770062 -157.647132)
		(end 160.770062 -158.848298)
		(width 0.1016)
		(layer "F.Cu")
		(net "LAN2_NC_SI_TDX0")
	)
	(via
		(at 159.964374 -159.653986)
		(size 0.508)
		(drill 0.254)
		(layers "F.Cu" "B.Cu")
		(net "LAN2_NC_SI_TDX0")
	)
	(segment
		(start 165.34638 -160.444942)
		(end 164.889942 -159.988504)
		(width 0.1016)
		(layer "F.Cu")
		(net "LAN2_NC_SI_CRS_DV")
	)
	(segment
		(start 165.34638 -160.96996)
		(end 165.34638 -160.444942)
		(width 0.1016)
		(layer "F.Cu")
		(net "LAN2_NC_SI_CRS_DV")
	)
	(segment
		(start 163.770056 -157.647132)
		(end 163.770056 -158.73857)
		(width 0.1016)
		(layer "F.Cu")
		(net "LAN2_NC_SI_CRS_DV")
	)
	(segment
		(start 164.889942 -159.858456)
		(end 164.889942 -159.988504)
		(width 0.1016)
		(layer "F.Cu")
		(net "LAN2_NC_SI_CRS_DV")
	)
	(segment
		(start 163.770056 -158.73857)
		(end 164.889942 -159.858456)
		(width 0.1016)
		(layer "F.Cu")
		(net "LAN2_NC_SI_CRS_DV")
	)
	(via
		(at 164.889942 -159.988504)
		(size 0.508)
		(drill 0.254)
		(layers "F.Cu" "B.Cu")
		(net "LAN2_NC_SI_CRS_DV")
	)
	(segment
		(start 157.971998 -144.14754)
		(end 157.971998 -144.054322)
		(width 0.1016)
		(layer "F.Cu")
		(net "PU_LAN2_TDI")
	)
	(segment
		(start 160.770062 -146.945604)
		(end 157.971998 -144.14754)
		(width 0.1016)
		(layer "F.Cu")
		(net "PU_LAN2_TDI")
	)
	(segment
		(start 157.971998 -144.054322)
		(end 157.971998 -143.33728)
		(width 0.1016)
		(layer "F.Cu")
		(net "PU_LAN2_TDI")
	)
	(segment
		(start 160.770062 -148.547328)
		(end 160.770062 -146.945604)
		(width 0.1016)
		(layer "F.Cu")
		(net "PU_LAN2_TDI")
	)
	(via
		(at 157.971998 -144.054322)
		(size 0.508)
		(drill 0.254)
		(layers "F.Cu" "B.Cu")
		(net "PU_LAN2_TDI")
	)
	(segment
		(start 162.269932 -159.762952)
		(end 162.880802 -160.373822)
		(width 0.1016)
		(layer "F.Cu")
		(net "LAN2_NC_SI_RXD0")
	)
	(segment
		(start 162.269932 -157.647132)
		(end 162.269932 -159.762952)
		(width 0.1016)
		(layer "F.Cu")
		(net "LAN2_NC_SI_RXD0")
	)
	(segment
		(start 163.255198 -160.748218)
		(end 162.880802 -160.373822)
		(width 0.1016)
		(layer "F.Cu")
		(net "LAN2_NC_SI_RXD0")
	)
	(segment
		(start 163.255198 -160.995868)
		(end 163.255198 -160.748218)
		(width 0.1016)
		(layer "F.Cu")
		(net "LAN2_NC_SI_RXD0")
	)
	(via
		(at 162.880802 -160.373822)
		(size 0.508)
		(drill 0.254)
		(layers "F.Cu" "B.Cu")
		(net "LAN2_NC_SI_RXD0")
	)
	(segment
		(start 162.17138 -160.835086)
		(end 161.763456 -160.427162)
		(width 0.1016)
		(layer "F.Cu")
		(net "LAN2_NC_SI_TX_EN")
	)
	(segment
		(start 161.763456 -160.427162)
		(end 161.763456 -159.288734)
		(width 0.1016)
		(layer "F.Cu")
		(net "LAN2_NC_SI_TX_EN")
	)
	(segment
		(start 161.77006 -159.28213)
		(end 161.77006 -157.647132)
		(width 0.1016)
		(layer "F.Cu")
		(net "LAN2_NC_SI_TX_EN")
	)
	(segment
		(start 161.763456 -159.288734)
		(end 161.77006 -159.28213)
		(width 0.1016)
		(layer "F.Cu")
		(net "LAN2_NC_SI_TX_EN")
	)
	(segment
		(start 162.17138 -160.96996)
		(end 162.17138 -160.835086)
		(width 0.1016)
		(layer "F.Cu")
		(net "LAN2_NC_SI_TX_EN")
	)
	(via
		(at 161.77006 -159.28213)
		(size 0.508)
		(drill 0.254)
		(layers "F.Cu" "B.Cu")
		(net "LAN2_NC_SI_TX_EN")
	)
	(segment
		(start 158.770066 -159.405574)
		(end 158.48076 -159.69488)
		(width 0.1016)
		(layer "F.Cu")
		(net "SPI_LAN2_NVM_SK")
	)
	(segment
		(start 166.211504 -165.329616)
		(end 166.211504 -165.118288)
		(width 0.1016)
		(layer "F.Cu")
		(net "SPI_LAN2_NVM_SK")
	)
	(segment
		(start 161.859214 -165.575488)
		(end 165.965632 -165.575488)
		(width 0.1016)
		(layer "F.Cu")
		(net "SPI_LAN2_NVM_SK")
	)
	(segment
		(start 158.80588 -162.522154)
		(end 161.859214 -165.575488)
		(width 0.1016)
		(layer "F.Cu")
		(net "SPI_LAN2_NVM_SK")
	)
	(segment
		(start 165.965632 -165.575488)
		(end 166.211504 -165.329616)
		(width 0.1016)
		(layer "F.Cu")
		(net "SPI_LAN2_NVM_SK")
	)
	(segment
		(start 158.48076 -159.69488)
		(end 158.80588 -160.02)
		(width 0.1016)
		(layer "F.Cu")
		(net "SPI_LAN2_NVM_SK")
	)
	(segment
		(start 158.80588 -160.02)
		(end 158.80588 -162.522154)
		(width 0.1016)
		(layer "F.Cu")
		(net "SPI_LAN2_NVM_SK")
	)
	(segment
		(start 158.770066 -157.647132)
		(end 158.770066 -159.405574)
		(width 0.1016)
		(layer "F.Cu")
		(net "SPI_LAN2_NVM_SK")
	)
	(via
		(at 158.48076 -159.69488)
		(size 0.508)
		(drill 0.254)
		(layers "F.Cu" "B.Cu")
		(net "SPI_LAN2_NVM_SK")
	)
	(segment
		(start 153.312368 -149.073362)
		(end 153.770584 -149.531578)
		(width 0.1016)
		(layer "F.Cu")
		(net "LAN2_TEST_EN")
	)
	(segment
		(start 153.770584 -150.000208)
		(end 154.96032 -150.000208)
		(width 0.1016)
		(layer "F.Cu")
		(net "LAN2_TEST_EN")
	)
	(segment
		(start 154.96032 -150.000208)
		(end 155.807156 -150.847298)
		(width 0.1016)
		(layer "F.Cu")
		(net "LAN2_TEST_EN")
	)
	(segment
		(start 153.07056 -149.073362)
		(end 153.312368 -149.073362)
		(width 0.1016)
		(layer "F.Cu")
		(net "LAN2_TEST_EN")
	)
	(segment
		(start 153.770584 -149.531578)
		(end 153.770584 -150.000208)
		(width 0.1016)
		(layer "F.Cu")
		(net "LAN2_TEST_EN")
	)
	(segment
		(start 155.807156 -150.847298)
		(end 156.470096 -150.847298)
		(width 0.1016)
		(layer "F.Cu")
		(net "LAN2_TEST_EN")
	)
	(via
		(at 153.770584 -150.000208)
		(size 0.508)
		(drill 0.254)
		(layers "F.Cu" "B.Cu")
		(net "LAN2_TEST_EN")
	)
	(segment
		(start 165.411404 -163.848288)
		(end 164.73424 -163.848288)
		(width 0.1016)
		(layer "F.Cu")
		(net "LAN2_NVM_SI_R")
	)
	(segment
		(start 163.91128 -163.848288)
		(end 162.796474 -163.848288)
		(width 0.1016)
		(layer "F.Cu")
		(net "LAN2_NVM_SI_R")
	)
	(segment
		(start 164.32276 -163.436808)
		(end 163.91128 -163.848288)
		(width 0.1016)
		(layer "F.Cu")
		(net "LAN2_NVM_SI_R")
	)
	(segment
		(start 164.73424 -163.848288)
		(end 164.32276 -163.436808)
		(width 0.1016)
		(layer "F.Cu")
		(net "LAN2_NVM_SI_R")
	)
	(segment
		(start 164.32276 -163.436808)
		(end 164.32276 -163.435792)
		(width 0.1016)
		(layer "F.Cu")
		(net "LAN2_NVM_SI_R")
	)
	(via
		(at 164.32276 -163.435792)
		(size 0.508)
		(drill 0.254)
		(layers "F.Cu" "B.Cu")
		(net "LAN2_NVM_SI_R")
	)
	(segment
		(start 155.257246 -160.075118)
		(end 155.339288 -159.993076)
		(width 0.1016)
		(layer "F.Cu")
		(net "PLT_RST_LAN2_N")
	)
	(segment
		(start 156.470096 -156.847286)
		(end 156.470096 -157.50921)
		(width 0.1016)
		(layer "F.Cu")
		(net "PLT_RST_LAN2_N")
	)
	(segment
		(start 156.470096 -157.50921)
		(end 155.339288 -158.640018)
		(width 0.1016)
		(layer "F.Cu")
		(net "PLT_RST_LAN2_N")
	)
	(segment
		(start 155.339288 -158.640018)
		(end 155.339288 -159.993076)
		(width 0.1016)
		(layer "F.Cu")
		(net "PLT_RST_LAN2_N")
	)
	(segment
		(start 155.257246 -160.81375)
		(end 155.257246 -160.075118)
		(width 0.1016)
		(layer "F.Cu")
		(net "PLT_RST_LAN2_N")
	)
	(via
		(at 155.339288 -159.993076)
		(size 0.508)
		(drill 0.254)
		(layers "F.Cu" "B.Cu")
		(net "PLT_RST_LAN2_N")
	)
	(segment
		(start 156.13507 -167.658288)
		(end 155.7528 -168.040558)
		(width 0.1016)
		(layer "F.Cu")
		(net "LAN2_NVM_CS_N_R")
	)
	(segment
		(start 155.49753 -167.785288)
		(end 155.7528 -168.040558)
		(width 0.1016)
		(layer "F.Cu")
		(net "LAN2_NVM_CS_N_R")
	)
	(segment
		(start 154.951176 -167.785288)
		(end 155.49753 -167.785288)
		(width 0.1016)
		(layer "F.Cu")
		(net "LAN2_NVM_CS_N_R")
	)
	(segment
		(start 157.513274 -167.658288)
		(end 156.13507 -167.658288)
		(width 0.1016)
		(layer "F.Cu")
		(net "LAN2_NVM_CS_N_R")
	)
	(via
		(at 155.7528 -168.040558)
		(size 0.508)
		(drill 0.254)
		(layers "F.Cu" "B.Cu")
		(net "LAN2_NVM_CS_N_R")
	)
	(segment
		(start 158.770066 -147.511008)
		(end 155.148534 -143.889476)
		(width 0.1016)
		(layer "F.Cu")
		(net "SMB_LAN2_DAT")
	)
	(segment
		(start 153.526998 -143.28648)
		(end 154.542998 -143.28648)
		(width 0.1016)
		(layer "F.Cu")
		(net "SMB_LAN2_DAT")
	)
	(segment
		(start 154.542998 -143.28648)
		(end 154.545538 -143.28648)
		(width 0.1016)
		(layer "F.Cu")
		(net "SMB_LAN2_DAT")
	)
	(segment
		(start 154.545538 -143.28648)
		(end 155.148534 -143.889476)
		(width 0.1016)
		(layer "F.Cu")
		(net "SMB_LAN2_DAT")
	)
	(segment
		(start 158.770066 -148.547328)
		(end 158.770066 -147.511008)
		(width 0.1016)
		(layer "F.Cu")
		(net "SMB_LAN2_DAT")
	)
	(via
		(at 155.148534 -143.889476)
		(size 0.508)
		(drill 0.254)
		(layers "F.Cu" "B.Cu")
		(net "SMB_LAN2_DAT")
	)
	(segment
		(start 159.770064 -147.368006)
		(end 159.279336 -146.877278)
		(width 0.1016)
		(layer "F.Cu")
		(net "PU_LAN2_TMS")
	)
	(segment
		(start 155.685998 -143.71574)
		(end 158.23438 -146.264122)
		(width 0.1016)
		(layer "F.Cu")
		(net "PU_LAN2_TMS")
	)
	(segment
		(start 155.685998 -143.33728)
		(end 155.685998 -143.71574)
		(width 0.1016)
		(layer "F.Cu")
		(net "PU_LAN2_TMS")
	)
	(segment
		(start 158.23438 -146.264122)
		(end 158.66618 -146.264122)
		(width 0.1016)
		(layer "F.Cu")
		(net "PU_LAN2_TMS")
	)
	(segment
		(start 159.770064 -148.547328)
		(end 159.770064 -147.368006)
		(width 0.1016)
		(layer "F.Cu")
		(net "PU_LAN2_TMS")
	)
	(segment
		(start 158.66618 -146.264122)
		(end 159.279336 -146.877278)
		(width 0.1016)
		(layer "F.Cu")
		(net "PU_LAN2_TMS")
	)
	(via
		(at 159.279336 -146.877278)
		(size 0.508)
		(drill 0.254)
		(layers "F.Cu" "B.Cu")
		(net "PU_LAN2_TMS")
	)
	(segment
		(start 156.828998 -143.69034)
		(end 158.71698 -145.578322)
		(width 0.1016)
		(layer "F.Cu")
		(net "LAN2_AUX_PWR")
	)
	(segment
		(start 156.828998 -143.33728)
		(end 156.828998 -143.69034)
		(width 0.1016)
		(layer "F.Cu")
		(net "LAN2_AUX_PWR")
	)
	(segment
		(start 160.269936 -148.547328)
		(end 160.269936 -147.131278)
		(width 0.1016)
		(layer "F.Cu")
		(net "LAN2_AUX_PWR")
	)
	(segment
		(start 160.269936 -147.131278)
		(end 158.71698 -145.578322)
		(width 0.1016)
		(layer "F.Cu")
		(net "LAN2_AUX_PWR")
	)
	(via
		(at 158.71698 -145.578322)
		(size 0.508)
		(drill 0.254)
		(layers "F.Cu" "B.Cu")
		(net "LAN2_AUX_PWR")
	)
	(segment
		(start 153.164286 -144.715738)
		(end 152.664922 -144.216374)
		(width 0.1016)
		(layer "F.Cu")
		(net "SMB_LAN2_ALT_N")
	)
	(segment
		(start 158.26994 -148.547328)
		(end 158.26994 -147.725638)
		(width 0.1016)
		(layer "F.Cu")
		(net "SMB_LAN2_ALT_N")
	)
	(segment
		(start 158.26994 -147.725638)
		(end 155.26004 -144.715738)
		(width 0.1016)
		(layer "F.Cu")
		(net "SMB_LAN2_ALT_N")
	)
	(segment
		(start 152.510998 -144.06245)
		(end 152.664922 -144.216374)
		(width 0.1016)
		(layer "F.Cu")
		(net "SMB_LAN2_ALT_N")
	)
	(segment
		(start 155.26004 -144.715738)
		(end 153.164286 -144.715738)
		(width 0.1016)
		(layer "F.Cu")
		(net "SMB_LAN2_ALT_N")
	)
	(segment
		(start 151.494998 -143.28648)
		(end 152.510998 -143.28648)
		(width 0.1016)
		(layer "F.Cu")
		(net "SMB_LAN2_ALT_N")
	)
	(segment
		(start 152.510998 -143.28648)
		(end 152.510998 -144.06245)
		(width 0.1016)
		(layer "F.Cu")
		(net "SMB_LAN2_ALT_N")
	)
	(via
		(at 152.664922 -144.216374)
		(size 0.508)
		(drill 0.254)
		(layers "F.Cu" "B.Cu")
		(net "SMB_LAN2_ALT_N")
	)
	(segment
		(start 171.48302 -150.288498)
		(end 172.654722 -150.288498)
		(width 0.10414)
		(layer "F.Cu")
		(net "LAN2_MDI2_DN")
	)
	(segment
		(start 166.098474 -150.877778)
		(end 166.067994 -150.847298)
		(width 0.10414)
		(layer "F.Cu")
		(net "LAN2_MDI2_DN")
	)
	(segment
		(start 179.930044 -158.32836)
		(end 179.930044 -159.0421)
		(width 0.10414)
		(layer "F.Cu")
		(net "LAN2_MDI2_DN")
	)
	(segment
		(start 179.512214 -157.91053)
		(end 179.930044 -158.32836)
		(width 0.10414)
		(layer "F.Cu")
		(net "LAN2_MDI2_DN")
	)
	(segment
		(start 167.40124 -150.288498)
		(end 166.81196 -150.877778)
		(width 0.10414)
		(layer "F.Cu")
		(net "LAN2_MDI2_DN")
	)
	(segment
		(start 171.48302 -150.288498)
		(end 167.40124 -150.288498)
		(width 0.10414)
		(layer "F.Cu")
		(net "LAN2_MDI2_DN")
	)
	(segment
		(start 166.067994 -150.847298)
		(end 165.5699 -150.847298)
		(width 0.10414)
		(layer "F.Cu")
		(net "LAN2_MDI2_DN")
	)
	(segment
		(start 179.512214 -156.618432)
		(end 179.512214 -157.91053)
		(width 0.10414)
		(layer "F.Cu")
		(net "LAN2_MDI2_DN")
	)
	(segment
		(start 172.654722 -150.288498)
		(end 175.101758 -152.735534)
		(width 0.10414)
		(layer "F.Cu")
		(net "LAN2_MDI2_DN")
	)
	(segment
		(start 175.629316 -152.735534)
		(end 179.512214 -156.618432)
		(width 0.10414)
		(layer "F.Cu")
		(net "LAN2_MDI2_DN")
	)
	(segment
		(start 175.101758 -152.735534)
		(end 175.629316 -152.735534)
		(width 0.10414)
		(layer "F.Cu")
		(net "LAN2_MDI2_DN")
	)
	(segment
		(start 166.81196 -150.877778)
		(end 166.098474 -150.877778)
		(width 0.10414)
		(layer "F.Cu")
		(net "LAN2_MDI2_DN")
	)
	(via
		(at 171.48302 -150.288498)
		(size 0.4064)
		(drill 0.2032)
		(layers "F.Cu" "B.Cu")
		(net "LAN2_MDI2_DN")
	)
	(segment
		(start 164.582602 -159.16656)
		(end 164.956744 -159.16656)
		(width 0.1016)
		(layer "F.Cu")
		(net "LAN2_NC_SI_CLK_IN")
	)
	(segment
		(start 164.269928 -157.647132)
		(end 164.269928 -158.853886)
		(width 0.1016)
		(layer "F.Cu")
		(net "LAN2_NC_SI_CLK_IN")
	)
	(segment
		(start 166.41318 -160.622996)
		(end 166.172134 -160.38195)
		(width 0.1016)
		(layer "F.Cu")
		(net "LAN2_NC_SI_CLK_IN")
	)
	(segment
		(start 164.269928 -158.853886)
		(end 164.582602 -159.16656)
		(width 0.1016)
		(layer "F.Cu")
		(net "LAN2_NC_SI_CLK_IN")
	)
	(segment
		(start 166.41318 -160.99536)
		(end 166.41318 -160.622996)
		(width 0.1016)
		(layer "F.Cu")
		(net "LAN2_NC_SI_CLK_IN")
	)
	(segment
		(start 164.956744 -159.16656)
		(end 166.172134 -160.38195)
		(width 0.1016)
		(layer "F.Cu")
		(net "LAN2_NC_SI_CLK_IN")
	)
	(via
		(at 166.172134 -160.38195)
		(size 0.508)
		(drill 0.254)
		(layers "F.Cu" "B.Cu")
		(net "LAN2_NC_SI_CLK_IN")
	)
	(segment
		(start 165.411404 -165.118288)
		(end 164.632132 -165.118288)
		(width 0.1016)
		(layer "F.Cu")
		(net "LAN2_NVM_SK_R")
	)
	(segment
		(start 162.796474 -165.118288)
		(end 164.485828 -165.118288)
		(width 0.1016)
		(layer "F.Cu")
		(net "LAN2_NVM_SK_R")
	)
	(segment
		(start 164.632132 -165.118288)
		(end 164.55898 -165.045136)
		(width 0.1016)
		(layer "F.Cu")
		(net "LAN2_NVM_SK_R")
	)
	(segment
		(start 164.485828 -165.118288)
		(end 164.55898 -165.045136)
		(width 0.1016)
		(layer "F.Cu")
		(net "LAN2_NVM_SK_R")
	)
	(via
		(at 164.55898 -165.045136)
		(size 0.508)
		(drill 0.254)
		(layers "F.Cu" "B.Cu")
		(net "LAN2_NVM_SK_R")
	)
	(segment
		(start 161.070798 -160.360868)
		(end 161.070798 -160.970468)
		(width 0.1016)
		(layer "F.Cu")
		(net "LAN2_NC_SI_TDX1")
	)
	(segment
		(start 161.269934 -160.161732)
		(end 161.269934 -157.647132)
		(width 0.1016)
		(layer "F.Cu")
		(net "LAN2_NC_SI_TDX1")
	)
	(segment
		(start 161.070798 -160.360868)
		(end 161.269934 -160.161732)
		(width 0.1016)
		(layer "F.Cu")
		(net "LAN2_NC_SI_TDX1")
	)
	(via
		(at 161.070798 -160.360868)
		(size 0.508)
		(drill 0.254)
		(layers "F.Cu" "B.Cu")
		(net "LAN2_NC_SI_TDX1")
	)
	(segment
		(start 162.770058 -158.93161)
		(end 163.161726 -159.323278)
		(width 0.1016)
		(layer "F.Cu")
		(net "LAN2_NC_SI_RXD1")
	)
	(segment
		(start 162.770058 -157.647132)
		(end 162.770058 -158.93161)
		(width 0.1016)
		(layer "F.Cu")
		(net "LAN2_NC_SI_RXD1")
	)
	(segment
		(start 164.271198 -160.995868)
		(end 164.271198 -159.846264)
		(width 0.1016)
		(layer "F.Cu")
		(net "LAN2_NC_SI_RXD1")
	)
	(segment
		(start 163.161726 -159.323278)
		(end 163.737544 -159.323278)
		(width 0.1016)
		(layer "F.Cu")
		(net "LAN2_NC_SI_RXD1")
	)
	(segment
		(start 164.271198 -159.846264)
		(end 163.748212 -159.323278)
		(width 0.1016)
		(layer "F.Cu")
		(net "LAN2_NC_SI_RXD1")
	)
	(segment
		(start 163.748212 -159.323278)
		(end 163.737544 -159.323278)
		(width 0.1016)
		(layer "F.Cu")
		(net "LAN2_NC_SI_RXD1")
	)
	(via
		(at 163.737544 -159.323278)
		(size 0.508)
		(drill 0.254)
		(layers "F.Cu" "B.Cu")
		(net "LAN2_NC_SI_RXD1")
	)
	(segment
		(start 44.817538 -159.472884)
		(end 44.817538 -161.783268)
		(width 0.1016)
		(layer "F.Cu")
		(net "PU_LAN1_TDI")
	)
	(segment
		(start 44.817538 -161.783268)
		(end 45.49648 -162.46221)
		(width 0.1016)
		(layer "F.Cu")
		(net "PU_LAN1_TDI")
	)
	(segment
		(start 46.53407 -163.4998)
		(end 45.49648 -162.46221)
		(width 0.1016)
		(layer "F.Cu")
		(net "PU_LAN1_TDI")
	)
	(segment
		(start 47.60214 -163.4998)
		(end 46.53407 -163.4998)
		(width 0.1016)
		(layer "F.Cu")
		(net "PU_LAN1_TDI")
	)
	(via
		(at 45.49648 -162.46221)
		(size 0.508)
		(drill 0.254)
		(layers "F.Cu" "B.Cu")
		(net "PU_LAN1_TDI")
	)
	(segment
		(start 156.767022 -146.715988)
		(end 156.264102 -146.715988)
		(width 0.1016)
		(layer "F.Cu")
		(net "SMB_LAN2_CLK")
	)
	(segment
		(start 154.746452 -145.198338)
		(end 151.445214 -145.198338)
		(width 0.1016)
		(layer "F.Cu")
		(net "SMB_LAN2_CLK")
	)
	(segment
		(start 150.478998 -144.232122)
		(end 150.478998 -143.901922)
		(width 0.1016)
		(layer "F.Cu")
		(net "SMB_LAN2_CLK")
	)
	(segment
		(start 149.462998 -143.28648)
		(end 150.478998 -143.28648)
		(width 0.1016)
		(layer "F.Cu")
		(net "SMB_LAN2_CLK")
	)
	(segment
		(start 157.770068 -148.547328)
		(end 157.770068 -147.719034)
		(width 0.1016)
		(layer "F.Cu")
		(net "SMB_LAN2_CLK")
	)
	(segment
		(start 157.770068 -147.719034)
		(end 156.767022 -146.715988)
		(width 0.1016)
		(layer "F.Cu")
		(net "SMB_LAN2_CLK")
	)
	(segment
		(start 150.478998 -143.28648)
		(end 150.478998 -143.901922)
		(width 0.1016)
		(layer "F.Cu")
		(net "SMB_LAN2_CLK")
	)
	(segment
		(start 156.264102 -146.715988)
		(end 154.746452 -145.198338)
		(width 0.1016)
		(layer "F.Cu")
		(net "SMB_LAN2_CLK")
	)
	(segment
		(start 151.445214 -145.198338)
		(end 150.478998 -144.232122)
		(width 0.1016)
		(layer "F.Cu")
		(net "SMB_LAN2_CLK")
	)
	(via
		(at 150.478998 -143.901922)
		(size 0.508)
		(drill 0.254)
		(layers "F.Cu" "B.Cu")
		(net "SMB_LAN2_CLK")
	)
	(segment
		(start 45.817536 -159.472884)
		(end 45.817536 -160.652206)
		(width 0.1016)
		(layer "F.Cu")
		(net "PU_LAN1_TMS")
	)
	(segment
		(start 45.817536 -160.652206)
		(end 46.34992 -161.18459)
		(width 0.1016)
		(layer "F.Cu")
		(net "PU_LAN1_TMS")
	)
	(segment
		(start 46.92142 -161.75609)
		(end 46.34992 -161.18459)
		(width 0.1016)
		(layer "F.Cu")
		(net "PU_LAN1_TMS")
	)
	(segment
		(start 47.35322 -161.75609)
		(end 46.92142 -161.75609)
		(width 0.1016)
		(layer "F.Cu")
		(net "PU_LAN1_TMS")
	)
	(segment
		(start 48.74514 -163.4998)
		(end 48.74514 -163.14801)
		(width 0.1016)
		(layer "F.Cu")
		(net "PU_LAN1_TMS")
	)
	(segment
		(start 48.74514 -163.14801)
		(end 47.35322 -161.75609)
		(width 0.1016)
		(layer "F.Cu")
		(net "PU_LAN1_TMS")
	)
	(via
		(at 46.34992 -161.18459)
		(size 0.508)
		(drill 0.254)
		(layers "F.Cu" "B.Cu")
		(net "PU_LAN1_TMS")
	)
	(segment
		(start 155.73248 -155.249626)
		(end 155.142184 -155.249626)
		(width 0.127)
		(layer "F.Cu")
		(net "PCIE_LAN2_RX_C_DN")
	)
	(segment
		(start 156.470096 -155.347162)
		(end 155.830016 -155.347162)
		(width 0.127)
		(layer "F.Cu")
		(net "PCIE_LAN2_RX_C_DN")
	)
	(segment
		(start 151.870156 -155.992322)
		(end 154.012138 -155.992322)
		(width 0.127)
		(layer "F.Cu")
		(net "PCIE_LAN2_RX_C_DN")
	)
	(segment
		(start 155.830016 -155.347162)
		(end 155.73248 -155.249626)
		(width 0.127)
		(layer "F.Cu")
		(net "PCIE_LAN2_RX_C_DN")
	)
	(segment
		(start 154.754834 -155.249626)
		(end 155.142184 -155.249626)
		(width 0.127)
		(layer "F.Cu")
		(net "PCIE_LAN2_RX_C_DN")
	)
	(segment
		(start 151.514048 -156.34843)
		(end 151.870156 -155.992322)
		(width 0.127)
		(layer "F.Cu")
		(net "PCIE_LAN2_RX_C_DN")
	)
	(segment
		(start 154.012138 -155.992322)
		(end 154.754834 -155.249626)
		(width 0.127)
		(layer "F.Cu")
		(net "PCIE_LAN2_RX_C_DN")
	)
	(via
		(at 155.142184 -155.249626)
		(size 0.4064)
		(drill 0.2032)
		(layers "F.Cu" "B.Cu")
		(net "PCIE_LAN2_RX_C_DN")
	)
	(segment
		(start 154.51074 -162.967162)
		(end 153.3525 -164.125402)
		(width 0.1016)
		(layer "F.Cu")
		(net "SPI_LAN2_NVM_SO")
	)
	(segment
		(start 153.3525 -164.125402)
		(end 153.3525 -166.316406)
		(width 0.1016)
		(layer "F.Cu")
		(net "SPI_LAN2_NVM_SO")
	)
	(segment
		(start 158.04896 -161.359596)
		(end 158.04896 -159.255714)
		(width 0.1016)
		(layer "F.Cu")
		(net "SPI_LAN2_NVM_SO")
	)
	(segment
		(start 158.26994 -159.034734)
		(end 158.26994 -157.647132)
		(width 0.1016)
		(layer "F.Cu")
		(net "SPI_LAN2_NVM_SO")
	)
	(segment
		(start 153.3525 -166.316406)
		(end 153.551382 -166.515288)
		(width 0.1016)
		(layer "F.Cu")
		(net "SPI_LAN2_NVM_SO")
	)
	(segment
		(start 153.551382 -166.515288)
		(end 154.151076 -166.515288)
		(width 0.1016)
		(layer "F.Cu")
		(net "SPI_LAN2_NVM_SO")
	)
	(segment
		(start 158.11754 -161.428176)
		(end 158.04896 -161.359596)
		(width 0.1016)
		(layer "F.Cu")
		(net "SPI_LAN2_NVM_SO")
	)
	(segment
		(start 158.04896 -159.255714)
		(end 158.26994 -159.034734)
		(width 0.1016)
		(layer "F.Cu")
		(net "SPI_LAN2_NVM_SO")
	)
	(via
		(at 154.51074 -162.967162)
		(size 0.508)
		(drill 0.254)
		(layers "F.Cu" "B.Cu")
		(net "SPI_LAN2_NVM_SO")
	)
	(via
		(at 158.11754 -161.428176)
		(size 0.508)
		(drill 0.254)
		(layers "F.Cu" "B.Cu")
		(net "SPI_LAN2_NVM_SO")
	)
	(segment
		(start 157.303978 -161.498026)
		(end 156.765244 -162.03676)
		(width 0.1143)
		(layer "In2.Cu")
		(net "SPI_LAN2_NVM_SO")
	)
	(segment
		(start 156.765244 -162.03676)
		(end 156.081984 -162.03676)
		(width 0.1143)
		(layer "In2.Cu")
		(net "SPI_LAN2_NVM_SO")
	)
	(segment
		(start 158.04769 -161.498026)
		(end 157.303978 -161.498026)
		(width 0.1143)
		(layer "In2.Cu")
		(net "SPI_LAN2_NVM_SO")
	)
	(segment
		(start 155.151836 -162.967162)
		(end 154.51074 -162.967162)
		(width 0.1143)
		(layer "In2.Cu")
		(net "SPI_LAN2_NVM_SO")
	)
	(segment
		(start 156.081984 -162.03676)
		(end 155.151836 -162.967162)
		(width 0.1143)
		(layer "In2.Cu")
		(net "SPI_LAN2_NVM_SO")
	)
	(segment
		(start 158.11754 -161.428176)
		(end 158.04769 -161.498026)
		(width 0.1143)
		(layer "In2.Cu")
		(net "SPI_LAN2_NVM_SO")
	)
	(segment
		(start 162.524948 -143.659352)
		(end 162.524948 -144.46123)
		(width 0.1016)
		(layer "F.Cu")
		(net "LAN2_XTAL_IN")
	)
	(segment
		(start 164.13607 -142.04823)
		(end 162.524948 -143.659352)
		(width 0.1016)
		(layer "F.Cu")
		(net "LAN2_XTAL_IN")
	)
	(segment
		(start 162.476942 -144.509236)
		(end 162.476942 -146.529552)
		(width 0.1016)
		(layer "F.Cu")
		(net "LAN2_XTAL_IN")
	)
	(segment
		(start 162.476942 -147.06346)
		(end 162.476942 -146.529552)
		(width 0.1016)
		(layer "F.Cu")
		(net "LAN2_XTAL_IN")
	)
	(segment
		(start 162.269932 -148.547328)
		(end 162.269932 -147.27047)
		(width 0.1016)
		(layer "F.Cu")
		(net "LAN2_XTAL_IN")
	)
	(segment
		(start 162.269932 -147.27047)
		(end 162.476942 -147.06346)
		(width 0.1016)
		(layer "F.Cu")
		(net "LAN2_XTAL_IN")
	)
	(segment
		(start 162.524948 -144.46123)
		(end 162.476942 -144.509236)
		(width 0.1016)
		(layer "F.Cu")
		(net "LAN2_XTAL_IN")
	)
	(via
		(at 162.476942 -146.529552)
		(size 0.508)
		(drill 0.254)
		(layers "F.Cu" "B.Cu")
		(net "LAN2_XTAL_IN")
	)
	(segment
		(start 46.937676 -162.480498)
		(end 46.925992 -162.480498)
		(width 0.1016)
		(layer "F.Cu")
		(net "LAN1_AUX_PWR")
	)
	(segment
		(start 48.19904 -165.79977)
		(end 48.19904 -163.19119)
		(width 0.1016)
		(layer "F.Cu")
		(net "LAN1_AUX_PWR")
	)
	(segment
		(start 47.60214 -166.0398)
		(end 47.95901 -166.0398)
		(width 0.1016)
		(layer "F.Cu")
		(net "LAN1_AUX_PWR")
	)
	(segment
		(start 45.317664 -159.472884)
		(end 45.317664 -160.860486)
		(width 0.1016)
		(layer "F.Cu")
		(net "LAN1_AUX_PWR")
	)
	(segment
		(start 47.500032 -162.492182)
		(end 46.937676 -162.492182)
		(width 0.1016)
		(layer "F.Cu")
		(net "LAN1_AUX_PWR")
	)
	(segment
		(start 47.95901 -166.0398)
		(end 48.19904 -165.79977)
		(width 0.1016)
		(layer "F.Cu")
		(net "LAN1_AUX_PWR")
	)
	(segment
		(start 48.19904 -163.19119)
		(end 47.500032 -162.492182)
		(width 0.1016)
		(layer "F.Cu")
		(net "LAN1_AUX_PWR")
	)
	(segment
		(start 45.317664 -160.860486)
		(end 46.937676 -162.480498)
		(width 0.1016)
		(layer "F.Cu")
		(net "LAN1_AUX_PWR")
	)
	(segment
		(start 46.937676 -162.492182)
		(end 46.925992 -162.480498)
		(width 0.1016)
		(layer "F.Cu")
		(net "LAN1_AUX_PWR")
	)
	(via
		(at 46.925992 -162.480498)
		(size 0.508)
		(drill 0.254)
		(layers "F.Cu" "B.Cu")
		(net "LAN1_AUX_PWR")
	)
	(segment
		(start 114.76736 -166.906702)
		(end 115.726718 -166.906702)
		(width 0.1016)
		(layer "F.Cu")
		(net "PSU1_HUB_EN")
	)
	(segment
		(start 115.972336 -169.768266)
		(end 115.972336 -168.60647)
		(width 0.1016)
		(layer "F.Cu")
		(net "PSU1_HUB_EN")
	)
	(segment
		(start 114.76736 -170.021504)
		(end 115.719098 -170.021504)
		(width 0.1016)
		(layer "F.Cu")
		(net "PSU1_HUB_EN")
	)
	(segment
		(start 115.972336 -168.60647)
		(end 116.113052 -168.465754)
		(width 0.1016)
		(layer "F.Cu")
		(net "PSU1_HUB_EN")
	)
	(segment
		(start 116.113052 -167.293036)
		(end 116.113052 -168.465754)
		(width 0.1016)
		(layer "F.Cu")
		(net "PSU1_HUB_EN")
	)
	(segment
		(start 115.719098 -170.021504)
		(end 115.972336 -169.768266)
		(width 0.1016)
		(layer "F.Cu")
		(net "PSU1_HUB_EN")
	)
	(segment
		(start 115.726718 -166.906702)
		(end 116.113052 -167.293036)
		(width 0.1016)
		(layer "F.Cu")
		(net "PSU1_HUB_EN")
	)
	(via
		(at 116.113052 -168.465754)
		(size 0.508)
		(drill 0.254)
		(layers "F.Cu" "B.Cu")
		(net "PSU1_HUB_EN")
	)
	(segment
		(start 115.121182 -166.980362)
		(end 115.121182 -167.473884)
		(width 0.1016)
		(layer "B.Cu")
		(net "PSU1_HUB_EN")
	)
	(segment
		(start 115.121182 -167.473884)
		(end 116.113052 -168.465754)
		(width 0.1016)
		(layer "B.Cu")
		(net "PSU1_HUB_EN")
	)
	(segment
		(start 161.77006 -148.547328)
		(end 161.77006 -145.123154)
		(width 0.1016)
		(layer "F.Cu")
		(net "LAN2_XTAL_OUT")
	)
	(segment
		(start 161.77006 -144.811242)
		(end 161.77006 -145.123154)
		(width 0.1016)
		(layer "F.Cu")
		(net "LAN2_XTAL_OUT")
	)
	(segment
		(start 161.420048 -144.46123)
		(end 161.77006 -144.811242)
		(width 0.1016)
		(layer "F.Cu")
		(net "LAN2_XTAL_OUT")
	)
	(segment
		(start 159.935926 -142.04823)
		(end 161.420048 -143.532352)
		(width 0.1016)
		(layer "F.Cu")
		(net "LAN2_XTAL_OUT")
	)
	(segment
		(start 161.420048 -143.532352)
		(end 161.420048 -144.46123)
		(width 0.1016)
		(layer "F.Cu")
		(net "LAN2_XTAL_OUT")
	)
	(via
		(at 161.77006 -145.123154)
		(size 0.508)
		(drill 0.254)
		(layers "F.Cu" "B.Cu")
		(net "LAN2_XTAL_OUT")
	)
	(segment
		(start 49.679606 -157.172914)
		(end 51.003962 -158.49727)
		(width 0.1016)
		(layer "F.Cu")
		(net "LAN1_TEST_EN")
	)
	(segment
		(start 53.161946 -158.998158)
		(end 51.938428 -158.998158)
		(width 0.1016)
		(layer "F.Cu")
		(net "LAN1_TEST_EN")
	)
	(segment
		(start 51.003962 -158.49727)
		(end 51.43754 -158.49727)
		(width 0.1016)
		(layer "F.Cu")
		(net "LAN1_TEST_EN")
	)
	(segment
		(start 49.117504 -157.172914)
		(end 49.679606 -157.172914)
		(width 0.1016)
		(layer "F.Cu")
		(net "LAN1_TEST_EN")
	)
	(segment
		(start 51.938428 -158.998158)
		(end 51.43754 -158.49727)
		(width 0.1016)
		(layer "F.Cu")
		(net "LAN1_TEST_EN")
	)
	(via
		(at 51.43754 -158.49727)
		(size 0.508)
		(drill 0.254)
		(layers "F.Cu" "B.Cu")
		(net "LAN1_TEST_EN")
	)
	(segment
		(start 155.960572 -166.388288)
		(end 155.6893 -166.65956)
		(width 0.1016)
		(layer "F.Cu")
		(net "LAN2_NVM_SO_R")
	)
	(segment
		(start 157.513274 -166.388288)
		(end 155.960572 -166.388288)
		(width 0.1016)
		(layer "F.Cu")
		(net "LAN2_NVM_SO_R")
	)
	(segment
		(start 155.545028 -166.515288)
		(end 155.6893 -166.65956)
		(width 0.1016)
		(layer "F.Cu")
		(net "LAN2_NVM_SO_R")
	)
	(segment
		(start 154.951176 -166.515288)
		(end 155.545028 -166.515288)
		(width 0.1016)
		(layer "F.Cu")
		(net "LAN2_NVM_SO_R")
	)
	(via
		(at 155.6893 -166.65956)
		(size 0.508)
		(drill 0.254)
		(layers "F.Cu" "B.Cu")
		(net "LAN2_NVM_SO_R")
	)
	(segment
		(start 118.61292 -169.431462)
		(end 118.61292 -169.432986)
		(width 0.1016)
		(layer "F.Cu")
		(net "PSU2_HUB_EN")
	)
	(segment
		(start 116.54536 -167.104568)
		(end 115.697508 -166.256716)
		(width 0.1016)
		(layer "F.Cu")
		(net "PSU2_HUB_EN")
	)
	(segment
		(start 119.57304 -168.802558)
		(end 118.944136 -169.431462)
		(width 0.1016)
		(layer "F.Cu")
		(net "PSU2_HUB_EN")
	)
	(segment
		(start 119.71655 -168.071546)
		(end 119.57304 -168.215056)
		(width 0.1016)
		(layer "F.Cu")
		(net "PSU2_HUB_EN")
	)
	(segment
		(start 118.944136 -169.431462)
		(end 118.61292 -169.431462)
		(width 0.1016)
		(layer "F.Cu")
		(net "PSU2_HUB_EN")
	)
	(segment
		(start 116.54536 -168.425114)
		(end 116.54536 -167.104568)
		(width 0.1016)
		(layer "F.Cu")
		(net "PSU2_HUB_EN")
	)
	(segment
		(start 115.697508 -166.256716)
		(end 114.76736 -166.256716)
		(width 0.1016)
		(layer "F.Cu")
		(net "PSU2_HUB_EN")
	)
	(segment
		(start 119.57304 -168.215056)
		(end 119.57304 -168.802558)
		(width 0.1016)
		(layer "F.Cu")
		(net "PSU2_HUB_EN")
	)
	(segment
		(start 118.61292 -169.431462)
		(end 117.551708 -169.431462)
		(width 0.1016)
		(layer "F.Cu")
		(net "PSU2_HUB_EN")
	)
	(segment
		(start 117.551708 -169.431462)
		(end 116.54536 -168.425114)
		(width 0.1016)
		(layer "F.Cu")
		(net "PSU2_HUB_EN")
	)
	(segment
		(start 120.60936 -168.071546)
		(end 119.71655 -168.071546)
		(width 0.1016)
		(layer "F.Cu")
		(net "PSU2_HUB_EN")
	)
	(via
		(at 118.61292 -169.432986)
		(size 0.508)
		(drill 0.254)
		(layers "F.Cu" "B.Cu")
		(net "PSU2_HUB_EN")
	)
	(segment
		(start 119.280432 -169.432986)
		(end 120.153176 -168.560242)
		(width 0.1016)
		(layer "B.Cu")
		(net "PSU2_HUB_EN")
	)
	(segment
		(start 120.153176 -168.560242)
		(end 120.234202 -168.560242)
		(width 0.1016)
		(layer "B.Cu")
		(net "PSU2_HUB_EN")
	)
	(segment
		(start 118.61292 -169.432986)
		(end 119.280432 -169.432986)
		(width 0.1016)
		(layer "B.Cu")
		(net "PSU2_HUB_EN")
	)
	(segment
		(start 169.562018 -149.032214)
		(end 169.722546 -149.192742)
		(width 0.10414)
		(layer "F.Cu")
		(net "LAN2_MDI3_DP")
	)
	(segment
		(start 182.948072 -156.943552)
		(end 183.140096 -156.905706)
		(width 0.10414)
		(layer "F.Cu")
		(net "LAN2_MDI3_DP")
	)
	(segment
		(start 167.676068 -149.032214)
		(end 168.616122 -149.032214)
		(width 0.10414)
		(layer "F.Cu")
		(net "LAN2_MDI3_DP")
	)
	(segment
		(start 183.740044 -158.32836)
		(end 183.740044 -159.0421)
		(width 0.10414)
		(layer "F.Cu")
		(net "LAN2_MDI3_DP")
	)
	(segment
		(start 174.052484 -150.475442)
		(end 175.010318 -151.433276)
		(width 0.10414)
		(layer "F.Cu")
		(net "LAN2_MDI3_DP")
	)
	(segment
		(start 184.157874 -157.742128)
		(end 184.157874 -157.91053)
		(width 0.10414)
		(layer "F.Cu")
		(net "LAN2_MDI3_DP")
	)
	(segment
		(start 171.614338 -149.192742)
		(end 171.926758 -149.192742)
		(width 0.10414)
		(layer "F.Cu")
		(net "LAN2_MDI3_DP")
	)
	(segment
		(start 182.688484 -156.7688)
		(end 182.948072 -156.943552)
		(width 0.10414)
		(layer "F.Cu")
		(net "LAN2_MDI3_DP")
	)
	(segment
		(start 183.66867 -157.261814)
		(end 183.988202 -157.57271)
		(width 0.10414)
		(layer "F.Cu")
		(net "LAN2_MDI3_DP")
	)
	(segment
		(start 169.722546 -149.192742)
		(end 170.034966 -149.192742)
		(width 0.10414)
		(layer "F.Cu")
		(net "LAN2_MDI3_DP")
	)
	(segment
		(start 170.668442 -149.192742)
		(end 170.980862 -149.192742)
		(width 0.10414)
		(layer "F.Cu")
		(net "LAN2_MDI3_DP")
	)
	(segment
		(start 171.926758 -149.192742)
		(end 172.087286 -149.032214)
		(width 0.10414)
		(layer "F.Cu")
		(net "LAN2_MDI3_DP")
	)
	(segment
		(start 166.029894 -149.821646)
		(end 166.886636 -149.821646)
		(width 0.10414)
		(layer "F.Cu")
		(net "LAN2_MDI3_DP")
	)
	(segment
		(start 172.609256 -149.032214)
		(end 174.052484 -150.475442)
		(width 0.10414)
		(layer "F.Cu")
		(net "LAN2_MDI3_DP")
	)
	(segment
		(start 170.980862 -149.192742)
		(end 171.14139 -149.032214)
		(width 0.10414)
		(layer "F.Cu")
		(net "LAN2_MDI3_DP")
	)
	(segment
		(start 171.45381 -149.032214)
		(end 171.614338 -149.192742)
		(width 0.10414)
		(layer "F.Cu")
		(net "LAN2_MDI3_DP")
	)
	(segment
		(start 184.157874 -157.91053)
		(end 183.740044 -158.32836)
		(width 0.10414)
		(layer "F.Cu")
		(net "LAN2_MDI3_DP")
	)
	(segment
		(start 166.886636 -149.821646)
		(end 167.676068 -149.032214)
		(width 0.10414)
		(layer "F.Cu")
		(net "LAN2_MDI3_DP")
	)
	(segment
		(start 182.650892 -156.576522)
		(end 182.688484 -156.7688)
		(width 0.10414)
		(layer "F.Cu")
		(net "LAN2_MDI3_DP")
	)
	(segment
		(start 172.087286 -149.032214)
		(end 172.609256 -149.032214)
		(width 0.10414)
		(layer "F.Cu")
		(net "LAN2_MDI3_DP")
	)
	(segment
		(start 171.14139 -149.032214)
		(end 171.45381 -149.032214)
		(width 0.10414)
		(layer "F.Cu")
		(net "LAN2_MDI3_DP")
	)
	(segment
		(start 168.77665 -149.192742)
		(end 169.08907 -149.192742)
		(width 0.10414)
		(layer "F.Cu")
		(net "LAN2_MDI3_DP")
	)
	(segment
		(start 168.616122 -149.032214)
		(end 168.77665 -149.192742)
		(width 0.10414)
		(layer "F.Cu")
		(net "LAN2_MDI3_DP")
	)
	(segment
		(start 170.195494 -149.032214)
		(end 170.507914 -149.032214)
		(width 0.10414)
		(layer "F.Cu")
		(net "LAN2_MDI3_DP")
	)
	(segment
		(start 182.391304 -156.40177)
		(end 182.650892 -156.576522)
		(width 0.10414)
		(layer "F.Cu")
		(net "LAN2_MDI3_DP")
	)
	(segment
		(start 165.5699 -149.8473)
		(end 166.00424 -149.8473)
		(width 0.10414)
		(layer "F.Cu")
		(net "LAN2_MDI3_DP")
	)
	(segment
		(start 175.010318 -151.433276)
		(end 181.9021 -156.072586)
		(width 0.10414)
		(layer "F.Cu")
		(net "LAN2_MDI3_DP")
	)
	(segment
		(start 183.988202 -157.57271)
		(end 184.157874 -157.742128)
		(width 0.10414)
		(layer "F.Cu")
		(net "LAN2_MDI3_DP")
	)
	(segment
		(start 170.507914 -149.032214)
		(end 170.668442 -149.192742)
		(width 0.10414)
		(layer "F.Cu")
		(net "LAN2_MDI3_DP")
	)
	(segment
		(start 181.9021 -156.072586)
		(end 181.939692 -156.264864)
		(width 0.10414)
		(layer "F.Cu")
		(net "LAN2_MDI3_DP")
	)
	(segment
		(start 182.19928 -156.439616)
		(end 182.391304 -156.40177)
		(width 0.10414)
		(layer "F.Cu")
		(net "LAN2_MDI3_DP")
	)
	(segment
		(start 181.939692 -156.264864)
		(end 182.19928 -156.439616)
		(width 0.10414)
		(layer "F.Cu")
		(net "LAN2_MDI3_DP")
	)
	(segment
		(start 166.00424 -149.8473)
		(end 166.029894 -149.821646)
		(width 0.10414)
		(layer "F.Cu")
		(net "LAN2_MDI3_DP")
	)
	(segment
		(start 170.034966 -149.192742)
		(end 170.195494 -149.032214)
		(width 0.10414)
		(layer "F.Cu")
		(net "LAN2_MDI3_DP")
	)
	(segment
		(start 183.140096 -156.905706)
		(end 183.66867 -157.261814)
		(width 0.10414)
		(layer "F.Cu")
		(net "LAN2_MDI3_DP")
	)
	(segment
		(start 169.249598 -149.032214)
		(end 169.562018 -149.032214)
		(width 0.10414)
		(layer "F.Cu")
		(net "LAN2_MDI3_DP")
	)
	(segment
		(start 169.08907 -149.192742)
		(end 169.249598 -149.032214)
		(width 0.10414)
		(layer "F.Cu")
		(net "LAN2_MDI3_DP")
	)
	(via
		(at 174.052484 -150.475442)
		(size 0.4064)
		(drill 0.2032)
		(layers "F.Cu" "B.Cu")
		(net "LAN2_MDI3_DP")
	)
	(via
		(at 181.1782 -147.06473)
		(size 0.508)
		(drill 0.254)
		(layers "F.Cu" "B.Cu")
		(net "LAN2_CTRL_P1V9")
	)
	(via
		(at 181.15026 -148.090128)
		(size 0.508)
		(drill 0.254)
		(layers "F.Cu" "B.Cu")
		(net "LAN2_CTRL_P1V9")
	)
	(via
		(at 167.5384 -158.44139)
		(size 0.508)
		(drill 0.254)
		(layers "F.Cu" "B.Cu")
		(net "LAN2_CTRL_P1V9")
	)
	(via
		(at 168.54424 -158.754826)
		(size 0.508)
		(drill 0.254)
		(layers "F.Cu" "B.Cu")
		(net "LAN2_CTRL_P1V9")
	)
	(segment
		(start 184.592214 -157.91053)
		(end 185.010044 -158.32836)
		(width 0.10414)
		(layer "F.Cu")
		(net "LAN2_MDI3_DN")
	)
	(segment
		(start 169.75328 -148.597874)
		(end 172.789342 -148.597874)
		(width 0.10414)
		(layer "F.Cu")
		(net "LAN2_MDI3_DN")
	)
	(segment
		(start 175.28794 -151.096218)
		(end 183.943752 -156.922978)
		(width 0.10414)
		(layer "F.Cu")
		(net "LAN2_MDI3_DN")
	)
	(segment
		(start 183.943752 -156.922978)
		(end 184.293256 -157.263084)
		(width 0.10414)
		(layer "F.Cu")
		(net "LAN2_MDI3_DN")
	)
	(segment
		(start 166.021512 -149.347174)
		(end 165.5699 -149.347174)
		(width 0.10414)
		(layer "F.Cu")
		(net "LAN2_MDI3_DN")
	)
	(segment
		(start 184.293256 -157.263084)
		(end 184.592214 -157.561788)
		(width 0.10414)
		(layer "F.Cu")
		(net "LAN2_MDI3_DN")
	)
	(segment
		(start 184.592214 -157.561788)
		(end 184.592214 -157.91053)
		(width 0.10414)
		(layer "F.Cu")
		(net "LAN2_MDI3_DN")
	)
	(segment
		(start 185.010044 -158.32836)
		(end 185.010044 -159.0421)
		(width 0.10414)
		(layer "F.Cu")
		(net "LAN2_MDI3_DN")
	)
	(segment
		(start 166.70655 -149.387306)
		(end 166.061644 -149.387306)
		(width 0.10414)
		(layer "F.Cu")
		(net "LAN2_MDI3_DN")
	)
	(segment
		(start 169.75328 -148.597874)
		(end 167.495982 -148.597874)
		(width 0.10414)
		(layer "F.Cu")
		(net "LAN2_MDI3_DN")
	)
	(segment
		(start 166.061644 -149.387306)
		(end 166.021512 -149.347174)
		(width 0.10414)
		(layer "F.Cu")
		(net "LAN2_MDI3_DN")
	)
	(segment
		(start 172.789342 -148.597874)
		(end 175.28794 -151.096218)
		(width 0.10414)
		(layer "F.Cu")
		(net "LAN2_MDI3_DN")
	)
	(segment
		(start 167.495982 -148.597874)
		(end 166.70655 -149.387306)
		(width 0.10414)
		(layer "F.Cu")
		(net "LAN2_MDI3_DN")
	)
	(via
		(at 169.75328 -148.597874)
		(size 0.4064)
		(drill 0.2032)
		(layers "F.Cu" "B.Cu")
		(net "LAN2_MDI3_DN")
	)
	(segment
		(start 116.995194 -170.039792)
		(end 116.989098 -170.033696)
		(width 0.1016)
		(layer "F.Cu")
		(net "PSU3_HUB_EN")
	)
	(segment
		(start 115.955318 -164.306504)
		(end 114.76736 -164.306504)
		(width 0.1016)
		(layer "F.Cu")
		(net "PSU3_HUB_EN")
	)
	(segment
		(start 117.347238 -166.244778)
		(end 117.347238 -165.698424)
		(width 0.1016)
		(layer "F.Cu")
		(net "PSU3_HUB_EN")
	)
	(segment
		(start 120.60936 -170.021504)
		(end 120.591072 -170.039792)
		(width 0.1016)
		(layer "F.Cu")
		(net "PSU3_HUB_EN")
	)
	(segment
		(start 120.591072 -170.039792)
		(end 116.995194 -170.039792)
		(width 0.1016)
		(layer "F.Cu")
		(net "PSU3_HUB_EN")
	)
	(segment
		(start 117.347238 -165.698424)
		(end 115.955318 -164.306504)
		(width 0.1016)
		(layer "F.Cu")
		(net "PSU3_HUB_EN")
	)
	(via
		(at 116.989098 -170.033696)
		(size 0.508)
		(drill 0.254)
		(layers "F.Cu" "B.Cu")
		(net "PSU3_HUB_EN")
	)
	(via
		(at 117.347238 -166.244778)
		(size 0.508)
		(drill 0.254)
		(layers "F.Cu" "B.Cu")
		(net "PSU3_HUB_EN")
	)
	(segment
		(start 117.347238 -166.244778)
		(end 117.158516 -166.244778)
		(width 0.1016)
		(layer "B.Cu")
		(net "PSU3_HUB_EN")
	)
	(segment
		(start 116.989098 -168.14546)
		(end 116.570252 -167.726614)
		(width 0.1016)
		(layer "B.Cu")
		(net "PSU3_HUB_EN")
	)
	(segment
		(start 116.570252 -167.726614)
		(end 116.570252 -166.420292)
		(width 0.1016)
		(layer "B.Cu")
		(net "PSU3_HUB_EN")
	)
	(segment
		(start 117.158516 -166.244778)
		(end 116.983002 -166.420292)
		(width 0.1016)
		(layer "B.Cu")
		(net "PSU3_HUB_EN")
	)
	(segment
		(start 116.989098 -170.033696)
		(end 116.989098 -168.14546)
		(width 0.1016)
		(layer "B.Cu")
		(net "PSU3_HUB_EN")
	)
	(segment
		(start 116.983002 -166.420292)
		(end 116.570252 -166.420292)
		(width 0.1016)
		(layer "B.Cu")
		(net "PSU3_HUB_EN")
	)
	(segment
		(start 171.16298 -153.646124)
		(end 171.16298 -155.12923)
		(width 0.10414)
		(layer "F.Cu")
		(net "LAN2_MDI0_DP")
	)
	(segment
		(start 172.959522 -156.847794)
		(end 172.832014 -156.975556)
		(width 0.10414)
		(layer "F.Cu")
		(net "LAN2_MDI0_DP")
	)
	(segment
		(start 172.392086 -156.847794)
		(end 172.079666 -156.847794)
		(width 0.10414)
		(layer "F.Cu")
		(net "LAN2_MDI0_DP")
	)
	(segment
		(start 173.271942 -156.847794)
		(end 172.959522 -156.847794)
		(width 0.10414)
		(layer "F.Cu")
		(net "LAN2_MDI0_DP")
	)
	(segment
		(start 173.88078 -155.788614)
		(end 173.88078 -156.210508)
		(width 0.10414)
		(layer "F.Cu")
		(net "LAN2_MDI0_DP")
	)
	(segment
		(start 167.712898 -153.811732)
		(end 167.899588 -153.811732)
		(width 0.10414)
		(layer "F.Cu")
		(net "LAN2_MDI0_DP")
	)
	(segment
		(start 167.555926 -153.968958)
		(end 167.712898 -153.811732)
		(width 0.10414)
		(layer "F.Cu")
		(net "LAN2_MDI0_DP")
	)
	(segment
		(start 173.596554 -156.975556)
		(end 173.39945 -156.975556)
		(width 0.10414)
		(layer "F.Cu")
		(net "LAN2_MDI0_DP")
	)
	(segment
		(start 173.39945 -156.975556)
		(end 173.271942 -156.847794)
		(width 0.10414)
		(layer "F.Cu")
		(net "LAN2_MDI0_DP")
	)
	(segment
		(start 168.565322 -155.436062)
		(end 169.563034 -155.436062)
		(width 0.10414)
		(layer "F.Cu")
		(net "LAN2_MDI0_DP")
	)
	(segment
		(start 171.983654 -155.673044)
		(end 172.296074 -155.673044)
		(width 0.10414)
		(layer "F.Cu")
		(net "LAN2_MDI0_DP")
	)
	(segment
		(start 171.818554 -156.975556)
		(end 171.457874 -157.336236)
		(width 0.10414)
		(layer "F.Cu")
		(net "LAN2_MDI0_DP")
	)
	(segment
		(start 170.1419 -154.5844)
		(end 170.1419 -154.27198)
		(width 0.10414)
		(layer "F.Cu")
		(net "LAN2_MDI0_DP")
	)
	(segment
		(start 172.519594 -156.975556)
		(end 172.392086 -156.847794)
		(width 0.10414)
		(layer "F.Cu")
		(net "LAN2_MDI0_DP")
	)
	(segment
		(start 172.079666 -156.847794)
		(end 171.952158 -156.975556)
		(width 0.10414)
		(layer "F.Cu")
		(net "LAN2_MDI0_DP")
	)
	(segment
		(start 170.020488 -153.646124)
		(end 170.223688 -153.442924)
		(width 0.10414)
		(layer "F.Cu")
		(net "LAN2_MDI0_DP")
	)
	(segment
		(start 170.020488 -154.150568)
		(end 170.020488 -153.646124)
		(width 0.10414)
		(layer "F.Cu")
		(net "LAN2_MDI0_DP")
	)
	(segment
		(start 171.457874 -157.91053)
		(end 171.040044 -158.32836)
		(width 0.10414)
		(layer "F.Cu")
		(net "LAN2_MDI0_DP")
	)
	(segment
		(start 167.243506 -153.968958)
		(end 167.555926 -153.968958)
		(width 0.10414)
		(layer "F.Cu")
		(net "LAN2_MDI0_DP")
	)
	(segment
		(start 166.0525 -153.847292)
		(end 166.08806 -153.811732)
		(width 0.10414)
		(layer "F.Cu")
		(net "LAN2_MDI0_DP")
	)
	(segment
		(start 172.406818 -155.5623)
		(end 172.719238 -155.5623)
		(width 0.10414)
		(layer "F.Cu")
		(net "LAN2_MDI0_DP")
	)
	(segment
		(start 171.040044 -158.32836)
		(end 171.040044 -159.0421)
		(width 0.10414)
		(layer "F.Cu")
		(net "LAN2_MDI0_DP")
	)
	(segment
		(start 167.086534 -153.811732)
		(end 167.243506 -153.968958)
		(width 0.10414)
		(layer "F.Cu")
		(net "LAN2_MDI0_DP")
	)
	(segment
		(start 171.952158 -156.975556)
		(end 171.818554 -156.975556)
		(width 0.10414)
		(layer "F.Cu")
		(net "LAN2_MDI0_DP")
	)
	(segment
		(start 170.223688 -153.442924)
		(end 170.95978 -153.442924)
		(width 0.10414)
		(layer "F.Cu")
		(net "LAN2_MDI0_DP")
	)
	(segment
		(start 173.88078 -156.210508)
		(end 173.88078 -156.69133)
		(width 0.10414)
		(layer "F.Cu")
		(net "LAN2_MDI0_DP")
	)
	(segment
		(start 168.107868 -154.978608)
		(end 168.565322 -155.436062)
		(width 0.10414)
		(layer "F.Cu")
		(net "LAN2_MDI0_DP")
	)
	(segment
		(start 167.899588 -153.811732)
		(end 168.107868 -154.020012)
		(width 0.10414)
		(layer "F.Cu")
		(net "LAN2_MDI0_DP")
	)
	(segment
		(start 170.020488 -154.705812)
		(end 170.1419 -154.5844)
		(width 0.10414)
		(layer "F.Cu")
		(net "LAN2_MDI0_DP")
	)
	(segment
		(start 173.88078 -156.69133)
		(end 173.596554 -156.975556)
		(width 0.10414)
		(layer "F.Cu")
		(net "LAN2_MDI0_DP")
	)
	(segment
		(start 172.832014 -156.975556)
		(end 172.519594 -156.975556)
		(width 0.10414)
		(layer "F.Cu")
		(net "LAN2_MDI0_DP")
	)
	(segment
		(start 172.296074 -155.673044)
		(end 172.406818 -155.5623)
		(width 0.10414)
		(layer "F.Cu")
		(net "LAN2_MDI0_DP")
	)
	(segment
		(start 171.16298 -155.12923)
		(end 171.59605 -155.5623)
		(width 0.10414)
		(layer "F.Cu")
		(net "LAN2_MDI0_DP")
	)
	(segment
		(start 173.654466 -155.5623)
		(end 173.88078 -155.788614)
		(width 0.10414)
		(layer "F.Cu")
		(net "LAN2_MDI0_DP")
	)
	(segment
		(start 170.95978 -153.442924)
		(end 171.16298 -153.646124)
		(width 0.10414)
		(layer "F.Cu")
		(net "LAN2_MDI0_DP")
	)
	(segment
		(start 173.142402 -155.673044)
		(end 173.253146 -155.5623)
		(width 0.10414)
		(layer "F.Cu")
		(net "LAN2_MDI0_DP")
	)
	(segment
		(start 169.563034 -155.436062)
		(end 170.020488 -154.978608)
		(width 0.10414)
		(layer "F.Cu")
		(net "LAN2_MDI0_DP")
	)
	(segment
		(start 165.5699 -153.847292)
		(end 166.0525 -153.847292)
		(width 0.10414)
		(layer "F.Cu")
		(net "LAN2_MDI0_DP")
	)
	(segment
		(start 172.719238 -155.5623)
		(end 172.829982 -155.673044)
		(width 0.10414)
		(layer "F.Cu")
		(net "LAN2_MDI0_DP")
	)
	(segment
		(start 171.59605 -155.5623)
		(end 171.87291 -155.5623)
		(width 0.10414)
		(layer "F.Cu")
		(net "LAN2_MDI0_DP")
	)
	(segment
		(start 173.253146 -155.5623)
		(end 173.654466 -155.5623)
		(width 0.10414)
		(layer "F.Cu")
		(net "LAN2_MDI0_DP")
	)
	(segment
		(start 168.107868 -154.020012)
		(end 168.107868 -154.978608)
		(width 0.10414)
		(layer "F.Cu")
		(net "LAN2_MDI0_DP")
	)
	(segment
		(start 170.020488 -154.978608)
		(end 170.020488 -154.705812)
		(width 0.10414)
		(layer "F.Cu")
		(net "LAN2_MDI0_DP")
	)
	(segment
		(start 166.08806 -153.811732)
		(end 167.086534 -153.811732)
		(width 0.10414)
		(layer "F.Cu")
		(net "LAN2_MDI0_DP")
	)
	(segment
		(start 170.1419 -154.27198)
		(end 170.020488 -154.150568)
		(width 0.10414)
		(layer "F.Cu")
		(net "LAN2_MDI0_DP")
	)
	(segment
		(start 171.87291 -155.5623)
		(end 171.983654 -155.673044)
		(width 0.10414)
		(layer "F.Cu")
		(net "LAN2_MDI0_DP")
	)
	(segment
		(start 171.457874 -157.336236)
		(end 171.457874 -157.91053)
		(width 0.10414)
		(layer "F.Cu")
		(net "LAN2_MDI0_DP")
	)
	(segment
		(start 172.829982 -155.673044)
		(end 173.142402 -155.673044)
		(width 0.10414)
		(layer "F.Cu")
		(net "LAN2_MDI0_DP")
	)
	(via
		(at 173.88078 -156.210508)
		(size 0.4064)
		(drill 0.2032)
		(layers "F.Cu" "B.Cu")
		(net "LAN2_MDI0_DP")
	)
	(segment
		(start 122.677428 -169.571416)
		(end 122.566176 -169.682668)
		(width 0.1016)
		(layer "F.Cu")
		(net "PU_I2C_SCL4")
	)
	(segment
		(start 123.30811 -169.571416)
		(end 122.677428 -169.571416)
		(width 0.1016)
		(layer "F.Cu")
		(net "PU_I2C_SCL4")
	)
	(segment
		(start 120.60936 -170.671744)
		(end 121.807224 -170.671744)
		(width 0.1016)
		(layer "F.Cu")
		(net "PU_I2C_SCL4")
	)
	(segment
		(start 121.807224 -170.671744)
		(end 122.566176 -169.912792)
		(width 0.1016)
		(layer "F.Cu")
		(net "PU_I2C_SCL4")
	)
	(segment
		(start 122.566176 -169.912792)
		(end 122.566176 -169.682668)
		(width 0.1016)
		(layer "F.Cu")
		(net "PU_I2C_SCL4")
	)
	(via
		(at 122.566176 -169.682668)
		(size 0.508)
		(drill 0.254)
		(layers "F.Cu" "B.Cu")
		(net "PU_I2C_SCL4")
	)
	(segment
		(start 166.08806 -153.347166)
		(end 165.5699 -153.347166)
		(width 0.10414)
		(layer "F.Cu")
		(net "LAN2_MDI0_DN")
	)
	(segment
		(start 168.745408 -155.001722)
		(end 169.382948 -155.001722)
		(width 0.10414)
		(layer "F.Cu")
		(net "LAN2_MDI0_DN")
	)
	(segment
		(start 171.139866 -153.008584)
		(end 171.59732 -153.466038)
		(width 0.10414)
		(layer "F.Cu")
		(net "LAN2_MDI0_DN")
	)
	(segment
		(start 166.94658 -153.377392)
		(end 168.079674 -153.377392)
		(width 0.10414)
		(layer "F.Cu")
		(net "LAN2_MDI0_DN")
	)
	(segment
		(start 168.542208 -154.798522)
		(end 168.745408 -155.001722)
		(width 0.10414)
		(layer "F.Cu")
		(net "LAN2_MDI0_DN")
	)
	(segment
		(start 171.892214 -157.91053)
		(end 172.310044 -158.32836)
		(width 0.10414)
		(layer "F.Cu")
		(net "LAN2_MDI0_DN")
	)
	(segment
		(start 171.892214 -157.516322)
		(end 171.892214 -157.91053)
		(width 0.10414)
		(layer "F.Cu")
		(net "LAN2_MDI0_DN")
	)
	(segment
		(start 171.59732 -154.949144)
		(end 171.776136 -155.12796)
		(width 0.10414)
		(layer "F.Cu")
		(net "LAN2_MDI0_DN")
	)
	(segment
		(start 166.118286 -153.377392)
		(end 166.08806 -153.347166)
		(width 0.10414)
		(layer "F.Cu")
		(net "LAN2_MDI0_DN")
	)
	(segment
		(start 174.31512 -155.608528)
		(end 174.31512 -156.871416)
		(width 0.10414)
		(layer "F.Cu")
		(net "LAN2_MDI0_DN")
	)
	(segment
		(start 171.776136 -155.12796)
		(end 173.834552 -155.12796)
		(width 0.10414)
		(layer "F.Cu")
		(net "LAN2_MDI0_DN")
	)
	(segment
		(start 171.59732 -153.466038)
		(end 171.59732 -154.949144)
		(width 0.10414)
		(layer "F.Cu")
		(net "LAN2_MDI0_DN")
	)
	(segment
		(start 170.043602 -153.008584)
		(end 171.139866 -153.008584)
		(width 0.10414)
		(layer "F.Cu")
		(net "LAN2_MDI0_DN")
	)
	(segment
		(start 169.586148 -153.466038)
		(end 170.043602 -153.008584)
		(width 0.10414)
		(layer "F.Cu")
		(net "LAN2_MDI0_DN")
	)
	(segment
		(start 172.310044 -158.32836)
		(end 172.310044 -159.0421)
		(width 0.10414)
		(layer "F.Cu")
		(net "LAN2_MDI0_DN")
	)
	(segment
		(start 171.99864 -157.409896)
		(end 171.892214 -157.516322)
		(width 0.10414)
		(layer "F.Cu")
		(net "LAN2_MDI0_DN")
	)
	(segment
		(start 169.586148 -154.798522)
		(end 169.586148 -153.466038)
		(width 0.10414)
		(layer "F.Cu")
		(net "LAN2_MDI0_DN")
	)
	(segment
		(start 166.94658 -153.377392)
		(end 166.118286 -153.377392)
		(width 0.10414)
		(layer "F.Cu")
		(net "LAN2_MDI0_DN")
	)
	(segment
		(start 168.542208 -153.839926)
		(end 168.542208 -154.798522)
		(width 0.10414)
		(layer "F.Cu")
		(net "LAN2_MDI0_DN")
	)
	(segment
		(start 168.079674 -153.377392)
		(end 168.542208 -153.839926)
		(width 0.10414)
		(layer "F.Cu")
		(net "LAN2_MDI0_DN")
	)
	(segment
		(start 169.382948 -155.001722)
		(end 169.586148 -154.798522)
		(width 0.10414)
		(layer "F.Cu")
		(net "LAN2_MDI0_DN")
	)
	(segment
		(start 174.31512 -156.871416)
		(end 173.77664 -157.409896)
		(width 0.10414)
		(layer "F.Cu")
		(net "LAN2_MDI0_DN")
	)
	(segment
		(start 173.834552 -155.12796)
		(end 174.31512 -155.608528)
		(width 0.10414)
		(layer "F.Cu")
		(net "LAN2_MDI0_DN")
	)
	(segment
		(start 173.77664 -157.409896)
		(end 171.99864 -157.409896)
		(width 0.10414)
		(layer "F.Cu")
		(net "LAN2_MDI0_DN")
	)
	(via
		(at 166.94658 -153.377392)
		(size 0.4064)
		(drill 0.2032)
		(layers "F.Cu" "B.Cu")
		(net "LAN2_MDI0_DN")
	)
	(segment
		(start 10.58799 -20.20316)
		(end 10.58799 -18.56994)
		(width 0.1016)
		(layer "F.Cu")
		(net "UART_RX_P2")
	)
	(segment
		(start 140.39342 -45.963586)
		(end 140.39342 -44.577508)
		(width 0.1016)
		(layer "F.Cu")
		(net "UART_RX_P2")
	)
	(segment
		(start 140.76172 -47.199804)
		(end 140.76172 -46.331886)
		(width 0.1016)
		(layer "F.Cu")
		(net "UART_RX_P2")
	)
	(segment
		(start 140.39342 -44.577508)
		(end 140.0556 -44.239688)
		(width 0.1016)
		(layer "F.Cu")
		(net "UART_RX_P2")
	)
	(segment
		(start 140.0556 -44.239688)
		(end 140.05433 -44.239688)
		(width 0.1016)
		(layer "F.Cu")
		(net "UART_RX_P2")
	)
	(segment
		(start 140.76172 -46.331886)
		(end 140.39342 -45.963586)
		(width 0.1016)
		(layer "F.Cu")
		(net "UART_RX_P2")
	)
	(via
		(at 140.05433 -44.239688)
		(size 0.508)
		(drill 0.254)
		(layers "F.Cu" "B.Cu")
		(net "UART_RX_P2")
	)
	(via
		(at 10.58799 -18.56994)
		(size 0.508)
		(drill 0.254)
		(layers "F.Cu" "B.Cu")
		(net "UART_RX_P2")
	)
	(segment
		(start 66.411348 -15.27302)
		(end 86.284562 -15.27302)
		(width 0.1143)
		(layer "In7.Cu")
		(net "UART_RX_P2")
	)
	(segment
		(start 113.459768 -13.476224)
		(end 113.67008 -13.685774)
		(width 0.1143)
		(layer "In7.Cu")
		(net "UART_RX_P2")
	)
	(segment
		(start 20.554188 -10.18159)
		(end 22.161754 -11.789156)
		(width 0.1143)
		(layer "In7.Cu")
		(net "UART_RX_P2")
	)
	(segment
		(start 22.161754 -11.789156)
		(end 35.358832 -11.789156)
		(width 0.1143)
		(layer "In7.Cu")
		(net "UART_RX_P2")
	)
	(segment
		(start 126.65456 -35.7759)
		(end 127.696976 -35.7759)
		(width 0.1143)
		(layer "In7.Cu")
		(net "UART_RX_P2")
	)
	(segment
		(start 119.33428 -31.290006)
		(end 123.272042 -35.227768)
		(width 0.1143)
		(layer "In7.Cu")
		(net "UART_RX_P2")
	)
	(segment
		(start 36.72332 -12.755372)
		(end 36.97986 -13.011912)
		(width 0.1143)
		(layer "In7.Cu")
		(net "UART_RX_P2")
	)
	(segment
		(start 13.010896 -10.18159)
		(end 20.554188 -10.18159)
		(width 0.1143)
		(layer "In7.Cu")
		(net "UART_RX_P2")
	)
	(segment
		(start 64.28486 -15.625826)
		(end 64.65062 -15.625826)
		(width 0.1143)
		(layer "In7.Cu")
		(net "UART_RX_P2")
	)
	(segment
		(start 123.272042 -35.227768)
		(end 126.106428 -35.227768)
		(width 0.1143)
		(layer "In7.Cu")
		(net "UART_RX_P2")
	)
	(segment
		(start 10.08126 -18.06321)
		(end 10.08126 -13.111226)
		(width 0.1143)
		(layer "In7.Cu")
		(net "UART_RX_P2")
	)
	(segment
		(start 127.696976 -35.7759)
		(end 131.982464 -40.061388)
		(width 0.1143)
		(layer "In7.Cu")
		(net "UART_RX_P2")
	)
	(segment
		(start 88.080088 -13.476224)
		(end 113.459768 -13.476224)
		(width 0.1143)
		(layer "In7.Cu")
		(net "UART_RX_P2")
	)
	(segment
		(start 113.67008 -13.685774)
		(end 119.33428 -19.349974)
		(width 0.1143)
		(layer "In7.Cu")
		(net "UART_RX_P2")
	)
	(segment
		(start 139.81684 -44.239688)
		(end 140.05433 -44.239688)
		(width 0.1143)
		(layer "In7.Cu")
		(net "UART_RX_P2")
	)
	(segment
		(start 36.341304 -12.771628)
		(end 36.35756 -12.755372)
		(width 0.1143)
		(layer "In7.Cu")
		(net "UART_RX_P2")
	)
	(segment
		(start 126.106428 -35.227768)
		(end 126.65456 -35.7759)
		(width 0.1143)
		(layer "In7.Cu")
		(net "UART_RX_P2")
	)
	(segment
		(start 35.358832 -11.789156)
		(end 36.341304 -12.771628)
		(width 0.1143)
		(layer "In7.Cu")
		(net "UART_RX_P2")
	)
	(segment
		(start 39.62273 -16.049498)
		(end 63.861188 -16.049498)
		(width 0.1143)
		(layer "In7.Cu")
		(net "UART_RX_P2")
	)
	(segment
		(start 36.35756 -12.755372)
		(end 36.72332 -12.755372)
		(width 0.1143)
		(layer "In7.Cu")
		(net "UART_RX_P2")
	)
	(segment
		(start 10.08126 -13.111226)
		(end 13.010896 -10.18159)
		(width 0.1143)
		(layer "In7.Cu")
		(net "UART_RX_P2")
	)
	(segment
		(start 64.669162 -15.644368)
		(end 66.04 -15.644368)
		(width 0.1143)
		(layer "In7.Cu")
		(net "UART_RX_P2")
	)
	(segment
		(start 119.33428 -19.349974)
		(end 119.33428 -31.290006)
		(width 0.1143)
		(layer "In7.Cu")
		(net "UART_RX_P2")
	)
	(segment
		(start 36.97986 -13.011912)
		(end 36.97986 -13.375132)
		(width 0.1143)
		(layer "In7.Cu")
		(net "UART_RX_P2")
	)
	(segment
		(start 131.982464 -40.061388)
		(end 135.63854 -40.061388)
		(width 0.1143)
		(layer "In7.Cu")
		(net "UART_RX_P2")
	)
	(segment
		(start 66.04 -15.644368)
		(end 66.411348 -15.27302)
		(width 0.1143)
		(layer "In7.Cu")
		(net "UART_RX_P2")
	)
	(segment
		(start 10.58799 -18.56994)
		(end 10.08126 -18.06321)
		(width 0.1143)
		(layer "In7.Cu")
		(net "UART_RX_P2")
	)
	(segment
		(start 86.284562 -15.27302)
		(end 88.080088 -13.476224)
		(width 0.1143)
		(layer "In7.Cu")
		(net "UART_RX_P2")
	)
	(segment
		(start 63.861188 -16.049498)
		(end 64.28486 -15.625826)
		(width 0.1143)
		(layer "In7.Cu")
		(net "UART_RX_P2")
	)
	(segment
		(start 64.65062 -15.625826)
		(end 64.669162 -15.644368)
		(width 0.1143)
		(layer "In7.Cu")
		(net "UART_RX_P2")
	)
	(segment
		(start 36.964112 -13.39088)
		(end 39.62273 -16.049498)
		(width 0.1143)
		(layer "In7.Cu")
		(net "UART_RX_P2")
	)
	(segment
		(start 135.63854 -40.061388)
		(end 139.81684 -44.239688)
		(width 0.1143)
		(layer "In7.Cu")
		(net "UART_RX_P2")
	)
	(segment
		(start 36.97986 -13.375132)
		(end 36.964112 -13.39088)
		(width 0.1143)
		(layer "In7.Cu")
		(net "UART_RX_P2")
	)
	(segment
		(start 157.513274 -165.118288)
		(end 156.251402 -165.118288)
		(width 0.1016)
		(layer "F.Cu")
		(net "LAN2_NVM_WP_N")
	)
	(segment
		(start 155.904184 -164.77107)
		(end 155.429966 -165.245288)
		(width 0.1016)
		(layer "F.Cu")
		(net "LAN2_NVM_WP_N")
	)
	(segment
		(start 155.429966 -165.245288)
		(end 154.951176 -165.245288)
		(width 0.1016)
		(layer "F.Cu")
		(net "LAN2_NVM_WP_N")
	)
	(segment
		(start 156.251402 -165.118288)
		(end 155.904184 -164.77107)
		(width 0.1016)
		(layer "F.Cu")
		(net "LAN2_NVM_WP_N")
	)
	(via
		(at 155.904184 -164.77107)
		(size 0.508)
		(drill 0.254)
		(layers "F.Cu" "B.Cu")
		(net "LAN2_NVM_WP_N")
	)
	(segment
		(start 122.100594 -170.964098)
		(end 122.529092 -170.964098)
		(width 0.1016)
		(layer "F.Cu")
		(net "PU_I2C_SDA4")
	)
	(segment
		(start 123.30811 -170.587416)
		(end 122.905774 -170.587416)
		(width 0.1016)
		(layer "F.Cu")
		(net "PU_I2C_SDA4")
	)
	(segment
		(start 122.905774 -170.587416)
		(end 122.529092 -170.964098)
		(width 0.1016)
		(layer "F.Cu")
		(net "PU_I2C_SDA4")
	)
	(segment
		(start 120.60936 -171.32173)
		(end 121.742962 -171.32173)
		(width 0.1016)
		(layer "F.Cu")
		(net "PU_I2C_SDA4")
	)
	(segment
		(start 121.742962 -171.32173)
		(end 122.100594 -170.964098)
		(width 0.1016)
		(layer "F.Cu")
		(net "PU_I2C_SDA4")
	)
	(via
		(at 122.529092 -170.964098)
		(size 0.508)
		(drill 0.254)
		(layers "F.Cu" "B.Cu")
		(net "PU_I2C_SDA4")
	)
	(segment
		(start 157.770068 -158.926022)
		(end 157.770068 -157.647132)
		(width 0.1016)
		(layer "F.Cu")
		(net "SPI_LAN2_NVM_CS_N")
	)
	(segment
		(start 153.67254 -162.92449)
		(end 153.0604 -163.53663)
		(width 0.1016)
		(layer "F.Cu")
		(net "SPI_LAN2_NVM_CS_N")
	)
	(segment
		(start 157.302708 -159.393382)
		(end 157.770068 -158.926022)
		(width 0.1016)
		(layer "F.Cu")
		(net "SPI_LAN2_NVM_CS_N")
	)
	(segment
		(start 153.0604 -163.53663)
		(end 153.0604 -167.221662)
		(width 0.1016)
		(layer "F.Cu")
		(net "SPI_LAN2_NVM_CS_N")
	)
	(segment
		(start 153.0604 -167.221662)
		(end 153.624026 -167.785288)
		(width 0.1016)
		(layer "F.Cu")
		(net "SPI_LAN2_NVM_CS_N")
	)
	(segment
		(start 157.302708 -160.79851)
		(end 157.302708 -159.393382)
		(width 0.1016)
		(layer "F.Cu")
		(net "SPI_LAN2_NVM_CS_N")
	)
	(segment
		(start 153.624026 -167.785288)
		(end 154.151076 -167.785288)
		(width 0.1016)
		(layer "F.Cu")
		(net "SPI_LAN2_NVM_CS_N")
	)
	(segment
		(start 156.70657 -160.79851)
		(end 157.302708 -160.79851)
		(width 0.1016)
		(layer "F.Cu")
		(net "SPI_LAN2_NVM_CS_N")
	)
	(segment
		(start 156.64942 -160.85566)
		(end 156.70657 -160.79851)
		(width 0.1016)
		(layer "F.Cu")
		(net "SPI_LAN2_NVM_CS_N")
	)
	(via
		(at 153.67254 -162.92449)
		(size 0.508)
		(drill 0.254)
		(layers "F.Cu" "B.Cu")
		(net "SPI_LAN2_NVM_CS_N")
	)
	(via
		(at 156.64942 -160.85566)
		(size 0.508)
		(drill 0.254)
		(layers "F.Cu" "B.Cu")
		(net "SPI_LAN2_NVM_CS_N")
	)
	(segment
		(start 153.67254 -162.923728)
		(end 153.67254 -162.92449)
		(width 0.1143)
		(layer "In2.Cu")
		(net "SPI_LAN2_NVM_CS_N")
	)
	(segment
		(start 156.64942 -160.85566)
		(end 155.096972 -162.408108)
		(width 0.1143)
		(layer "In2.Cu")
		(net "SPI_LAN2_NVM_CS_N")
	)
	(segment
		(start 155.096972 -162.408108)
		(end 154.18816 -162.408108)
		(width 0.1143)
		(layer "In2.Cu")
		(net "SPI_LAN2_NVM_CS_N")
	)
	(segment
		(start 154.18816 -162.408108)
		(end 153.67254 -162.923728)
		(width 0.1143)
		(layer "In2.Cu")
		(net "SPI_LAN2_NVM_CS_N")
	)
	(segment
		(start 155.830016 -154.84729)
		(end 155.73248 -154.944826)
		(width 0.127)
		(layer "F.Cu")
		(net "PCIE_LAN2_RX_C_DP")
	)
	(segment
		(start 154.628342 -154.944826)
		(end 153.885646 -155.687522)
		(width 0.127)
		(layer "F.Cu")
		(net "PCIE_LAN2_RX_C_DP")
	)
	(segment
		(start 153.885646 -155.687522)
		(end 152.576784 -155.687522)
		(width 0.127)
		(layer "F.Cu")
		(net "PCIE_LAN2_RX_C_DP")
	)
	(segment
		(start 151.514048 -155.33243)
		(end 151.86914 -155.687522)
		(width 0.127)
		(layer "F.Cu")
		(net "PCIE_LAN2_RX_C_DP")
	)
	(segment
		(start 151.86914 -155.687522)
		(end 152.576784 -155.687522)
		(width 0.127)
		(layer "F.Cu")
		(net "PCIE_LAN2_RX_C_DP")
	)
	(segment
		(start 155.73248 -154.944826)
		(end 154.628342 -154.944826)
		(width 0.127)
		(layer "F.Cu")
		(net "PCIE_LAN2_RX_C_DP")
	)
	(segment
		(start 156.470096 -154.84729)
		(end 155.830016 -154.84729)
		(width 0.127)
		(layer "F.Cu")
		(net "PCIE_LAN2_RX_C_DP")
	)
	(via
		(at 152.576784 -155.687522)
		(size 0.4064)
		(drill 0.2032)
		(layers "F.Cu" "B.Cu")
		(net "PCIE_LAN2_RX_C_DP")
	)
	(segment
		(start 140.750544 -45.837094)
		(end 141.261592 -46.348142)
		(width 0.1016)
		(layer "F.Cu")
		(net "UART_TX_P2")
	)
	(segment
		(start 140.692886 -51.076606)
		(end 140.692886 -49.68113)
		(width 0.1016)
		(layer "F.Cu")
		(net "UART_TX_P2")
	)
	(segment
		(start 139.676886 -51.076606)
		(end 140.692886 -51.076606)
		(width 0.1016)
		(layer "F.Cu")
		(net "UART_TX_P2")
	)
	(segment
		(start 8.638032 -26.04516)
		(end 8.638032 -23.118318)
		(width 0.1016)
		(layer "F.Cu")
		(net "UART_TX_P2")
	)
	(segment
		(start 140.692886 -49.68113)
		(end 141.261592 -49.112424)
		(width 0.1016)
		(layer "F.Cu")
		(net "UART_TX_P2")
	)
	(segment
		(start 141.261592 -46.348142)
		(end 141.261592 -47.199804)
		(width 0.1016)
		(layer "F.Cu")
		(net "UART_TX_P2")
	)
	(segment
		(start 141.261592 -49.112424)
		(end 141.261592 -47.199804)
		(width 0.1016)
		(layer "F.Cu")
		(net "UART_TX_P2")
	)
	(segment
		(start 141.09954 -44.163488)
		(end 140.750544 -44.512484)
		(width 0.1016)
		(layer "F.Cu")
		(net "UART_TX_P2")
	)
	(segment
		(start 140.750544 -44.512484)
		(end 140.750544 -45.837094)
		(width 0.1016)
		(layer "F.Cu")
		(net "UART_TX_P2")
	)
	(via
		(at 8.638032 -23.118318)
		(size 0.508)
		(drill 0.254)
		(layers "F.Cu" "B.Cu")
		(net "UART_TX_P2")
	)
	(via
		(at 141.09954 -44.163488)
		(size 0.508)
		(drill 0.254)
		(layers "F.Cu" "B.Cu")
		(net "UART_TX_P2")
	)
	(segment
		(start 137.209022 -39.426134)
		(end 132.245354 -39.426134)
		(width 0.1143)
		(layer "In7.Cu")
		(net "UART_TX_P2")
	)
	(segment
		(start 125.287786 -34.414968)
		(end 119.96928 -29.096462)
		(width 0.1143)
		(layer "In7.Cu")
		(net "UART_TX_P2")
	)
	(segment
		(start 119.96928 -29.096462)
		(end 119.96928 -19.08683)
		(width 0.1143)
		(layer "In7.Cu")
		(net "UART_TX_P2")
	)
	(segment
		(start 43.428158 -15.227554)
		(end 42.739056 -14.538452)
		(width 0.1143)
		(layer "In7.Cu")
		(net "UART_TX_P2")
	)
	(segment
		(start 119.96928 -19.08683)
		(end 113.723674 -12.841224)
		(width 0.1143)
		(layer "In7.Cu")
		(net "UART_TX_P2")
	)
	(segment
		(start 126.917704 -35.1409)
		(end 126.191772 -34.414968)
		(width 0.1143)
		(layer "In7.Cu")
		(net "UART_TX_P2")
	)
	(segment
		(start 36.991036 -12.120372)
		(end 36.589208 -12.120372)
		(width 0.1143)
		(layer "In7.Cu")
		(net "UART_TX_P2")
	)
	(segment
		(start 87.815166 -12.841224)
		(end 86.01837 -14.63802)
		(width 0.1143)
		(layer "In7.Cu")
		(net "UART_TX_P2")
	)
	(segment
		(start 65.071498 -14.990826)
		(end 63.88608 -14.990826)
		(width 0.1143)
		(layer "In7.Cu")
		(net "UART_TX_P2")
	)
	(segment
		(start 36.991544 -12.12088)
		(end 36.991036 -12.120372)
		(width 0.1143)
		(layer "In7.Cu")
		(net "UART_TX_P2")
	)
	(segment
		(start 113.723674 -12.841224)
		(end 87.815166 -12.841224)
		(width 0.1143)
		(layer "In7.Cu")
		(net "UART_TX_P2")
	)
	(segment
		(start 127.96012 -35.1409)
		(end 126.917704 -35.1409)
		(width 0.1143)
		(layer "In7.Cu")
		(net "UART_TX_P2")
	)
	(segment
		(start 12.747752 -9.54659)
		(end 8.638032 -13.65631)
		(width 0.1143)
		(layer "In7.Cu")
		(net "UART_TX_P2")
	)
	(segment
		(start 126.191772 -34.414968)
		(end 125.287786 -34.414968)
		(width 0.1143)
		(layer "In7.Cu")
		(net "UART_TX_P2")
	)
	(segment
		(start 86.01837 -14.63802)
		(end 66.091308 -14.63802)
		(width 0.1143)
		(layer "In7.Cu")
		(net "UART_TX_P2")
	)
	(segment
		(start 35.622992 -11.154156)
		(end 34.134806 -11.154156)
		(width 0.1143)
		(layer "In7.Cu")
		(net "UART_TX_P2")
	)
	(segment
		(start 8.638032 -13.65631)
		(end 8.638032 -23.118318)
		(width 0.1143)
		(layer "In7.Cu")
		(net "UART_TX_P2")
	)
	(segment
		(start 20.820888 -9.54659)
		(end 12.747752 -9.54659)
		(width 0.1143)
		(layer "In7.Cu")
		(net "UART_TX_P2")
	)
	(segment
		(start 38.2905 -12.95527)
		(end 37.45611 -12.12088)
		(width 0.1143)
		(layer "In7.Cu")
		(net "UART_TX_P2")
	)
	(segment
		(start 141.09954 -43.316652)
		(end 137.209022 -39.426134)
		(width 0.1143)
		(layer "In7.Cu")
		(net "UART_TX_P2")
	)
	(segment
		(start 63.649352 -15.227554)
		(end 43.428158 -15.227554)
		(width 0.1143)
		(layer "In7.Cu")
		(net "UART_TX_P2")
	)
	(segment
		(start 63.88608 -14.990826)
		(end 63.649352 -15.227554)
		(width 0.1143)
		(layer "In7.Cu")
		(net "UART_TX_P2")
	)
	(segment
		(start 37.45611 -12.12088)
		(end 36.991544 -12.12088)
		(width 0.1143)
		(layer "In7.Cu")
		(net "UART_TX_P2")
	)
	(segment
		(start 65.09004 -15.009368)
		(end 65.071498 -14.990826)
		(width 0.1143)
		(layer "In7.Cu")
		(net "UART_TX_P2")
	)
	(segment
		(start 42.739056 -14.538452)
		(end 39.233602 -14.538452)
		(width 0.1143)
		(layer "In7.Cu")
		(net "UART_TX_P2")
	)
	(segment
		(start 39.233602 -14.538452)
		(end 38.2905 -13.59535)
		(width 0.1143)
		(layer "In7.Cu")
		(net "UART_TX_P2")
	)
	(segment
		(start 38.2905 -13.59535)
		(end 38.2905 -12.95527)
		(width 0.1143)
		(layer "In7.Cu")
		(net "UART_TX_P2")
	)
	(segment
		(start 65.71996 -15.009368)
		(end 65.09004 -15.009368)
		(width 0.1143)
		(layer "In7.Cu")
		(net "UART_TX_P2")
	)
	(segment
		(start 141.09954 -44.163488)
		(end 141.09954 -43.316652)
		(width 0.1143)
		(layer "In7.Cu")
		(net "UART_TX_P2")
	)
	(segment
		(start 21.869654 -10.595356)
		(end 20.820888 -9.54659)
		(width 0.1143)
		(layer "In7.Cu")
		(net "UART_TX_P2")
	)
	(segment
		(start 36.589208 -12.120372)
		(end 35.622992 -11.154156)
		(width 0.1143)
		(layer "In7.Cu")
		(net "UART_TX_P2")
	)
	(segment
		(start 33.576006 -10.595356)
		(end 21.869654 -10.595356)
		(width 0.1143)
		(layer "In7.Cu")
		(net "UART_TX_P2")
	)
	(segment
		(start 34.134806 -11.154156)
		(end 33.576006 -10.595356)
		(width 0.1143)
		(layer "In7.Cu")
		(net "UART_TX_P2")
	)
	(segment
		(start 66.091308 -14.63802)
		(end 65.71996 -15.009368)
		(width 0.1143)
		(layer "In7.Cu")
		(net "UART_TX_P2")
	)
	(segment
		(start 132.245354 -39.426134)
		(end 127.96012 -35.1409)
		(width 0.1143)
		(layer "In7.Cu")
		(net "UART_TX_P2")
	)
	(segment
		(start 9.938004 -20.20316)
		(end 9.938004 -21.496274)
		(width 0.1016)
		(layer "F.Cu")
		(net "UART_DSR_P2_N")
	)
	(segment
		(start 141.647672 -45.038264)
		(end 141.647672 -44.839636)
		(width 0.1016)
		(layer "F.Cu")
		(net "UART_DSR_P2_N")
	)
	(segment
		(start 142.26159 -47.199804)
		(end 142.26159 -45.652182)
		(width 0.1016)
		(layer "F.Cu")
		(net "UART_DSR_P2_N")
	)
	(segment
		(start 142.26159 -45.652182)
		(end 141.647672 -45.038264)
		(width 0.1016)
		(layer "F.Cu")
		(net "UART_DSR_P2_N")
	)
	(via
		(at 141.647672 -44.839636)
		(size 0.508)
		(drill 0.254)
		(layers "F.Cu" "B.Cu")
		(net "UART_DSR_P2_N")
	)
	(via
		(at 9.938004 -21.496274)
		(size 0.508)
		(drill 0.254)
		(layers "F.Cu" "B.Cu")
		(net "UART_DSR_P2_N")
	)
	(segment
		(start 112.753902 -13.793724)
		(end 88.212422 -13.793724)
		(width 0.1143)
		(layer "In7.Cu")
		(net "UART_DSR_P2_N")
	)
	(segment
		(start 119.01678 -20.056602)
		(end 116.259864 -17.299686)
		(width 0.1143)
		(layer "In7.Cu")
		(net "UART_DSR_P2_N")
	)
	(segment
		(start 116.259864 -17.299686)
		(end 116.04244 -17.299686)
		(width 0.1143)
		(layer "In7.Cu")
		(net "UART_DSR_P2_N")
	)
	(segment
		(start 10.39876 -14.459458)
		(end 11.02614 -15.086838)
		(width 0.1143)
		(layer "In7.Cu")
		(net "UART_DSR_P2_N")
	)
	(segment
		(start 64.180974 -16.39824)
		(end 38.42131 -16.39824)
		(width 0.1143)
		(layer "In7.Cu")
		(net "UART_DSR_P2_N")
	)
	(segment
		(start 119.01678 -31.421578)
		(end 119.01678 -20.056602)
		(width 0.1143)
		(layer "In7.Cu")
		(net "UART_DSR_P2_N")
	)
	(segment
		(start 35.286188 -12.168632)
		(end 22.091396 -12.168632)
		(width 0.1143)
		(layer "In7.Cu")
		(net "UART_DSR_P2_N")
	)
	(segment
		(start 66.543428 -15.59052)
		(end 66.17208 -15.961868)
		(width 0.1143)
		(layer "In7.Cu")
		(net "UART_DSR_P2_N")
	)
	(segment
		(start 64.28486 -16.502126)
		(end 64.180974 -16.39824)
		(width 0.1143)
		(layer "In7.Cu")
		(net "UART_DSR_P2_N")
	)
	(segment
		(start 141.647672 -44.839636)
		(end 139.940792 -44.839636)
		(width 0.1143)
		(layer "In7.Cu")
		(net "UART_DSR_P2_N")
	)
	(segment
		(start 88.212422 -13.793724)
		(end 86.417404 -15.59052)
		(width 0.1143)
		(layer "In7.Cu")
		(net "UART_DSR_P2_N")
	)
	(segment
		(start 86.417404 -15.59052)
		(end 66.543428 -15.59052)
		(width 0.1143)
		(layer "In7.Cu")
		(net "UART_DSR_P2_N")
	)
	(segment
		(start 116.04244 -17.299686)
		(end 115.7859 -17.043146)
		(width 0.1143)
		(layer "In7.Cu")
		(net "UART_DSR_P2_N")
	)
	(segment
		(start 20.421854 -10.49909)
		(end 13.142468 -10.49909)
		(width 0.1143)
		(layer "In7.Cu")
		(net "UART_DSR_P2_N")
	)
	(segment
		(start 13.142468 -10.49909)
		(end 10.39876 -13.242798)
		(width 0.1143)
		(layer "In7.Cu")
		(net "UART_DSR_P2_N")
	)
	(segment
		(start 35.73653 -12.618212)
		(end 35.286188 -12.168632)
		(width 0.1143)
		(layer "In7.Cu")
		(net "UART_DSR_P2_N")
	)
	(segment
		(start 38.42131 -16.39824)
		(end 37.39388 -15.37081)
		(width 0.1143)
		(layer "In7.Cu")
		(net "UART_DSR_P2_N")
	)
	(segment
		(start 66.17208 -15.961868)
		(end 65.573656 -15.961868)
		(width 0.1143)
		(layer "In7.Cu")
		(net "UART_DSR_P2_N")
	)
	(segment
		(start 37.39388 -15.37081)
		(end 37.39388 -14.801342)
		(width 0.1143)
		(layer "In7.Cu")
		(net "UART_DSR_P2_N")
	)
	(segment
		(start 65.573656 -15.961868)
		(end 65.573656 -15.97279)
		(width 0.1143)
		(layer "In7.Cu")
		(net "UART_DSR_P2_N")
	)
	(segment
		(start 127.565404 -36.0934)
		(end 126.522988 -36.0934)
		(width 0.1143)
		(layer "In7.Cu")
		(net "UART_DSR_P2_N")
	)
	(segment
		(start 139.940792 -44.839636)
		(end 135.769858 -40.668702)
		(width 0.1143)
		(layer "In7.Cu")
		(net "UART_DSR_P2_N")
	)
	(segment
		(start 35.73653 -13.143992)
		(end 35.73653 -12.618212)
		(width 0.1143)
		(layer "In7.Cu")
		(net "UART_DSR_P2_N")
	)
	(segment
		(start 126.012956 -35.583368)
		(end 123.17857 -35.583368)
		(width 0.1143)
		(layer "In7.Cu")
		(net "UART_DSR_P2_N")
	)
	(segment
		(start 11.02614 -15.086838)
		(end 11.02614 -20.408138)
		(width 0.1143)
		(layer "In7.Cu")
		(net "UART_DSR_P2_N")
	)
	(segment
		(start 22.091396 -12.168632)
		(end 20.421854 -10.49909)
		(width 0.1143)
		(layer "In7.Cu")
		(net "UART_DSR_P2_N")
	)
	(segment
		(start 132.140706 -40.668702)
		(end 127.565404 -36.0934)
		(width 0.1143)
		(layer "In7.Cu")
		(net "UART_DSR_P2_N")
	)
	(segment
		(start 37.39388 -14.801342)
		(end 35.73653 -13.143992)
		(width 0.1143)
		(layer "In7.Cu")
		(net "UART_DSR_P2_N")
	)
	(segment
		(start 135.769858 -40.668702)
		(end 132.140706 -40.668702)
		(width 0.1143)
		(layer "In7.Cu")
		(net "UART_DSR_P2_N")
	)
	(segment
		(start 11.02614 -20.408138)
		(end 9.938004 -21.496274)
		(width 0.1143)
		(layer "In7.Cu")
		(net "UART_DSR_P2_N")
	)
	(segment
		(start 123.17857 -35.583368)
		(end 119.01678 -31.421578)
		(width 0.1143)
		(layer "In7.Cu")
		(net "UART_DSR_P2_N")
	)
	(segment
		(start 115.7859 -17.043146)
		(end 115.7859 -16.825722)
		(width 0.1143)
		(layer "In7.Cu")
		(net "UART_DSR_P2_N")
	)
	(segment
		(start 10.39876 -13.242798)
		(end 10.39876 -14.459458)
		(width 0.1143)
		(layer "In7.Cu")
		(net "UART_DSR_P2_N")
	)
	(segment
		(start 115.7859 -16.825722)
		(end 112.753902 -13.793724)
		(width 0.1143)
		(layer "In7.Cu")
		(net "UART_DSR_P2_N")
	)
	(segment
		(start 126.522988 -36.0934)
		(end 126.012956 -35.583368)
		(width 0.1143)
		(layer "In7.Cu")
		(net "UART_DSR_P2_N")
	)
	(segment
		(start 65.573656 -15.97279)
		(end 65.04432 -16.502126)
		(width 0.1143)
		(layer "In7.Cu")
		(net "UART_DSR_P2_N")
	)
	(segment
		(start 65.04432 -16.502126)
		(end 64.28486 -16.502126)
		(width 0.1143)
		(layer "In7.Cu")
		(net "UART_DSR_P2_N")
	)
	(segment
		(start 101.90607 -165.795706)
		(end 101.402642 -165.292278)
		(width 0.1016)
		(layer "F.Cu")
		(net "FNACTRL2_TMP_IN")
	)
	(segment
		(start 103.214932 -165.795706)
		(end 101.90607 -165.795706)
		(width 0.1016)
		(layer "F.Cu")
		(net "FNACTRL2_TMP_IN")
	)
	(segment
		(start 101.402642 -165.292278)
		(end 101.402642 -163.81222)
		(width 0.1016)
		(layer "F.Cu")
		(net "FNACTRL2_TMP_IN")
	)
	(via
		(at 101.402642 -163.81222)
		(size 0.508)
		(drill 0.254)
		(layers "F.Cu" "B.Cu")
		(net "FNACTRL2_TMP_IN")
	)
	(segment
		(start 99.487482 -165.251892)
		(end 99.96297 -165.251892)
		(width 0.1016)
		(layer "B.Cu")
		(net "FNACTRL2_TMP_IN")
	)
	(segment
		(start 99.96297 -165.251892)
		(end 101.402642 -163.81222)
		(width 0.1016)
		(layer "B.Cu")
		(net "FNACTRL2_TMP_IN")
	)
	(segment
		(start 105.101136 -171.562268)
		(end 105.147364 -171.608496)
		(width 0.1016)
		(layer "F.Cu")
		(net "FNACTRL1_TMP_IN")
	)
	(segment
		(start 103.214932 -171.562268)
		(end 105.101136 -171.562268)
		(width 0.1016)
		(layer "F.Cu")
		(net "FNACTRL1_TMP_IN")
	)
	(segment
		(start 107.8738 -166.56939)
		(end 108.034836 -166.730426)
		(width 0.1016)
		(layer "F.Cu")
		(net "FNACTRL1_TMP_IN")
	)
	(segment
		(start 107.8738 -165.565582)
		(end 107.8738 -166.56939)
		(width 0.1016)
		(layer "F.Cu")
		(net "FNACTRL1_TMP_IN")
	)
	(via
		(at 108.034836 -166.730426)
		(size 0.508)
		(drill 0.254)
		(layers "F.Cu" "B.Cu")
		(net "FNACTRL1_TMP_IN")
	)
	(via
		(at 105.147364 -171.608496)
		(size 0.508)
		(drill 0.254)
		(layers "F.Cu" "B.Cu")
		(net "FNACTRL1_TMP_IN")
	)
	(segment
		(start 106.429556 -168.872408)
		(end 108.034836 -167.267128)
		(width 0.1016)
		(layer "B.Cu")
		(net "FNACTRL1_TMP_IN")
	)
	(segment
		(start 108.034836 -167.267128)
		(end 108.034836 -166.730426)
		(width 0.1016)
		(layer "B.Cu")
		(net "FNACTRL1_TMP_IN")
	)
	(segment
		(start 105.17886 -171.608496)
		(end 106.429556 -170.3578)
		(width 0.1016)
		(layer "B.Cu")
		(net "FNACTRL1_TMP_IN")
	)
	(segment
		(start 105.147364 -171.608496)
		(end 105.17886 -171.608496)
		(width 0.1016)
		(layer "B.Cu")
		(net "FNACTRL1_TMP_IN")
	)
	(segment
		(start 106.429556 -170.3578)
		(end 106.429556 -168.872408)
		(width 0.1016)
		(layer "B.Cu")
		(net "FNACTRL1_TMP_IN")
	)
	(via
		(at 97.441258 -164.148516)
		(size 0.6604)
		(drill 0.3302)
		(layers "F.Cu" "B.Cu")
		(net "TMP05_FUNC2")
	)
	(segment
		(start 96.98228 -166.13124)
		(end 96.98228 -164.607494)
		(width 0.1016)
		(layer "B.Cu")
		(net "TMP05_FUNC2")
	)
	(segment
		(start 97.503234 -167.151812)
		(end 97.50044 -167.154606)
		(width 0.1016)
		(layer "B.Cu")
		(net "TMP05_FUNC2")
	)
	(segment
		(start 96.98228 -164.607494)
		(end 97.441258 -164.148516)
		(width 0.1016)
		(layer "B.Cu")
		(net "TMP05_FUNC2")
	)
	(segment
		(start 99.487482 -167.151812)
		(end 97.503234 -167.151812)
		(width 0.1016)
		(layer "B.Cu")
		(net "TMP05_FUNC2")
	)
	(segment
		(start 97.50044 -167.154606)
		(end 97.50044 -166.6494)
		(width 0.1016)
		(layer "B.Cu")
		(net "TMP05_FUNC2")
	)
	(segment
		(start 97.50044 -166.6494)
		(end 96.98228 -166.13124)
		(width 0.1016)
		(layer "B.Cu")
		(net "TMP05_FUNC2")
	)
	(segment
		(start 122.451622 -39.889684)
		(end 120.43156 -39.889684)
		(width 0.1016)
		(layer "F.Cu")
		(net "SIO_CLKIN")
	)
	(segment
		(start 119.538242 -39.93769)
		(end 120.383554 -39.93769)
		(width 0.1016)
		(layer "F.Cu")
		(net "SIO_CLKIN")
	)
	(segment
		(start 120.43156 -39.889684)
		(end 120.383554 -39.93769)
		(width 0.1016)
		(layer "F.Cu")
		(net "SIO_CLKIN")
	)
	(via
		(at 120.383554 -39.93769)
		(size 0.508)
		(drill 0.254)
		(layers "F.Cu" "B.Cu")
		(net "SIO_CLKIN")
	)
	(segment
		(start 142.761716 -47.199804)
		(end 142.761716 -49.78527)
		(width 0.1016)
		(layer "F.Cu")
		(net "UART_RTS_P2_N")
	)
	(segment
		(start 7.988046 -24.81834)
		(end 8.19404 -24.612346)
		(width 0.1016)
		(layer "F.Cu")
		(net "UART_RTS_P2_N")
	)
	(segment
		(start 142.150084 -44.316904)
		(end 142.150084 -45.066966)
		(width 0.1016)
		(layer "F.Cu")
		(net "UART_RTS_P2_N")
	)
	(segment
		(start 142.761716 -45.678598)
		(end 142.761716 -47.199804)
		(width 0.1016)
		(layer "F.Cu")
		(net "UART_RTS_P2_N")
	)
	(segment
		(start 142.724886 -49.8221)
		(end 142.724886 -51.076606)
		(width 0.1016)
		(layer "F.Cu")
		(net "UART_RTS_P2_N")
	)
	(segment
		(start 142.150084 -45.066966)
		(end 142.761716 -45.678598)
		(width 0.1016)
		(layer "F.Cu")
		(net "UART_RTS_P2_N")
	)
	(segment
		(start 141.708886 -51.076606)
		(end 142.724886 -51.076606)
		(width 0.1016)
		(layer "F.Cu")
		(net "UART_RTS_P2_N")
	)
	(segment
		(start 142.761716 -49.78527)
		(end 142.724886 -49.8221)
		(width 0.1016)
		(layer "F.Cu")
		(net "UART_RTS_P2_N")
	)
	(segment
		(start 7.988046 -26.04516)
		(end 7.988046 -24.81834)
		(width 0.1016)
		(layer "F.Cu")
		(net "UART_RTS_P2_N")
	)
	(via
		(at 8.19404 -24.612346)
		(size 0.508)
		(drill 0.254)
		(layers "F.Cu" "B.Cu")
		(net "UART_RTS_P2_N")
	)
	(via
		(at 142.150084 -44.316904)
		(size 0.508)
		(drill 0.254)
		(layers "F.Cu" "B.Cu")
		(net "UART_RTS_P2_N")
	)
	(segment
		(start 120.28678 -18.955258)
		(end 120.28678 -28.96489)
		(width 0.1143)
		(layer "In7.Cu")
		(net "UART_RTS_P2_N")
	)
	(segment
		(start 132.376926 -39.108634)
		(end 137.340594 -39.108634)
		(width 0.1143)
		(layer "In7.Cu")
		(net "UART_RTS_P2_N")
	)
	(segment
		(start 40.273224 -14.206474)
		(end 42.85742 -14.206474)
		(width 0.1143)
		(layer "In7.Cu")
		(net "UART_RTS_P2_N")
	)
	(segment
		(start 142.150084 -43.918124)
		(end 142.150084 -44.316904)
		(width 0.1143)
		(layer "In7.Cu")
		(net "UART_RTS_P2_N")
	)
	(segment
		(start 113.855246 -12.523724)
		(end 120.28678 -18.955258)
		(width 0.1143)
		(layer "In7.Cu")
		(net "UART_RTS_P2_N")
	)
	(segment
		(start 37.12464 -11.80338)
		(end 37.87013 -11.80338)
		(width 0.1143)
		(layer "In7.Cu")
		(net "UART_RTS_P2_N")
	)
	(segment
		(start 43.561 -14.910054)
		(end 63.517272 -14.910054)
		(width 0.1143)
		(layer "In7.Cu")
		(net "UART_RTS_P2_N")
	)
	(segment
		(start 85.75802 -14.32052)
		(end 87.554816 -12.523724)
		(width 0.1143)
		(layer "In7.Cu")
		(net "UART_RTS_P2_N")
	)
	(segment
		(start 42.85742 -14.206474)
		(end 43.561 -14.910054)
		(width 0.1143)
		(layer "In7.Cu")
		(net "UART_RTS_P2_N")
	)
	(segment
		(start 126.52629 -34.025586)
		(end 127.293878 -34.025586)
		(width 0.1143)
		(layer "In7.Cu")
		(net "UART_RTS_P2_N")
	)
	(segment
		(start 63.517272 -14.910054)
		(end 63.754 -14.673326)
		(width 0.1143)
		(layer "In7.Cu")
		(net "UART_RTS_P2_N")
	)
	(segment
		(start 65.22212 -14.691868)
		(end 65.58661 -14.691868)
		(width 0.1143)
		(layer "In7.Cu")
		(net "UART_RTS_P2_N")
	)
	(segment
		(start 35.729926 -10.812018)
		(end 36.72078 -11.802872)
		(width 0.1143)
		(layer "In7.Cu")
		(net "UART_RTS_P2_N")
	)
	(segment
		(start 124.162058 -32.840168)
		(end 125.340872 -32.840168)
		(width 0.1143)
		(layer "In7.Cu")
		(net "UART_RTS_P2_N")
	)
	(segment
		(start 87.554816 -12.523724)
		(end 113.855246 -12.523724)
		(width 0.1143)
		(layer "In7.Cu")
		(net "UART_RTS_P2_N")
	)
	(segment
		(start 63.754 -14.673326)
		(end 65.203578 -14.673326)
		(width 0.1143)
		(layer "In7.Cu")
		(net "UART_RTS_P2_N")
	)
	(segment
		(start 65.957958 -14.32052)
		(end 85.75802 -14.32052)
		(width 0.1143)
		(layer "In7.Cu")
		(net "UART_RTS_P2_N")
	)
	(segment
		(start 33.710118 -10.277856)
		(end 34.24428 -10.812018)
		(width 0.1143)
		(layer "In7.Cu")
		(net "UART_RTS_P2_N")
	)
	(segment
		(start 34.24428 -10.812018)
		(end 35.729926 -10.812018)
		(width 0.1143)
		(layer "In7.Cu")
		(net "UART_RTS_P2_N")
	)
	(segment
		(start 8.19404 -13.65123)
		(end 12.61618 -9.22909)
		(width 0.1143)
		(layer "In7.Cu")
		(net "UART_RTS_P2_N")
	)
	(segment
		(start 37.12464 -11.802872)
		(end 37.12464 -11.80338)
		(width 0.1143)
		(layer "In7.Cu")
		(net "UART_RTS_P2_N")
	)
	(segment
		(start 127.293878 -34.025586)
		(end 132.376926 -39.108634)
		(width 0.1143)
		(layer "In7.Cu")
		(net "UART_RTS_P2_N")
	)
	(segment
		(start 137.340594 -39.108634)
		(end 142.150084 -43.918124)
		(width 0.1143)
		(layer "In7.Cu")
		(net "UART_RTS_P2_N")
	)
	(segment
		(start 65.203578 -14.673326)
		(end 65.22212 -14.691868)
		(width 0.1143)
		(layer "In7.Cu")
		(net "UART_RTS_P2_N")
	)
	(segment
		(start 12.61618 -9.22909)
		(end 20.95373 -9.22909)
		(width 0.1143)
		(layer "In7.Cu")
		(net "UART_RTS_P2_N")
	)
	(segment
		(start 8.19404 -24.612346)
		(end 8.19404 -13.65123)
		(width 0.1143)
		(layer "In7.Cu")
		(net "UART_RTS_P2_N")
	)
	(segment
		(start 65.58661 -14.691868)
		(end 65.957958 -14.32052)
		(width 0.1143)
		(layer "In7.Cu")
		(net "UART_RTS_P2_N")
	)
	(segment
		(start 20.95373 -9.22909)
		(end 22.002496 -10.277856)
		(width 0.1143)
		(layer "In7.Cu")
		(net "UART_RTS_P2_N")
	)
	(segment
		(start 36.72078 -11.802872)
		(end 37.12464 -11.802872)
		(width 0.1143)
		(layer "In7.Cu")
		(net "UART_RTS_P2_N")
	)
	(segment
		(start 37.87013 -11.80338)
		(end 40.273224 -14.206474)
		(width 0.1143)
		(layer "In7.Cu")
		(net "UART_RTS_P2_N")
	)
	(segment
		(start 125.340872 -32.840168)
		(end 126.52629 -34.025586)
		(width 0.1143)
		(layer "In7.Cu")
		(net "UART_RTS_P2_N")
	)
	(segment
		(start 22.002496 -10.277856)
		(end 33.710118 -10.277856)
		(width 0.1143)
		(layer "In7.Cu")
		(net "UART_RTS_P2_N")
	)
	(segment
		(start 120.28678 -28.96489)
		(end 124.162058 -32.840168)
		(width 0.1143)
		(layer "In7.Cu")
		(net "UART_RTS_P2_N")
	)
	(segment
		(start 109.428788 -164.1094)
		(end 109.77372 -164.454332)
		(width 0.1016)
		(layer "F.Cu")
		(net "TMP05_FUNC1")
	)
	(segment
		(start 109.07268 -164.1094)
		(end 109.428788 -164.1094)
		(width 0.1016)
		(layer "F.Cu")
		(net "TMP05_FUNC1")
	)
	(segment
		(start 109.77372 -165.565582)
		(end 109.77372 -164.454332)
		(width 0.1016)
		(layer "F.Cu")
		(net "TMP05_FUNC1")
	)
	(via
		(at 109.77372 -164.454332)
		(size 0.508)
		(drill 0.254)
		(layers "F.Cu" "B.Cu")
		(net "TMP05_FUNC1")
	)
	(segment
		(start 143.034766 -45.305726)
		(end 143.261588 -45.532548)
		(width 0.1016)
		(layer "F.Cu")
		(net "UART_DTR_P2_N")
	)
	(segment
		(start 143.716248 -50.635154)
		(end 143.716248 -53.302916)
		(width 0.1016)
		(layer "F.Cu")
		(net "UART_DTR_P2_N")
	)
	(segment
		(start 143.505936 -54.529228)
		(end 143.505936 -53.513228)
		(width 0.1016)
		(layer "F.Cu")
		(net "UART_DTR_P2_N")
	)
	(segment
		(start 143.261588 -50.180494)
		(end 143.716248 -50.635154)
		(width 0.1016)
		(layer "F.Cu")
		(net "UART_DTR_P2_N")
	)
	(segment
		(start 9.288018 -26.04516)
		(end 9.288018 -27.428952)
		(width 0.1016)
		(layer "F.Cu")
		(net "UART_DTR_P2_N")
	)
	(segment
		(start 143.716248 -53.302916)
		(end 143.505936 -53.513228)
		(width 0.1016)
		(layer "F.Cu")
		(net "UART_DTR_P2_N")
	)
	(segment
		(start 143.261588 -45.532548)
		(end 143.261588 -47.199804)
		(width 0.1016)
		(layer "F.Cu")
		(net "UART_DTR_P2_N")
	)
	(segment
		(start 143.261588 -47.199804)
		(end 143.261588 -50.180494)
		(width 0.1016)
		(layer "F.Cu")
		(net "UART_DTR_P2_N")
	)
	(via
		(at 143.034766 -45.305726)
		(size 0.508)
		(drill 0.254)
		(layers "F.Cu" "B.Cu")
		(net "UART_DTR_P2_N")
	)
	(via
		(at 9.288018 -27.428952)
		(size 0.508)
		(drill 0.254)
		(layers "F.Cu" "B.Cu")
		(net "UART_DTR_P2_N")
	)
	(segment
		(start 36.2712 -10.300716)
		(end 35.906202 -9.935718)
		(width 0.1143)
		(layer "In7.Cu")
		(net "UART_DTR_P2_N")
	)
	(segment
		(start 120.60682 -18.774156)
		(end 113.963704 -12.13104)
		(width 0.1143)
		(layer "In7.Cu")
		(net "UART_DTR_P2_N")
	)
	(segment
		(start 43.694858 -14.592554)
		(end 42.991278 -13.888974)
		(width 0.1143)
		(layer "In7.Cu")
		(net "UART_DTR_P2_N")
	)
	(segment
		(start 40.406574 -13.888974)
		(end 38.00348 -11.48588)
		(width 0.1143)
		(layer "In7.Cu")
		(net "UART_DTR_P2_N")
	)
	(segment
		(start 136.63676 -38.02126)
		(end 136.45388 -38.20414)
		(width 0.1143)
		(layer "In7.Cu")
		(net "UART_DTR_P2_N")
	)
	(segment
		(start 42.991278 -13.888974)
		(end 40.406574 -13.888974)
		(width 0.1143)
		(layer "In7.Cu")
		(net "UART_DTR_P2_N")
	)
	(segment
		(start 143.034766 -44.056046)
		(end 136.99998 -38.02126)
		(width 0.1143)
		(layer "In7.Cu")
		(net "UART_DTR_P2_N")
	)
	(segment
		(start 63.622428 -14.355826)
		(end 63.3857 -14.592554)
		(width 0.1143)
		(layer "In7.Cu")
		(net "UART_DTR_P2_N")
	)
	(segment
		(start 127.42672 -33.709356)
		(end 127.42672 -33.708086)
		(width 0.1143)
		(layer "In7.Cu")
		(net "UART_DTR_P2_N")
	)
	(segment
		(start 143.034766 -45.305726)
		(end 143.034766 -44.056046)
		(width 0.1143)
		(layer "In7.Cu")
		(net "UART_DTR_P2_N")
	)
	(segment
		(start 12.47648 -8.91159)
		(end 8.000238 -13.387832)
		(width 0.1143)
		(layer "In7.Cu")
		(net "UART_DTR_P2_N")
	)
	(segment
		(start 21.45792 -9.284208)
		(end 21.45792 -9.283192)
		(width 0.1143)
		(layer "In7.Cu")
		(net "UART_DTR_P2_N")
	)
	(segment
		(start 20.82038 -8.911336)
		(end 20.820126 -8.91159)
		(width 0.1143)
		(layer "In7.Cu")
		(net "UART_DTR_P2_N")
	)
	(segment
		(start 7.99846 -13.387832)
		(end 7.99846 -13.390118)
		(width 0.1143)
		(layer "In7.Cu")
		(net "UART_DTR_P2_N")
	)
	(segment
		(start 65.11798 -13.83157)
		(end 64.593724 -14.355826)
		(width 0.1143)
		(layer "In7.Cu")
		(net "UART_DTR_P2_N")
	)
	(segment
		(start 85.62594 -14.00302)
		(end 66.544698 -14.00302)
		(width 0.1143)
		(layer "In7.Cu")
		(net "UART_DTR_P2_N")
	)
	(segment
		(start 7.99846 -13.390118)
		(end 7.75589 -13.632688)
		(width 0.1143)
		(layer "In7.Cu")
		(net "UART_DTR_P2_N")
	)
	(segment
		(start 7.75589 -13.632688)
		(end 7.75589 -25.896824)
		(width 0.1143)
		(layer "In7.Cu")
		(net "UART_DTR_P2_N")
	)
	(segment
		(start 131.921504 -38.20414)
		(end 127.42672 -33.709356)
		(width 0.1143)
		(layer "In7.Cu")
		(net "UART_DTR_P2_N")
	)
	(segment
		(start 87.49792 -12.13104)
		(end 85.62594 -14.00302)
		(width 0.1143)
		(layer "In7.Cu")
		(net "UART_DTR_P2_N")
	)
	(segment
		(start 8.000238 -13.387832)
		(end 7.99846 -13.387832)
		(width 0.1143)
		(layer "In7.Cu")
		(net "UART_DTR_P2_N")
	)
	(segment
		(start 35.906202 -9.935718)
		(end 22.10943 -9.935718)
		(width 0.1143)
		(layer "In7.Cu")
		(net "UART_DTR_P2_N")
	)
	(segment
		(start 22.10943 -9.935718)
		(end 21.45792 -9.284208)
		(width 0.1143)
		(layer "In7.Cu")
		(net "UART_DTR_P2_N")
	)
	(segment
		(start 136.99998 -38.02126)
		(end 136.63676 -38.02126)
		(width 0.1143)
		(layer "In7.Cu")
		(net "UART_DTR_P2_N")
	)
	(segment
		(start 127.42672 -33.708086)
		(end 126.721108 -33.708086)
		(width 0.1143)
		(layer "In7.Cu")
		(net "UART_DTR_P2_N")
	)
	(segment
		(start 21.45792 -9.283192)
		(end 21.086318 -8.91159)
		(width 0.1143)
		(layer "In7.Cu")
		(net "UART_DTR_P2_N")
	)
	(segment
		(start 65.37452 -13.198602)
		(end 65.11798 -13.455142)
		(width 0.1143)
		(layer "In7.Cu")
		(net "UART_DTR_P2_N")
	)
	(segment
		(start 66.544698 -14.00302)
		(end 65.74028 -13.198602)
		(width 0.1143)
		(layer "In7.Cu")
		(net "UART_DTR_P2_N")
	)
	(segment
		(start 21.086318 -8.91159)
		(end 21.08708 -8.91159)
		(width 0.1143)
		(layer "In7.Cu")
		(net "UART_DTR_P2_N")
	)
	(segment
		(start 125.46711 -32.454088)
		(end 124.22505 -32.454088)
		(width 0.1143)
		(layer "In7.Cu")
		(net "UART_DTR_P2_N")
	)
	(segment
		(start 37.25672 -11.485372)
		(end 36.928298 -11.485372)
		(width 0.1143)
		(layer "In7.Cu")
		(net "UART_DTR_P2_N")
	)
	(segment
		(start 64.593724 -14.355826)
		(end 63.622428 -14.355826)
		(width 0.1143)
		(layer "In7.Cu")
		(net "UART_DTR_P2_N")
	)
	(segment
		(start 113.963704 -12.13104)
		(end 87.49792 -12.13104)
		(width 0.1143)
		(layer "In7.Cu")
		(net "UART_DTR_P2_N")
	)
	(segment
		(start 36.928298 -11.485372)
		(end 36.2712 -10.828274)
		(width 0.1143)
		(layer "In7.Cu")
		(net "UART_DTR_P2_N")
	)
	(segment
		(start 126.721108 -33.708086)
		(end 125.46711 -32.454088)
		(width 0.1143)
		(layer "In7.Cu")
		(net "UART_DTR_P2_N")
	)
	(segment
		(start 38.00348 -11.48588)
		(end 37.25672 -11.48588)
		(width 0.1143)
		(layer "In7.Cu")
		(net "UART_DTR_P2_N")
	)
	(segment
		(start 120.62206 -18.791682)
		(end 120.60682 -18.776442)
		(width 0.1143)
		(layer "In7.Cu")
		(net "UART_DTR_P2_N")
	)
	(segment
		(start 120.62206 -28.851098)
		(end 120.62206 -18.791682)
		(width 0.1143)
		(layer "In7.Cu")
		(net "UART_DTR_P2_N")
	)
	(segment
		(start 65.11798 -13.455142)
		(end 65.11798 -13.83157)
		(width 0.1143)
		(layer "In7.Cu")
		(net "UART_DTR_P2_N")
	)
	(segment
		(start 7.75589 -25.896824)
		(end 9.288018 -27.428952)
		(width 0.1143)
		(layer "In7.Cu")
		(net "UART_DTR_P2_N")
	)
	(segment
		(start 136.45388 -38.20414)
		(end 131.921504 -38.20414)
		(width 0.1143)
		(layer "In7.Cu")
		(net "UART_DTR_P2_N")
	)
	(segment
		(start 37.25672 -11.48588)
		(end 37.25672 -11.485372)
		(width 0.1143)
		(layer "In7.Cu")
		(net "UART_DTR_P2_N")
	)
	(segment
		(start 120.60682 -18.776442)
		(end 120.60682 -18.774156)
		(width 0.1143)
		(layer "In7.Cu")
		(net "UART_DTR_P2_N")
	)
	(segment
		(start 124.22505 -32.454088)
		(end 120.62206 -28.851098)
		(width 0.1143)
		(layer "In7.Cu")
		(net "UART_DTR_P2_N")
	)
	(segment
		(start 20.820126 -8.91159)
		(end 12.47648 -8.91159)
		(width 0.1143)
		(layer "In7.Cu")
		(net "UART_DTR_P2_N")
	)
	(segment
		(start 21.08708 -8.91159)
		(end 21.08708 -8.911336)
		(width 0.1143)
		(layer "In7.Cu")
		(net "UART_DTR_P2_N")
	)
	(segment
		(start 21.08708 -8.911336)
		(end 20.82038 -8.911336)
		(width 0.1143)
		(layer "In7.Cu")
		(net "UART_DTR_P2_N")
	)
	(segment
		(start 63.3857 -14.592554)
		(end 43.694858 -14.592554)
		(width 0.1143)
		(layer "In7.Cu")
		(net "UART_DTR_P2_N")
	)
	(segment
		(start 36.2712 -10.828274)
		(end 36.2712 -10.300716)
		(width 0.1143)
		(layer "In7.Cu")
		(net "UART_DTR_P2_N")
	)
	(segment
		(start 65.74028 -13.198602)
		(end 65.37452 -13.198602)
		(width 0.1143)
		(layer "In7.Cu")
		(net "UART_DTR_P2_N")
	)
	(segment
		(start 101.259132 -166.443152)
		(end 101.246686 -166.430706)
		(width 0.1016)
		(layer "F.Cu")
		(net "FNACTRL2_T_ST")
	)
	(segment
		(start 101.629718 -166.430706)
		(end 101.617272 -166.443152)
		(width 0.1016)
		(layer "F.Cu")
		(net "FNACTRL2_T_ST")
	)
	(segment
		(start 101.246686 -166.430706)
		(end 101.187504 -166.430706)
		(width 0.1016)
		(layer "F.Cu")
		(net "FNACTRL2_T_ST")
	)
	(segment
		(start 101.187504 -166.430706)
		(end 100.676964 -165.920166)
		(width 0.1016)
		(layer "F.Cu")
		(net "FNACTRL2_T_ST")
	)
	(segment
		(start 103.214932 -166.430706)
		(end 101.629718 -166.430706)
		(width 0.1016)
		(layer "F.Cu")
		(net "FNACTRL2_T_ST")
	)
	(segment
		(start 101.617272 -166.443152)
		(end 101.259132 -166.443152)
		(width 0.1016)
		(layer "F.Cu")
		(net "FNACTRL2_T_ST")
	)
	(via
		(at 100.676964 -165.920166)
		(size 0.508)
		(drill 0.254)
		(layers "F.Cu" "B.Cu")
		(net "FNACTRL2_T_ST")
	)
	(via
		(at 97.82683 -165.690804)
		(size 0.6604)
		(drill 0.3302)
		(layers "F.Cu" "B.Cu")
		(net "FNACTRL2_T_ST")
	)
	(segment
		(start 100.676964 -165.920166)
		(end 100.395278 -166.201852)
		(width 0.1016)
		(layer "B.Cu")
		(net "FNACTRL2_T_ST")
	)
	(segment
		(start 98.337878 -166.201852)
		(end 97.82683 -165.690804)
		(width 0.1016)
		(layer "B.Cu")
		(net "FNACTRL2_T_ST")
	)
	(segment
		(start 99.487482 -166.201852)
		(end 98.337878 -166.201852)
		(width 0.1016)
		(layer "B.Cu")
		(net "FNACTRL2_T_ST")
	)
	(segment
		(start 100.395278 -166.201852)
		(end 99.487482 -166.201852)
		(width 0.1016)
		(layer "B.Cu")
		(net "FNACTRL2_T_ST")
	)
	(segment
		(start 159.62376 -184.805574)
		(end 159.998664 -184.805574)
		(width 0.1016)
		(layer "F.Cu")
		(net "FAN_PWM")
	)
	(segment
		(start 161.02838 -183.775858)
		(end 161.02838 -183.650382)
		(width 0.1016)
		(layer "F.Cu")
		(net "FAN_PWM")
	)
	(segment
		(start 159.998664 -184.805574)
		(end 161.02838 -183.775858)
		(width 0.1016)
		(layer "F.Cu")
		(net "FAN_PWM")
	)
	(via
		(at 100.7237 -172.787564)
		(size 0.508)
		(drill 0.254)
		(layers "F.Cu" "B.Cu")
		(net "FAN_PWM")
	)
	(via
		(at 161.02838 -183.650382)
		(size 0.508)
		(drill 0.254)
		(layers "F.Cu" "B.Cu")
		(net "FAN_PWM")
	)
	(segment
		(start 101.096064 -171.758102)
		(end 101.096064 -172.680122)
		(width 0.1016)
		(layer "B.Cu")
		(net "FAN_PWM")
	)
	(segment
		(start 101.096064 -172.680122)
		(end 100.988622 -172.787564)
		(width 0.1016)
		(layer "B.Cu")
		(net "FAN_PWM")
	)
	(segment
		(start 101.731318 -171.122848)
		(end 101.096064 -171.758102)
		(width 0.1016)
		(layer "B.Cu")
		(net "FAN_PWM")
	)
	(segment
		(start 100.988622 -172.787564)
		(end 100.7237 -172.787564)
		(width 0.1016)
		(layer "B.Cu")
		(net "FAN_PWM")
	)
	(segment
		(start 100.688394 -168.802812)
		(end 100.688394 -169.034714)
		(width 0.1016)
		(layer "B.Cu")
		(net "FAN_PWM")
	)
	(segment
		(start 101.731318 -170.077638)
		(end 101.731318 -171.122848)
		(width 0.1016)
		(layer "B.Cu")
		(net "FAN_PWM")
	)
	(segment
		(start 100.688394 -169.034714)
		(end 101.731318 -170.077638)
		(width 0.1016)
		(layer "B.Cu")
		(net "FAN_PWM")
	)
	(segment
		(start 158.899352 -188.83757)
		(end 110.75924 -188.83757)
		(width 0.1143)
		(layer "In7.Cu")
		(net "FAN_PWM")
	)
	(segment
		(start 110.75924 -188.83757)
		(end 109.01934 -187.09767)
		(width 0.1143)
		(layer "In7.Cu")
		(net "FAN_PWM")
	)
	(segment
		(start 107.62742 -185.43905)
		(end 107.235752 -185.047382)
		(width 0.1143)
		(layer "In7.Cu")
		(net "FAN_PWM")
	)
	(segment
		(start 107.235752 -185.047382)
		(end 106.385106 -185.047382)
		(width 0.1143)
		(layer "In7.Cu")
		(net "FAN_PWM")
	)
	(segment
		(start 109.01934 -187.09767)
		(end 109.01934 -186.431174)
		(width 0.1143)
		(layer "In7.Cu")
		(net "FAN_PWM")
	)
	(segment
		(start 100.7237 -175.727868)
		(end 100.7237 -172.787564)
		(width 0.1143)
		(layer "In7.Cu")
		(net "FAN_PWM")
	)
	(segment
		(start 160.46831 -187.10783)
		(end 160.46831 -189.440566)
		(width 0.1143)
		(layer "In7.Cu")
		(net "FAN_PWM")
	)
	(segment
		(start 160.46831 -189.440566)
		(end 160.21177 -189.697106)
		(width 0.1143)
		(layer "In7.Cu")
		(net "FAN_PWM")
	)
	(segment
		(start 160.21177 -189.697106)
		(end 159.758888 -189.697106)
		(width 0.1143)
		(layer "In7.Cu")
		(net "FAN_PWM")
	)
	(segment
		(start 102.7938 -179.65674)
		(end 102.7938 -177.797968)
		(width 0.1143)
		(layer "In7.Cu")
		(net "FAN_PWM")
	)
	(segment
		(start 159.758888 -189.697106)
		(end 158.899352 -188.83757)
		(width 0.1143)
		(layer "In7.Cu")
		(net "FAN_PWM")
	)
	(segment
		(start 109.01934 -186.431174)
		(end 108.027216 -185.43905)
		(width 0.1143)
		(layer "In7.Cu")
		(net "FAN_PWM")
	)
	(segment
		(start 102.7938 -177.797968)
		(end 100.7237 -175.727868)
		(width 0.1143)
		(layer "In7.Cu")
		(net "FAN_PWM")
	)
	(segment
		(start 103.20528 -181.867556)
		(end 103.20528 -180.06822)
		(width 0.1143)
		(layer "In7.Cu")
		(net "FAN_PWM")
	)
	(segment
		(start 108.027216 -185.43905)
		(end 107.62742 -185.43905)
		(width 0.1143)
		(layer "In7.Cu")
		(net "FAN_PWM")
	)
	(segment
		(start 161.02838 -183.650382)
		(end 161.02838 -184.234328)
		(width 0.1143)
		(layer "In7.Cu")
		(net "FAN_PWM")
	)
	(segment
		(start 103.20528 -180.06822)
		(end 102.7938 -179.65674)
		(width 0.1143)
		(layer "In7.Cu")
		(net "FAN_PWM")
	)
	(segment
		(start 106.385106 -185.047382)
		(end 103.20528 -181.867556)
		(width 0.1143)
		(layer "In7.Cu")
		(net "FAN_PWM")
	)
	(segment
		(start 161.02838 -184.234328)
		(end 160.88741 -184.375298)
		(width 0.1143)
		(layer "In7.Cu")
		(net "FAN_PWM")
	)
	(segment
		(start 160.88741 -186.68873)
		(end 160.46831 -187.10783)
		(width 0.1143)
		(layer "In7.Cu")
		(net "FAN_PWM")
	)
	(segment
		(start 160.88741 -184.375298)
		(end 160.88741 -186.68873)
		(width 0.1143)
		(layer "In7.Cu")
		(net "FAN_PWM")
	)
	(segment
		(start 105.51922 -164.769546)
		(end 105.770426 -164.769546)
		(width 0.1016)
		(layer "F.Cu")
		(net "FNACTRL2_ADD")
	)
	(segment
		(start 103.984806 -165.160706)
		(end 104.194102 -165.370002)
		(width 0.1016)
		(layer "F.Cu")
		(net "FNACTRL2_ADD")
	)
	(segment
		(start 104.804972 -164.52088)
		(end 105.03789 -164.288216)
		(width 0.1016)
		(layer "F.Cu")
		(net "FNACTRL2_ADD")
	)
	(segment
		(start 104.552242 -165.370002)
		(end 104.804972 -165.117272)
		(width 0.1016)
		(layer "F.Cu")
		(net "FNACTRL2_ADD")
	)
	(segment
		(start 103.214932 -165.160706)
		(end 103.984806 -165.160706)
		(width 0.1016)
		(layer "F.Cu")
		(net "FNACTRL2_ADD")
	)
	(segment
		(start 104.194102 -165.370002)
		(end 104.552242 -165.370002)
		(width 0.1016)
		(layer "F.Cu")
		(net "FNACTRL2_ADD")
	)
	(segment
		(start 104.804972 -165.117272)
		(end 104.804972 -164.52088)
		(width 0.1016)
		(layer "F.Cu")
		(net "FNACTRL2_ADD")
	)
	(segment
		(start 105.03789 -164.288216)
		(end 105.51922 -164.769546)
		(width 0.1016)
		(layer "F.Cu")
		(net "FNACTRL2_ADD")
	)
	(segment
		(start 105.770426 -164.769546)
		(end 105.770426 -165.793928)
		(width 0.1016)
		(layer "F.Cu")
		(net "FNACTRL2_ADD")
	)
	(via
		(at 105.03789 -164.288216)
		(size 0.508)
		(drill 0.254)
		(layers "F.Cu" "B.Cu")
		(net "FNACTRL2_ADD")
	)
	(segment
		(start 154.2923 -36.602162)
		(end 154.2923 -38.41877)
		(width 0.1016)
		(layer "F.Cu")
		(net "UART_CTS_P1_N")
	)
	(segment
		(start 147.71751 -39.362126)
		(end 147.3581 -39.721536)
		(width 0.1016)
		(layer "F.Cu")
		(net "UART_CTS_P1_N")
	)
	(segment
		(start 147.025106 -40.056816)
		(end 147.025106 -40.447722)
		(width 0.1016)
		(layer "F.Cu")
		(net "UART_CTS_P1_N")
	)
	(segment
		(start 154.07513 -36.384992)
		(end 154.2923 -36.602162)
		(width 0.1016)
		(layer "F.Cu")
		(net "UART_CTS_P1_N")
	)
	(segment
		(start 146.583146 -40.889682)
		(end 145.571718 -40.889682)
		(width 0.1016)
		(layer "F.Cu")
		(net "UART_CTS_P1_N")
	)
	(segment
		(start 152.429972 -36.384992)
		(end 154.07513 -36.384992)
		(width 0.1016)
		(layer "F.Cu")
		(net "UART_CTS_P1_N")
	)
	(segment
		(start 147.3581 -39.721536)
		(end 147.3581 -39.723822)
		(width 0.1016)
		(layer "F.Cu")
		(net "UART_CTS_P1_N")
	)
	(segment
		(start 147.025106 -40.447722)
		(end 146.583146 -40.889682)
		(width 0.1016)
		(layer "F.Cu")
		(net "UART_CTS_P1_N")
	)
	(segment
		(start 147.3581 -39.723822)
		(end 147.025106 -40.056816)
		(width 0.1016)
		(layer "F.Cu")
		(net "UART_CTS_P1_N")
	)
	(segment
		(start 154.2923 -38.41877)
		(end 153.892758 -38.818312)
		(width 0.1016)
		(layer "F.Cu")
		(net "UART_CTS_P1_N")
	)
	(segment
		(start 148.261324 -38.818312)
		(end 147.71751 -39.362126)
		(width 0.1016)
		(layer "F.Cu")
		(net "UART_CTS_P1_N")
	)
	(segment
		(start 153.892758 -38.818312)
		(end 148.261324 -38.818312)
		(width 0.1016)
		(layer "F.Cu")
		(net "UART_CTS_P1_N")
	)
	(via
		(at 147.71751 -39.362126)
		(size 0.508)
		(drill 0.254)
		(layers "F.Cu" "B.Cu")
		(net "UART_CTS_P1_N")
	)
	(segment
		(start 137.52576 -110.383574)
		(end 137.52576 -109.673898)
		(width 0.4572)
		(layer "F.Cu")
		(net "GND")
	)
	(segment
		(start 91.214448 -176.562512)
		(end 91.876118 -176.562512)
		(width 0.508)
		(layer "F.Cu")
		(net "GND")
	)
	(segment
		(start 87.394796 -31.596838)
		(end 88.050116 -30.941518)
		(width 0.381)
		(layer "F.Cu")
		(net "GND")
	)
	(segment
		(start 102.549706 -17.68094)
		(end 102.549706 -18.486882)
		(width 0.4572)
		(layer "F.Cu")
		(net "GND")
	)
	(segment
		(start 46.006766 -63.898526)
		(end 45.857414 -64.047878)
		(width 0.3048)
		(layer "F.Cu")
		(net "GND")
	)
	(segment
		(start 61.503306 -81.571846)
		(end 61.503306 -81.281016)
		(width 0.3048)
		(layer "F.Cu")
		(net "GND")
	)
	(segment
		(start 124.672852 -144.15135)
		(end 124.672852 -143.69415)
		(width 0.1778)
		(layer "F.Cu")
		(net "GND")
	)
	(segment
		(start 64.95923 -86.143846)
		(end 65.475866 -86.143846)
		(width 0.254)
		(layer "F.Cu")
		(net "GND")
	)
	(segment
		(start 89.39276 -184.349898)
		(end 89.04732 -184.004458)
		(width 0.508)
		(layer "F.Cu")
		(net "GND")
	)
	(segment
		(start 128.25476 -184.225438)
		(end 128.55067 -183.929528)
		(width 0.381)
		(layer "F.Cu")
		(net "GND")
	)
	(segment
		(start 35.269678 -82.179922)
		(end 34.346896 -82.179922)
		(width 0.4572)
		(layer "F.Cu")
		(net "GND")
	)
	(segment
		(start 39.3446 -140.165328)
		(end 39.346378 -140.16355)
		(width 0.3556)
		(layer "F.Cu")
		(net "GND")
	)
	(segment
		(start 49.609248 -73.343262)
		(end 49.609248 -74.043286)
		(width 0.3048)
		(layer "F.Cu")
		(net "GND")
	)
	(segment
		(start 69.015102 -201.09053)
		(end 69.015102 -200.32853)
		(width 0.508)
		(layer "F.Cu")
		(net "GND")
	)
	(segment
		(start 90.866468 -125.19152)
		(end 90.866468 -124.2949)
		(width 0.2032)
		(layer "F.Cu")
		(net "GND")
	)
	(segment
		(start 47.361094 -130.56362)
		(end 46.432978 -130.56362)
		(width 0.3556)
		(layer "F.Cu")
		(net "GND")
	)
	(segment
		(start 79.79791 -92.433394)
		(end 79.79791 -92.076524)
		(width 0.508)
		(layer "F.Cu")
		(net "GND")
	)
	(segment
		(start 86.34222 -167.949626)
		(end 86.361524 -167.949626)
		(width 0.254)
		(layer "F.Cu")
		(net "GND")
	)
	(segment
		(start 41.212516 -78.760066)
		(end 41.75125 -78.760066)
		(width 0.254)
		(layer "F.Cu")
		(net "GND")
	)
	(segment
		(start 106.323638 -69.478652)
		(end 106.323638 -69.27088)
		(width 0.3048)
		(layer "F.Cu")
		(net "GND")
	)
	(segment
		(start 145.189702 -150.19655)
		(end 145.932398 -150.19655)
		(width 0.508)
		(layer "F.Cu")
		(net "GND")
	)
	(segment
		(start 66.787776 -78.649322)
		(end 66.394076 -78.255622)
		(width 0.3048)
		(layer "F.Cu")
		(net "GND")
	)
	(segment
		(start 65.341754 -133.659118)
		(end 65.341754 -133.659626)
		(width 0.381)
		(layer "F.Cu")
		(net "GND")
	)
	(segment
		(start 71.201026 -102.413308)
		(end 70.55485 -102.413308)
		(width 0.4572)
		(layer "F.Cu")
		(net "GND")
	)
	(segment
		(start 36.531042 -173.458378)
		(end 36.531042 -174.634906)
		(width 0.508)
		(layer "F.Cu")
		(net "GND")
	)
	(segment
		(start 72.063864 -79.895192)
		(end 72.221598 -79.737458)
		(width 0.3048)
		(layer "F.Cu")
		(net "GND")
	)
	(segment
		(start 53.424582 -67.360038)
		(end 53.797962 -67.733418)
		(width 0.254)
		(layer "F.Cu")
		(net "GND")
	)
	(segment
		(start 169.513504 -156.827474)
		(end 169.57294 -156.768038)
		(width 0.508)
		(layer "F.Cu")
		(net "GND")
	)
	(segment
		(start 20.12569 -130.328416)
		(end 20.73529 -130.328416)
		(width 0.4572)
		(layer "F.Cu")
		(net "GND")
	)
	(segment
		(start 82.73796 -109.116368)
		(end 82.73796 -109.732318)
		(width 0.508)
		(layer "F.Cu")
		(net "GND")
	)
	(segment
		(start 57.585102 -30.989778)
		(end 57.450228 -30.854904)
		(width 0.4572)
		(layer "F.Cu")
		(net "GND")
	)
	(segment
		(start 107.522518 -179.157376)
		(end 107.396788 -179.031646)
		(width 0.4572)
		(layer "F.Cu")
		(net "GND")
	)
	(segment
		(start 72.5424 -137.659618)
		(end 72.541892 -137.659618)
		(width 0.3556)
		(layer "F.Cu")
		(net "GND")
	)
	(segment
		(start 72.063864 -67.376548)
		(end 72.063864 -67.408044)
		(width 0.3048)
		(layer "F.Cu")
		(net "GND")
	)
	(segment
		(start 56.98744 -173.828964)
		(end 57.656222 -174.497746)
		(width 0.4572)
		(layer "F.Cu")
		(net "GND")
	)
	(segment
		(start 65.339722 -136.059418)
		(end 65.341754 -136.059418)
		(width 0.381)
		(layer "F.Cu")
		(net "GND")
	)
	(segment
		(start 20.0279 -40.098218)
		(end 20.0279 -40.097964)
		(width 0.508)
		(layer "F.Cu")
		(net "GND")
	)
	(segment
		(start 68.311776 -70.704202)
		(end 67.918076 -70.310502)
		(width 0.254)
		(layer "F.Cu")
		(net "GND")
	)
	(segment
		(start 84.82076 -187.726574)
		(end 84.82076 -186.91733)
		(width 0.508)
		(layer "F.Cu")
		(net "GND")
	)
	(segment
		(start 68.680076 -78.255622)
		(end 69.073776 -78.649322)
		(width 0.3048)
		(layer "F.Cu")
		(net "GND")
	)
	(segment
		(start 44.713398 -78.70063)
		(end 44.713398 -79.244952)
		(width 0.3048)
		(layer "F.Cu")
		(net "GND")
	)
	(segment
		(start 41.665144 -65.12687)
		(end 41.88968 -65.12687)
		(width 0.4064)
		(layer "F.Cu")
		(net "GND")
	)
	(segment
		(start 137.193528 -59.688222)
		(end 136.315704 -59.688222)
		(width 0.508)
		(layer "F.Cu")
		(net "GND")
	)
	(segment
		(start 61.279532 -81.057242)
		(end 61.601096 -80.735678)
		(width 0.3048)
		(layer "F.Cu")
		(net "GND")
	)
	(segment
		(start 43.964352 -64.736218)
		(end 44.084494 -64.736218)
		(width 0.3048)
		(layer "F.Cu")
		(net "GND")
	)
	(segment
		(start 52.382928 -64.15151)
		(end 52.382928 -64.725804)
		(width 0.3048)
		(layer "F.Cu")
		(net "GND")
	)
	(segment
		(start 110.460028 -64.406526)
		(end 108.653072 -64.406526)
		(width 0.3048)
		(layer "F.Cu")
		(net "GND")
	)
	(segment
		(start 62.405514 -86.66861)
		(end 62.211458 -86.862666)
		(width 0.254)
		(layer "F.Cu")
		(net "GND")
	)
	(segment
		(start 73.742042 -143.659606)
		(end 73.341992 -143.259556)
		(width 0.3556)
		(layer "F.Cu")
		(net "GND")
	)
	(segment
		(start 68.680076 -70.310502)
		(end 69.073776 -70.704202)
		(width 0.3048)
		(layer "F.Cu")
		(net "GND")
	)
	(segment
		(start 110.60176 -187.726574)
		(end 110.60176 -186.925712)
		(width 0.508)
		(layer "F.Cu")
		(net "GND")
	)
	(segment
		(start 91.237308 -175.388778)
		(end 91.20759 -175.418496)
		(width 0.4572)
		(layer "F.Cu")
		(net "GND")
	)
	(segment
		(start 79.842106 -165.735)
		(end 78.81112 -165.735)
		(width 0.254)
		(layer "F.Cu")
		(net "GND")
	)
	(segment
		(start 177.51044 -121.865644)
		(end 177.010314 -121.365518)
		(width 0.381)
		(layer "F.Cu")
		(net "GND")
	)
	(segment
		(start 127.73406 -187.032646)
		(end 127.42926 -187.032646)
		(width 0.508)
		(layer "F.Cu")
		(net "GND")
	)
	(segment
		(start 39.35603 -136.165082)
		(end 39.357554 -136.163558)
		(width 0.3556)
		(layer "F.Cu")
		(net "GND")
	)
	(segment
		(start 133.080252 -134.29615)
		(end 132.938012 -134.43839)
		(width 0.1778)
		(layer "F.Cu")
		(net "GND")
	)
	(segment
		(start 49.228248 -78.389226)
		(end 49.044606 -78.572868)
		(width 0.3048)
		(layer "F.Cu")
		(net "GND")
	)
	(segment
		(start 78.123796 -161.699702)
		(end 78.123796 -160.975548)
		(width 0.508)
		(layer "F.Cu")
		(net "GND")
	)
	(segment
		(start 116.392452 -116.93017)
		(end 118.67642 -116.93017)
		(width 0.254)
		(layer "F.Cu")
		(net "GND")
	)
	(segment
		(start 101.250242 -27.784298)
		(end 101.250242 -29.149802)
		(width 0.4572)
		(layer "F.Cu")
		(net "GND")
	)
	(segment
		(start 50.53076 -180.974746)
		(end 50.53076 -180.303424)
		(width 0.4572)
		(layer "F.Cu")
		(net "GND")
	)
	(segment
		(start 82.7278 -83.241134)
		(end 81.98231 -83.241134)
		(width 0.508)
		(layer "F.Cu")
		(net "GND")
	)
	(segment
		(start 104.047036 -155.524962)
		(end 103.816658 -155.524962)
		(width 0.254)
		(layer "F.Cu")
		(net "GND")
	)
	(segment
		(start 41.762172 -88.439498)
		(end 41.88968 -88.31199)
		(width 0.381)
		(layer "F.Cu")
		(net "GND")
	)
	(segment
		(start 130.42392 -137.540746)
		(end 130.42392 -136.734296)
		(width 0.1778)
		(layer "F.Cu")
		(net "GND")
	)
	(segment
		(start 163.252404 -121.584466)
		(end 164.180774 -121.584466)
		(width 0.508)
		(layer "F.Cu")
		(net "GND")
	)
	(segment
		(start 45.128688 -90.958162)
		(end 44.708064 -90.958162)
		(width 0.381)
		(layer "F.Cu")
		(net "GND")
	)
	(segment
		(start 62.809374 -80.194658)
		(end 62.8269 -80.212184)
		(width 0.3556)
		(layer "F.Cu")
		(net "GND")
	)
	(segment
		(start 47.319184 -82.896964)
		(end 47.302166 -82.896964)
		(width 0.3048)
		(layer "F.Cu")
		(net "GND")
	)
	(segment
		(start 53.391562 -27.548078)
		(end 53.546502 -27.548078)
		(width 0.4572)
		(layer "F.Cu")
		(net "GND")
	)
	(segment
		(start 66.9417 -134.457694)
		(end 66.9417 -134.459472)
		(width 0.381)
		(layer "F.Cu")
		(net "GND")
	)
	(segment
		(start 72.942196 -140.459206)
		(end 72.5424 -140.05941)
		(width 0.3556)
		(layer "F.Cu")
		(net "GND")
	)
	(segment
		(start 28.974288 -122.164856)
		(end 28.688792 -122.164856)
		(width 0.4572)
		(layer "F.Cu")
		(net "GND")
	)
	(segment
		(start 75.474068 -94.872048)
		(end 75.474068 -94.531942)
		(width 0.4572)
		(layer "F.Cu")
		(net "GND")
	)
	(segment
		(start 73.24344 -83.431126)
		(end 73.24344 -83.70062)
		(width 0.3048)
		(layer "F.Cu")
		(net "GND")
	)
	(segment
		(start 71.742554 -126.459488)
		(end 72.142096 -126.85903)
		(width 0.3556)
		(layer "F.Cu")
		(net "GND")
	)
	(segment
		(start 140.089636 -142.575534)
		(end 141.288008 -142.575534)
		(width 0.1778)
		(layer "F.Cu")
		(net "GND")
	)
	(segment
		(start 116.18976 -184.318402)
		(end 116.3447 -184.163462)
		(width 0.508)
		(layer "F.Cu")
		(net "GND")
	)
	(segment
		(start 106.444034 -129.357882)
		(end 106.444034 -129.343912)
		(width 0.4572)
		(layer "F.Cu")
		(net "GND")
	)
	(segment
		(start 44.656248 -83.274662)
		(end 44.656248 -83.123786)
		(width 0.254)
		(layer "F.Cu")
		(net "GND")
	)
	(segment
		(start 94.611444 -187.822586)
		(end 95.39605 -187.822586)
		(width 0.508)
		(layer "F.Cu")
		(net "GND")
	)
	(segment
		(start 172.279056 -94.38259)
		(end 172.279056 -93.877892)
		(width 0.4572)
		(layer "F.Cu")
		(net "GND")
	)
	(segment
		(start 46.942248 -75.329542)
		(end 46.942248 -76.029566)
		(width 0.3048)
		(layer "F.Cu")
		(net "GND")
	)
	(segment
		(start 64.940942 -136.458198)
		(end 65.339722 -136.059418)
		(width 0.381)
		(layer "F.Cu")
		(net "GND")
	)
	(segment
		(start 157.513274 -163.848288)
		(end 156.103066 -163.848288)
		(width 0.4572)
		(layer "F.Cu")
		(net "GND")
	)
	(segment
		(start 53.345842 -181.061868)
		(end 52.81676 -181.59095)
		(width 0.508)
		(layer "F.Cu")
		(net "GND")
	)
	(segment
		(start 114.882676 -24.432006)
		(end 114.882676 -23.855426)
		(width 0.254)
		(layer "F.Cu")
		(net "GND")
	)
	(segment
		(start 20.90674 -59.146694)
		(end 20.121118 -59.146694)
		(width 0.508)
		(layer "F.Cu")
		(net "GND")
	)
	(segment
		(start 137.212578 -120.114568)
		(end 136.503664 -120.114568)
		(width 0.1778)
		(layer "F.Cu")
		(net "GND")
	)
	(segment
		(start 71.10476 -184.805574)
		(end 71.10476 -183.928004)
		(width 0.508)
		(layer "F.Cu")
		(net "GND")
	)
	(segment
		(start 49.719738 -69.370702)
		(end 49.680368 -69.370702)
		(width 0.3048)
		(layer "F.Cu")
		(net "GND")
	)
	(segment
		(start 137.172192 -159.928814)
		(end 136.240012 -159.928814)
		(width 0.508)
		(layer "F.Cu")
		(net "GND")
	)
	(segment
		(start 66.17589 -83.857846)
		(end 65.475866 -83.857846)
		(width 0.3048)
		(layer "F.Cu")
		(net "GND")
	)
	(segment
		(start 30.98292 -131.14401)
		(end 30.98292 -130.513074)
		(width 0.4572)
		(layer "F.Cu")
		(net "GND")
	)
	(segment
		(start 130.837686 -174.108618)
		(end 129.775712 -174.108618)
		(width 0.254)
		(layer "F.Cu")
		(net "GND")
	)
	(segment
		(start 54.602634 -86.889844)
		(end 54.602634 -88.042242)
		(width 0.3048)
		(layer "F.Cu")
		(net "GND")
	)
	(segment
		(start 49.83734 -69.276976)
		(end 49.825402 -69.265038)
		(width 0.3048)
		(layer "F.Cu")
		(net "GND")
	)
	(segment
		(start 110.380018 -149.245066)
		(end 111.129064 -149.245066)
		(width 0.508)
		(layer "F.Cu")
		(net "GND")
	)
	(segment
		(start 143.310102 -133.178804)
		(end 144.040352 -133.178804)
		(width 0.4572)
		(layer "F.Cu")
		(net "GND")
	)
	(segment
		(start 47.474632 -89.60104)
		(end 47.452788 -89.579196)
		(width 0.254)
		(layer "F.Cu")
		(net "GND")
	)
	(segment
		(start 117.68963 -147.746466)
		(end 116.899944 -147.746466)
		(width 0.508)
		(layer "F.Cu")
		(net "GND")
	)
	(segment
		(start 43.51528 -88.097614)
		(end 43.51528 -88.910414)
		(width 0.381)
		(layer "F.Cu")
		(net "GND")
	)
	(segment
		(start 130.657346 -167.108632)
		(end 129.775712 -167.108632)
		(width 0.254)
		(layer "F.Cu")
		(net "GND")
	)
	(segment
		(start 74.142092 -143.259556)
		(end 74.141838 -143.259556)
		(width 0.3556)
		(layer "F.Cu")
		(net "GND")
	)
	(segment
		(start 51.014884 -205.199488)
		(end 51.014884 -201.09053)
		(width 0.508)
		(layer "F.Cu")
		(net "GND")
	)
	(segment
		(start 103.476806 -181.31409)
		(end 103.288084 -181.31409)
		(width 0.4572)
		(layer "F.Cu")
		(net "GND")
	)
	(segment
		(start 74.111612 -62.390274)
		(end 74.111612 -62.68847)
		(width 0.3048)
		(layer "F.Cu")
		(net "GND")
	)
	(segment
		(start 63.340996 -136.458198)
		(end 63.739776 -136.059418)
		(width 0.381)
		(layer "F.Cu")
		(net "GND")
	)
	(segment
		(start 138.425936 -177.652426)
		(end 138.525758 -177.752248)
		(width 0.254)
		(layer "F.Cu")
		(net "GND")
	)
	(segment
		(start 61.530738 -65.129918)
		(end 61.924438 -64.736218)
		(width 0.254)
		(layer "F.Cu")
		(net "GND")
	)
	(segment
		(start 57.770522 -67.741038)
		(end 58.470546 -67.741038)
		(width 0.254)
		(layer "F.Cu")
		(net "GND")
	)
	(segment
		(start 63.667894 -97.73412)
		(end 63.177166 -97.243392)
		(width 0.4572)
		(layer "F.Cu")
		(net "GND")
	)
	(segment
		(start 43.859196 -18.89506)
		(end 50.183034 -18.89506)
		(width 0.254)
		(layer "F.Cu")
		(net "GND")
	)
	(segment
		(start 72.61606 -79.084678)
		(end 72.795384 -79.264002)
		(width 0.3048)
		(layer "F.Cu")
		(net "GND")
	)
	(segment
		(start 66.142362 -140.05941)
		(end 66.141854 -140.05941)
		(width 0.3556)
		(layer "F.Cu")
		(net "GND")
	)
	(segment
		(start 15.14856 -41.795192)
		(end 15.14856 -40.989504)
		(width 0.508)
		(layer "F.Cu")
		(net "GND")
	)
	(segment
		(start 69.059044 -75.569318)
		(end 69.059044 -76.269342)
		(width 0.3048)
		(layer "F.Cu")
		(net "GND")
	)
	(segment
		(start 66.150236 -19.609308)
		(end 66.4845 -19.275044)
		(width 0.381)
		(layer "F.Cu")
		(net "GND")
	)
	(segment
		(start 177.51044 -122.865642)
		(end 177.010568 -122.36577)
		(width 0.381)
		(layer "F.Cu")
		(net "GND")
	)
	(segment
		(start 164.087302 -90.14079)
		(end 164.087302 -90.95994)
		(width 0.508)
		(layer "F.Cu")
		(net "GND")
	)
	(segment
		(start 69.059044 -68.351654)
		(end 69.059044 -68.324222)
		(width 0.3048)
		(layer "F.Cu")
		(net "GND")
	)
	(segment
		(start 64.542416 -140.05941)
		(end 64.541908 -140.05941)
		(width 0.3556)
		(layer "F.Cu")
		(net "GND")
	)
	(segment
		(start 44.656248 -72.057006)
		(end 44.656248 -71.356982)
		(width 0.3048)
		(layer "F.Cu")
		(net "GND")
	)
	(segment
		(start 72.942196 -137.259314)
		(end 72.5424 -136.859518)
		(width 0.3556)
		(layer "F.Cu")
		(net "GND")
	)
	(segment
		(start 56.065166 -99.046284)
		(end 56.065166 -97.110042)
		(width 0.4572)
		(layer "F.Cu")
		(net "GND")
	)
	(segment
		(start 122.818652 -25.52954)
		(end 122.818652 -26.174192)
		(width 0.508)
		(layer "F.Cu")
		(net "GND")
	)
	(segment
		(start 54.033166 -97.110042)
		(end 53.017166 -97.110042)
		(width 0.4572)
		(layer "F.Cu")
		(net "GND")
	)
	(segment
		(start 73.298812 -63.50127)
		(end 72.486012 -62.68847)
		(width 0.3048)
		(layer "F.Cu")
		(net "GND")
	)
	(segment
		(start 58.330338 -84.512658)
		(end 58.330338 -84.520278)
		(width 0.3048)
		(layer "F.Cu")
		(net "GND")
	)
	(segment
		(start 80.701388 -155.663392)
		(end 80.528414 -155.490418)
		(width 0.254)
		(layer "F.Cu")
		(net "GND")
	)
	(segment
		(start 21.59254 -40.532558)
		(end 20.46224 -40.532558)
		(width 0.508)
		(layer "F.Cu")
		(net "GND")
	)
	(segment
		(start 60.800996 -78.999842)
		(end 60.58154 -78.780386)
		(width 0.3556)
		(layer "F.Cu")
		(net "GND")
	)
	(segment
		(start 53.797962 -67.733418)
		(end 53.797962 -67.741038)
		(width 0.254)
		(layer "F.Cu")
		(net "GND")
	)
	(segment
		(start 42.753534 -74.512932)
		(end 42.580052 -74.33945)
		(width 0.3048)
		(layer "F.Cu")
		(net "GND")
	)
	(segment
		(start 66.809366 -67.345306)
		(end 66.443098 -66.979038)
		(width 0.3048)
		(layer "F.Cu")
		(net "GND")
	)
	(segment
		(start 59.220608 -148.241258)
		(end 58.371486 -148.241258)
		(width 0.508)
		(layer "F.Cu")
		(net "GND")
	)
	(segment
		(start 74.827384 -83.344766)
		(end 74.701908 -83.470242)
		(width 0.254)
		(layer "F.Cu")
		(net "GND")
	)
	(segment
		(start 49.849532 -69.265038)
		(end 49.837848 -69.276976)
		(width 0.3048)
		(layer "F.Cu")
		(net "GND")
	)
	(segment
		(start 71.296276 -81.528158)
		(end 70.964044 -81.528158)
		(width 0.3048)
		(layer "F.Cu")
		(net "GND")
	)
	(segment
		(start 69.774054 -84.786216)
		(end 69.821044 -84.739226)
		(width 0.3556)
		(layer "F.Cu")
		(net "GND")
	)
	(segment
		(start 47.321216 -73.345294)
		(end 47.321216 -74.041254)
		(width 0.3048)
		(layer "F.Cu")
		(net "GND")
	)
	(segment
		(start 66.441828 -87.330026)
		(end 66.441828 -86.912196)
		(width 0.3048)
		(layer "F.Cu")
		(net "GND")
	)
	(segment
		(start 43.249088 -79.519018)
		(end 43.249088 -79.677768)
		(width 0.254)
		(layer "F.Cu")
		(net "GND")
	)
	(segment
		(start 12.012168 -112.127284)
		(end 14.440662 -112.127284)
		(width 0.254)
		(layer "F.Cu")
		(net "GND")
	)
	(segment
		(start 24.014938 -201.09053)
		(end 24.014938 -200.32853)
		(width 0.508)
		(layer "F.Cu")
		(net "GND")
	)
	(segment
		(start 51.45024 -29.149802)
		(end 51.45024 -27.380438)
		(width 0.4572)
		(layer "F.Cu")
		(net "GND")
	)
	(segment
		(start 65.339722 -136.859518)
		(end 65.341754 -136.859518)
		(width 0.381)
		(layer "F.Cu")
		(net "GND")
	)
	(segment
		(start 58.35015 -20.94992)
		(end 58.35015 -22.534626)
		(width 0.4572)
		(layer "F.Cu")
		(net "GND")
	)
	(segment
		(start 131.872482 -56.939942)
		(end 131.185412 -56.252872)
		(width 0.4572)
		(layer "F.Cu")
		(net "GND")
	)
	(segment
		(start 72.5424 -140.85951)
		(end 72.541892 -140.85951)
		(width 0.3556)
		(layer "F.Cu")
		(net "GND")
	)
	(segment
		(start 42.392854 -85.343238)
		(end 42.392854 -85.600032)
		(width 0.254)
		(layer "F.Cu")
		(net "GND")
	)
	(segment
		(start 34.306256 -188.652404)
		(end 34.21888 -188.565028)
		(width 0.508)
		(layer "F.Cu")
		(net "GND")
	)
	(segment
		(start 94.071186 -167.158924)
		(end 94.067376 -167.162734)
		(width 0.508)
		(layer "F.Cu")
		(net "GND")
	)
	(segment
		(start 124.85116 -186.96686)
		(end 124.94006 -186.87796)
		(width 0.381)
		(layer "F.Cu")
		(net "GND")
	)
	(segment
		(start 74.7903 -81.844642)
		(end 74.250042 -81.844642)
		(width 0.254)
		(layer "F.Cu")
		(net "GND")
	)
	(segment
		(start 56.315864 -63.86703)
		(end 56.315864 -63.160402)
		(width 0.3048)
		(layer "F.Cu")
		(net "GND")
	)
	(segment
		(start 42.70248 -87.284814)
		(end 41.88968 -87.284814)
		(width 0.381)
		(layer "F.Cu")
		(net "GND")
	)
	(segment
		(start 73.8378 -74.553318)
		(end 73.9267 -74.464418)
		(width 0.3048)
		(layer "F.Cu")
		(net "GND")
	)
	(segment
		(start 131.81076 -184.653174)
		(end 131.81076 -183.772302)
		(width 0.508)
		(layer "F.Cu")
		(net "GND")
	)
	(segment
		(start 70.964044 -70.310502)
		(end 70.964044 -69.610478)
		(width 0.3048)
		(layer "F.Cu")
		(net "GND")
	)
	(segment
		(start 177.010568 -122.36577)
		(end 177.010314 -122.36577)
		(width 0.381)
		(layer "F.Cu")
		(net "GND")
	)
	(segment
		(start 118.049548 -111.43107)
		(end 116.249196 -111.43107)
		(width 0.254)
		(layer "F.Cu")
		(net "GND")
	)
	(segment
		(start 129.261616 -30.079696)
		(end 129.261616 -31.512002)
		(width 0.254)
		(layer "F.Cu")
		(net "GND")
	)
	(segment
		(start 73.342246 -135.259572)
		(end 73.341738 -135.259572)
		(width 0.3556)
		(layer "F.Cu")
		(net "GND")
	)
	(segment
		(start 45.589444 -86.862666)
		(end 44.899072 -86.862666)
		(width 0.254)
		(layer "F.Cu")
		(net "GND")
	)
	(segment
		(start 50.109628 -87.016844)
		(end 50.109628 -86.879938)
		(width 0.254)
		(layer "F.Cu")
		(net "GND")
	)
	(segment
		(start 75.96886 -160.866582)
		(end 76.611988 -160.223454)
		(width 0.508)
		(layer "F.Cu")
		(net "GND")
	)
	(segment
		(start 56.484266 -67.358006)
		(end 56.877966 -66.964306)
		(width 0.3048)
		(layer "F.Cu")
		(net "GND")
	)
	(segment
		(start 91.5035 -183.34228)
		(end 91.7829 -183.06288)
		(width 0.508)
		(layer "F.Cu")
		(net "GND")
	)
	(segment
		(start 121.2596 -137.824718)
		(end 117.334792 -141.749526)
		(width 0.254)
		(layer "F.Cu")
		(net "GND")
	)
	(segment
		(start 74.95794 -66.792094)
		(end 74.852784 -66.89725)
		(width 0.254)
		(layer "F.Cu")
		(net "GND")
	)
	(segment
		(start 62.80658 -80.194658)
		(end 62.809374 -80.194658)
		(width 0.3556)
		(layer "F.Cu")
		(net "GND")
	)
	(segment
		(start 42.70248 -61.94933)
		(end 42.70248 -62.68847)
		(width 0.381)
		(layer "F.Cu")
		(net "GND")
	)
	(segment
		(start 62.401196 -80.600042)
		(end 62.80658 -80.194658)
		(width 0.3556)
		(layer "F.Cu")
		(net "GND")
	)
	(segment
		(start 73.298558 -65.688972)
		(end 73.298558 -66.144394)
		(width 0.3048)
		(layer "F.Cu")
		(net "GND")
	)
	(segment
		(start 61.503306 -81.281016)
		(end 61.279532 -81.057242)
		(width 0.3048)
		(layer "F.Cu")
		(net "GND")
	)
	(segment
		(start 57.530746 -84.619846)
		(end 56.952134 -84.041234)
		(width 0.3048)
		(layer "F.Cu")
		(net "GND")
	)
	(segment
		(start 52.360576 -64.129158)
		(end 52.382928 -64.15151)
		(width 0.3048)
		(layer "F.Cu")
		(net "GND")
	)
	(segment
		(start 70.9422 -140.05941)
		(end 70.941692 -140.05941)
		(width 0.3556)
		(layer "F.Cu")
		(net "GND")
	)
	(segment
		(start 124.10821 -171.603416)
		(end 124.753878 -171.603416)
		(width 0.508)
		(layer "F.Cu")
		(net "GND")
	)
	(segment
		(start 39.247318 -130.538474)
		(end 39.272718 -130.563874)
		(width 0.3556)
		(layer "F.Cu")
		(net "GND")
	)
	(segment
		(start 154.632914 -186.88685)
		(end 155.05176 -187.305696)
		(width 0.508)
		(layer "F.Cu")
		(net "GND")
	)
	(segment
		(start 59.740546 -88.30564)
		(end 59.685428 -88.360758)
		(width 0.3048)
		(layer "F.Cu")
		(net "GND")
	)
	(segment
		(start 42.711116 -86.49589)
		(end 42.515282 -86.691724)
		(width 0.381)
		(layer "F.Cu")
		(net "GND")
	)
	(segment
		(start 136.025636 -164.695378)
		(end 136.025636 -163.358576)
		(width 0.254)
		(layer "F.Cu")
		(net "GND")
	)
	(segment
		(start 62.691264 -149.137624)
		(end 63.383414 -149.137624)
		(width 0.508)
		(layer "F.Cu")
		(net "GND")
	)
	(segment
		(start 58.971688 -98.759264)
		(end 59.113166 -98.617786)
		(width 0.4572)
		(layer "F.Cu")
		(net "GND")
	)
	(segment
		(start 55.150766 -84.634578)
		(end 55.544466 -84.240878)
		(width 0.254)
		(layer "F.Cu")
		(net "GND")
	)
	(segment
		(start 59.383422 -68.503038)
		(end 59.756802 -68.876418)
		(width 0.3048)
		(layer "F.Cu")
		(net "GND")
	)
	(segment
		(start 167.558212 -174.766478)
		(end 168.41216 -174.766478)
		(width 0.508)
		(layer "F.Cu")
		(net "GND")
	)
	(segment
		(start 13.125196 -135.485632)
		(end 16.463264 -135.485632)
		(width 0.254)
		(layer "F.Cu")
		(net "GND")
	)
	(segment
		(start 114.76736 -164.956744)
		(end 115.910868 -164.956744)
		(width 0.3556)
		(layer "F.Cu")
		(net "GND")
	)
	(segment
		(start 177.010568 -119.365522)
		(end 177.010314 -119.365522)
		(width 0.381)
		(layer "F.Cu")
		(net "GND")
	)
	(segment
		(start 135.504682 -45.072046)
		(end 136.250426 -45.81779)
		(width 0.2794)
		(layer "F.Cu")
		(net "GND")
	)
	(segment
		(start 66.780664 -75.569318)
		(end 66.773044 -75.569318)
		(width 0.3048)
		(layer "F.Cu")
		(net "GND")
	)
	(segment
		(start 60.800996 -76.599288)
		(end 60.800996 -76.599542)
		(width 0.254)
		(layer "F.Cu")
		(net "GND")
	)
	(segment
		(start 156.19476 -186.92114)
		(end 156.19476 -187.726574)
		(width 0.508)
		(layer "F.Cu")
		(net "GND")
	)
	(segment
		(start 68.542408 -142.459456)
		(end 68.5419 -142.459456)
		(width 0.3556)
		(layer "F.Cu")
		(net "GND")
	)
	(segment
		(start 91.21267 -180.626512)
		(end 91.468702 -180.626512)
		(width 0.508)
		(layer "F.Cu")
		(net "GND")
	)
	(segment
		(start 81.39176 -187.726574)
		(end 81.39176 -186.951874)
		(width 0.508)
		(layer "F.Cu")
		(net "GND")
	)
	(segment
		(start 50.752248 -76.209398)
		(end 51.158648 -76.615798)
		(width 0.3048)
		(layer "F.Cu")
		(net "GND")
	)
	(segment
		(start 46.562772 -62.556898)
		(end 46.040802 -62.556898)
		(width 0.254)
		(layer "F.Cu")
		(net "GND")
	)
	(segment
		(start 36.787582 -19.453352)
		(end 36.493958 -19.453352)
		(width 0.508)
		(layer "F.Cu")
		(net "GND")
	)
	(segment
		(start 49.228248 -76.029566)
		(end 49.990248 -76.029566)
		(width 0.3048)
		(layer "F.Cu")
		(net "GND")
	)
	(segment
		(start 52.647596 -89.693496)
		(end 52.634896 -89.693496)
		(width 0.254)
		(layer "F.Cu")
		(net "GND")
	)
	(segment
		(start 62.55131 -90.38717)
		(end 62.40018 -90.23604)
		(width 0.254)
		(layer "F.Cu")
		(net "GND")
	)
	(segment
		(start 137.774172 -117.714522)
		(end 136.503664 -117.714522)
		(width 0.1778)
		(layer "F.Cu")
		(net "GND")
	)
	(segment
		(start 74.259948 -77.331824)
		(end 74.250042 -77.34173)
		(width 0.254)
		(layer "F.Cu")
		(net "GND")
	)
	(segment
		(start 172.237146 -99.03841)
		(end 171.939712 -99.335844)
		(width 0.1778)
		(layer "F.Cu")
		(net "GND")
	)
	(segment
		(start 43.45813 -71.161402)
		(end 43.45813 -71.192898)
		(width 0.3048)
		(layer "F.Cu")
		(net "GND")
	)
	(segment
		(start 50.53076 -186.862974)
		(end 50.53076 -187.726574)
		(width 0.508)
		(layer "F.Cu")
		(net "GND")
	)
	(segment
		(start 45.97146 -27.62758)
		(end 46.048422 -27.704542)
		(width 0.4572)
		(layer "F.Cu")
		(net "GND")
	)
	(segment
		(start 42.702734 -85.925914)
		(end 42.702734 -85.909912)
		(width 0.254)
		(layer "F.Cu")
		(net "GND")
	)
	(segment
		(start 66.750692 -106.143044)
		(end 66.990214 -105.903522)
		(width 0.4572)
		(layer "F.Cu")
		(net "GND")
	)
	(segment
		(start 79.971392 -161.0487)
		(end 79.971392 -161.650172)
		(width 0.508)
		(layer "F.Cu")
		(net "GND")
	)
	(segment
		(start 171.14647 -98.935794)
		(end 172.13453 -98.935794)
		(width 0.1778)
		(layer "F.Cu")
		(net "GND")
	)
	(segment
		(start 72.901556 -65.491868)
		(end 72.768968 -65.624456)
		(width 0.3048)
		(layer "F.Cu")
		(net "GND")
	)
	(segment
		(start 60.974478 -89.061798)
		(end 60.961524 -89.048844)
		(width 0.254)
		(layer "F.Cu")
		(net "GND")
	)
	(segment
		(start 138.591036 -156.743908)
		(end 137.58926 -156.743908)
		(width 0.508)
		(layer "F.Cu")
		(net "GND")
	)
	(segment
		(start 67.54241 -4.201414)
		(end 66.875406 -4.201414)
		(width 0.4572)
		(layer "F.Cu")
		(net "GND")
	)
	(segment
		(start 137.123932 -55.93588)
		(end 136.912604 -55.724552)
		(width 0.4572)
		(layer "F.Cu")
		(net "GND")
	)
	(segment
		(start 81.84134 -85.522054)
		(end 82.15884 -85.839554)
		(width 0.508)
		(layer "F.Cu")
		(net "GND")
	)
	(segment
		(start 180.919374 -134.39902)
		(end 180.919374 -133.54939)
		(width 0.508)
		(layer "F.Cu")
		(net "GND")
	)
	(segment
		(start 73.298812 -64.31407)
		(end 73.298812 -64.773048)
		(width 0.3048)
		(layer "F.Cu")
		(net "GND")
	)
	(segment
		(start 72.244712 -175.124618)
		(end 73.37552 -175.124618)
		(width 0.254)
		(layer "F.Cu")
		(net "GND")
	)
	(segment
		(start 28.06446 -100.929948)
		(end 28.6512 -100.929948)
		(width 0.4572)
		(layer "F.Cu")
		(net "GND")
	)
	(segment
		(start 144.502632 -186.914282)
		(end 144.502632 -186.936634)
		(width 0.4572)
		(layer "F.Cu")
		(net "GND")
	)
	(segment
		(start 156.141928 -186.821318)
		(end 156.141928 -186.868308)
		(width 0.508)
		(layer "F.Cu")
		(net "GND")
	)
	(segment
		(start 26.84018 -104.460548)
		(end 26.84018 -104.737662)
		(width 0.4572)
		(layer "F.Cu")
		(net "GND")
	)
	(segment
		(start 59.044078 -86.343744)
		(end 58.525156 -86.862666)
		(width 0.254)
		(layer "F.Cu")
		(net "GND")
	)
	(segment
		(start 157.33776 -186.901328)
		(end 157.33776 -187.726574)
		(width 0.508)
		(layer "F.Cu")
		(net "GND")
	)
	(segment
		(start 104.73182 -64.404494)
		(end 104.73182 -64.406526)
		(width 0.3048)
		(layer "F.Cu")
		(net "GND")
	)
	(segment
		(start 49.290224 -65.201038)
		(end 49.608994 -64.882268)
		(width 0.254)
		(layer "F.Cu")
		(net "GND")
	)
	(segment
		(start 150.347172 -165.95979)
		(end 151.062182 -165.95979)
		(width 0.4572)
		(layer "F.Cu")
		(net "GND")
	)
	(segment
		(start 52.634896 -89.693496)
		(end 52.634896 -88.605106)
		(width 0.254)
		(layer "F.Cu")
		(net "GND")
	)
	(segment
		(start 62.94247 -140.05941)
		(end 63.340996 -140.457936)
		(width 0.3556)
		(layer "F.Cu")
		(net "GND")
	)
	(segment
		(start 67.547236 -4.196588)
		(end 67.54241 -4.201414)
		(width 0.4572)
		(layer "F.Cu")
		(net "GND")
	)
	(segment
		(start 72.063864 -70.928992)
		(end 72.063864 -70.889368)
		(width 0.3048)
		(layer "F.Cu")
		(net "GND")
	)
	(segment
		(start 46.942248 -75.30211)
		(end 46.942248 -75.329542)
		(width 0.3048)
		(layer "F.Cu")
		(net "GND")
	)
	(segment
		(start 43.920156 -76.913994)
		(end 43.87723 -76.871068)
		(width 0.3048)
		(layer "F.Cu")
		(net "GND")
	)
	(segment
		(start 60.141104 -129.258314)
		(end 60.541916 -129.659126)
		(width 0.381)
		(layer "F.Cu")
		(net "GND")
	)
	(segment
		(start 47.880016 -64.18707)
		(end 47.864268 -64.171322)
		(width 0.3048)
		(layer "F.Cu")
		(net "GND")
	)
	(segment
		(start 152.27046 -146.025362)
		(end 151.51862 -146.025362)
		(width 0.508)
		(layer "F.Cu")
		(net "GND")
	)
	(segment
		(start 34.478214 -184.193942)
		(end 34.868612 -184.193942)
		(width 0.4572)
		(layer "F.Cu")
		(net "GND")
	)
	(segment
		(start 54.033166 -97.507044)
		(end 54.033166 -97.110042)
		(width 0.4572)
		(layer "F.Cu")
		(net "GND")
	)
	(segment
		(start 73.715372 -77.61732)
		(end 74.0283 -77.61732)
		(width 0.3048)
		(layer "F.Cu")
		(net "GND")
	)
	(segment
		(start 40.033194 -138.563604)
		(end 39.38524 -138.563604)
		(width 0.3556)
		(layer "F.Cu")
		(net "GND")
	)
	(segment
		(start 124.596652 -144.22755)
		(end 124.672852 -144.15135)
		(width 0.1778)
		(layer "F.Cu")
		(net "GND")
	)
	(segment
		(start 125.94336 -187.023248)
		(end 125.984 -186.982608)
		(width 0.381)
		(layer "F.Cu")
		(net "GND")
	)
	(segment
		(start 43.053 -81.416906)
		(end 43.043094 -81.407)
		(width 0.3048)
		(layer "F.Cu")
		(net "GND")
	)
	(segment
		(start 106.873548 -179.031646)
		(end 106.826558 -178.984656)
		(width 0.4572)
		(layer "F.Cu")
		(net "GND")
	)
	(segment
		(start 46.432978 -136.163558)
		(end 46.432978 -136.164574)
		(width 0.3556)
		(layer "F.Cu")
		(net "GND")
	)
	(segment
		(start 79.146146 -160.223454)
		(end 79.971392 -161.0487)
		(width 0.508)
		(layer "F.Cu")
		(net "GND")
	)
	(segment
		(start 41.228518 -63.468758)
		(end 41.251378 -63.491618)
		(width 0.381)
		(layer "F.Cu")
		(net "GND")
	)
	(segment
		(start 175.010318 -122.36577)
		(end 174.510446 -122.865642)
		(width 0.508)
		(layer "F.Cu")
		(net "GND")
	)
	(segment
		(start 125.287532 -53.278532)
		(end 126.670054 -53.278532)
		(width 0.4572)
		(layer "F.Cu")
		(net "GND")
	)
	(segment
		(start 65.33896 -141.65961)
		(end 64.940942 -142.057628)
		(width 0.3556)
		(layer "F.Cu")
		(net "GND")
	)
	(segment
		(start 30.710886 -171.32046)
		(end 31.264098 -171.32046)
		(width 0.508)
		(layer "F.Cu")
		(net "GND")
	)
	(segment
		(start 69.821044 -69.237098)
		(end 70.194424 -69.610478)
		(width 0.3048)
		(layer "F.Cu")
		(net "GND")
	)
	(segment
		(start 18.01495 -205.199488)
		(end 18.01495 -201.09053)
		(width 0.508)
		(layer "F.Cu")
		(net "GND")
	)
	(segment
		(start 64.861186 -67.705478)
		(end 64.515746 -67.360038)
		(width 0.254)
		(layer "F.Cu")
		(net "GND")
	)
	(segment
		(start 72.5424 -143.259556)
		(end 72.541892 -143.259556)
		(width 0.3556)
		(layer "F.Cu")
		(net "GND")
	)
	(segment
		(start 123.75896 -187.040774)
		(end 123.93676 -186.862974)
		(width 0.508)
		(layer "F.Cu")
		(net "GND")
	)
	(segment
		(start 43.983656 -65.476882)
		(end 43.986958 -65.476882)
		(width 0.3048)
		(layer "F.Cu")
		(net "GND")
	)
	(segment
		(start 43.51528 -62.68847)
		(end 44.32808 -62.68847)
		(width 0.381)
		(layer "F.Cu")
		(net "GND")
	)
	(segment
		(start 51.812952 -63.160402)
		(end 51.812952 -63.86703)
		(width 0.3048)
		(layer "F.Cu")
		(net "GND")
	)
	(segment
		(start 126.015242 -58.62828)
		(end 126.015242 -59.309)
		(width 0.4572)
		(layer "F.Cu")
		(net "GND")
	)
	(segment
		(start 64.437514 -65.240916)
		(end 65.083436 -64.594994)
		(width 0.254)
		(layer "F.Cu")
		(net "GND")
	)
	(segment
		(start 67.742308 -136.859518)
		(end 67.7418 -136.859518)
		(width 0.381)
		(layer "F.Cu")
		(net "GND")
	)
	(segment
		(start 108.764832 -66.575686)
		(end 108.764832 -66.827654)
		(width 0.3048)
		(layer "F.Cu")
		(net "GND")
	)
	(segment
		(start 59.335924 -89.129362)
		(end 59.335924 -89.048844)
		(width 0.254)
		(layer "F.Cu")
		(net "GND")
	)
	(segment
		(start 66.223388 -87.548466)
		(end 66.441828 -87.330026)
		(width 0.3048)
		(layer "F.Cu")
		(net "GND")
	)
	(segment
		(start 15.425166 -51.898804)
		(end 14.668246 -51.898804)
		(width 0.4572)
		(layer "F.Cu")
		(net "GND")
	)
	(segment
		(start 45.784516 -78.645766)
		(end 45.784516 -78.908402)
		(width 0.3048)
		(layer "F.Cu")
		(net "GND")
	)
	(segment
		(start 55.544466 -85.000846)
		(end 55.544466 -85.002878)
		(width 0.254)
		(layer "F.Cu")
		(net "GND")
	)
	(segment
		(start 127.951992 -137.21969)
		(end 128.53797 -136.633712)
		(width 0.1778)
		(layer "F.Cu")
		(net "GND")
	)
	(segment
		(start 105.13822 -162.51174)
		(end 105.002838 -162.51174)
		(width 0.508)
		(layer "F.Cu")
		(net "GND")
	)
	(segment
		(start 46.432978 -140.165074)
		(end 46.432978 -140.16355)
		(width 0.3556)
		(layer "F.Cu")
		(net "GND")
	)
	(segment
		(start 65.341754 -140.85951)
		(end 65.339214 -140.85951)
		(width 0.3556)
		(layer "F.Cu")
		(net "GND")
	)
	(segment
		(start 44.713398 -79.244952)
		(end 44.656248 -79.302102)
		(width 0.3048)
		(layer "F.Cu")
		(net "GND")
	)
	(segment
		(start 81.84134 -85.520784)
		(end 81.84134 -85.522054)
		(width 0.508)
		(layer "F.Cu")
		(net "GND")
	)
	(segment
		(start 80.363568 -85.93328)
		(end 81.108042 -85.93328)
		(width 0.508)
		(layer "F.Cu")
		(net "GND")
	)
	(segment
		(start 65.34658 -7.450836)
		(end 65.37325 -7.424166)
		(width 0.508)
		(layer "F.Cu")
		(net "GND")
	)
	(segment
		(start 118.47576 -184.805574)
		(end 118.47576 -184.01411)
		(width 0.508)
		(layer "F.Cu")
		(net "GND")
	)
	(segment
		(start 151.62276 -183.769508)
		(end 151.62276 -184.805574)
		(width 0.508)
		(layer "F.Cu")
		(net "GND")
	)
	(segment
		(start 44.327572 -62.163706)
		(end 44.32808 -62.163706)
		(width 0.381)
		(layer "F.Cu")
		(net "GND")
	)
	(segment
		(start 66.392044 -77.555598)
		(end 66.392044 -78.255622)
		(width 0.3048)
		(layer "F.Cu")
		(net "GND")
	)
	(segment
		(start 134.22376 -187.021216)
		(end 134.22376 -186.862974)
		(width 0.381)
		(layer "F.Cu")
		(net "GND")
	)
	(segment
		(start 169.57421 -171.95292)
		(end 168.87698 -171.95292)
		(width 0.508)
		(layer "F.Cu")
		(net "GND")
	)
	(segment
		(start 99.531678 -181.315106)
		(end 99.206812 -181.315106)
		(width 0.4064)
		(layer "F.Cu")
		(net "GND")
	)
	(segment
		(start 136.161272 -159.850074)
		(end 136.161272 -159.848804)
		(width 0.508)
		(layer "F.Cu")
		(net "GND")
	)
	(segment
		(start 74.250042 -69.961506)
		(end 75.007978 -69.961506)
		(width 0.3048)
		(layer "F.Cu")
		(net "GND")
	)
	(segment
		(start 57.600596 -78.199742)
		(end 57.200546 -78.599792)
		(width 0.3556)
		(layer "F.Cu")
		(net "GND")
	)
	(segment
		(start 102.234746 -140.752322)
		(end 102.393496 -140.911072)
		(width 0.4572)
		(layer "F.Cu")
		(net "GND")
	)
	(segment
		(start 43.249088 -70.513194)
		(end 43.249088 -70.04304)
		(width 0.254)
		(layer "F.Cu")
		(net "GND")
	)
	(segment
		(start 64.539876 -132.859526)
		(end 64.141096 -133.258306)
		(width 0.3556)
		(layer "F.Cu")
		(net "GND")
	)
	(segment
		(start 107.041188 -128.746758)
		(end 107.134152 -128.746758)
		(width 0.4572)
		(layer "F.Cu")
		(net "GND")
	)
	(segment
		(start 82.56016 -121.952766)
		(end 82.56016 -121.951496)
		(width 0.2032)
		(layer "F.Cu")
		(net "GND")
	)
	(segment
		(start 9.108948 -158.220156)
		(end 9.108948 -156.731208)
		(width 0.381)
		(layer "F.Cu")
		(net "GND")
	)
	(segment
		(start 60.212478 -81.952846)
		(end 59.90082 -81.641188)
		(width 0.3048)
		(layer "F.Cu")
		(net "GND")
	)
	(segment
		(start 31.614618 -171.67098)
		(end 31.614618 -171.671234)
		(width 0.508)
		(layer "F.Cu")
		(net "GND")
	)
	(segment
		(start 88.950292 -20.94992)
		(end 88.950292 -22.422358)
		(width 0.381)
		(layer "F.Cu")
		(net "GND")
	)
	(segment
		(start 64.940942 -141.257782)
		(end 64.54267 -140.85951)
		(width 0.3556)
		(layer "F.Cu")
		(net "GND")
	)
	(segment
		(start 20.921472 -74.607928)
		(end 20.921472 -75.47229)
		(width 0.4572)
		(layer "F.Cu")
		(net "GND")
	)
	(segment
		(start 137.017252 -63.582042)
		(end 137.559288 -64.124078)
		(width 0.4572)
		(layer "F.Cu")
		(net "GND")
	)
	(segment
		(start 68.81876 -187.726574)
		(end 68.81876 -186.853068)
		(width 0.508)
		(layer "F.Cu")
		(net "GND")
	)
	(segment
		(start 155.86456 -86.313772)
		(end 155.86456 -85.594444)
		(width 0.508)
		(layer "F.Cu")
		(net "GND")
	)
	(segment
		(start 63.121286 -86.158578)
		(end 63.489586 -85.790278)
		(width 0.254)
		(layer "F.Cu")
		(net "GND")
	)
	(segment
		(start 80.994758 -179.874672)
		(end 80.994758 -178.898804)
		(width 0.254)
		(layer "F.Cu")
		(net "GND")
	)
	(segment
		(start 90.702384 -186.826398)
		(end 90.702384 -186.175904)
		(width 0.508)
		(layer "F.Cu")
		(net "GND")
	)
	(segment
		(start 19.78533 -43.84167)
		(end 20.58162 -43.84167)
		(width 0.508)
		(layer "F.Cu")
		(net "GND")
	)
	(segment
		(start 60.878466 -87.427816)
		(end 60.605924 -87.700358)
		(width 0.3048)
		(layer "F.Cu")
		(net "GND")
	)
	(segment
		(start 63.741808 -132.859526)
		(end 63.739776 -132.859526)
		(width 0.3556)
		(layer "F.Cu")
		(net "GND")
	)
	(segment
		(start 70.683882 -62.047374)
		(end 70.181216 -62.55004)
		(width 0.254)
		(layer "F.Cu")
		(net "GND")
	)
	(segment
		(start 175.901604 -138.95451)
		(end 176.947576 -138.95451)
		(width 0.508)
		(layer "F.Cu")
		(net "GND")
	)
	(segment
		(start 159.60852 -187.711334)
		(end 159.62376 -187.726574)
		(width 0.508)
		(layer "F.Cu")
		(net "GND")
	)
	(segment
		(start 151.26081 -31.18485)
		(end 152.429972 -31.18485)
		(width 0.3556)
		(layer "F.Cu")
		(net "GND")
	)
	(segment
		(start 41.068498 -78.904084)
		(end 41.212516 -78.760066)
		(width 0.254)
		(layer "F.Cu")
		(net "GND")
	)
	(segment
		(start 157.821376 -173.552358)
		(end 159.375602 -173.552358)
		(width 0.381)
		(layer "F.Cu")
		(net "GND")
	)
	(segment
		(start 24.375872 -94.261178)
		(end 24.375872 -93.424756)
		(width 0.508)
		(layer "F.Cu")
		(net "GND")
	)
	(segment
		(start 153.908252 -186.85891)
		(end 153.908252 -187.726066)
		(width 0.508)
		(layer "F.Cu")
		(net "GND")
	)
	(segment
		(start 64.514222 -174.752508)
		(end 64.514222 -175.707548)
		(width 0.4572)
		(layer "F.Cu")
		(net "GND")
	)
	(segment
		(start 72.09028 -100.651564)
		(end 72.250554 -100.49129)
		(width 0.508)
		(layer "F.Cu")
		(net "GND")
	)
	(segment
		(start 156.186886 -171.496482)
		(end 156.186886 -170.672252)
		(width 0.508)
		(layer "F.Cu")
		(net "GND")
	)
	(segment
		(start 71.807578 -76.031852)
		(end 71.807578 -76.157582)
		(width 0.3048)
		(layer "F.Cu")
		(net "GND")
	)
	(segment
		(start 44.642024 -72.918574)
		(end 44.642024 -72.948038)
		(width 0.3048)
		(layer "F.Cu")
		(net "GND")
	)
	(segment
		(start 49.609248 -74.043286)
		(end 49.163478 -74.489056)
		(width 0.3048)
		(layer "F.Cu")
		(net "GND")
	)
	(segment
		(start 34.074354 -12.03198)
		(end 34.0741 -12.03198)
		(width 0.254)
		(layer "F.Cu")
		(net "GND")
	)
	(segment
		(start 62.211458 -86.862666)
		(end 61.889386 -86.862666)
		(width 0.254)
		(layer "F.Cu")
		(net "GND")
	)
	(segment
		(start 65.338706 -143.259556)
		(end 64.940942 -143.65732)
		(width 0.3556)
		(layer "F.Cu")
		(net "GND")
	)
	(segment
		(start 110.460028 -74.906124)
		(end 112.033304 -74.906124)
		(width 0.3048)
		(layer "F.Cu")
		(net "GND")
	)
	(segment
		(start 128.940052 -132.6007)
		(end 128.171702 -132.6007)
		(width 0.4572)
		(layer "F.Cu")
		(net "GND")
	)
	(segment
		(start 68.355718 -89.062814)
		(end 68.341748 -89.048844)
		(width 0.254)
		(layer "F.Cu")
		(net "GND")
	)
	(segment
		(start 52.539138 -66.598038)
		(end 52.511706 -66.598038)
		(width 0.254)
		(layer "F.Cu")
		(net "GND")
	)
	(segment
		(start 12.854178 -161.882328)
		(end 14.035024 -161.882328)
		(width 0.508)
		(layer "F.Cu")
		(net "GND")
	)
	(segment
		(start 64.429386 -68.887086)
		(end 64.429386 -68.884038)
		(width 0.254)
		(layer "F.Cu")
		(net "GND")
	)
	(segment
		(start 91.21267 -178.594512)
		(end 91.21267 -177.578512)
		(width 0.508)
		(layer "F.Cu")
		(net "GND")
	)
	(segment
		(start 24.426672 -58.830972)
		(end 24.426672 -57.362344)
		(width 0.508)
		(layer "F.Cu")
		(net "GND")
	)
	(segment
		(start 116.226082 -17.575276)
		(end 116.226082 -16.861536)
		(width 0.4572)
		(layer "F.Cu")
		(net "GND")
	)
	(segment
		(start 66.01333 -170.630088)
		(end 65.346834 -170.630088)
		(width 0.4572)
		(layer "F.Cu")
		(net "GND")
	)
	(segment
		(start 56.27624 -84.238846)
		(end 56.24449 -84.238846)
		(width 0.3048)
		(layer "F.Cu")
		(net "GND")
	)
	(segment
		(start 43.249088 -70.513194)
		(end 43.307762 -70.571868)
		(width 0.3048)
		(layer "F.Cu")
		(net "GND")
	)
	(segment
		(start 135.01878 -181.95163)
		(end 135.717788 -181.95163)
		(width 0.4572)
		(layer "F.Cu")
		(net "GND")
	)
	(segment
		(start 112.76076 -186.862974)
		(end 112.76076 -187.726574)
		(width 0.508)
		(layer "F.Cu")
		(net "GND")
	)
	(segment
		(start 178.059842 -139.65301)
		(end 178.059842 -140.629132)
		(width 0.508)
		(layer "F.Cu")
		(net "GND")
	)
	(segment
		(start 43.980354 -108.598208)
		(end 43.980354 -109.0549)
		(width 0.254)
		(layer "F.Cu")
		(net "GND")
	)
	(segment
		(start 68.940934 -1.859026)
		(end 69.114416 -1.685544)
		(width 0.508)
		(layer "F.Cu")
		(net "GND")
	)
	(segment
		(start 45.633132 -137.765282)
		(end 46.03242 -138.16457)
		(width 0.3556)
		(layer "F.Cu")
		(net "GND")
	)
	(segment
		(start 125.787912 -139.775438)
		(end 126.90094 -139.775438)
		(width 0.1778)
		(layer "F.Cu")
		(net "GND")
	)
	(segment
		(start 158.038546 -127.314452)
		(end 158.038546 -128.65989)
		(width 0.508)
		(layer "F.Cu")
		(net "GND")
	)
	(segment
		(start 131.185412 -56.252872)
		(end 130.429 -56.252872)
		(width 0.4572)
		(layer "F.Cu")
		(net "GND")
	)
	(segment
		(start 68.39204 -5.696204)
		(end 68.622418 -5.696204)
		(width 0.254)
		(layer "F.Cu")
		(net "GND")
	)
	(segment
		(start 142.07236 -137.775442)
		(end 141.288008 -137.775442)
		(width 0.1778)
		(layer "F.Cu")
		(net "GND")
	)
	(segment
		(start 88.753188 -186.91352)
		(end 88.94572 -186.91352)
		(width 0.508)
		(layer "F.Cu")
		(net "GND")
	)
	(segment
		(start 48.847248 -69.370702)
		(end 48.686212 -69.209666)
		(width 0.3048)
		(layer "F.Cu")
		(net "GND")
	)
	(segment
		(start 70.14337 -140.85951)
		(end 70.141846 -140.85951)
		(width 0.3556)
		(layer "F.Cu")
		(net "GND")
	)
	(segment
		(start 41.127172 -64.588898)
		(end 41.665144 -65.12687)
		(width 0.4064)
		(layer "F.Cu")
		(net "GND")
	)
	(segment
		(start 43.417998 -66.179192)
		(end 43.249088 -66.010282)
		(width 0.3048)
		(layer "F.Cu")
		(net "GND")
	)
	(segment
		(start 49.343818 -86.804246)
		(end 49.402238 -86.862666)
		(width 0.254)
		(layer "F.Cu")
		(net "GND")
	)
	(segment
		(start 67.462146 -85.000846)
		(end 68.16217 -85.000846)
		(width 0.254)
		(layer "F.Cu")
		(net "GND")
	)
	(segment
		(start 179.015644 -205.199488)
		(end 179.015644 -200.983596)
		(width 0.508)
		(layer "F.Cu")
		(net "GND")
	)
	(segment
		(start 41.88968 -63.468758)
		(end 41.88968 -62.68847)
		(width 0.3048)
		(layer "F.Cu")
		(net "GND")
	)
	(segment
		(start 127.875792 -137.21969)
		(end 127.951992 -137.21969)
		(width 0.1778)
		(layer "F.Cu")
		(net "GND")
	)
	(segment
		(start 9.38022 -154.46375)
		(end 9.381998 -154.46375)
		(width 0.508)
		(layer "F.Cu")
		(net "GND")
	)
	(segment
		(start 156.779468 -173.405038)
		(end 157.674056 -173.405038)
		(width 0.508)
		(layer "F.Cu")
		(net "GND")
	)
	(segment
		(start 68.121276 -87.343742)
		(end 68.121276 -86.879938)
		(width 0.254)
		(layer "F.Cu")
		(net "GND")
	)
	(segment
		(start 51.223418 -70.275196)
		(end 51.223418 -69.733668)
		(width 0.3048)
		(layer "F.Cu")
		(net "GND")
	)
	(segment
		(start 64.015112 -204.699616)
		(end 64.015112 -201.09053)
		(width 0.508)
		(layer "F.Cu")
		(net "GND")
	)
	(segment
		(start 107.993942 -174.901352)
		(end 107.42549 -174.3329)
		(width 0.508)
		(layer "F.Cu")
		(net "GND")
	)
	(segment
		(start 63.340996 -133.258306)
		(end 63.741808 -133.659118)
		(width 0.381)
		(layer "F.Cu")
		(net "GND")
	)
	(segment
		(start 60.850526 -65.440306)
		(end 61.160914 -65.129918)
		(width 0.254)
		(layer "F.Cu")
		(net "GND")
	)
	(segment
		(start 148.937726 -149.864318)
		(end 148.937726 -148.793454)
		(width 0.508)
		(layer "F.Cu")
		(net "GND")
	)
	(segment
		(start 44.029122 -81.416906)
		(end 43.920156 -81.416906)
		(width 0.254)
		(layer "F.Cu")
		(net "GND")
	)
	(segment
		(start 47.880016 -64.725804)
		(end 47.880016 -64.18707)
		(width 0.3048)
		(layer "F.Cu")
		(net "GND")
	)
	(segment
		(start 100.226622 -158.52521)
		(end 100.228146 -158.523686)
		(width 0.4572)
		(layer "F.Cu")
		(net "GND")
	)
	(segment
		(start 13.894562 -30.250384)
		(end 13.894562 -31.190184)
		(width 0.508)
		(layer "F.Cu")
		(net "GND")
	)
	(segment
		(start 46.96968 -129.191004)
		(end 46.74235 -128.963674)
		(width 0.254)
		(layer "F.Cu")
		(net "GND")
	)
	(segment
		(start 34.0741 -12.03198)
		(end 33.5407 -12.56538)
		(width 0.254)
		(layer "F.Cu")
		(net "GND")
	)
	(segment
		(start 58.971688 -98.758756)
		(end 58.971688 -98.759264)
		(width 0.4572)
		(layer "F.Cu")
		(net "GND")
	)
	(segment
		(start 166.41318 -161.79546)
		(end 166.41318 -162.415728)
		(width 0.4572)
		(layer "F.Cu")
		(net "GND")
	)
	(segment
		(start 59.67476 -184.805574)
		(end 59.67476 -183.97855)
		(width 0.508)
		(layer "F.Cu")
		(net "GND")
	)
	(segment
		(start 51.781456 -63.898526)
		(end 52.012088 -64.129158)
		(width 0.3048)
		(layer "F.Cu")
		(net "GND")
	)
	(segment
		(start 63.729362 -68.884038)
		(end 63.729362 -69.646038)
		(width 0.254)
		(layer "F.Cu")
		(net "GND")
	)
	(segment
		(start 50.752248 -70.712838)
		(end 50.752248 -71.356982)
		(width 0.3048)
		(layer "F.Cu")
		(net "GND")
	)
	(segment
		(start 68.219066 -5.52323)
		(end 68.39204 -5.696204)
		(width 0.254)
		(layer "F.Cu")
		(net "GND")
	)
	(segment
		(start 83.67776 -187.726574)
		(end 83.67776 -186.896756)
		(width 0.508)
		(layer "F.Cu")
		(net "GND")
	)
	(segment
		(start 80.145382 -97.726246)
		(end 80.202532 -97.669096)
		(width 0.4572)
		(layer "F.Cu")
		(net "GND")
	)
	(segment
		(start 47.186596 -63.990474)
		(end 47.186596 -64.594994)
		(width 0.3048)
		(layer "F.Cu")
		(net "GND")
	)
	(segment
		(start 63.741808 -140.05941)
		(end 63.739522 -140.05941)
		(width 0.3556)
		(layer "F.Cu")
		(net "GND")
	)
	(segment
		(start 47.241714 -71.057516)
		(end 46.942248 -71.356982)
		(width 0.3048)
		(layer "F.Cu")
		(net "GND")
	)
	(segment
		(start 64.18961 -81.780888)
		(end 63.90132 -81.492598)
		(width 0.3048)
		(layer "F.Cu")
		(net "GND")
	)
	(segment
		(start 73.994264 -81.588864)
		(end 74.250042 -81.844642)
		(width 0.254)
		(layer "F.Cu")
		(net "GND")
	)
	(segment
		(start 172.13453 -98.935794)
		(end 172.237146 -99.03841)
		(width 0.1778)
		(layer "F.Cu")
		(net "GND")
	)
	(segment
		(start 43.986958 -83.48853)
		(end 44.200826 -83.274662)
		(width 0.3048)
		(layer "F.Cu")
		(net "GND")
	)
	(segment
		(start 93.015054 -205.199488)
		(end 93.015054 -200.907904)
		(width 0.508)
		(layer "F.Cu")
		(net "GND")
	)
	(segment
		(start 43.87723 -76.871068)
		(end 42.82694 -76.871068)
		(width 0.3048)
		(layer "F.Cu")
		(net "GND")
	)
	(segment
		(start 107.09402 -164.769546)
		(end 106.570526 -164.769546)
		(width 0.4572)
		(layer "F.Cu")
		(net "GND")
	)
	(segment
		(start 41.533572 -61.972698)
		(end 41.533572 -62.332362)
		(width 0.3048)
		(layer "F.Cu")
		(net "GND")
	)
	(segment
		(start 105.958894 -68.906136)
		(end 104.73182 -68.906136)
		(width 0.3048)
		(layer "F.Cu")
		(net "GND")
	)
	(segment
		(start 66.142108 -135.259572)
		(end 66.141854 -135.259572)
		(width 0.381)
		(layer "F.Cu")
		(net "GND")
	)
	(segment
		(start 45.14088 -88.910414)
		(end 45.14088 -89.540588)
		(width 0.381)
		(layer "F.Cu")
		(net "GND")
	)
	(segment
		(start 43.307762 -70.571868)
		(end 43.827192 -70.571868)
		(width 0.3048)
		(layer "F.Cu")
		(net "GND")
	)
	(segment
		(start 139.000992 -26.202894)
		(end 139.000992 -27.071828)
		(width 0.508)
		(layer "F.Cu")
		(net "GND")
	)
	(segment
		(start 138.922252 -155.194)
		(end 138.922252 -155.912312)
		(width 0.508)
		(layer "F.Cu")
		(net "GND")
	)
	(segment
		(start 32.27324 -116.848382)
		(end 32.27324 -116.85016)
		(width 0.508)
		(layer "F.Cu")
		(net "GND")
	)
	(segment
		(start 66.394076 -78.255622)
		(end 66.392044 -78.255622)
		(width 0.3048)
		(layer "F.Cu")
		(net "GND")
	)
	(segment
		(start 67.3862 -178.341274)
		(end 67.555364 -178.510438)
		(width 0.508)
		(layer "F.Cu")
		(net "GND")
	)
	(segment
		(start 140.692886 -51.876706)
		(end 140.692886 -52.679854)
		(width 0.508)
		(layer "F.Cu")
		(net "GND")
	)
	(segment
		(start 65.339722 -132.859526)
		(end 64.940942 -133.258306)
		(width 0.3556)
		(layer "F.Cu")
		(net "GND")
	)
	(segment
		(start 152.945846 -60.01893)
		(end 153.841196 -60.01893)
		(width 0.508)
		(layer "F.Cu")
		(net "GND")
	)
	(segment
		(start 47.302166 -82.896964)
		(end 46.942248 -83.256882)
		(width 0.3048)
		(layer "F.Cu")
		(net "GND")
	)
	(segment
		(start 46.942248 -72.057006)
		(end 46.942248 -71.356982)
		(width 0.3048)
		(layer "F.Cu")
		(net "GND")
	)
	(segment
		(start 69.092572 -79.541878)
		(end 69.059044 -79.541878)
		(width 0.3048)
		(layer "F.Cu")
		(net "GND")
	)
	(segment
		(start 83.550252 -22.653498)
		(end 83.550252 -20.94992)
		(width 0.381)
		(layer "F.Cu")
		(net "GND")
	)
	(segment
		(start 73.711816 -78.54569)
		(end 73.63968 -78.617826)
		(width 0.3048)
		(layer "F.Cu")
		(net "GND")
	)
	(segment
		(start 55.988712 -148.290788)
		(end 55.988712 -147.388834)
		(width 0.508)
		(layer "F.Cu")
		(net "GND")
	)
	(segment
		(start 136.240012 -159.928814)
		(end 136.161272 -159.850074)
		(width 0.508)
		(layer "F.Cu")
		(net "GND")
	)
	(segment
		(start 93.72473 -174.306992)
		(end 94.051882 -174.306992)
		(width 0.508)
		(layer "F.Cu")
		(net "GND")
	)
	(segment
		(start 77.86116 -183.963564)
		(end 77.86116 -184.703974)
		(width 0.508)
		(layer "F.Cu")
		(net "GND")
	)
	(segment
		(start 170.443144 -96.590358)
		(end 170.443144 -96.943672)
		(width 0.254)
		(layer "F.Cu")
		(net "GND")
	)
	(segment
		(start 68.199508 -87.421974)
		(end 68.121276 -87.343742)
		(width 0.254)
		(layer "F.Cu")
		(net "GND")
	)
	(segment
		(start 82.98942 -154.80792)
		(end 82.987642 -154.80792)
		(width 0.4572)
		(layer "F.Cu")
		(net "GND")
	)
	(segment
		(start 66.62293 -86.40826)
		(end 66.440304 -86.40826)
		(width 0.3048)
		(layer "F.Cu")
		(net "GND")
	)
	(segment
		(start 83.728052 -22.831298)
		(end 83.550252 -22.653498)
		(width 0.381)
		(layer "F.Cu")
		(net "GND")
	)
	(segment
		(start 82.740246 -107.097322)
		(end 82.740246 -106.350054)
		(width 0.508)
		(layer "F.Cu")
		(net "GND")
	)
	(segment
		(start 50.659538 -70.027038)
		(end 50.525426 -70.027038)
		(width 0.3048)
		(layer "F.Cu")
		(net "GND")
	)
	(segment
		(start 63.741808 -133.659118)
		(end 63.741808 -133.659626)
		(width 0.381)
		(layer "F.Cu")
		(net "GND")
	)
	(segment
		(start 171.939712 -99.335844)
		(end 171.14647 -99.335844)
		(width 0.1778)
		(layer "F.Cu")
		(net "GND")
	)
	(segment
		(start 134.753858 -112.982248)
		(end 134.753858 -113.96472)
		(width 0.1778)
		(layer "F.Cu")
		(net "GND")
	)
	(segment
		(start 67.67576 -187.726574)
		(end 67.67576 -186.95162)
		(width 0.508)
		(layer "F.Cu")
		(net "GND")
	)
	(segment
		(start 191.769492 -113.419128)
		(end 192.588642 -113.419128)
		(width 0.508)
		(layer "F.Cu")
		(net "GND")
	)
	(segment
		(start 102.978204 -159.209232)
		(end 103.498142 -158.689294)
		(width 0.4572)
		(layer "F.Cu")
		(net "GND")
	)
	(segment
		(start 149.20976 -166.867332)
		(end 148.9837 -167.093392)
		(width 0.508)
		(layer "F.Cu")
		(net "GND")
	)
	(segment
		(start 40.177974 -3.6703)
		(end 40.177974 -3.042412)
		(width 0.4572)
		(layer "F.Cu")
		(net "GND")
	)
	(segment
		(start 116.18976 -184.805574)
		(end 116.18976 -184.318402)
		(width 0.508)
		(layer "F.Cu")
		(net "GND")
	)
	(segment
		(start 44.656248 -83.123786)
		(end 45.418248 -82.361786)
		(width 0.254)
		(layer "F.Cu")
		(net "GND")
	)
	(segment
		(start 51.811682 -68.884038)
		(end 52.511706 -68.884038)
		(width 0.254)
		(layer "F.Cu")
		(net "GND")
	)
	(segment
		(start 42.536618 -61.783468)
		(end 42.70248 -61.94933)
		(width 0.381)
		(layer "F.Cu")
		(net "GND")
	)
	(segment
		(start 184.614566 -131.002278)
		(end 185.405268 -131.002278)
		(width 0.4572)
		(layer "F.Cu")
		(net "GND")
	)
	(segment
		(start 44.656248 -85.72119)
		(end 44.656248 -85.960966)
		(width 0.3048)
		(layer "F.Cu")
		(net "GND")
	)
	(segment
		(start 111.754158 -70.40626)
		(end 110.460028 -70.40626)
		(width 0.3048)
		(layer "F.Cu")
		(net "GND")
	)
	(segment
		(start 89.004394 -7.667752)
		(end 89.004394 -5.404358)
		(width 0.508)
		(layer "F.Cu")
		(net "GND")
	)
	(segment
		(start 106.425492 -73.627234)
		(end 106.242612 -73.627234)
		(width 0.3048)
		(layer "F.Cu")
		(net "GND")
	)
	(segment
		(start 79.015082 -205.199488)
		(end 79.015082 -201.135234)
		(width 0.508)
		(layer "F.Cu")
		(net "GND")
	)
	(segment
		(start 46.552866 -66.215006)
		(end 46.552866 -66.217038)
		(width 0.254)
		(layer "F.Cu")
		(net "GND")
	)
	(segment
		(start 137.58926 -156.743908)
		(end 136.7536 -155.908248)
		(width 0.508)
		(layer "F.Cu")
		(net "GND")
	)
	(segment
		(start 27.131264 -105.028746)
		(end 27.772868 -105.028746)
		(width 0.4572)
		(layer "F.Cu")
		(net "GND")
	)
	(segment
		(start 50.299874 -62.55004)
		(end 50.536856 -62.55004)
		(width 0.3048)
		(layer "F.Cu")
		(net "GND")
	)
	(segment
		(start 34.709862 -84.339684)
		(end 35.402774 -84.339684)
		(width 0.508)
		(layer "F.Cu")
		(net "GND")
	)
	(segment
		(start 137.626852 -115.779042)
		(end 137.291318 -116.114576)
		(width 0.1778)
		(layer "F.Cu")
		(net "GND")
	)
	(segment
		(start 37.948362 -19.015202)
		(end 37.225732 -19.015202)
		(width 0.508)
		(layer "F.Cu")
		(net "GND")
	)
	(segment
		(start 64.539876 -136.059418)
		(end 64.541908 -136.059418)
		(width 0.381)
		(layer "F.Cu")
		(net "GND")
	)
	(segment
		(start 42.750232 -20.94992)
		(end 42.750232 -22.456648)
		(width 0.381)
		(layer "F.Cu")
		(net "GND")
	)
	(segment
		(start 116.015516 -205.199488)
		(end 116.015516 -201.034904)
		(width 0.508)
		(layer "F.Cu")
		(net "GND")
	)
	(segment
		(start 174.646336 -62.734952)
		(end 174.646336 -63.94958)
		(width 0.4064)
		(layer "F.Cu")
		(net "GND")
	)
	(segment
		(start 45.067982 -88.241378)
		(end 45.067982 -87.551006)
		(width 0.254)
		(layer "F.Cu")
		(net "GND")
	)
	(segment
		(start 70.964044 -79.168498)
		(end 70.964044 -78.973426)
		(width 0.3048)
		(layer "F.Cu")
		(net "GND")
	)
	(segment
		(start 18.381472 -73.807828)
		(end 18.381472 -73.128124)
		(width 0.4572)
		(layer "F.Cu")
		(net "GND")
	)
	(segment
		(start 187.254642 -115.527328)
		(end 188.315854 -115.527328)
		(width 0.508)
		(layer "F.Cu")
		(net "GND")
	)
	(segment
		(start 139.173458 -53.89626)
		(end 138.523472 -53.89626)
		(width 0.4572)
		(layer "F.Cu")
		(net "GND")
	)
	(segment
		(start 74.111612 -63.50127)
		(end 74.111612 -62.68847)
		(width 0.3048)
		(layer "F.Cu")
		(net "GND")
	)
	(segment
		(start 56.166766 -162.328606)
		(end 56.166766 -163.160202)
		(width 0.508)
		(layer "F.Cu")
		(net "GND")
	)
	(segment
		(start 49.444402 -67.360038)
		(end 49.37633 -67.360038)
		(width 0.3048)
		(layer "F.Cu")
		(net "GND")
	)
	(segment
		(start 41.71823 -110.955836)
		(end 41.040558 -110.955836)
		(width 0.4572)
		(layer "F.Cu")
		(net "GND")
	)
	(segment
		(start 127.42926 -187.032646)
		(end 127.03556 -187.426346)
		(width 0.508)
		(layer "F.Cu")
		(net "GND")
	)
	(segment
		(start 58.53176 -187.726574)
		(end 58.53176 -187.048648)
		(width 0.508)
		(layer "F.Cu")
		(net "GND")
	)
	(segment
		(start 28.688792 -122.164856)
		(end 28.466288 -122.38736)
		(width 0.4572)
		(layer "F.Cu")
		(net "GND")
	)
	(segment
		(start 156.674566 -138.878056)
		(end 155.839414 -138.878056)
		(width 0.508)
		(layer "F.Cu")
		(net "GND")
	)
	(segment
		(start 72.244712 -168.124632)
		(end 73.449434 -168.124632)
		(width 0.254)
		(layer "F.Cu")
		(net "GND")
	)
	(segment
		(start 43.249088 -75.016106)
		(end 43.2181 -74.985118)
		(width 0.254)
		(layer "F.Cu")
		(net "GND")
	)
	(segment
		(start 83.54822 -155.369514)
		(end 83.54822 -155.36672)
		(width 0.4572)
		(layer "F.Cu")
		(net "GND")
	)
	(segment
		(start 82.02676 -182.811674)
		(end 82.763614 -182.811674)
		(width 0.508)
		(layer "F.Cu")
		(net "GND")
	)
	(segment
		(start 50.754788 -69.265038)
		(end 50.525426 -69.265038)
		(width 0.254)
		(layer "F.Cu")
		(net "GND")
	)
	(segment
		(start 60.118498 -97.849436)
		(end 60.118498 -97.850198)
		(width 0.4572)
		(layer "F.Cu")
		(net "GND")
	)
	(segment
		(start 140.090652 -144.40535)
		(end 140.260832 -144.57553)
		(width 0.1778)
		(layer "F.Cu")
		(net "GND")
	)
	(segment
		(start 38.044374 -184.58307)
		(end 38.06444 -184.563004)
		(width 0.508)
		(layer "F.Cu")
		(net "GND")
	)
	(segment
		(start 107.421172 -73.533254)
		(end 108.866432 -73.533254)
		(width 0.3048)
		(layer "F.Cu")
		(net "GND")
	)
	(segment
		(start 51.222402 -181.024276)
		(end 51.222402 -181.021482)
		(width 0.508)
		(layer "F.Cu")
		(net "GND")
	)
	(segment
		(start 137.730992 -26.158444)
		(end 137.730992 -27.008582)
		(width 0.508)
		(layer "F.Cu")
		(net "GND")
	)
	(segment
		(start 105.397046 -18.264124)
		(end 105.397046 -19.123914)
		(width 0.508)
		(layer "F.Cu")
		(net "GND")
	)
	(segment
		(start 73.742042 -137.259314)
		(end 73.342246 -136.859518)
		(width 0.3556)
		(layer "F.Cu")
		(net "GND")
	)
	(segment
		(start 51.891946 -77.291692)
		(end 51.999896 -77.399642)
		(width 0.3048)
		(layer "F.Cu")
		(net "GND")
	)
	(segment
		(start 95.74784 -201.06132)
		(end 95.74784 -200.29932)
		(width 0.508)
		(layer "F.Cu")
		(net "GND")
	)
	(segment
		(start 74.11466 -186.939682)
		(end 74.53376 -187.358782)
		(width 0.508)
		(layer "F.Cu")
		(net "GND")
	)
	(segment
		(start 46.026578 -138.16457)
		(end 46.03242 -138.16457)
		(width 0.3556)
		(layer "F.Cu")
		(net "GND")
	)
	(segment
		(start 67.701922 -66.598038)
		(end 67.701922 -67.360038)
		(width 0.254)
		(layer "F.Cu")
		(net "GND")
	)
	(segment
		(start 146.303238 -166.608506)
		(end 145.275808 -166.608506)
		(width 0.254)
		(layer "F.Cu")
		(net "GND")
	)
	(segment
		(start 71.848218 -71.144638)
		(end 72.063864 -70.928992)
		(width 0.3048)
		(layer "F.Cu")
		(net "GND")
	)
	(segment
		(start 49.601628 -78.015846)
		(end 49.228248 -78.389226)
		(width 0.3048)
		(layer "F.Cu")
		(net "GND")
	)
	(segment
		(start 15.301468 -55.509922)
		(end 14.321282 -55.509922)
		(width 0.508)
		(layer "F.Cu")
		(net "GND")
	)
	(segment
		(start 49.825402 -66.979038)
		(end 49.444402 -67.360038)
		(width 0.3048)
		(layer "F.Cu")
		(net "GND")
	)
	(segment
		(start 64.940942 -143.65732)
		(end 64.543178 -143.259556)
		(width 0.3556)
		(layer "F.Cu")
		(net "GND")
	)
	(segment
		(start 105.86847 -61.90615)
		(end 104.73182 -61.90615)
		(width 0.3048)
		(layer "F.Cu")
		(net "GND")
	)
	(segment
		(start 69.821044 -83.514438)
		(end 69.886068 -83.579462)
		(width 0.3556)
		(layer "F.Cu")
		(net "GND")
	)
	(segment
		(start 64.543178 -143.259556)
		(end 64.541908 -143.259556)
		(width 0.3556)
		(layer "F.Cu")
		(net "GND")
	)
	(segment
		(start 44.200826 -83.274662)
		(end 44.656248 -83.274662)
		(width 0.3048)
		(layer "F.Cu")
		(net "GND")
	)
	(segment
		(start 170.675046 -96.358456)
		(end 170.443144 -96.590358)
		(width 0.254)
		(layer "F.Cu")
		(net "GND")
	)
	(segment
		(start 48.24476 -181.511956)
		(end 48.24476 -181.846474)
		(width 0.508)
		(layer "F.Cu")
		(net "GND")
	)
	(segment
		(start 63.838836 -89.048844)
		(end 63.838836 -89.625678)
		(width 0.254)
		(layer "F.Cu")
		(net "GND")
	)
	(segment
		(start 51.30673 -95.527876)
		(end 51.30673 -94.920054)
		(width 0.4572)
		(layer "F.Cu")
		(net "GND")
	)
	(segment
		(start 70.860412 -62.68847)
		(end 70.860412 -62.20587)
		(width 0.3048)
		(layer "F.Cu")
		(net "GND")
	)
	(segment
		(start 43.603672 -65.096898)
		(end 43.983656 -65.476882)
		(width 0.3048)
		(layer "F.Cu")
		(net "GND")
	)
	(segment
		(start 62.60465 -170.630088)
		(end 61.873384 -170.630088)
		(width 0.4572)
		(layer "F.Cu")
		(net "GND")
	)
	(segment
		(start 47.31004 -63.86703)
		(end 47.278544 -63.898526)
		(width 0.3048)
		(layer "F.Cu")
		(net "GND")
	)
	(segment
		(start 87.30742 -184.533032)
		(end 87.10676 -184.733692)
		(width 0.508)
		(layer "F.Cu")
		(net "GND")
	)
	(segment
		(start 98.9457 -180.717952)
		(end 98.8949 -180.667152)
		(width 0.4064)
		(layer "F.Cu")
		(net "GND")
	)
	(segment
		(start 161.83102 -187.68187)
		(end 162.541712 -187.68187)
		(width 0.508)
		(layer "F.Cu")
		(net "GND")
	)
	(segment
		(start 70.9422 -142.459456)
		(end 70.941692 -142.459456)
		(width 0.3556)
		(layer "F.Cu")
		(net "GND")
	)
	(segment
		(start 46.942248 -74.416666)
		(end 47.315628 -74.043286)
		(width 0.3048)
		(layer "F.Cu")
		(net "GND")
	)
	(segment
		(start 181.497986 -143.06042)
		(end 180.561742 -143.06042)
		(width 0.4572)
		(layer "F.Cu")
		(net "GND")
	)
	(segment
		(start 55.15229 -61.99759)
		(end 55.039768 -62.110112)
		(width 0.3048)
		(layer "F.Cu")
		(net "GND")
	)
	(segment
		(start 45.049186 -84.427314)
		(end 45.418248 -84.058252)
		(width 0.3048)
		(layer "F.Cu")
		(net "GND")
	)
	(segment
		(start 45.659548 -86.879938)
		(end 45.606716 -86.879938)
		(width 0.254)
		(layer "F.Cu")
		(net "GND")
	)
	(segment
		(start 91.968066 -97.099628)
		(end 91.968066 -98.54438)
		(width 0.508)
		(layer "F.Cu")
		(net "GND")
	)
	(segment
		(start 52.511706 -67.358006)
		(end 52.511706 -67.360038)
		(width 0.254)
		(layer "F.Cu")
		(net "GND")
	)
	(segment
		(start 74.705464 -71.400162)
		(end 74.250042 -71.400162)
		(width 0.3048)
		(layer "F.Cu")
		(net "GND")
	)
	(segment
		(start 41.088818 -72.959468)
		(end 41.416732 -72.631554)
		(width 0.254)
		(layer "F.Cu")
		(net "GND")
	)
	(segment
		(start 20.46224 -40.532558)
		(end 20.0279 -40.098218)
		(width 0.508)
		(layer "F.Cu")
		(net "GND")
	)
	(segment
		(start 70.701916 -62.047374)
		(end 70.683882 -62.047374)
		(width 0.254)
		(layer "F.Cu")
		(net "GND")
	)
	(segment
		(start 72.142096 -142.859252)
		(end 71.7423 -142.459456)
		(width 0.3556)
		(layer "F.Cu")
		(net "GND")
	)
	(segment
		(start 67.7418 -128.857502)
		(end 67.7418 -128.859534)
		(width 0.3556)
		(layer "F.Cu")
		(net "GND")
	)
	(segment
		(start 96.015048 -202.691492)
		(end 95.74784 -202.424284)
		(width 0.508)
		(layer "F.Cu")
		(net "GND")
	)
	(segment
		(start 67.141344 -64.25692)
		(end 67.109848 -64.25692)
		(width 0.254)
		(layer "F.Cu")
		(net "GND")
	)
	(segment
		(start 46.180248 -80.002126)
		(end 46.180248 -80.009746)
		(width 0.254)
		(layer "F.Cu")
		(net "GND")
	)
	(segment
		(start 62.8269 -80.212184)
		(end 62.8269 -80.225646)
		(width 0.3556)
		(layer "F.Cu")
		(net "GND")
	)
	(segment
		(start 136.7536 -155.908248)
		(end 136.7536 -155.906216)
		(width 0.508)
		(layer "F.Cu")
		(net "GND")
	)
	(segment
		(start 64.940942 -135.658352)
		(end 65.339722 -135.259572)
		(width 0.381)
		(layer "F.Cu")
		(net "GND")
	)
	(segment
		(start 53.962046 -160.014158)
		(end 54.850792 -160.014158)
		(width 0.508)
		(layer "F.Cu")
		(net "GND")
	)
	(segment
		(start 42.763186 -70.01002)
		(end 42.753534 -70.01002)
		(width 0.3048)
		(layer "F.Cu")
		(net "GND")
	)
	(segment
		(start 80.506824 -120.807226)
		(end 80.506824 -121.623582)
		(width 0.508)
		(layer "F.Cu")
		(net "GND")
	)
	(segment
		(start 47.323248 -70.070726)
		(end 47.323248 -70.79488)
		(width 0.3048)
		(layer "F.Cu")
		(net "GND")
	)
	(segment
		(start 189.24905 -126.1872)
		(end 190.0682 -126.1872)
		(width 0.508)
		(layer "F.Cu")
		(net "GND")
	)
	(segment
		(start 71.341996 -142.859252)
		(end 70.9422 -142.459456)
		(width 0.3556)
		(layer "F.Cu")
		(net "GND")
	)
	(segment
		(start 79.457296 -98.517202)
		(end 80.107282 -98.517202)
		(width 0.4572)
		(layer "F.Cu")
		(net "GND")
	)
	(segment
		(start 47.704248 -72.733408)
		(end 47.704248 -72.057006)
		(width 0.3048)
		(layer "F.Cu")
		(net "GND")
	)
	(segment
		(start 46.659292 -72.566022)
		(end 46.942248 -72.283066)
		(width 0.3048)
		(layer "F.Cu")
		(net "GND")
	)
	(segment
		(start 66.942208 -135.259572)
		(end 66.9417 -135.259572)
		(width 0.381)
		(layer "F.Cu")
		(net "GND")
	)
	(segment
		(start 143.552672 -173.891956)
		(end 143.835882 -173.608746)
		(width 0.254)
		(layer "F.Cu")
		(net "GND")
	)
	(segment
		(start 41.270936 -70.256146)
		(end 41.718738 -69.808344)
		(width 0.254)
		(layer "F.Cu")
		(net "GND")
	)
	(segment
		(start 67.340988 -137.258298)
		(end 66.942208 -136.859518)
		(width 0.381)
		(layer "F.Cu")
		(net "GND")
	)
	(segment
		(start 61.889386 -87.382096)
		(end 61.720476 -87.551006)
		(width 0.3048)
		(layer "F.Cu")
		(net "GND")
	)
	(segment
		(start 72.5424 -140.05941)
		(end 72.541892 -140.05941)
		(width 0.3556)
		(layer "F.Cu")
		(net "GND")
	)
	(segment
		(start 110.460028 -68.906136)
		(end 112.30991 -68.906136)
		(width 0.3048)
		(layer "F.Cu")
		(net "GND")
	)
	(segment
		(start 165.335712 -162.37966)
		(end 165.335712 -161.780728)
		(width 0.508)
		(layer "F.Cu")
		(net "GND")
	)
	(segment
		(start 167.675052 -93.682566)
		(end 167.858694 -93.866208)
		(width 0.508)
		(layer "F.Cu")
		(net "GND")
	)
	(segment
		(start 72.5424 -142.459456)
		(end 72.541892 -142.459456)
		(width 0.3556)
		(layer "F.Cu")
		(net "GND")
	)
	(segment
		(start 148.63572 -175.28032)
		(end 148.47189 -175.28032)
		(width 0.381)
		(layer "F.Cu")
		(net "GND")
	)
	(segment
		(start 51.071272 -73.343262)
		(end 50.371248 -73.343262)
		(width 0.3048)
		(layer "F.Cu")
		(net "GND")
	)
	(segment
		(start 73.342246 -137.659618)
		(end 73.341738 -137.659618)
		(width 0.3556)
		(layer "F.Cu")
		(net "GND")
	)
	(segment
		(start 51.158648 -78.71587)
		(end 51.158648 -78.895702)
		(width 0.3048)
		(layer "F.Cu")
		(net "GND")
	)
	(segment
		(start 51.689508 -64.594994)
		(end 51.820318 -64.725804)
		(width 0.3048)
		(layer "F.Cu")
		(net "GND")
	)
	(segment
		(start 149.342602 -183.923432)
		(end 149.342602 -184.799732)
		(width 0.508)
		(layer "F.Cu")
		(net "GND")
	)
	(segment
		(start 106.0323 -136.297924)
		(end 104.94645 -136.297924)
		(width 0.1778)
		(layer "F.Cu")
		(net "GND")
	)
	(segment
		(start 98.9457 -181.053994)
		(end 98.9457 -180.717952)
		(width 0.4064)
		(layer "F.Cu")
		(net "GND")
	)
	(segment
		(start 144.040352 -133.178804)
		(end 144.289272 -133.427724)
		(width 0.4572)
		(layer "F.Cu")
		(net "GND")
	)
	(segment
		(start 124.7394 -163.665154)
		(end 124.7394 -163.663376)
		(width 0.508)
		(layer "F.Cu")
		(net "GND")
	)
	(segment
		(start 64.141096 -134.058406)
		(end 64.541908 -134.459218)
		(width 0.381)
		(layer "F.Cu")
		(net "GND")
	)
	(segment
		(start 43.30954 -69.982588)
		(end 43.26382 -69.936868)
		(width 0.3048)
		(layer "F.Cu")
		(net "GND")
	)
	(segment
		(start 42.582338 -77.079094)
		(end 42.13606 -77.079094)
		(width 0.254)
		(layer "F.Cu")
		(net "GND")
	)
	(segment
		(start 32.98444 -3.701034)
		(end 32.98444 -3.255264)
		(width 0.4572)
		(layer "F.Cu")
		(net "GND")
	)
	(segment
		(start 11.1379 -153.110438)
		(end 11.24458 -153.217118)
		(width 0.508)
		(layer "F.Cu")
		(net "GND")
	)
	(segment
		(start 66.063876 -88.684862)
		(end 66.143632 -88.605106)
		(width 0.254)
		(layer "F.Cu")
		(net "GND")
	)
	(segment
		(start 97.6503 -29.149802)
		(end 97.6503 -27.64282)
		(width 0.4572)
		(layer "F.Cu")
		(net "GND")
	)
	(segment
		(start 60.21705 -82.714846)
		(end 60.21705 -81.952846)
		(width 0.3048)
		(layer "F.Cu")
		(net "GND")
	)
	(segment
		(start 159.351726 -75.416664)
		(end 159.351726 -76.34097)
		(width 0.4572)
		(layer "F.Cu")
		(net "GND")
	)
	(segment
		(start 41.88968 -88.31199)
		(end 41.88968 -87.284814)
		(width 0.381)
		(layer "F.Cu")
		(net "GND")
	)
	(segment
		(start 46.858428 -173.87697)
		(end 47.242222 -174.260764)
		(width 0.4572)
		(layer "F.Cu")
		(net "GND")
	)
	(segment
		(start 59.740546 -87.778844)
		(end 59.740546 -88.30564)
		(width 0.3048)
		(layer "F.Cu")
		(net "GND")
	)
	(segment
		(start 44.479972 -69.668898)
		(end 44.778168 -69.370702)
		(width 0.3048)
		(layer "F.Cu")
		(net "GND")
	)
	(segment
		(start 67.923664 -69.610478)
		(end 68.297044 -69.237098)
		(width 0.3048)
		(layer "F.Cu")
		(net "GND")
	)
	(segment
		(start 46.942248 -72.283066)
		(end 46.942248 -72.057006)
		(width 0.3048)
		(layer "F.Cu")
		(net "GND")
	)
	(segment
		(start 60.21705 -81.952846)
		(end 60.447936 -81.952846)
		(width 0.3048)
		(layer "F.Cu")
		(net "GND")
	)
	(segment
		(start 71.613014 -63.49492)
		(end 71.652892 -63.49492)
		(width 0.3048)
		(layer "F.Cu")
		(net "GND")
	)
	(segment
		(start 106.349292 -71.026274)
		(end 106.349292 -70.734174)
		(width 0.3048)
		(layer "F.Cu")
		(net "GND")
	)
	(segment
		(start 47.67834 -87.297768)
		(end 47.67834 -86.813136)
		(width 0.254)
		(layer "F.Cu")
		(net "GND")
	)
	(segment
		(start 43.2181 -74.985118)
		(end 42.243756 -74.985118)
		(width 0.254)
		(layer "F.Cu")
		(net "GND")
	)
	(segment
		(start 124.762006 -172.632624)
		(end 124.754894 -172.625512)
		(width 0.508)
		(layer "F.Cu")
		(net "GND")
	)
	(segment
		(start 72.081136 -74.68489)
		(end 71.365872 -74.68489)
		(width 0.3048)
		(layer "F.Cu")
		(net "GND")
	)
	(segment
		(start 91.21267 -177.578512)
		(end 91.21267 -176.56429)
		(width 0.508)
		(layer "F.Cu")
		(net "GND")
	)
	(segment
		(start 56.24576 -187.726574)
		(end 56.24576 -186.927236)
		(width 0.508)
		(layer "F.Cu")
		(net "GND")
	)
	(segment
		(start 15.997174 -15.860522)
		(end 15.997174 -15.09776)
		(width 0.508)
		(layer "F.Cu")
		(net "GND")
	)
	(segment
		(start 58.60415 -84.238846)
		(end 58.330338 -84.512658)
		(width 0.3048)
		(layer "F.Cu")
		(net "GND")
	)
	(segment
		(start 72.64654 -70.114668)
		(end 72.795384 -70.263512)
		(width 0.3048)
		(layer "F.Cu")
		(net "GND")
	)
	(segment
		(start 69.015102 -205.199488)
		(end 69.015102 -201.09053)
		(width 0.508)
		(layer "F.Cu")
		(net "GND")
	)
	(segment
		(start 46.816772 -62.810898)
		(end 46.562772 -62.556898)
		(width 0.254)
		(layer "F.Cu")
		(net "GND")
	)
	(segment
		(start 71.345044 -79.541878)
		(end 71.337424 -79.541878)
		(width 0.3048)
		(layer "F.Cu")
		(net "GND")
	)
	(segment
		(start 105.002838 -162.51174)
		(end 104.73309 -162.781488)
		(width 0.508)
		(layer "F.Cu")
		(net "GND")
	)
	(segment
		(start 51.014884 -201.09053)
		(end 51.014884 -200.32853)
		(width 0.508)
		(layer "F.Cu")
		(net "GND")
	)
	(segment
		(start 66.141854 -143.259556)
		(end 66.141854 -143.256508)
		(width 0.3556)
		(layer "F.Cu")
		(net "GND")
	)
	(segment
		(start 126.90094 -139.775438)
		(end 127.009652 -139.88415)
		(width 0.1778)
		(layer "F.Cu")
		(net "GND")
	)
	(segment
		(start 66.802762 -86.588092)
		(end 66.62293 -86.40826)
		(width 0.3048)
		(layer "F.Cu")
		(net "GND")
	)
	(segment
		(start 151.60244 -183.749188)
		(end 151.62276 -183.769508)
		(width 0.508)
		(layer "F.Cu")
		(net "GND")
	)
	(segment
		(start 174.510446 -118.86565)
		(end 175.010318 -119.365522)
		(width 0.381)
		(layer "F.Cu")
		(net "GND")
	)
	(segment
		(start 59.756802 -68.876418)
		(end 59.756802 -68.884038)
		(width 0.3048)
		(layer "F.Cu")
		(net "GND")
	)
	(segment
		(start 80.701388 -156.120084)
		(end 80.701388 -155.663392)
		(width 0.254)
		(layer "F.Cu")
		(net "GND")
	)
	(segment
		(start 51.67376 -181.47284)
		(end 51.67376 -181.838092)
		(width 0.508)
		(layer "F.Cu")
		(net "GND")
	)
	(segment
		(start 56.87695 -88.605106)
		(end 57.137808 -88.605106)
		(width 0.254)
		(layer "F.Cu")
		(net "GND")
	)
	(segment
		(start 65.341754 -142.459456)
		(end 65.33896 -142.459456)
		(width 0.3556)
		(layer "F.Cu")
		(net "GND")
	)
	(segment
		(start 9.056624 -118.70817)
		(end 9.056624 -129.992374)
		(width 0.254)
		(layer "F.Cu")
		(net "GND")
	)
	(segment
		(start 66.443098 -65.455038)
		(end 66.415666 -65.455038)
		(width 0.254)
		(layer "F.Cu")
		(net "GND")
	)
	(segment
		(start 61.05017 -29.149802)
		(end 61.05017 -27.624278)
		(width 0.4572)
		(layer "F.Cu")
		(net "GND")
	)
	(segment
		(start 42.11574 -78.760066)
		(end 41.75125 -78.760066)
		(width 0.254)
		(layer "F.Cu")
		(net "GND")
	)
	(segment
		(start 55.544466 -85.002878)
		(end 55.150766 -85.396578)
		(width 0.254)
		(layer "F.Cu")
		(net "GND")
	)
	(segment
		(start 59.90082 -80.700118)
		(end 59.90082 -81.300066)
		(width 0.3048)
		(layer "F.Cu")
		(net "GND")
	)
	(segment
		(start 66.44132 -64.004698)
		(end 66.857626 -64.004698)
		(width 0.254)
		(layer "F.Cu")
		(net "GND")
	)
	(segment
		(start 139.02436 -121.807224)
		(end 139.02436 -122.94235)
		(width 0.508)
		(layer "F.Cu")
		(net "GND")
	)
	(segment
		(start 70.54215 -140.459206)
		(end 70.142354 -140.05941)
		(width 0.3556)
		(layer "F.Cu")
		(net "GND")
	)
	(segment
		(start 71.317104 -82.908648)
		(end 72.081136 -83.67268)
		(width 0.3048)
		(layer "F.Cu")
		(net "GND")
	)
	(segment
		(start 74.542142 -135.659368)
		(end 74.142346 -135.259572)
		(width 0.3556)
		(layer "F.Cu")
		(net "GND")
	)
	(segment
		(start 43.609006 -184.016142)
		(end 43.609006 -185.14568)
		(width 0.4572)
		(layer "F.Cu")
		(net "GND")
	)
	(segment
		(start 87.394542 -31.596838)
		(end 87.394796 -31.596838)
		(width 0.381)
		(layer "F.Cu")
		(net "GND")
	)
	(segment
		(start 161.099754 -173.607222)
		(end 161.043112 -173.55058)
		(width 0.381)
		(layer "F.Cu")
		(net "GND")
	)
	(segment
		(start 160.723326 -138.064494)
		(end 160.723326 -137.080752)
		(width 0.508)
		(layer "F.Cu")
		(net "GND")
	)
	(segment
		(start 8.722614 -2.459482)
		(end 8.722614 -3.272282)
		(width 0.381)
		(layer "F.Cu")
		(net "GND")
	)
	(segment
		(start 44.607226 -178.301904)
		(end 45.282612 -178.301904)
		(width 0.4572)
		(layer "F.Cu")
		(net "GND")
	)
	(segment
		(start 64.940942 -134.058406)
		(end 65.341754 -134.459218)
		(width 0.381)
		(layer "F.Cu")
		(net "GND")
	)
	(segment
		(start 18.25752 -51.081686)
		(end 19.141186 -51.081686)
		(width 0.508)
		(layer "F.Cu")
		(net "GND")
	)
	(segment
		(start 42.243756 -74.985118)
		(end 42.194988 -74.93635)
		(width 0.254)
		(layer "F.Cu")
		(net "GND")
	)
	(segment
		(start 8.553958 -8.779256)
		(end 7.691628 -8.779256)
		(width 0.508)
		(layer "F.Cu")
		(net "GND")
	)
	(segment
		(start 49.317656 -71.356982)
		(end 49.228248 -71.356982)
		(width 0.3048)
		(layer "F.Cu")
		(net "GND")
	)
	(segment
		(start 71.341996 -140.459206)
		(end 70.9422 -140.05941)
		(width 0.3556)
		(layer "F.Cu")
		(net "GND")
	)
	(segment
		(start 72.942196 -143.659352)
		(end 72.5424 -143.259556)
		(width 0.3556)
		(layer "F.Cu")
		(net "GND")
	)
	(segment
		(start 72.014334 -72.613266)
		(end 72.014334 -73.100692)
		(width 0.3048)
		(layer "F.Cu")
		(net "GND")
	)
	(segment
		(start 47.708566 -88.04656)
		(end 47.708566 -88.181688)
		(width 0.3048)
		(layer "F.Cu")
		(net "GND")
	)
	(segment
		(start 106.323638 -69.27088)
		(end 105.958894 -68.906136)
		(width 0.3048)
		(layer "F.Cu")
		(net "GND")
	)
	(segment
		(start 11.8999 -134.260336)
		(end 13.125196 -135.485632)
		(width 0.254)
		(layer "F.Cu")
		(net "GND")
	)
	(segment
		(start 50.183034 -18.89506)
		(end 53.751226 -15.326868)
		(width 0.254)
		(layer "F.Cu")
		(net "GND")
	)
	(segment
		(start 57.741566 -129.259076)
		(end 58.14187 -129.65938)
		(width 0.3556)
		(layer "F.Cu")
		(net "GND")
	)
	(segment
		(start 35.45205 -77.63256)
		(end 34.57702 -77.63256)
		(width 0.4572)
		(layer "F.Cu")
		(net "GND")
	)
	(segment
		(start 52.864766 -65.409826)
		(end 53.090318 -65.184274)
		(width 0.254)
		(layer "F.Cu")
		(net "GND")
	)
	(segment
		(start 75.16114 -67.882516)
		(end 74.70775 -68.335906)
		(width 0.254)
		(layer "F.Cu")
		(net "GND")
	)
	(segment
		(start 74.542142 -137.259314)
		(end 74.142346 -136.859518)
		(width 0.3556)
		(layer "F.Cu")
		(net "GND")
	)
	(segment
		(start 32.944054 -116.518182)
		(end 32.60344 -116.518182)
		(width 0.508)
		(layer "F.Cu")
		(net "GND")
	)
	(segment
		(start 126.015496 -201.034904)
		(end 126.015496 -205.199488)
		(width 0.508)
		(layer "F.Cu")
		(net "GND")
	)
	(segment
		(start 119.71274 -185.945018)
		(end 119.48922 -185.721498)
		(width 0.508)
		(layer "F.Cu")
		(net "GND")
	)
	(segment
		(start 45.037248 -81.152746)
		(end 45.037248 -81.288382)
		(width 0.3048)
		(layer "F.Cu")
		(net "GND")
	)
	(segment
		(start 44.66082 -75.329542)
		(end 44.656248 -75.329542)
		(width 0.3048)
		(layer "F.Cu")
		(net "GND")
	)
	(segment
		(start 71.345044 -79.541878)
		(end 71.71055 -79.541878)
		(width 0.254)
		(layer "F.Cu")
		(net "GND")
	)
	(segment
		(start 54.015132 -205.199488)
		(end 54.015132 -201.09053)
		(width 0.508)
		(layer "F.Cu")
		(net "GND")
	)
	(segment
		(start 56.585358 -89.678764)
		(end 56.458612 -89.552018)
		(width 0.254)
		(layer "F.Cu")
		(net "GND")
	)
	(segment
		(start 74.11466 -186.937904)
		(end 74.11466 -186.939682)
		(width 0.508)
		(layer "F.Cu")
		(net "GND")
	)
	(segment
		(start 67.7418 -141.660626)
		(end 67.7418 -141.65961)
		(width 0.3556)
		(layer "F.Cu")
		(net "GND")
	)
	(segment
		(start 51.158648 -78.895702)
		(end 50.752248 -79.302102)
		(width 0.3048)
		(layer "F.Cu")
		(net "GND")
	)
	(segment
		(start 68.401946 -68.21932)
		(end 68.297044 -68.324222)
		(width 0.254)
		(layer "F.Cu")
		(net "GND")
	)
	(segment
		(start 60.541916 -129.659126)
		(end 60.541916 -129.659634)
		(width 0.381)
		(layer "F.Cu")
		(net "GND")
	)
	(segment
		(start 71.345044 -75.569318)
		(end 71.807578 -76.031852)
		(width 0.3048)
		(layer "F.Cu")
		(net "GND")
	)
	(segment
		(start 45.044868 -81.988406)
		(end 45.037248 -81.988406)
		(width 0.254)
		(layer "F.Cu")
		(net "GND")
	)
	(segment
		(start 43.249088 -79.677768)
		(end 42.69613 -80.230726)
		(width 0.254)
		(layer "F.Cu")
		(net "GND")
	)
	(segment
		(start 49.37633 -67.360038)
		(end 49.20869 -67.527678)
		(width 0.3048)
		(layer "F.Cu")
		(net "GND")
	)
	(segment
		(start 118.67642 -116.93017)
		(end 121.2596 -119.51335)
		(width 0.254)
		(layer "F.Cu")
		(net "GND")
	)
	(segment
		(start 148.19376 -187.726574)
		(end 148.19376 -186.907424)
		(width 0.508)
		(layer "F.Cu")
		(net "GND")
	)
	(segment
		(start 41.068498 -78.83017)
		(end 41.068498 -78.904084)
		(width 0.254)
		(layer "F.Cu")
		(net "GND")
	)
	(segment
		(start 57.55894 -181.224428)
		(end 57.55894 -180.790088)
		(width 0.508)
		(layer "F.Cu")
		(net "GND")
	)
	(segment
		(start 79.95666 -165.620446)
		(end 79.842106 -165.735)
		(width 0.254)
		(layer "F.Cu")
		(net "GND")
	)
	(segment
		(start 71.7423 -142.459456)
		(end 71.741792 -142.459456)
		(width 0.3556)
		(layer "F.Cu")
		(net "GND")
	)
	(segment
		(start 60.447936 -81.952846)
		(end 60.800996 -81.599786)
		(width 0.3048)
		(layer "F.Cu")
		(net "GND")
	)
	(segment
		(start 66.765424 -79.541878)
		(end 66.773044 -79.541878)
		(width 0.3048)
		(layer "F.Cu")
		(net "GND")
	)
	(segment
		(start 134.437882 -113.380012)
		(end 134.437882 -113.049812)
		(width 0.1778)
		(layer "F.Cu")
		(net "GND")
	)
	(segment
		(start 45.037248 -74.113136)
		(end 45.037248 -74.043286)
		(width 0.3048)
		(layer "F.Cu")
		(net "GND")
	)
	(segment
		(start 63.133986 -84.594446)
		(end 63.489586 -84.238846)
		(width 0.254)
		(layer "F.Cu")
		(net "GND")
	)
	(segment
		(start 94.95028 -20.94992)
		(end 94.95028 -22.4536)
		(width 0.381)
		(layer "F.Cu")
		(net "GND")
	)
	(segment
		(start 116.100352 -66.621914)
		(end 115.311428 -66.621914)
		(width 0.4572)
		(layer "F.Cu")
		(net "GND")
	)
	(segment
		(start 154.28214 -179.089304)
		(end 154.983688 -179.089304)
		(width 0.508)
		(layer "F.Cu")
		(net "GND")
	)
	(segment
		(start 73.752964 -79.684626)
		(end 72.795384 -79.684626)
		(width 0.3048)
		(layer "F.Cu")
		(net "GND")
	)
	(segment
		(start 11.04392 -7.127748)
		(end 11.04392 -8.786368)
		(width 0.508)
		(layer "F.Cu")
		(net "GND")
	)
	(segment
		(start 124.725684 -52.706524)
		(end 124.725684 -52.716684)
		(width 0.4572)
		(layer "F.Cu")
		(net "GND")
	)
	(segment
		(start 141.08176 -186.91225)
		(end 141.08176 -187.726574)
		(width 0.381)
		(layer "F.Cu")
		(net "GND")
	)
	(segment
		(start 107.42549 -174.3329)
		(end 107.42549 -174.098458)
		(width 0.508)
		(layer "F.Cu")
		(net "GND")
	)
	(segment
		(start 51.811682 -67.360038)
		(end 52.511706 -67.360038)
		(width 0.3048)
		(layer "F.Cu")
		(net "GND")
	)
	(segment
		(start 165.389052 -106.01579)
		(end 165.243256 -105.869994)
		(width 0.1778)
		(layer "F.Cu")
		(net "GND")
	)
	(segment
		(start 47.323248 -70.79488)
		(end 47.241714 -70.876414)
		(width 0.3048)
		(layer "F.Cu")
		(net "GND")
	)
	(segment
		(start 162.296856 -118.335552)
		(end 161.42843 -118.335552)
		(width 0.508)
		(layer "F.Cu")
		(net "GND")
	)
	(segment
		(start 45.59681 -88.042242)
		(end 45.295058 -88.343994)
		(width 0.3048)
		(layer "F.Cu")
		(net "GND")
	)
	(segment
		(start 59.186318 -170.604688)
		(end 58.39333 -170.604688)
		(width 0.4572)
		(layer "F.Cu")
		(net "GND")
	)
	(segment
		(start 42.69613 -80.230726)
		(end 42.69613 -80.249522)
		(width 0.254)
		(layer "F.Cu")
		(net "GND")
	)
	(segment
		(start 71.345044 -80.241902)
		(end 71.345044 -79.541878)
		(width 0.3048)
		(layer "F.Cu")
		(net "GND")
	)
	(segment
		(start 46.389544 -63.898526)
		(end 46.006766 -63.898526)
		(width 0.3048)
		(layer "F.Cu")
		(net "GND")
	)
	(segment
		(start 76.81976 -187.726574)
		(end 76.81976 -187.091066)
		(width 0.508)
		(layer "F.Cu")
		(net "GND")
	)
	(segment
		(start 43.417998 -85.212428)
		(end 43.937428 -85.212428)
		(width 0.3048)
		(layer "F.Cu")
		(net "GND")
	)
	(segment
		(start 73.384918 -74.553318)
		(end 73.8378 -74.553318)
		(width 0.3048)
		(layer "F.Cu")
		(net "GND")
	)
	(segment
		(start 64.429386 -65.836038)
		(end 64.437514 -65.82791)
		(width 0.254)
		(layer "F.Cu")
		(net "GND")
	)
	(segment
		(start 70.964044 -77.555598)
		(end 70.964044 -78.255622)
		(width 0.3048)
		(layer "F.Cu")
		(net "GND")
	)
	(segment
		(start 65.38976 -187.726574)
		(end 65.38976 -186.954414)
		(width 0.508)
		(layer "F.Cu")
		(net "GND")
	)
	(segment
		(start 38.299898 -3.086354)
		(end 38.299898 -2.348484)
		(width 0.4572)
		(layer "F.Cu")
		(net "GND")
	)
	(segment
		(start 41.156636 -84.701634)
		(end 41.75125 -84.701634)
		(width 0.254)
		(layer "F.Cu")
		(net "GND")
	)
	(segment
		(start 138.523472 -53.89626)
		(end 138.38174 -53.754528)
		(width 0.4572)
		(layer "F.Cu")
		(net "GND")
	)
	(segment
		(start 34.056828 -11.033506)
		(end 33.394396 -11.033506)
		(width 0.4572)
		(layer "F.Cu")
		(net "GND")
	)
	(segment
		(start 64.141096 -136.458198)
		(end 64.539876 -136.059418)
		(width 0.381)
		(layer "F.Cu")
		(net "GND")
	)
	(segment
		(start 132.5372 -54.52745)
		(end 132.5372 -55.372)
		(width 0.508)
		(layer "F.Cu")
		(net "GND")
	)
	(segment
		(start 48.682148 -86.561168)
		(end 48.842422 -86.561168)
		(width 0.254)
		(layer "F.Cu")
		(net "GND")
	)
	(segment
		(start 26.985722 -103.221282)
		(end 26.985722 -104.315006)
		(width 0.4572)
		(layer "F.Cu")
		(net "GND")
	)
	(segment
		(start 44.967652 -163.558982)
		(end 44.967652 -164.37229)
		(width 0.508)
		(layer "F.Cu")
		(net "GND")
	)
	(segment
		(start 19.538696 -97.973388)
		(end 18.774918 -97.973388)
		(width 0.508)
		(layer "F.Cu")
		(net "GND")
	)
	(segment
		(start 43.956732 -83.518756)
		(end 43.986958 -83.48853)
		(width 0.3048)
		(layer "F.Cu")
		(net "GND")
	)
	(segment
		(start 32.57296 -169.312082)
		(end 32.796734 -169.535856)
		(width 0.508)
		(layer "F.Cu")
		(net "GND")
	)
	(segment
		(start 56.64454 -87.437468)
		(end 56.758078 -87.551006)
		(width 0.254)
		(layer "F.Cu")
		(net "GND")
	)
	(segment
		(start 36.3601 -71.405242)
		(end 36.3601 -72.335898)
		(width 0.508)
		(layer "F.Cu")
		(net "GND")
	)
	(segment
		(start 14.76756 -115.128802)
		(end 14.29385 -115.602512)
		(width 0.254)
		(layer "F.Cu")
		(net "GND")
	)
	(segment
		(start 156.01569 -201.034904)
		(end 156.01569 -205.199488)
		(width 0.508)
		(layer "F.Cu")
		(net "GND")
	)
	(segment
		(start 109.262672 -67.325494)
		(end 109.343444 -67.406266)
		(width 0.3048)
		(layer "F.Cu")
		(net "GND")
	)
	(segment
		(start 44.656248 -68.084446)
		(end 44.656248 -67.384422)
		(width 0.3048)
		(layer "F.Cu")
		(net "GND")
	)
	(segment
		(start 68.68922 -169.056304)
		(end 69.0499 -168.695624)
		(width 0.508)
		(layer "F.Cu")
		(net "GND")
	)
	(segment
		(start 71.7423 -135.259572)
		(end 71.741792 -135.259572)
		(width 0.381)
		(layer "F.Cu")
		(net "GND")
	)
	(segment
		(start 162.17138 -161.77006)
		(end 162.17138 -162.37966)
		(width 0.508)
		(layer "F.Cu")
		(net "GND")
	)
	(segment
		(start 69.062092 -66.845942)
		(end 68.814188 -66.598038)
		(width 0.381)
		(layer "F.Cu")
		(net "GND")
	)
	(segment
		(start 171.551092 -137.351008)
		(end 172.29201 -137.351008)
		(width 0.508)
		(layer "F.Cu")
		(net "GND")
	)
	(segment
		(start 146.390868 -166.520876)
		(end 146.303238 -166.608506)
		(width 0.254)
		(layer "F.Cu")
		(net "GND")
	)
	(segment
		(start 71.616316 -64.260222)
		(end 71.613014 -64.25692)
		(width 0.3048)
		(layer "F.Cu")
		(net "GND")
	)
	(segment
		(start 68.042282 -82.762598)
		(end 67.916044 -82.63636)
		(width 0.254)
		(layer "F.Cu")
		(net "GND")
	)
	(segment
		(start 66.540888 -142.857474)
		(end 66.14287 -142.459456)
		(width 0.3556)
		(layer "F.Cu")
		(net "GND")
	)
	(segment
		(start 86.686644 -167.624506)
		(end 87.744808 -167.624506)
		(width 0.254)
		(layer "F.Cu")
		(net "GND")
	)
	(segment
		(start 93.435932 -167.023542)
		(end 93.575124 -167.162734)
		(width 0.508)
		(layer "F.Cu")
		(net "GND")
	)
	(segment
		(start 14.76756 -112.454182)
		(end 14.76756 -115.128802)
		(width 0.254)
		(layer "F.Cu")
		(net "GND")
	)
	(segment
		(start 64.141096 -137.258298)
		(end 64.539876 -136.859518)
		(width 0.381)
		(layer "F.Cu")
		(net "GND")
	)
	(segment
		(start 70.9422 -136.059418)
		(end 70.941692 -136.059418)
		(width 0.3556)
		(layer "F.Cu")
		(net "GND")
	)
	(segment
		(start 72.205088 -69.488558)
		(end 71.596504 -69.488558)
		(width 0.3048)
		(layer "F.Cu")
		(net "GND")
	)
	(segment
		(start 51.820318 -64.725804)
		(end 52.382928 -64.725804)
		(width 0.3048)
		(layer "F.Cu")
		(net "GND")
	)
	(segment
		(start 64.940942 -140.457936)
		(end 64.542416 -140.05941)
		(width 0.3556)
		(layer "F.Cu")
		(net "GND")
	)
	(segment
		(start 50.910236 -120.460262)
		(end 50.910236 -121.49963)
		(width 0.508)
		(layer "F.Cu")
		(net "GND")
	)
	(segment
		(start 63.838836 -88.787986)
		(end 63.838836 -89.048844)
		(width 0.254)
		(layer "F.Cu")
		(net "GND")
	)
	(segment
		(start 96.015048 -205.199488)
		(end 96.015048 -202.691492)
		(width 0.508)
		(layer "F.Cu")
		(net "GND")
	)
	(segment
		(start 109.199172 -67.325494)
		(end 109.262672 -67.325494)
		(width 0.3048)
		(layer "F.Cu")
		(net "GND")
	)
	(segment
		(start 133.71576 -110.383574)
		(end 133.71576 -109.747558)
		(width 0.381)
		(layer "F.Cu")
		(net "GND")
	)
	(segment
		(start 153.908252 -187.726066)
		(end 153.90876 -187.726574)
		(width 0.508)
		(layer "F.Cu")
		(net "GND")
	)
	(segment
		(start 34.842958 -186.620404)
		(end 34.233358 -186.620404)
		(width 0.4572)
		(layer "F.Cu")
		(net "GND")
	)
	(segment
		(start 132.31876 -187.243974)
		(end 131.93776 -186.862974)
		(width 0.381)
		(layer "F.Cu")
		(net "GND")
	)
	(segment
		(start 46.601888 -85.799168)
		(end 46.31309 -86.087966)
		(width 0.3048)
		(layer "F.Cu")
		(net "GND")
	)
	(segment
		(start 92.72778 -167.14851)
		(end 92.555822 -167.14851)
		(width 0.381)
		(layer "F.Cu")
		(net "GND")
	)
	(segment
		(start 135.36676 -184.19826)
		(end 135.36676 -184.805574)
		(width 0.508)
		(layer "F.Cu")
		(net "GND")
	)
	(segment
		(start 50.952908 -69.733668)
		(end 50.659538 -70.027038)
		(width 0.3048)
		(layer "F.Cu")
		(net "GND")
	)
	(segment
		(start 68.219066 -4.91871)
		(end 68.219066 -5.52323)
		(width 0.254)
		(layer "F.Cu")
		(net "GND")
	)
	(segment
		(start 42.328592 -78.972918)
		(end 42.11574 -78.760066)
		(width 0.254)
		(layer "F.Cu")
		(net "GND")
	)
	(segment
		(start 60.000896 -80.600042)
		(end 59.90082 -80.700118)
		(width 0.3048)
		(layer "F.Cu")
		(net "GND")
	)
	(segment
		(start 43.603672 -65.096898)
		(end 43.964352 -64.736218)
		(width 0.3048)
		(layer "F.Cu")
		(net "GND")
	)
	(segment
		(start 141.467586 -112.524286)
		(end 140.68044 -112.524286)
		(width 0.4572)
		(layer "F.Cu")
		(net "GND")
	)
	(segment
		(start 124.160026 -165.507416)
		(end 124.10821 -165.507416)
		(width 0.508)
		(layer "F.Cu")
		(net "GND")
	)
	(segment
		(start 57.83834 -84.211668)
		(end 57.83834 -84.312252)
		(width 0.3048)
		(layer "F.Cu")
		(net "GND")
	)
	(segment
		(start 85.350096 -20.94992)
		(end 85.350096 -22.396704)
		(width 0.381)
		(layer "F.Cu")
		(net "GND")
	)
	(segment
		(start 152.355804 -135.155432)
		(end 151.574754 -135.155432)
		(width 0.508)
		(layer "F.Cu")
		(net "GND")
	)
	(segment
		(start 61.720476 -87.551006)
		(end 61.597286 -87.427816)
		(width 0.3048)
		(layer "F.Cu")
		(net "GND")
	)
	(segment
		(start 50.886868 -84.619846)
		(end 50.28565 -84.619846)
		(width 0.3048)
		(layer "F.Cu")
		(net "GND")
	)
	(segment
		(start 28.6512 -100.929948)
		(end 28.85948 -101.138228)
		(width 0.4572)
		(layer "F.Cu")
		(net "GND")
	)
	(segment
		(start 106.435652 -61.623194)
		(end 106.151426 -61.623194)
		(width 0.3048)
		(layer "F.Cu")
		(net "GND")
	)
	(segment
		(start 126.831344 -137.775442)
		(end 127.035052 -137.97915)
		(width 0.1778)
		(layer "F.Cu")
		(net "GND")
	)
	(segment
		(start 45.418248 -82.361786)
		(end 45.044868 -81.988406)
		(width 0.254)
		(layer "F.Cu")
		(net "GND")
	)
	(segment
		(start 42.70248 -87.284814)
		(end 43.51528 -87.284814)
		(width 0.381)
		(layer "F.Cu")
		(net "GND")
	)
	(segment
		(start 66.388488 -63.047118)
		(end 66.44132 -63.09995)
		(width 0.254)
		(layer "F.Cu")
		(net "GND")
	)
	(segment
		(start 35.269678 -78.877922)
		(end 35.269678 -79.893922)
		(width 0.4572)
		(layer "F.Cu")
		(net "GND")
	)
	(segment
		(start 72.568562 -1.69418)
		(end 72.568562 -2.492502)
		(width 0.508)
		(layer "F.Cu")
		(net "GND")
	)
	(segment
		(start 153.651204 -70.732904)
		(end 153.122122 -70.203822)
		(width 0.508)
		(layer "F.Cu")
		(net "GND")
	)
	(segment
		(start 83.63204 -153.258774)
		(end 83.63204 -153.480516)
		(width 0.4572)
		(layer "F.Cu")
		(net "GND")
	)
	(segment
		(start 113.90376 -184.805574)
		(end 113.59896 -184.500774)
		(width 0.508)
		(layer "F.Cu")
		(net "GND")
	)
	(segment
		(start 64.311784 -87.00389)
		(end 64.311784 -87.60841)
		(width 0.254)
		(layer "F.Cu")
		(net "GND")
	)
	(segment
		(start 97.973896 -4.449826)
		(end 97.27946 -4.449826)
		(width 0.508)
		(layer "F.Cu")
		(net "GND")
	)
	(segment
		(start 29.014928 -205.199488)
		(end 29.014928 -201.09053)
		(width 0.508)
		(layer "F.Cu")
		(net "GND")
	)
	(segment
		(start 91.858084 -175.063912)
		(end 91.533218 -175.388778)
		(width 0.4572)
		(layer "F.Cu")
		(net "GND")
	)
	(segment
		(start 157.37586 -186.863228)
		(end 157.33776 -186.901328)
		(width 0.508)
		(layer "F.Cu")
		(net "GND")
	)
	(segment
		(start 141.94663 -40.309038)
		(end 142.631668 -39.624)
		(width 0.3048)
		(layer "F.Cu")
		(net "GND")
	)
	(segment
		(start 45.51172 -172.600366)
		(end 45.51172 -171.50207)
		(width 0.508)
		(layer "F.Cu")
		(net "GND")
	)
	(segment
		(start 138.79576 -187.726574)
		(end 138.79576 -186.862974)
		(width 0.508)
		(layer "F.Cu")
		(net "GND")
	)
	(segment
		(start 127.009652 -139.88415)
		(end 126.718314 -140.175488)
		(width 0.1778)
		(layer "F.Cu")
		(net "GND")
	)
	(segment
		(start 70.956424 -69.610478)
		(end 70.583044 -69.237098)
		(width 0.3048)
		(layer "F.Cu")
		(net "GND")
	)
	(segment
		(start 56.952134 -84.041234)
		(end 56.473852 -84.041234)
		(width 0.3048)
		(layer "F.Cu")
		(net "GND")
	)
	(segment
		(start 128.93802 -152.338024)
		(end 128.768094 -152.50795)
		(width 0.2032)
		(layer "F.Cu")
		(net "GND")
	)
	(segment
		(start 75.607672 -76.380086)
		(end 75.361546 -76.626212)
		(width 0.254)
		(layer "F.Cu")
		(net "GND")
	)
	(segment
		(start 63.3349 -22.58568)
		(end 63.3349 -20.94992)
		(width 0.381)
		(layer "F.Cu")
		(net "GND")
	)
	(segment
		(start 98.905822 -22.664928)
		(end 98.9076 -22.664928)
		(width 0.381)
		(layer "F.Cu")
		(net "GND")
	)
	(segment
		(start 145.138902 -146.20875)
		(end 146.018504 -146.20875)
		(width 0.508)
		(layer "F.Cu")
		(net "GND")
	)
	(segment
		(start 61.07176 -180.435758)
		(end 61.07176 -179.922424)
		(width 0.4572)
		(layer "F.Cu")
		(net "GND")
	)
	(segment
		(start 72.142096 -126.85903)
		(end 71.741792 -127.259334)
		(width 0.3556)
		(layer "F.Cu")
		(net "GND")
	)
	(segment
		(start 47.10176 -181.846474)
		(end 47.10176 -180.974746)
		(width 0.508)
		(layer "F.Cu")
		(net "GND")
	)
	(segment
		(start 70.54215 -141.25829)
		(end 70.14337 -140.85951)
		(width 0.3556)
		(layer "F.Cu")
		(net "GND")
	)
	(segment
		(start 34.418778 -106.139488)
		(end 34.976816 -105.58145)
		(width 0.4572)
		(layer "F.Cu")
		(net "GND")
	)
	(segment
		(start 58.470546 -67.739006)
		(end 58.470546 -67.741038)
		(width 0.254)
		(layer "F.Cu")
		(net "GND")
	)
	(segment
		(start 128.452372 -137.88771)
		(end 128.452372 -137.49909)
		(width 0.1778)
		(layer "F.Cu")
		(net "GND")
	)
	(segment
		(start 67.154044 -82.228182)
		(end 66.886328 -81.960466)
		(width 0.3048)
		(layer "F.Cu")
		(net "GND")
	)
	(segment
		(start 138.338052 -152.53335)
		(end 138.53795 -152.333452)
		(width 0.1778)
		(layer "F.Cu")
		(net "GND")
	)
	(segment
		(start 67.340988 -127.658114)
		(end 67.19189 -127.807466)
		(width 0.3556)
		(layer "F.Cu")
		(net "GND")
	)
	(segment
		(start 39.047674 -132.266436)
		(end 39.14902 -132.16509)
		(width 0.3556)
		(layer "F.Cu")
		(net "GND")
	)
	(segment
		(start 63.741808 -134.459218)
		(end 63.741808 -134.459472)
		(width 0.381)
		(layer "F.Cu")
		(net "GND")
	)
	(segment
		(start 66.857626 -64.004698)
		(end 67.109848 -64.25692)
		(width 0.254)
		(layer "F.Cu")
		(net "GND")
	)
	(segment
		(start 70.964044 -73.583038)
		(end 70.964044 -74.283062)
		(width 0.3048)
		(layer "F.Cu")
		(net "GND")
	)
	(segment
		(start 64.515746 -67.360038)
		(end 64.429386 -67.360038)
		(width 0.254)
		(layer "F.Cu")
		(net "GND")
	)
	(segment
		(start 181.01564 -200.946258)
		(end 180.09616 -200.026778)
		(width 0.508)
		(layer "F.Cu")
		(net "GND")
	)
	(segment
		(start 56.484266 -67.360038)
		(end 56.484266 -67.358006)
		(width 0.3048)
		(layer "F.Cu")
		(net "GND")
	)
	(segment
		(start 85.411818 -146.163538)
		(end 85.411818 -145.459958)
		(width 0.4572)
		(layer "F.Cu")
		(net "GND")
	)
	(segment
		(start 54.595268 -86.862666)
		(end 54.61254 -86.879938)
		(width 0.254)
		(layer "F.Cu")
		(net "GND")
	)
	(segment
		(start 71.807578 -76.157582)
		(end 72.063864 -76.413868)
		(width 0.3048)
		(layer "F.Cu")
		(net "GND")
	)
	(segment
		(start 106.074718 -136.340342)
		(end 106.0323 -136.297924)
		(width 0.1778)
		(layer "F.Cu")
		(net "GND")
	)
	(segment
		(start 52.531518 -91.153996)
		(end 53.394356 -90.291158)
		(width 0.254)
		(layer "F.Cu")
		(net "GND")
	)
	(segment
		(start 47.308516 -74.935842)
		(end 46.942248 -75.30211)
		(width 0.3048)
		(layer "F.Cu")
		(net "GND")
	)
	(segment
		(start 51.299872 -70.298818)
		(end 51.199796 -70.298818)
		(width 0.3048)
		(layer "F.Cu")
		(net "GND")
	)
	(segment
		(start 74.53376 -187.358782)
		(end 74.53376 -187.726574)
		(width 0.508)
		(layer "F.Cu")
		(net "GND")
	)
	(segment
		(start 45.037248 -68.968874)
		(end 44.656248 -68.587874)
		(width 0.3048)
		(layer "F.Cu")
		(net "GND")
	)
	(segment
		(start 49.901602 -173.999144)
		(end 50.41519 -173.999144)
		(width 0.4572)
		(layer "F.Cu")
		(net "GND")
	)
	(segment
		(start 44.656248 -67.384422)
		(end 44.1325 -67.90817)
		(width 0.3048)
		(layer "F.Cu")
		(net "GND")
	)
	(segment
		(start 40.400732 -68.128642)
		(end 41.75125 -68.128642)
		(width 0.254)
		(layer "F.Cu")
		(net "GND")
	)
	(segment
		(start 62.941708 -140.05941)
		(end 62.94247 -140.05941)
		(width 0.3556)
		(layer "F.Cu")
		(net "GND")
	)
	(segment
		(start 64.541908 -132.859526)
		(end 64.539876 -132.859526)
		(width 0.3556)
		(layer "F.Cu")
		(net "GND")
	)
	(segment
		(start 60.58154 -78.419198)
		(end 60.800996 -78.199742)
		(width 0.3556)
		(layer "F.Cu")
		(net "GND")
	)
	(segment
		(start 73.342246 -136.859518)
		(end 73.341738 -136.859518)
		(width 0.3556)
		(layer "F.Cu")
		(net "GND")
	)
	(segment
		(start 68.401946 -67.360038)
		(end 68.401946 -68.21932)
		(width 0.254)
		(layer "F.Cu")
		(net "GND")
	)
	(segment
		(start 130.42392 -136.734296)
		(end 130.537966 -136.62025)
		(width 0.1778)
		(layer "F.Cu")
		(net "GND")
	)
	(segment
		(start 143.310102 -134.19455)
		(end 144.218914 -134.19455)
		(width 0.508)
		(layer "F.Cu")
		(net "GND")
	)
	(segment
		(start 88.291924 -181.190646)
		(end 87.57412 -181.190646)
		(width 0.508)
		(layer "F.Cu")
		(net "GND")
	)
	(segment
		(start 66.141854 -133.65734)
		(end 66.141854 -133.659626)
		(width 0.381)
		(layer "F.Cu")
		(net "GND")
	)
	(segment
		(start 122.66676 -187.133484)
		(end 122.72772 -187.072524)
		(width 0.508)
		(layer "F.Cu")
		(net "GND")
	)
	(segment
		(start 75.96886 -161.142934)
		(end 75.96886 -160.866582)
		(width 0.508)
		(layer "F.Cu")
		(net "GND")
	)
	(segment
		(start 19.543776 -100.039678)
		(end 18.803874 -100.039678)
		(width 0.508)
		(layer "F.Cu")
		(net "GND")
	)
	(segment
		(start 77.86116 -184.703974)
		(end 77.96276 -184.805574)
		(width 0.508)
		(layer "F.Cu")
		(net "GND")
	)
	(segment
		(start 52.81676 -187.726574)
		(end 52.81676 -186.862974)
		(width 0.508)
		(layer "F.Cu")
		(net "GND")
	)
	(segment
		(start 59.359038 -89.906094)
		(end 59.359038 -89.52611)
		(width 0.254)
		(layer "F.Cu")
		(net "GND")
	)
	(segment
		(start 43.362626 -89.063068)
		(end 42.69994 -89.063068)
		(width 0.381)
		(layer "F.Cu")
		(net "GND")
	)
	(segment
		(start 49.609248 -77.315822)
		(end 49.609248 -78.015846)
		(width 0.3048)
		(layer "F.Cu")
		(net "GND")
	)
	(segment
		(start 61.145166 -97.110042)
		(end 60.129166 -97.110042)
		(width 0.4572)
		(layer "F.Cu")
		(net "GND")
	)
	(segment
		(start 66.540888 -132.458206)
		(end 66.141854 -132.85724)
		(width 0.381)
		(layer "F.Cu")
		(net "GND")
	)
	(segment
		(start 180.015642 -205.199488)
		(end 180.015642 -200.937368)
		(width 0.508)
		(layer "F.Cu")
		(net "GND")
	)
	(segment
		(start 67.340988 -133.258306)
		(end 66.9417 -133.657594)
		(width 0.381)
		(layer "F.Cu")
		(net "GND")
	)
	(segment
		(start 177.71364 -139.720574)
		(end 177.992278 -139.720574)
		(width 0.508)
		(layer "F.Cu")
		(net "GND")
	)
	(segment
		(start 44.251626 -80.002126)
		(end 44.656248 -80.002126)
		(width 0.3048)
		(layer "F.Cu")
		(net "GND")
	)
	(segment
		(start 137.193528 -62.736222)
		(end 136.290304 -62.736222)
		(width 0.508)
		(layer "F.Cu")
		(net "GND")
	)
	(segment
		(start 43.920156 -81.416906)
		(end 43.053 -81.416906)
		(width 0.3048)
		(layer "F.Cu")
		(net "GND")
	)
	(segment
		(start 143.835882 -173.608746)
		(end 145.275808 -173.608746)
		(width 0.254)
		(layer "F.Cu")
		(net "GND")
	)
	(segment
		(start 53.144928 -171.290742)
		(end 53.056028 -171.201842)
		(width 0.508)
		(layer "F.Cu")
		(net "GND")
	)
	(segment
		(start 66.540888 -133.258306)
		(end 66.141854 -133.65734)
		(width 0.381)
		(layer "F.Cu")
		(net "GND")
	)
	(segment
		(start 92.555822 -167.14851)
		(end 92.10421 -166.696898)
		(width 0.381)
		(layer "F.Cu")
		(net "GND")
	)
	(segment
		(start 73.860914 -65.688972)
		(end 74.111612 -65.93967)
		(width 0.3048)
		(layer "F.Cu")
		(net "GND")
	)
	(segment
		(start 93.437964 -172.040804)
		(end 93.665548 -172.268388)
		(width 0.4572)
		(layer "F.Cu")
		(net "GND")
	)
	(segment
		(start 66.153538 -141.65961)
		(end 66.550286 -141.262862)
		(width 0.3556)
		(layer "F.Cu")
		(net "GND")
	)
	(segment
		(start 63.739776 -136.059418)
		(end 63.741808 -136.059418)
		(width 0.381)
		(layer "F.Cu")
		(net "GND")
	)
	(segment
		(start 46.552866 -65.458594)
		(end 46.915578 -65.821306)
		(width 0.3048)
		(layer "F.Cu")
		(net "GND")
	)
	(segment
		(start 43.249088 -65.451482)
		(end 43.603672 -65.096898)
		(width 0.3048)
		(layer "F.Cu")
		(net "GND")
	)
	(segment
		(start 64.82207 -69.27977)
		(end 64.455802 -69.646038)
		(width 0.254)
		(layer "F.Cu")
		(net "GND")
	)
	(segment
		(start 67.7418 -133.657594)
		(end 67.7418 -133.659626)
		(width 0.381)
		(layer "F.Cu")
		(net "GND")
	)
	(segment
		(start 62.443106 -69.265038)
		(end 62.443106 -68.503038)
		(width 0.3048)
		(layer "F.Cu")
		(net "GND")
	)
	(segment
		(start 63.340996 -137.258298)
		(end 63.739776 -136.859518)
		(width 0.381)
		(layer "F.Cu")
		(net "GND")
	)
	(segment
		(start 122.583702 -53.450236)
		(end 123.631452 -53.450236)
		(width 0.4572)
		(layer "F.Cu")
		(net "GND")
	)
	(segment
		(start 174.643034 -42.724578)
		(end 174.636684 -42.718228)
		(width 0.4572)
		(layer "F.Cu")
		(net "GND")
	)
	(segment
		(start 71.616316 -65.366646)
		(end 71.345044 -65.637918)
		(width 0.3048)
		(layer "F.Cu")
		(net "GND")
	)
	(segment
		(start 59.99607 -65.307718)
		(end 60.717938 -65.307718)
		(width 0.3048)
		(layer "F.Cu")
		(net "GND")
	)
	(segment
		(start 68.141088 -132.458206)
		(end 67.7418 -132.857494)
		(width 0.381)
		(layer "F.Cu")
		(net "GND")
	)
	(segment
		(start 45.633132 -138.558016)
		(end 46.026578 -138.16457)
		(width 0.3556)
		(layer "F.Cu")
		(net "GND")
	)
	(segment
		(start 35.366452 -83.294982)
		(end 35.366452 -84.303362)
		(width 0.508)
		(layer "F.Cu")
		(net "GND")
	)
	(segment
		(start 49.608994 -64.736218)
		(end 49.658524 -64.785748)
		(width 0.3048)
		(layer "F.Cu")
		(net "GND")
	)
	(segment
		(start 65.6082 -5.661406)
		(end 65.6082 -5.872988)
		(width 0.4572)
		(layer "F.Cu")
		(net "GND")
	)
	(segment
		(start 9.0551 -118.706646)
		(end 9.056624 -118.70817)
		(width 0.254)
		(layer "F.Cu")
		(net "GND")
	)
	(segment
		(start 68.547996 -67.360038)
		(end 69.062092 -66.845942)
		(width 0.381)
		(layer "F.Cu")
		(net "GND")
	)
	(segment
		(start 37.885878 -14.62532)
		(end 37.885878 -15.24254)
		(width 0.4572)
		(layer "F.Cu")
		(net "GND")
	)
	(segment
		(start 64.219836 -87.700358)
		(end 64.18834 -87.731854)
		(width 0.254)
		(layer "F.Cu")
		(net "GND")
	)
	(segment
		(start 73.9267 -74.464418)
		(end 74.250042 -74.464418)
		(width 0.3048)
		(layer "F.Cu")
		(net "GND")
	)
	(segment
		(start 67.7418 -132.857494)
		(end 67.7418 -132.859526)
		(width 0.381)
		(layer "F.Cu")
		(net "GND")
	)
	(segment
		(start 83.850226 -30.470602)
		(end 83.850226 -29.149802)
		(width 0.4572)
		(layer "F.Cu")
		(net "GND")
	)
	(segment
		(start 66.942208 -140.05941)
		(end 66.9417 -140.05941)
		(width 0.3556)
		(layer "F.Cu")
		(net "GND")
	)
	(segment
		(start 36.014914 -201.09053)
		(end 36.014914 -200.32853)
		(width 0.508)
		(layer "F.Cu")
		(net "GND")
	)
	(segment
		(start 165.951408 -73.236582)
		(end 165.951408 -74.012552)
		(width 0.4572)
		(layer "F.Cu")
		(net "GND")
	)
	(segment
		(start 46.178216 -79.302102)
		(end 46.180248 -79.302102)
		(width 0.254)
		(layer "F.Cu")
		(net "GND")
	)
	(segment
		(start 104.73309 -162.781488)
		(end 104.473502 -162.781488)
		(width 0.508)
		(layer "F.Cu")
		(net "GND")
	)
	(segment
		(start 57.386474 -86.862666)
		(end 57.217564 -87.031576)
		(width 0.254)
		(layer "F.Cu")
		(net "GND")
	)
	(segment
		(start 66.990214 -105.903522)
		(end 67.749928 -105.903522)
		(width 0.4572)
		(layer "F.Cu")
		(net "GND")
	)
	(segment
		(start 43.249088 -85.381338)
		(end 43.417998 -85.212428)
		(width 0.3048)
		(layer "F.Cu")
		(net "GND")
	)
	(segment
		(start 106.740198 -170.796204)
		(end 106.570526 -170.965876)
		(width 0.508)
		(layer "F.Cu")
		(net "GND")
	)
	(segment
		(start 68.678044 -70.310502)
		(end 68.680076 -70.310502)
		(width 0.3048)
		(layer "F.Cu")
		(net "GND")
	)
	(segment
		(start 49.990248 -71.356982)
		(end 50.752248 -71.356982)
		(width 0.3048)
		(layer "F.Cu")
		(net "GND")
	)
	(segment
		(start 57.217564 -87.031576)
		(end 57.217564 -87.551006)
		(width 0.254)
		(layer "F.Cu")
		(net "GND")
	)
	(segment
		(start 166.211504 -167.764968)
		(end 166.870634 -167.764968)
		(width 0.508)
		(layer "F.Cu")
		(net "GND")
	)
	(segment
		(start 69.447664 -69.610478)
		(end 69.821044 -69.237098)
		(width 0.3048)
		(layer "F.Cu")
		(net "GND")
	)
	(segment
		(start 20.12569 -131.344416)
		(end 20.73529 -131.344416)
		(width 0.4572)
		(layer "F.Cu")
		(net "GND")
	)
	(segment
		(start 67.620642 -64.736218)
		(end 67.141344 -64.25692)
		(width 0.254)
		(layer "F.Cu")
		(net "GND")
	)
	(segment
		(start 55.517034 -85.762846)
		(end 55.544466 -85.762846)
		(width 0.254)
		(layer "F.Cu")
		(net "GND")
	)
	(segment
		(start 48.137572 -69.318378)
		(end 48.085248 -69.370702)
		(width 0.3048)
		(layer "F.Cu")
		(net "GND")
	)
	(segment
		(start 48.899826 -89.601294)
		(end 48.899826 -89.132918)
		(width 0.254)
		(layer "F.Cu")
		(net "GND")
	)
	(segment
		(start 49.680368 -69.370702)
		(end 49.51857 -69.5325)
		(width 0.3048)
		(layer "F.Cu")
		(net "GND")
	)
	(segment
		(start 125.787912 -148.575522)
		(end 126.767844 -148.575522)
		(width 0.1778)
		(layer "F.Cu")
		(net "GND")
	)
	(segment
		(start 108.28401 -157.447742)
		(end 107.244134 -157.447742)
		(width 0.508)
		(layer "F.Cu")
		(net "GND")
	)
	(segment
		(start 66.141854 -143.256508)
		(end 66.540888 -142.857474)
		(width 0.3556)
		(layer "F.Cu")
		(net "GND")
	)
	(segment
		(start 64.001396 -80.935068)
		(end 64.001396 -80.600042)
		(width 0.3048)
		(layer "F.Cu")
		(net "GND")
	)
	(segment
		(start 73.342246 -141.65961)
		(end 73.341738 -141.65961)
		(width 0.3556)
		(layer "F.Cu")
		(net "GND")
	)
	(segment
		(start 57.38876 -180.619908)
		(end 57.38876 -179.922424)
		(width 0.508)
		(layer "F.Cu")
		(net "GND")
	)
	(segment
		(start 52.350162 -20.94992)
		(end 52.350162 -22.404578)
		(width 0.4572)
		(layer "F.Cu")
		(net "GND")
	)
	(segment
		(start 65.6082 -5.872988)
		(end 66.06794 -6.332728)
		(width 0.4572)
		(layer "F.Cu")
		(net "GND")
	)
	(segment
		(start 46.03242 -134.16407)
		(end 46.032166 -134.164324)
		(width 0.3556)
		(layer "F.Cu")
		(net "GND")
	)
	(segment
		(start 37.225732 -19.015202)
		(end 36.787582 -19.453352)
		(width 0.508)
		(layer "F.Cu")
		(net "GND")
	)
	(segment
		(start 75.67676 -184.805574)
		(end 75.67676 -183.991758)
		(width 0.508)
		(layer "F.Cu")
		(net "GND")
	)
	(segment
		(start 144.502632 -186.936634)
		(end 144.51076 -186.944762)
		(width 0.4572)
		(layer "F.Cu")
		(net "GND")
	)
	(segment
		(start 73.699116 -61.977778)
		(end 74.111612 -62.390274)
		(width 0.3048)
		(layer "F.Cu")
		(net "GND")
	)
	(segment
		(start 44.607226 -179.317904)
		(end 45.282612 -179.317904)
		(width 0.4572)
		(layer "F.Cu")
		(net "GND")
	)
	(segment
		(start 58.330338 -84.520278)
		(end 58.23077 -84.619846)
		(width 0.3048)
		(layer "F.Cu")
		(net "GND")
	)
	(segment
		(start 149.10816 -174.80788)
		(end 148.63572 -175.28032)
		(width 0.381)
		(layer "F.Cu")
		(net "GND")
	)
	(segment
		(start 168.843198 -105.706418)
		(end 168.843198 -104.839008)
		(width 0.1778)
		(layer "F.Cu")
		(net "GND")
	)
	(segment
		(start 68.941188 -142.858236)
		(end 68.542408 -142.459456)
		(width 0.3556)
		(layer "F.Cu")
		(net "GND")
	)
	(segment
		(start 131.81076 -183.772302)
		(end 131.699 -183.660542)
		(width 0.508)
		(layer "F.Cu")
		(net "GND")
	)
	(segment
		(start 42.580052 -74.33945)
		(end 42.180764 -74.33945)
		(width 0.3048)
		(layer "F.Cu")
		(net "GND")
	)
	(segment
		(start 67.154044 -75.195938)
		(end 66.780664 -75.569318)
		(width 0.3048)
		(layer "F.Cu")
		(net "GND")
	)
	(segment
		(start 67.82308 -65.298066)
		(end 67.620642 -65.095628)
		(width 0.254)
		(layer "F.Cu")
		(net "GND")
	)
	(segment
		(start 46.432978 -136.164574)
		(end 46.833028 -136.564624)
		(width 0.3556)
		(layer "F.Cu")
		(net "GND")
	)
	(segment
		(start 59.015122 -201.09053)
		(end 59.015122 -200.32853)
		(width 0.508)
		(layer "F.Cu")
		(net "GND")
	)
	(segment
		(start 71.7423 -137.659618)
		(end 71.741792 -137.659618)
		(width 0.3556)
		(layer "F.Cu")
		(net "GND")
	)
	(segment
		(start 42.753534 -79.015844)
		(end 42.710608 -78.972918)
		(width 0.254)
		(layer "F.Cu")
		(net "GND")
	)
	(segment
		(start 64.940942 -142.057628)
		(end 64.542924 -141.65961)
		(width 0.3556)
		(layer "F.Cu")
		(net "GND")
	)
	(segment
		(start 26.84018 -104.737662)
		(end 27.131264 -105.028746)
		(width 0.4572)
		(layer "F.Cu")
		(net "GND")
	)
	(segment
		(start 58.23077 -83.095846)
		(end 58.23077 -83.857846)
		(width 0.3048)
		(layer "F.Cu")
		(net "GND")
	)
	(segment
		(start 39.976298 -128.906778)
		(end 40.033194 -128.963674)
		(width 0.3556)
		(layer "F.Cu")
		(net "GND")
	)
	(segment
		(start 47.03953 -84.544408)
		(end 47.293784 -84.544408)
		(width 0.3048)
		(layer "F.Cu")
		(net "GND")
	)
	(segment
		(start 71.7423 -143.259556)
		(end 71.741792 -143.259556)
		(width 0.3556)
		(layer "F.Cu")
		(net "GND")
	)
	(segment
		(start 174.643034 -43.762168)
		(end 174.643034 -42.724578)
		(width 0.4572)
		(layer "F.Cu")
		(net "GND")
	)
	(segment
		(start 138.525758 -177.752248)
		(end 138.525758 -178.858672)
		(width 0.254)
		(layer "F.Cu")
		(net "GND")
	)
	(segment
		(start 63.739776 -136.859518)
		(end 63.741808 -136.859518)
		(width 0.381)
		(layer "F.Cu")
		(net "GND")
	)
	(segment
		(start 81.60385 -156.759402)
		(end 82.051144 -156.759402)
		(width 0.4572)
		(layer "F.Cu")
		(net "GND")
	)
	(segment
		(start 32.98444 -3.255264)
		(end 33.404556 -2.835148)
		(width 0.4572)
		(layer "F.Cu")
		(net "GND")
	)
	(segment
		(start 46.946566 -65.821306)
		(end 46.552866 -66.215006)
		(width 0.254)
		(layer "F.Cu")
		(net "GND")
	)
	(segment
		(start 30.992572 -131.153662)
		(end 30.98292 -131.14401)
		(width 0.4572)
		(layer "F.Cu")
		(net "GND")
	)
	(segment
		(start 159.252412 -75.31735)
		(end 159.351726 -75.416664)
		(width 0.4572)
		(layer "F.Cu")
		(net "GND")
	)
	(segment
		(start 40.43299 -134.964424)
		(end 40.83304 -134.564374)
		(width 0.3556)
		(layer "F.Cu")
		(net "GND")
	)
	(segment
		(start 46.552866 -65.455038)
		(end 46.552866 -64.661288)
		(width 0.3048)
		(layer "F.Cu")
		(net "GND")
	)
	(segment
		(start 125.8062 -51.2064)
		(end 125.8062 -50.470562)
		(width 0.4572)
		(layer "F.Cu")
		(net "GND")
	)
	(segment
		(start 121.015506 -205.199488)
		(end 121.015506 -201.034904)
		(width 0.508)
		(layer "F.Cu")
		(net "GND")
	)
	(segment
		(start 50.701448 -79.352902)
		(end 50.752248 -79.302102)
		(width 0.3048)
		(layer "F.Cu")
		(net "GND")
	)
	(segment
		(start 110.460028 -76.406248)
		(end 112.105694 -76.406248)
		(width 0.3048)
		(layer "F.Cu")
		(net "GND")
	)
	(segment
		(start 136.250426 -45.81779)
		(end 136.250426 -47.188628)
		(width 0.2794)
		(layer "F.Cu")
		(net "GND")
	)
	(segment
		(start 47.818294 -105.382314)
		(end 47.818294 -106.40695)
		(width 0.4572)
		(layer "F.Cu")
		(net "GND")
	)
	(segment
		(start 49.129696 -64.25692)
		(end 49.608994 -64.736218)
		(width 0.3048)
		(layer "F.Cu")
		(net "GND")
	)
	(segment
		(start 106.242612 -73.627234)
		(end 106.021632 -73.406254)
		(width 0.3048)
		(layer "F.Cu")
		(net "GND")
	)
	(segment
		(start 149.811994 -44.680124)
		(end 150.492714 -44.680124)
		(width 0.4572)
		(layer "F.Cu")
		(net "GND")
	)
	(segment
		(start 68.401946 -67.360038)
		(end 68.547996 -67.360038)
		(width 0.381)
		(layer "F.Cu")
		(net "GND")
	)
	(segment
		(start 124.754894 -172.625512)
		(end 124.10821 -172.625512)
		(width 0.508)
		(layer "F.Cu")
		(net "GND")
	)
	(segment
		(start 128.05156 -187.350146)
		(end 127.73406 -187.032646)
		(width 0.508)
		(layer "F.Cu")
		(net "GND")
	)
	(segment
		(start 63.729362 -69.646038)
		(end 64.429386 -69.646038)
		(width 0.254)
		(layer "F.Cu")
		(net "GND")
	)
	(segment
		(start 69.073776 -78.649322)
		(end 69.346572 -78.922118)
		(width 0.3048)
		(layer "F.Cu")
		(net "GND")
	)
	(segment
		(start 52.27193 -83.476846)
		(end 51.571906 -83.476846)
		(width 0.3048)
		(layer "F.Cu")
		(net "GND")
	)
	(segment
		(start 82.15884 -85.839554)
		(end 82.7278 -85.839554)
		(width 0.508)
		(layer "F.Cu")
		(net "GND")
	)
	(segment
		(start 15.248128 -58.085482)
		(end 16.18488 -58.085482)
		(width 0.4572)
		(layer "F.Cu")
		(net "GND")
	)
	(segment
		(start 18.918936 -58.39968)
		(end 19.967956 -58.39968)
		(width 0.508)
		(layer "F.Cu")
		(net "GND")
	)
	(segment
		(start 82.53476 -187.726574)
		(end 82.53476 -186.961018)
		(width 0.508)
		(layer "F.Cu")
		(net "GND")
	)
	(segment
		(start 71.365872 -74.68489)
		(end 70.964044 -74.283062)
		(width 0.3048)
		(layer "F.Cu")
		(net "GND")
	)
	(segment
		(start 163.235894 -128.32334)
		(end 164.314124 -128.32334)
		(width 0.508)
		(layer "F.Cu")
		(net "GND")
	)
	(segment
		(start 66.223388 -87.551006)
		(end 66.223388 -87.548466)
		(width 0.3048)
		(layer "F.Cu")
		(net "GND")
	)
	(segment
		(start 67.701922 -67.360038)
		(end 67.328542 -67.733418)
		(width 0.3048)
		(layer "F.Cu")
		(net "GND")
	)
	(segment
		(start 44.642024 -72.948038)
		(end 45.037248 -73.343262)
		(width 0.3048)
		(layer "F.Cu")
		(net "GND")
	)
	(segment
		(start 126.718314 -140.175488)
		(end 125.787912 -140.175488)
		(width 0.1778)
		(layer "F.Cu")
		(net "GND")
	)
	(segment
		(start 105.8291 -134.697978)
		(end 106.05008 -134.918958)
		(width 0.1778)
		(layer "F.Cu")
		(net "GND")
	)
	(segment
		(start 126.20117 -174.667926)
		(end 125.558042 -174.667926)
		(width 0.508)
		(layer "F.Cu")
		(net "GND")
	)
	(segment
		(start 63.340996 -134.058406)
		(end 63.741808 -134.459218)
		(width 0.381)
		(layer "F.Cu")
		(net "GND")
	)
	(segment
		(start 152.27046 -149.073362)
		(end 151.437086 -149.073362)
		(width 0.508)
		(layer "F.Cu")
		(net "GND")
	)
	(segment
		(start 72.063864 -67.408044)
		(end 72.014334 -67.457574)
		(width 0.3048)
		(layer "F.Cu")
		(net "GND")
	)
	(segment
		(start 11.24458 -153.217118)
		(end 11.24458 -153.73731)
		(width 0.508)
		(layer "F.Cu")
		(net "GND")
	)
	(segment
		(start 167.675052 -92.93479)
		(end 167.675052 -93.682566)
		(width 0.508)
		(layer "F.Cu")
		(net "GND")
	)
	(segment
		(start 104.033574 -180.757322)
		(end 103.476806 -181.31409)
		(width 0.4572)
		(layer "F.Cu")
		(net "GND")
	)
	(segment
		(start 53.056028 -171.201842)
		(end 53.056028 -170.630088)
		(width 0.508)
		(layer "F.Cu")
		(net "GND")
	)
	(segment
		(start 127.03556 -187.426346)
		(end 127.03556 -187.726574)
		(width 0.508)
		(layer "F.Cu")
		(net "GND")
	)
	(segment
		(start 41.88968 -65.93967)
		(end 40.754046 -65.93967)
		(width 0.381)
		(layer "F.Cu")
		(net "GND")
	)
	(segment
		(start 73.24344 -83.70062)
		(end 73.36663 -83.70062)
		(width 0.254)
		(layer "F.Cu")
		(net "GND")
	)
	(segment
		(start 53.70576 -179.922424)
		(end 53.70576 -180.70195)
		(width 0.4572)
		(layer "F.Cu")
		(net "GND")
	)
	(segment
		(start 161.600896 -33.589214)
		(end 162.29838 -33.589214)
		(width 0.508)
		(layer "F.Cu")
		(net "GND")
	)
	(segment
		(start 42.194988 -74.93635)
		(end 41.75125 -74.492612)
		(width 0.3048)
		(layer "F.Cu")
		(net "GND")
	)
	(segment
		(start 67.918076 -70.310502)
		(end 67.916044 -70.310502)
		(width 0.254)
		(layer "F.Cu")
		(net "GND")
	)
	(segment
		(start 60.473336 -90.421968)
		(end 60.473336 -89.56294)
		(width 0.254)
		(layer "F.Cu")
		(net "GND")
	)
	(segment
		(start 49.044606 -79.11846)
		(end 49.228248 -79.302102)
		(width 0.3048)
		(layer "F.Cu")
		(net "GND")
	)
	(segment
		(start 125.94336 -187.726574)
		(end 125.94336 -187.023248)
		(width 0.381)
		(layer "F.Cu")
		(net "GND")
	)
	(segment
		(start 148.857208 -173.375828)
		(end 148.85924 -173.375828)
		(width 0.508)
		(layer "F.Cu")
		(net "GND")
	)
	(segment
		(start 48.587406 -64.736218)
		(end 48.576992 -64.725804)
		(width 0.3048)
		(layer "F.Cu")
		(net "GND")
	)
	(segment
		(start 149.108922 -29.903928)
		(end 148.292566 -29.903928)
		(width 0.508)
		(layer "F.Cu")
		(net "GND")
	)
	(segment
		(start 88.12276 -187.726574)
		(end 88.12276 -187.543948)
		(width 0.508)
		(layer "F.Cu")
		(net "GND")
	)
	(segment
		(start 44.607226 -180.333904)
		(end 45.282612 -180.333904)
		(width 0.4572)
		(layer "F.Cu")
		(net "GND")
	)
	(segment
		(start 75.16114 -67.743324)
		(end 75.16114 -67.882516)
		(width 0.254)
		(layer "F.Cu")
		(net "GND")
	)
	(segment
		(start 134.60476 -187.726574)
		(end 134.60476 -187.402216)
		(width 0.381)
		(layer "F.Cu")
		(net "GND")
	)
	(segment
		(start 72.942196 -142.859252)
		(end 72.5424 -142.459456)
		(width 0.3556)
		(layer "F.Cu")
		(net "GND")
	)
	(segment
		(start 108.764832 -66.827654)
		(end 109.036612 -67.099434)
		(width 0.3048)
		(layer "F.Cu")
		(net "GND")
	)
	(segment
		(start 89.291414 -31.673038)
		(end 89.850214 -31.114238)
		(width 0.4572)
		(layer "F.Cu")
		(net "GND")
	)
	(segment
		(start 99.584002 -158.523686)
		(end 100.228146 -158.523686)
		(width 0.4572)
		(layer "F.Cu")
		(net "GND")
	)
	(segment
		(start 72.784208 -64.985646)
		(end 72.901556 -65.102994)
		(width 0.3048)
		(layer "F.Cu")
		(net "GND")
	)
	(segment
		(start 54.833012 -89.387426)
		(end 54.833012 -89.048844)
		(width 0.254)
		(layer "F.Cu")
		(net "GND")
	)
	(segment
		(start 149.10816 -174.807372)
		(end 149.10816 -174.80788)
		(width 0.381)
		(layer "F.Cu")
		(net "GND")
	)
	(segment
		(start 64.18961 -84.238846)
		(end 63.489586 -84.238846)
		(width 0.254)
		(layer "F.Cu")
		(net "GND")
	)
	(segment
		(start 42.24782 -80.249522)
		(end 42.69613 -80.249522)
		(width 0.254)
		(layer "F.Cu")
		(net "GND")
	)
	(segment
		(start 72.795384 -70.263512)
		(end 72.795384 -70.731634)
		(width 0.3048)
		(layer "F.Cu")
		(net "GND")
	)
	(segment
		(start 131.988052 -152.50795)
		(end 131.737862 -152.25776)
		(width 0.1778)
		(layer "F.Cu")
		(net "GND")
	)
	(segment
		(start 148.476208 -173.756828)
		(end 148.857208 -173.375828)
		(width 0.508)
		(layer "F.Cu")
		(net "GND")
	)
	(segment
		(start 113.486946 -167.011604)
		(end 113.486946 -167.486584)
		(width 0.254)
		(layer "F.Cu")
		(net "GND")
	)
	(segment
		(start 86.250272 -30.952948)
		(end 86.250272 -29.149802)
		(width 0.381)
		(layer "F.Cu")
		(net "GND")
	)
	(segment
		(start 47.349918 -131.705604)
		(end 46.891956 -132.163566)
		(width 0.3556)
		(layer "F.Cu")
		(net "GND")
	)
	(segment
		(start 43.334178 -67.898264)
		(end 42.757852 -67.898264)
		(width 0.3048)
		(layer "F.Cu")
		(net "GND")
	)
	(segment
		(start 149.057868 -40.373046)
		(end 148.951188 -40.373046)
		(width 0.4572)
		(layer "F.Cu")
		(net "GND")
	)
	(segment
		(start 42.70248 -64.31407)
		(end 43.51528 -64.31407)
		(width 0.4064)
		(layer "F.Cu")
		(net "GND")
	)
	(segment
		(start 41.88968 -63.468758)
		(end 41.88968 -63.50127)
		(width 0.381)
		(layer "F.Cu")
		(net "GND")
	)
	(segment
		(start 67.535044 -68.324222)
		(end 68.297044 -68.324222)
		(width 0.3048)
		(layer "F.Cu")
		(net "GND")
	)
	(segment
		(start 66.9417 -132.857494)
		(end 66.9417 -132.859526)
		(width 0.381)
		(layer "F.Cu")
		(net "GND")
	)
	(segment
		(start 73.341992 -140.85951)
		(end 73.341738 -140.85951)
		(width 0.3556)
		(layer "F.Cu")
		(net "GND")
	)
	(segment
		(start 135.08863 -183.92013)
		(end 135.36676 -184.19826)
		(width 0.508)
		(layer "F.Cu")
		(net "GND")
	)
	(segment
		(start 39.272718 -130.563874)
		(end 40.03294 -130.563874)
		(width 0.3556)
		(layer "F.Cu")
		(net "GND")
	)
	(segment
		(start 64.542924 -141.65961)
		(end 64.541908 -141.65961)
		(width 0.3556)
		(layer "F.Cu")
		(net "GND")
	)
	(segment
		(start 41.75125 -74.492612)
		(end 41.75125 -74.257154)
		(width 0.3048)
		(layer "F.Cu")
		(net "GND")
	)
	(segment
		(start 45.037248 -69.370702)
		(end 45.037248 -68.968874)
		(width 0.3048)
		(layer "F.Cu")
		(net "GND")
	)
	(segment
		(start 49.650142 -29.149802)
		(end 49.650142 -27.626818)
		(width 0.4572)
		(layer "F.Cu")
		(net "GND")
	)
	(segment
		(start 117.13591 -152.8318)
		(end 116.50091 -152.1968)
		(width 0.508)
		(layer "F.Cu")
		(net "GND")
	)
	(segment
		(start 71.491094 -81.722976)
		(end 71.296276 -81.528158)
		(width 0.3048)
		(layer "F.Cu")
		(net "GND")
	)
	(segment
		(start 59.113166 -98.617786)
		(end 59.113166 -97.110042)
		(width 0.4572)
		(layer "F.Cu")
		(net "GND")
	)
	(segment
		(start 43.920156 -67.90817)
		(end 43.344084 -67.90817)
		(width 0.3048)
		(layer "F.Cu")
		(net "GND")
	)
	(segment
		(start 170.879008 -93.423994)
		(end 170.436794 -93.866208)
		(width 0.508)
		(layer "F.Cu")
		(net "GND")
	)
	(segment
		(start 68.254372 -88.961468)
		(end 68.341748 -89.048844)
		(width 0.254)
		(layer "F.Cu")
		(net "GND")
	)
	(segment
		(start 54.861206 -170.630088)
		(end 55.684166 -170.630088)
		(width 0.4572)
		(layer "F.Cu")
		(net "GND")
	)
	(segment
		(start 65.341754 -141.65961)
		(end 65.33896 -141.65961)
		(width 0.3556)
		(layer "F.Cu")
		(net "GND")
	)
	(segment
		(start 73.247758 -81.588864)
		(end 73.994264 -81.588864)
		(width 0.254)
		(layer "F.Cu")
		(net "GND")
	)
	(segment
		(start 52.81676 -181.59095)
		(end 52.81676 -181.846474)
		(width 0.508)
		(layer "F.Cu")
		(net "GND")
	)
	(segment
		(start 139.93876 -186.862974)
		(end 139.93876 -187.726574)
		(width 0.508)
		(layer "F.Cu")
		(net "GND")
	)
	(segment
		(start 48.21174 -87.551006)
		(end 48.20412 -87.551006)
		(width 0.254)
		(layer "F.Cu")
		(net "GND")
	)
	(segment
		(start 38.482778 -11.86434)
		(end 38.482778 -13.489178)
		(width 0.1524)
		(layer "F.Cu")
		(net "GND")
	)
	(segment
		(start 57.55894 -180.790088)
		(end 57.38876 -180.619908)
		(width 0.508)
		(layer "F.Cu")
		(net "GND")
	)
	(segment
		(start 160.723326 -137.080752)
		(end 161.08426 -136.719818)
		(width 0.508)
		(layer "F.Cu")
		(net "GND")
	)
	(segment
		(start 49.988216 -79.302102)
		(end 49.990248 -79.302102)
		(width 0.254)
		(layer "F.Cu")
		(net "GND")
	)
	(segment
		(start 71.652892 -63.49492)
		(end 72.04964 -63.891668)
		(width 0.3048)
		(layer "F.Cu")
		(net "GND")
	)
	(segment
		(start 171.916598 -102.535736)
		(end 172.297852 -102.91699)
		(width 0.1778)
		(layer "F.Cu")
		(net "GND")
	)
	(segment
		(start 68.678044 -73.583038)
		(end 68.889372 -73.794366)
		(width 0.3048)
		(layer "F.Cu")
		(net "GND")
	)
	(segment
		(start 73.298558 -65.688972)
		(end 73.860914 -65.688972)
		(width 0.3048)
		(layer "F.Cu")
		(net "GND")
	)
	(segment
		(start 91.5035 -183.778398)
		(end 91.5035 -183.34228)
		(width 0.508)
		(layer "F.Cu")
		(net "GND")
	)
	(segment
		(start 67.340988 -132.458206)
		(end 66.9417 -132.857494)
		(width 0.381)
		(layer "F.Cu")
		(net "GND")
	)
	(segment
		(start 72.081136 -83.67268)
		(end 72.081136 -83.690714)
		(width 0.3048)
		(layer "F.Cu")
		(net "GND")
	)
	(segment
		(start 50.041048 -79.352902)
		(end 50.701448 -79.352902)
		(width 0.3048)
		(layer "F.Cu")
		(net "GND")
	)
	(segment
		(start 71.341996 -135.659368)
		(end 70.9422 -135.259572)
		(width 0.3556)
		(layer "F.Cu")
		(net "GND")
	)
	(segment
		(start 55.150766 -85.396578)
		(end 55.517034 -85.762846)
		(width 0.254)
		(layer "F.Cu")
		(net "GND")
	)
	(segment
		(start 52.012088 -64.129158)
		(end 52.360576 -64.129158)
		(width 0.3048)
		(layer "F.Cu")
		(net "GND")
	)
	(segment
		(start 109.25556 -169.07764)
		(end 109.77372 -168.55948)
		(width 0.508)
		(layer "F.Cu")
		(net "GND")
	)
	(segment
		(start 128.452372 -137.49909)
		(end 129.33807 -136.613392)
		(width 0.1778)
		(layer "F.Cu")
		(net "GND")
	)
	(segment
		(start 106.262932 -76.406248)
		(end 104.73182 -76.406248)
		(width 0.3048)
		(layer "F.Cu")
		(net "GND")
	)
	(segment
		(start 58.941716 -128.859026)
		(end 58.941716 -128.859534)
		(width 0.3556)
		(layer "F.Cu")
		(net "GND")
	)
	(segment
		(start 106.05008 -133.382512)
		(end 105.671366 -133.003798)
		(width 0.1778)
		(layer "F.Cu")
		(net "GND")
	)
	(segment
		(start 43.937428 -79.687928)
		(end 44.251626 -80.002126)
		(width 0.3048)
		(layer "F.Cu")
		(net "GND")
	)
	(segment
		(start 93.150182 -20.94992)
		(end 93.150182 -22.473158)
		(width 0.381)
		(layer "F.Cu")
		(net "GND")
	)
	(segment
		(start 68.889372 -73.794366)
		(end 68.889372 -74.071734)
		(width 0.3048)
		(layer "F.Cu")
		(net "GND")
	)
	(segment
		(start 35.54095 -73.402698)
		(end 35.03295 -73.910698)
		(width 0.508)
		(layer "F.Cu")
		(net "GND")
	)
	(segment
		(start 140.065252 -142.55115)
		(end 140.089636 -142.575534)
		(width 0.1778)
		(layer "F.Cu")
		(net "GND")
	)
	(segment
		(start 45.232828 -136.564116)
		(end 45.232828 -136.564624)
		(width 0.3556)
		(layer "F.Cu")
		(net "GND")
	)
	(segment
		(start 57.83834 -84.312252)
		(end 57.530746 -84.619846)
		(width 0.3048)
		(layer "F.Cu")
		(net "GND")
	)
	(segment
		(start 90.866468 -124.2949)
		(end 90.2081 -123.636532)
		(width 0.2032)
		(layer "F.Cu")
		(net "GND")
	)
	(segment
		(start 117.33276 -187.726574)
		(end 117.33276 -186.991498)
		(width 0.508)
		(layer "F.Cu")
		(net "GND")
	)
	(segment
		(start 43.52163 -88.103964)
		(end 43.51528 -88.097614)
		(width 0.3048)
		(layer "F.Cu")
		(net "GND")
	)
	(segment
		(start 190.3222 -126.1872)
		(end 190.0682 -126.1872)
		(width 0.508)
		(layer "F.Cu")
		(net "GND")
	)
	(segment
		(start 61.628274 -98.78314)
		(end 61.628274 -98.542856)
		(width 0.4572)
		(layer "F.Cu")
		(net "GND")
	)
	(segment
		(start 63.310516 -80.709262)
		(end 63.201296 -80.600042)
		(width 0.254)
		(layer "F.Cu")
		(net "GND")
	)
	(segment
		(start 43.937428 -75.185016)
		(end 44.511722 -75.185016)
		(width 0.254)
		(layer "F.Cu")
		(net "GND")
	)
	(segment
		(start 146.4818 -166.520876)
		(end 146.390868 -166.520876)
		(width 0.254)
		(layer "F.Cu")
		(net "GND")
	)
	(segment
		(start 28.85948 -101.138228)
		(end 28.85948 -101.138736)
		(width 0.4572)
		(layer "F.Cu")
		(net "GND")
	)
	(segment
		(start 144.51076 -186.944762)
		(end 144.51076 -187.726574)
		(width 0.4572)
		(layer "F.Cu")
		(net "GND")
	)
	(segment
		(start 43.26382 -69.936868)
		(end 42.836338 -69.936868)
		(width 0.3048)
		(layer "F.Cu")
		(net "GND")
	)
	(segment
		(start 94.051882 -177.354992)
		(end 92.691712 -177.354992)
		(width 0.508)
		(layer "F.Cu")
		(net "GND")
	)
	(segment
		(start 148.951188 -40.373046)
		(end 148.447252 -40.876982)
		(width 0.4572)
		(layer "F.Cu")
		(net "GND")
	)
	(segment
		(start 57.897268 -89.591388)
		(end 57.897268 -89.048844)
		(width 0.254)
		(layer "F.Cu")
		(net "GND")
	)
	(segment
		(start 145.164302 -148.21535)
		(end 145.95983 -148.21535)
		(width 0.508)
		(layer "F.Cu")
		(net "GND")
	)
	(segment
		(start 91.468702 -180.626512)
		(end 91.81846 -180.97627)
		(width 0.508)
		(layer "F.Cu")
		(net "GND")
	)
	(segment
		(start 73.829164 -83.470242)
		(end 74.250042 -83.470242)
		(width 0.254)
		(layer "F.Cu")
		(net "GND")
	)
	(segment
		(start 78.007464 -98.038666)
		(end 78.515718 -98.038666)
		(width 0.4572)
		(layer "F.Cu")
		(net "GND")
	)
	(segment
		(start 68.678044 -81.528158)
		(end 68.678044 -82.228182)
		(width 0.254)
		(layer "F.Cu")
		(net "GND")
	)
	(segment
		(start 30.324298 -169.072052)
		(end 29.91866 -169.47769)
		(width 0.508)
		(layer "F.Cu")
		(net "GND")
	)
	(segment
		(start 39.081202 -4.500372)
		(end 39.081202 -3.854704)
		(width 0.4572)
		(layer "F.Cu")
		(net "GND")
	)
	(segment
		(start 47.323248 -73.343262)
		(end 47.321216 -73.345294)
		(width 0.3048)
		(layer "F.Cu")
		(net "GND")
	)
	(segment
		(start 61.036708 -81.300066)
		(end 60.800996 -81.300066)
		(width 0.3048)
		(layer "F.Cu")
		(net "GND")
	)
	(segment
		(start 86.49335 -174.3964)
		(end 86.721696 -174.624746)
		(width 0.254)
		(layer "F.Cu")
		(net "GND")
	)
	(segment
		(start 67.535044 -68.324222)
		(end 67.535044 -69.016372)
		(width 0.4572)
		(layer "F.Cu")
		(net "GND")
	)
	(segment
		(start 142.84833 -184.037478)
		(end 143.36776 -184.556908)
		(width 0.508)
		(layer "F.Cu")
		(net "GND")
	)
	(segment
		(start 48.38065 -86.862666)
		(end 48.682148 -86.561168)
		(width 0.254)
		(layer "F.Cu")
		(net "GND")
	)
	(segment
		(start 96.829372 -160.019492)
		(end 97.935542 -160.019492)
		(width 0.508)
		(layer "F.Cu")
		(net "GND")
	)
	(segment
		(start 66.540888 -136.458198)
		(end 66.142108 -136.059418)
		(width 0.381)
		(layer "F.Cu")
		(net "GND")
	)
	(segment
		(start 165.335712 -161.780728)
		(end 165.34638 -161.77006)
		(width 0.508)
		(layer "F.Cu")
		(net "GND")
	)
	(segment
		(start 165.989 -186.055)
		(end 165.411404 -185.477404)
		(width 0.508)
		(layer "F.Cu")
		(net "GND")
	)
	(segment
		(start 41.75125 -84.701634)
		(end 42.212006 -85.16239)
		(width 0.254)
		(layer "F.Cu")
		(net "GND")
	)
	(segment
		(start 139.025884 -178.858672)
		(end 139.025884 -177.185574)
		(width 0.254)
		(layer "F.Cu")
		(net "GND")
	)
	(segment
		(start 187.95619 -123.860306)
		(end 188.665866 -123.860306)
		(width 0.4572)
		(layer "F.Cu")
		(net "GND")
	)
	(segment
		(start 111.015526 -205.199488)
		(end 111.015526 -201.034904)
		(width 0.508)
		(layer "F.Cu")
		(net "GND")
	)
	(segment
		(start 50.53076 -180.303424)
		(end 50.14976 -179.922424)
		(width 0.4572)
		(layer "F.Cu")
		(net "GND")
	)
	(segment
		(start 103.523288 -71.90613)
		(end 104.73182 -71.90613)
		(width 0.254)
		(layer "F.Cu")
		(net "GND")
	)
	(segment
		(start 69.440044 -69.610478)
		(end 69.447664 -69.610478)
		(width 0.3048)
		(layer "F.Cu")
		(net "GND")
	)
	(segment
		(start 80.24876 -187.726574)
		(end 80.24876 -186.924696)
		(width 0.508)
		(layer "F.Cu")
		(net "GND")
	)
	(segment
		(start 72.142096 -140.459206)
		(end 71.7423 -140.05941)
		(width 0.3556)
		(layer "F.Cu")
		(net "GND")
	)
	(segment
		(start 40.83304 -137.764012)
		(end 40.83304 -137.763758)
		(width 0.3556)
		(layer "F.Cu")
		(net "GND")
	)
	(segment
		(start 62.40018 -90.23604)
		(end 62.40018 -89.048844)
		(width 0.254)
		(layer "F.Cu")
		(net "GND")
	)
	(segment
		(start 14.440662 -112.127284)
		(end 14.76756 -112.454182)
		(width 0.254)
		(layer "F.Cu")
		(net "GND")
	)
	(segment
		(start 60.800996 -81.599786)
		(end 60.800996 -81.300066)
		(width 0.3048)
		(layer "F.Cu")
		(net "GND")
	)
	(segment
		(start 72.543162 -66.89725)
		(end 72.063864 -67.376548)
		(width 0.3048)
		(layer "F.Cu")
		(net "GND")
	)
	(segment
		(start 42.450258 -29.149802)
		(end 42.450258 -30.633162)
		(width 0.381)
		(layer "F.Cu")
		(net "GND")
	)
	(segment
		(start 82.87004 -121.641616)
		(end 83.816444 -121.641616)
		(width 0.2032)
		(layer "F.Cu")
		(net "GND")
	)
	(segment
		(start 80.994758 -164.374576)
		(end 80.994758 -165.767512)
		(width 0.254)
		(layer "F.Cu")
		(net "GND")
	)
	(segment
		(start 68.141088 -137.258298)
		(end 67.742308 -136.859518)
		(width 0.381)
		(layer "F.Cu")
		(net "GND")
	)
	(segment
		(start 73.641458 -77.691234)
		(end 73.715372 -77.61732)
		(width 0.3048)
		(layer "F.Cu")
		(net "GND")
	)
	(segment
		(start 66.55689 -81.960466)
		(end 66.17589 -81.579466)
		(width 0.3048)
		(layer "F.Cu")
		(net "GND")
	)
	(segment
		(start 151.10968 -31.33598)
		(end 151.26081 -31.18485)
		(width 0.3556)
		(layer "F.Cu")
		(net "GND")
	)
	(segment
		(start 104.22001 -156.154628)
		(end 104.22001 -155.697936)
		(width 0.254)
		(layer "F.Cu")
		(net "GND")
	)
	(segment
		(start 18.44929 -47.992284)
		(end 19.109944 -47.992284)
		(width 0.508)
		(layer "F.Cu")
		(net "GND")
	)
	(segment
		(start 45.049186 -84.468462)
		(end 45.049186 -84.427314)
		(width 0.3048)
		(layer "F.Cu")
		(net "GND")
	)
	(segment
		(start 89.39276 -184.805574)
		(end 89.39276 -184.349898)
		(width 0.508)
		(layer "F.Cu")
		(net "GND")
	)
	(segment
		(start 49.04105 -67.360038)
		(end 48.539146 -67.360038)
		(width 0.3048)
		(layer "F.Cu")
		(net "GND")
	)
	(segment
		(start 71.7423 -140.85951)
		(end 71.741792 -140.85951)
		(width 0.3556)
		(layer "F.Cu")
		(net "GND")
	)
	(segment
		(start 137.474452 -137.06475)
		(end 137.338054 -136.928352)
		(width 0.1778)
		(layer "F.Cu")
		(net "GND")
	)
	(segment
		(start 67.156076 -70.310502)
		(end 67.549776 -70.704202)
		(width 0.3048)
		(layer "F.Cu")
		(net "GND")
	)
	(segment
		(start 86.361524 -167.949626)
		(end 86.686644 -167.624506)
		(width 0.254)
		(layer "F.Cu")
		(net "GND")
	)
	(segment
		(start 95.048578 -120.236996)
		(end 95.830136 -120.236996)
		(width 0.4572)
		(layer "F.Cu")
		(net "GND")
	)
	(segment
		(start 106.151426 -61.623194)
		(end 105.86847 -61.90615)
		(width 0.3048)
		(layer "F.Cu")
		(net "GND")
	)
	(segment
		(start 124.672852 -143.69415)
		(end 124.991368 -143.375634)
		(width 0.1778)
		(layer "F.Cu")
		(net "GND")
	)
	(segment
		(start 128.37922 -110.92815)
		(end 127.633476 -110.92815)
		(width 0.508)
		(layer "F.Cu")
		(net "GND")
	)
	(segment
		(start 74.142346 -135.259572)
		(end 74.141838 -135.259572)
		(width 0.3556)
		(layer "F.Cu")
		(net "GND")
	)
	(segment
		(start 53.962046 -158.998158)
		(end 54.787546 -158.998158)
		(width 0.508)
		(layer "F.Cu")
		(net "GND")
	)
	(segment
		(start 23.030942 -52.286408)
		(end 21.98624 -52.286408)
		(width 0.4572)
		(layer "F.Cu")
		(net "GND")
	)
	(segment
		(start 162.296856 -117.319552)
		(end 161.27603 -117.319552)
		(width 0.508)
		(layer "F.Cu")
		(net "GND")
	)
	(segment
		(start 50.502058 -64.594994)
		(end 50.989484 -64.594994)
		(width 0.3048)
		(layer "F.Cu")
		(net "GND")
	)
	(segment
		(start 46.389544 -64.497966)
		(end 46.389544 -63.898526)
		(width 0.3048)
		(layer "F.Cu")
		(net "GND")
	)
	(segment
		(start 70.9422 -135.259572)
		(end 70.941692 -135.259572)
		(width 0.3556)
		(layer "F.Cu")
		(net "GND")
	)
	(segment
		(start 45.806868 -80.383126)
		(end 45.037248 -81.152746)
		(width 0.3048)
		(layer "F.Cu")
		(net "GND")
	)
	(segment
		(start 43.937428 -84.19084)
		(end 44.153582 -83.974686)
		(width 0.3048)
		(layer "F.Cu")
		(net "GND")
	)
	(segment
		(start 43.51528 -64.31407)
		(end 43.662346 -64.31407)
		(width 0.381)
		(layer "F.Cu")
		(net "GND")
	)
	(segment
		(start 163.261294 -124.97054)
		(end 164.11067 -124.97054)
		(width 0.508)
		(layer "F.Cu")
		(net "GND")
	)
	(segment
		(start 31.264098 -171.32046)
		(end 31.614618 -171.67098)
		(width 0.508)
		(layer "F.Cu")
		(net "GND")
	)
	(segment
		(start 34.842958 -188.652404)
		(end 34.306256 -188.652404)
		(width 0.508)
		(layer "F.Cu")
		(net "GND")
	)
	(segment
		(start 137.855452 -115.779042)
		(end 137.626852 -115.779042)
		(width 0.1778)
		(layer "F.Cu")
		(net "GND")
	)
	(segment
		(start 58.400696 -80.600042)
		(end 58.400696 -79.799942)
		(width 0.3048)
		(layer "F.Cu")
		(net "GND")
	)
	(segment
		(start 52.889404 -68.503038)
		(end 52.511706 -68.12534)
		(width 0.254)
		(layer "F.Cu")
		(net "GND")
	)
	(segment
		(start 70.142354 -141.65961)
		(end 70.141846 -141.65961)
		(width 0.3556)
		(layer "F.Cu")
		(net "GND")
	)
	(segment
		(start 45.606716 -86.879938)
		(end 45.589444 -86.862666)
		(width 0.254)
		(layer "F.Cu")
		(net "GND")
	)
	(segment
		(start 126.83871 -138.175492)
		(end 125.787912 -138.175492)
		(width 0.1778)
		(layer "F.Cu")
		(net "GND")
	)
	(segment
		(start 95.74784 -202.424284)
		(end 95.74784 -201.06132)
		(width 0.508)
		(layer "F.Cu")
		(net "GND")
	)
	(segment
		(start 59.250072 -29.149802)
		(end 59.250072 -30.922468)
		(width 0.4572)
		(layer "F.Cu")
		(net "GND")
	)
	(segment
		(start 108.90123 -136.397746)
		(end 109.201458 -136.697974)
		(width 0.1778)
		(layer "F.Cu")
		(net "GND")
	)
	(segment
		(start 150.47976 -187.001404)
		(end 150.47976 -187.726574)
		(width 0.508)
		(layer "F.Cu")
		(net "GND")
	)
	(segment
		(start 74.874882 -85.172804)
		(end 74.610976 -84.908898)
		(width 0.254)
		(layer "F.Cu")
		(net "GND")
	)
	(segment
		(start 177.40122 -53.881528)
		(end 178.228498 -53.881528)
		(width 0.508)
		(layer "F.Cu")
		(net "GND")
	)
	(segment
		(start 73.298812 -62.378082)
		(end 73.699116 -61.977778)
		(width 0.3048)
		(layer "F.Cu")
		(net "GND")
	)
	(segment
		(start 50.752248 -76.029566)
		(end 50.752248 -76.209398)
		(width 0.3048)
		(layer "F.Cu")
		(net "GND")
	)
	(segment
		(start 11.576812 -12.013946)
		(end 11.576812 -12.821412)
		(width 0.508)
		(layer "F.Cu")
		(net "GND")
	)
	(segment
		(start 66.141854 -141.65961)
		(end 66.153538 -141.65961)
		(width 0.3556)
		(layer "F.Cu")
		(net "GND")
	)
	(segment
		(start 56.245252 -99.22637)
		(end 56.065166 -99.046284)
		(width 0.4572)
		(layer "F.Cu")
		(net "GND")
	)
	(segment
		(start 51.9557 -89.048844)
		(end 52.211478 -88.793066)
		(width 0.254)
		(layer "F.Cu")
		(net "GND")
	)
	(segment
		(start 177.3047 -55.084472)
		(end 178.040538 -55.084472)
		(width 0.508)
		(layer "F.Cu")
		(net "GND")
	)
	(segment
		(start 132.737352 -67.458336)
		(end 134.499858 -67.458336)
		(width 0.508)
		(layer "F.Cu")
		(net "GND")
	)
	(segment
		(start 144.3228 -39.389812)
		(end 145.571718 -39.389812)
		(width 0.3048)
		(layer "F.Cu")
		(net "GND")
	)
	(segment
		(start 65.37325 -7.424166)
		(end 65.956942 -7.424166)
		(width 0.508)
		(layer "F.Cu")
		(net "GND")
	)
	(segment
		(start 73.742042 -142.859506)
		(end 73.341992 -142.459456)
		(width 0.3556)
		(layer "F.Cu")
		(net "GND")
	)
	(segment
		(start 115.3541 -63.259462)
		(end 115.3541 -63.259716)
		(width 0.4572)
		(layer "F.Cu")
		(net "GND")
	)
	(segment
		(start 48.4378 -106.25455)
		(end 48.2854 -106.40695)
		(width 0.4572)
		(layer "F.Cu")
		(net "GND")
	)
	(segment
		(start 47.362618 -130.565144)
		(end 47.361094 -130.56362)
		(width 0.3556)
		(layer "F.Cu")
		(net "GND")
	)
	(segment
		(start 71.341996 -142.059406)
		(end 70.9422 -141.65961)
		(width 0.3556)
		(layer "F.Cu")
		(net "GND")
	)
	(segment
		(start 71.741792 -127.259334)
		(end 71.741792 -127.259588)
		(width 0.3556)
		(layer "F.Cu")
		(net "GND")
	)
	(segment
		(start 59.685428 -88.360758)
		(end 59.685428 -88.438482)
		(width 0.3048)
		(layer "F.Cu")
		(net "GND")
	)
	(segment
		(start 139.98956 -113.983008)
		(end 139.98956 -113.230406)
		(width 0.508)
		(layer "F.Cu")
		(net "GND")
	)
	(segment
		(start 67.916044 -69.610478)
		(end 67.923664 -69.610478)
		(width 0.3048)
		(layer "F.Cu")
		(net "GND")
	)
	(segment
		(start 163.325048 -144.46123)
		(end 163.325048 -143.571722)
		(width 0.508)
		(layer "F.Cu")
		(net "GND")
	)
	(segment
		(start 71.137018 -82.728562)
		(end 71.317104 -82.908648)
		(width 0.3048)
		(layer "F.Cu")
		(net "GND")
	)
	(segment
		(start 145.138902 -147.19935)
		(end 145.983452 -147.19935)
		(width 0.4572)
		(layer "F.Cu")
		(net "GND")
	)
	(segment
		(start 94.051882 -177.354992)
		(end 94.051882 -178.370992)
		(width 0.508)
		(layer "F.Cu")
		(net "GND")
	)
	(segment
		(start 63.90132 -81.492598)
		(end 63.90132 -81.300066)
		(width 0.3048)
		(layer "F.Cu")
		(net "GND")
	)
	(segment
		(start 191.78905 -120.65)
		(end 192.151 -120.65)
		(width 0.508)
		(layer "F.Cu")
		(net "GND")
	)
	(segment
		(start 131.737862 -152.25776)
		(end 131.737862 -151.32558)
		(width 0.1778)
		(layer "F.Cu")
		(net "GND")
	)
	(segment
		(start 64.34836 -184.703974)
		(end 64.24676 -184.805574)
		(width 0.508)
		(layer "F.Cu")
		(net "GND")
	)
	(segment
		(start 14.485366 -65.290446)
		(end 13.731748 -65.290446)
		(width 0.4572)
		(layer "F.Cu")
		(net "GND")
	)
	(segment
		(start 56.743092 -88.739218)
		(end 56.87695 -88.605106)
		(width 0.254)
		(layer "F.Cu")
		(net "GND")
	)
	(segment
		(start 35.875468 -76.36383)
		(end 35.880548 -76.35875)
		(width 0.4572)
		(layer "F.Cu")
		(net "GND")
	)
	(segment
		(start 42.052494 -72.401176)
		(end 41.822116 -72.631554)
		(width 0.254)
		(layer "F.Cu")
		(net "GND")
	)
	(segment
		(start 62.793372 -84.594446)
		(end 63.133986 -84.594446)
		(width 0.254)
		(layer "F.Cu")
		(net "GND")
	)
	(segment
		(start 11.18616 -115.602512)
		(end 9.0551 -117.733572)
		(width 0.254)
		(layer "F.Cu")
		(net "GND")
	)
	(segment
		(start 59.299856 -89.16543)
		(end 59.335924 -89.129362)
		(width 0.254)
		(layer "F.Cu")
		(net "GND")
	)
	(segment
		(start 46.09338 -123.866656)
		(end 47.179738 -123.866656)
		(width 0.381)
		(layer "F.Cu")
		(net "GND")
	)
	(segment
		(start 160.619948 -144.46123)
		(end 160.619948 -143.647922)
		(width 0.508)
		(layer "F.Cu")
		(net "GND")
	)
	(segment
		(start 78.994254 -98.517202)
		(end 79.457296 -98.517202)
		(width 0.4572)
		(layer "F.Cu")
		(net "GND")
	)
	(segment
		(start 41.94302 -80.554322)
		(end 42.24782 -80.249522)
		(width 0.254)
		(layer "F.Cu")
		(net "GND")
	)
	(segment
		(start 80.66532 -182.877714)
		(end 80.59928 -182.811674)
		(width 0.508)
		(layer "F.Cu")
		(net "GND")
	)
	(segment
		(start 136.137904 -136.775698)
		(end 136.137904 -135.825484)
		(width 0.1778)
		(layer "F.Cu")
		(net "GND")
	)
	(segment
		(start 68.685664 -69.610478)
		(end 69.059044 -69.237098)
		(width 0.3048)
		(layer "F.Cu")
		(net "GND")
	)
	(segment
		(start 106.72064 -184.551574)
		(end 106.72064 -183.974486)
		(width 0.508)
		(layer "F.Cu")
		(net "GND")
	)
	(segment
		(start 59.716924 -87.700358)
		(end 59.716924 -87.755222)
		(width 0.3048)
		(layer "F.Cu")
		(net "GND")
	)
	(segment
		(start 47.293784 -84.544408)
		(end 47.599346 -84.238846)
		(width 0.3048)
		(layer "F.Cu")
		(net "GND")
	)
	(segment
		(start 46.180248 -80.009746)
		(end 45.806868 -80.383126)
		(width 0.254)
		(layer "F.Cu")
		(net "GND")
	)
	(segment
		(start 49.317656 -71.356982)
		(end 48.493172 -70.532498)
		(width 0.3048)
		(layer "F.Cu")
		(net "GND")
	)
	(segment
		(start 136.25576 -110.383574)
		(end 136.25576 -109.708442)
		(width 0.4572)
		(layer "F.Cu")
		(net "GND")
	)
	(segment
		(start 48.466248 -80.002126)
		(end 48.466248 -79.302102)
		(width 0.3048)
		(layer "F.Cu")
		(net "GND")
	)
	(segment
		(start 154.7622 -135.768842)
		(end 154.7622 -135.036052)
		(width 0.508)
		(layer "F.Cu")
		(net "GND")
	)
	(segment
		(start 83.729322 -22.831298)
		(end 83.728052 -22.831298)
		(width 0.381)
		(layer "F.Cu")
		(net "GND")
	)
	(segment
		(start 68.814188 -66.598038)
		(end 68.401946 -66.598038)
		(width 0.381)
		(layer "F.Cu")
		(net "GND")
	)
	(segment
		(start 42.70248 -86.878922)
		(end 42.70248 -87.284814)
		(width 0.381)
		(layer "F.Cu")
		(net "GND")
	)
	(segment
		(start 106.97464 -184.805574)
		(end 106.72064 -184.551574)
		(width 0.508)
		(layer "F.Cu")
		(net "GND")
	)
	(segment
		(start 49.0855 -86.804246)
		(end 49.343818 -86.804246)
		(width 0.254)
		(layer "F.Cu")
		(net "GND")
	)
	(segment
		(start 118.050818 -19.049238)
		(end 118.050818 -19.84883)
		(width 0.4572)
		(layer "F.Cu")
		(net "GND")
	)
	(segment
		(start 71.137018 -82.401156)
		(end 71.137018 -82.728562)
		(width 0.3048)
		(layer "F.Cu")
		(net "GND")
	)
	(segment
		(start 54.61254 -86.879938)
		(end 54.61254 -86.766146)
		(width 0.254)
		(layer "F.Cu")
		(net "GND")
	)
	(segment
		(start 68.506086 -169.87393)
		(end 68.506086 -170.83405)
		(width 0.508)
		(layer "F.Cu")
		(net "GND")
	)
	(segment
		(start 172.606208 -94.709742)
		(end 172.279056 -94.38259)
		(width 0.4572)
		(layer "F.Cu")
		(net "GND")
	)
	(segment
		(start 48.842422 -86.561168)
		(end 49.0855 -86.804246)
		(width 0.254)
		(layer "F.Cu")
		(net "GND")
	)
	(segment
		(start 67.742308 -136.059418)
		(end 67.7418 -136.059418)
		(width 0.381)
		(layer "F.Cu")
		(net "GND")
	)
	(segment
		(start 49.825402 -69.265038)
		(end 49.719738 -69.370702)
		(width 0.3048)
		(layer "F.Cu")
		(net "GND")
	)
	(segment
		(start 93.532452 -131.960112)
		(end 93.532452 -132.758942)
		(width 0.4572)
		(layer "F.Cu")
		(net "GND")
	)
	(segment
		(start 80.994758 -165.767512)
		(end 80.740758 -166.021512)
		(width 0.254)
		(layer "F.Cu")
		(net "GND")
	)
	(segment
		(start 40.45839 -85.39988)
		(end 41.156636 -84.701634)
		(width 0.254)
		(layer "F.Cu")
		(net "GND")
	)
	(segment
		(start 48.539146 -68.122038)
		(end 48.539146 -67.360038)
		(width 0.3048)
		(layer "F.Cu")
		(net "GND")
	)
	(segment
		(start 123.75896 -187.726574)
		(end 123.75896 -187.040774)
		(width 0.508)
		(layer "F.Cu")
		(net "GND")
	)
	(segment
		(start 65.341754 -143.259556)
		(end 65.338706 -143.259556)
		(width 0.3556)
		(layer "F.Cu")
		(net "GND")
	)
	(segment
		(start 86.44763 -145.459958)
		(end 85.411818 -145.459958)
		(width 0.4572)
		(layer "F.Cu")
		(net "GND")
	)
	(segment
		(start 74.542142 -142.05966)
		(end 74.142092 -141.65961)
		(width 0.3556)
		(layer "F.Cu")
		(net "GND")
	)
	(segment
		(start 99.916234 -17.689322)
		(end 99.916234 -18.521426)
		(width 0.4572)
		(layer "F.Cu")
		(net "GND")
	)
	(segment
		(start 30.722062 -169.072052)
		(end 30.324298 -169.072052)
		(width 0.508)
		(layer "F.Cu")
		(net "GND")
	)
	(segment
		(start 91.21267 -176.56429)
		(end 91.214448 -176.562512)
		(width 0.508)
		(layer "F.Cu")
		(net "GND")
	)
	(segment
		(start 9.0551 -117.733572)
		(end 9.0551 -118.706646)
		(width 0.254)
		(layer "F.Cu")
		(net "GND")
	)
	(segment
		(start 72.142096 -135.659368)
		(end 71.7423 -135.259572)
		(width 0.381)
		(layer "F.Cu")
		(net "GND")
	)
	(segment
		(start 64.18961 -81.952846)
		(end 64.18961 -81.780888)
		(width 0.3048)
		(layer "F.Cu")
		(net "GND")
	)
	(segment
		(start 54.19471 -174.752508)
		(end 54.19471 -175.806354)
		(width 0.4572)
		(layer "F.Cu")
		(net "GND")
	)
	(segment
		(start 43.51528 -87.284814)
		(end 43.57243 -87.341964)
		(width 0.3048)
		(layer "F.Cu")
		(net "GND")
	)
	(segment
		(start 179.622704 -11.93673)
		(end 179.622704 -12.845796)
		(width 0.508)
		(layer "F.Cu")
		(net "GND")
	)
	(segment
		(start 63.10376 -187.726574)
		(end 63.10376 -186.985402)
		(width 0.508)
		(layer "F.Cu")
		(net "GND")
	)
	(segment
		(start 57.770522 -67.741038)
		(end 57.770522 -68.503038)
		(width 0.3048)
		(layer "F.Cu")
		(net "GND")
	)
	(segment
		(start 71.285354 -64.919352)
		(end 71.616316 -64.919352)
		(width 0.254)
		(layer "F.Cu")
		(net "GND")
	)
	(segment
		(start 66.44132 -63.09995)
		(end 66.44132 -64.004698)
		(width 0.254)
		(layer "F.Cu")
		(net "GND")
	)
	(segment
		(start 109.45876 -187.726574)
		(end 109.45876 -186.91733)
		(width 0.508)
		(layer "F.Cu")
		(net "GND")
	)
	(segment
		(start 41.512744 -74.257154)
		(end 41.75125 -74.257154)
		(width 0.381)
		(layer "F.Cu")
		(net "GND")
	)
	(segment
		(start 126.767844 -148.575522)
		(end 126.966472 -148.77415)
		(width 0.1778)
		(layer "F.Cu")
		(net "GND")
	)
	(segment
		(start 65.898776 -89.989914)
		(end 66.063876 -89.824814)
		(width 0.254)
		(layer "F.Cu")
		(net "GND")
	)
	(segment
		(start 41.024302 -80.554322)
		(end 41.94302 -80.554322)
		(width 0.254)
		(layer "F.Cu")
		(net "GND")
	)
	(segment
		(start 46.486572 -64.594994)
		(end 46.389544 -64.497966)
		(width 0.3048)
		(layer "F.Cu")
		(net "GND")
	)
	(segment
		(start 109.201458 -136.697974)
		(end 110.014258 -136.697974)
		(width 0.1778)
		(layer "F.Cu")
		(net "GND")
	)
	(segment
		(start 28.466288 -122.38736)
		(end 28.466288 -122.874532)
		(width 0.4572)
		(layer "F.Cu")
		(net "GND")
	)
	(segment
		(start 44.231052 -62.067186)
		(end 44.327572 -62.163706)
		(width 0.381)
		(layer "F.Cu")
		(net "GND")
	)
	(segment
		(start 66.146934 -140.85951)
		(end 66.141854 -140.85951)
		(width 0.3556)
		(layer "F.Cu")
		(net "GND")
	)
	(segment
		(start 66.9417 -128.057402)
		(end 66.9417 -128.059434)
		(width 0.3556)
		(layer "F.Cu")
		(net "GND")
	)
	(segment
		(start 47.864268 -64.171322)
		(end 47.591472 -63.898526)
		(width 0.3048)
		(layer "F.Cu")
		(net "GND")
	)
	(segment
		(start 91.622372 -166.696898)
		(end 91.21267 -167.1066)
		(width 0.381)
		(layer "F.Cu")
		(net "GND")
	)
	(segment
		(start 59.756802 -68.129658)
		(end 59.383422 -68.503038)
		(width 0.3048)
		(layer "F.Cu")
		(net "GND")
	)
	(segment
		(start 72.142096 -141.259306)
		(end 71.7423 -140.85951)
		(width 0.3556)
		(layer "F.Cu")
		(net "GND")
	)
	(segment
		(start 73.993248 -76.662534)
		(end 73.806304 -76.662534)
		(width 0.254)
		(layer "F.Cu")
		(net "GND")
	)
	(segment
		(start 9.38022 -155.214828)
		(end 9.38022 -154.46375)
		(width 0.508)
		(layer "F.Cu")
		(net "GND")
	)
	(segment
		(start 59.359038 -89.52611)
		(end 59.299856 -89.466928)
		(width 0.254)
		(layer "F.Cu")
		(net "GND")
	)
	(segment
		(start 62.401196 -78.979522)
		(end 62.401196 -78.999842)
		(width 0.381)
		(layer "F.Cu")
		(net "GND")
	)
	(segment
		(start 93.352874 -162.942778)
		(end 94.337378 -162.942778)
		(width 0.508)
		(layer "F.Cu")
		(net "GND")
	)
	(segment
		(start 47.321216 -74.041254)
		(end 47.323248 -74.043286)
		(width 0.3048)
		(layer "F.Cu")
		(net "GND")
	)
	(segment
		(start 63.177166 -97.243392)
		(end 63.177166 -97.110042)
		(width 0.4572)
		(layer "F.Cu")
		(net "GND")
	)
	(segment
		(start 43.337226 -168.609264)
		(end 44.389294 -168.609264)
		(width 0.508)
		(layer "F.Cu")
		(net "GND")
	)
	(segment
		(start 44.314618 -74.482706)
		(end 44.491148 -74.659236)
		(width 0.254)
		(layer "F.Cu")
		(net "GND")
	)
	(segment
		(start 53.70576 -180.70195)
		(end 53.345842 -181.061868)
		(width 0.4572)
		(layer "F.Cu")
		(net "GND")
	)
	(segment
		(start 33.5407 -12.56538)
		(end 33.5407 -14.619986)
		(width 0.254)
		(layer "F.Cu")
		(net "GND")
	)
	(segment
		(start 43.099736 -86.49589)
		(end 42.711116 -86.49589)
		(width 0.381)
		(layer "F.Cu")
		(net "GND")
	)
	(segment
		(start 47.704248 -68.349622)
		(end 47.704248 -68.084446)
		(width 0.254)
		(layer "F.Cu")
		(net "GND")
	)
	(segment
		(start 67.620642 -65.095628)
		(end 67.620642 -64.736218)
		(width 0.254)
		(layer "F.Cu")
		(net "GND")
	)
	(segment
		(start 134.60476 -187.402216)
		(end 134.22376 -187.021216)
		(width 0.381)
		(layer "F.Cu")
		(net "GND")
	)
	(segment
		(start 53.546502 -27.548078)
		(end 53.850286 -27.851862)
		(width 0.4572)
		(layer "F.Cu")
		(net "GND")
	)
	(segment
		(start 43.57243 -87.341964)
		(end 44.388278 -87.341964)
		(width 0.254)
		(layer "F.Cu")
		(net "GND")
	)
	(segment
		(start 68.542154 -140.85951)
		(end 68.5419 -140.85951)
		(width 0.3556)
		(layer "F.Cu")
		(net "GND")
	)
	(segment
		(start 11.71956 -138.220196)
		(end 11.71956 -137.594848)
		(width 0.508)
		(layer "F.Cu")
		(net "GND")
	)
	(segment
		(start 106.482134 -154.823668)
		(end 106.482134 -155.512262)
		(width 0.4572)
		(layer "F.Cu")
		(net "GND")
	)
	(segment
		(start 43.344084 -67.90817)
		(end 43.336718 -67.900804)
		(width 0.3048)
		(layer "F.Cu")
		(net "GND")
	)
	(segment
		(start 130.79476 -183.936386)
		(end 130.784854 -183.92648)
		(width 0.508)
		(layer "F.Cu")
		(net "GND")
	)
	(segment
		(start 159.60852 -186.810904)
		(end 159.60852 -187.711334)
		(width 0.508)
		(layer "F.Cu")
		(net "GND")
	)
	(segment
		(start 51.205638 -85.396578)
		(end 51.277012 -85.467698)
		(width 0.3048)
		(layer "F.Cu")
		(net "GND")
	)
	(segment
		(start 58.314336 -164.934646)
		(end 58.314336 -165.777672)
		(width 0.508)
		(layer "F.Cu")
		(net "GND")
	)
	(segment
		(start 67.7418 -134.457694)
		(end 67.7418 -134.459472)
		(width 0.381)
		(layer "F.Cu")
		(net "GND")
	)
	(segment
		(start 47.321216 -77.315822)
		(end 47.323248 -77.315822)
		(width 0.3048)
		(layer "F.Cu")
		(net "GND")
	)
	(segment
		(start 43.921172 -72.411082)
		(end 44.275248 -72.057006)
		(width 0.3048)
		(layer "F.Cu")
		(net "GND")
	)
	(segment
		(start 60.942728 -84.066888)
		(end 60.389008 -84.066888)
		(width 0.3048)
		(layer "F.Cu")
		(net "GND")
	)
	(segment
		(start 5.08508 -167.373554)
		(end 4.336034 -167.373554)
		(width 0.508)
		(layer "F.Cu")
		(net "GND")
	)
	(segment
		(start 64.389254 -84.43849)
		(end 64.724026 -84.43849)
		(width 0.254)
		(layer "F.Cu")
		(net "GND")
	)
	(segment
		(start 55.65013 -29.149802)
		(end 55.65013 -27.60345)
		(width 0.4572)
		(layer "F.Cu")
		(net "GND")
	)
	(segment
		(start 90.551762 -18.990818)
		(end 90.354912 -18.793968)
		(width 0.4572)
		(layer "F.Cu")
		(net "GND")
	)
	(segment
		(start 60.800996 -78.999842)
		(end 61.601096 -79.799942)
		(width 0.3556)
		(layer "F.Cu")
		(net "GND")
	)
	(segment
		(start 65.339722 -135.259572)
		(end 65.341754 -135.259572)
		(width 0.381)
		(layer "F.Cu")
		(net "GND")
	)
	(segment
		(start 21.831554 -102.709472)
		(end 21.831554 -104.206802)
		(width 0.508)
		(layer "F.Cu")
		(net "GND")
	)
	(segment
		(start 49.608994 -64.882268)
		(end 49.608994 -64.736218)
		(width 0.254)
		(layer "F.Cu")
		(net "GND")
	)
	(segment
		(start 47.31004 -63.160402)
		(end 47.31004 -63.86703)
		(width 0.3048)
		(layer "F.Cu")
		(net "GND")
	)
	(segment
		(start 47.591472 -63.898526)
		(end 47.278544 -63.898526)
		(width 0.3048)
		(layer "F.Cu")
		(net "GND")
	)
	(segment
		(start 46.040802 -62.556898)
		(end 46.033944 -62.55004)
		(width 0.254)
		(layer "F.Cu")
		(net "GND")
	)
	(segment
		(start 34.227262 -184.444894)
		(end 34.478214 -184.193942)
		(width 0.4572)
		(layer "F.Cu")
		(net "GND")
	)
	(segment
		(start 169.243248 -104.839008)
		(end 169.243248 -106.106468)
		(width 0.1778)
		(layer "F.Cu")
		(net "GND")
	)
	(segment
		(start 131.015486 -201.034904)
		(end 131.015486 -205.199488)
		(width 0.508)
		(layer "F.Cu")
		(net "GND")
	)
	(segment
		(start 41.402 -64.31407)
		(end 41.127172 -64.588898)
		(width 0.381)
		(layer "F.Cu")
		(net "GND")
	)
	(segment
		(start 71.71055 -79.541878)
		(end 72.063864 -79.895192)
		(width 0.254)
		(layer "F.Cu")
		(net "GND")
	)
	(segment
		(start 71.10222 -64.736218)
		(end 71.285354 -64.919352)
		(width 0.254)
		(layer "F.Cu")
		(net "GND")
	)
	(segment
		(start 54.25821 -84.619846)
		(end 53.558186 -84.619846)
		(width 0.3048)
		(layer "F.Cu")
		(net "GND")
	)
	(segment
		(start 56.18861 -15.326868)
		(end 56.721756 -15.860014)
		(width 0.254)
		(layer "F.Cu")
		(net "GND")
	)
	(segment
		(start 58.808366 -84.03463)
		(end 58.60415 -84.238846)
		(width 0.3048)
		(layer "F.Cu")
		(net "GND")
	)
	(segment
		(start 63.340996 -141.258036)
		(end 63.739522 -140.85951)
		(width 0.381)
		(layer "F.Cu")
		(net "GND")
	)
	(segment
		(start 73.470516 -64.944752)
		(end 73.652634 -65.12687)
		(width 0.3048)
		(layer "F.Cu")
		(net "GND")
	)
	(segment
		(start 51.811682 -68.122038)
		(end 52.511706 -68.122038)
		(width 0.254)
		(layer "F.Cu")
		(net "GND")
	)
	(segment
		(start 16.463264 -135.485632)
		(end 16.899382 -135.049514)
		(width 0.254)
		(layer "F.Cu")
		(net "GND")
	)
	(segment
		(start 64.541908 -134.459218)
		(end 64.541908 -134.459472)
		(width 0.381)
		(layer "F.Cu")
		(net "GND")
	)
	(segment
		(start 161.043112 -173.55058)
		(end 159.375602 -173.55058)
		(width 0.381)
		(layer "F.Cu")
		(net "GND")
	)
	(segment
		(start 67.07759 -62.55004)
		(end 66.580512 -63.047118)
		(width 0.254)
		(layer "F.Cu")
		(net "GND")
	)
	(segment
		(start 72.5424 -141.65961)
		(end 72.541892 -141.65961)
		(width 0.3556)
		(layer "F.Cu")
		(net "GND")
	)
	(segment
		(start 93.811344 -184.774586)
		(end 93.811344 -185.790586)
		(width 0.508)
		(layer "F.Cu")
		(net "GND")
	)
	(segment
		(start 48.2473 -69.209666)
		(end 48.138588 -69.318378)
		(width 0.3048)
		(layer "F.Cu")
		(net "GND")
	)
	(segment
		(start 43.099736 -86.49589)
		(end 43.099736 -86.322916)
		(width 0.254)
		(layer "F.Cu")
		(net "GND")
	)
	(segment
		(start 114.532918 -24.781764)
		(end 114.882676 -24.432006)
		(width 0.254)
		(layer "F.Cu")
		(net "GND")
	)
	(segment
		(start 21.014944 -201.09053)
		(end 21.014944 -200.32853)
		(width 0.508)
		(layer "F.Cu")
		(net "GND")
	)
	(segment
		(start 53.850286 -27.851862)
		(end 53.850286 -29.149802)
		(width 0.4572)
		(layer "F.Cu")
		(net "GND")
	)
	(segment
		(start 50.3301 -89.4842)
		(end 50.3301 -89.048844)
		(width 0.254)
		(layer "F.Cu")
		(net "GND")
	)
	(segment
		(start 114.446304 -59.545474)
		(end 114.446304 -60.239148)
		(width 0.4572)
		(layer "F.Cu")
		(net "GND")
	)
	(segment
		(start 50.41519 -173.999144)
		(end 50.798222 -174.382176)
		(width 0.4572)
		(layer "F.Cu")
		(net "GND")
	)
	(segment
		(start 152.27046 -148.057362)
		(end 151.506936 -148.057362)
		(width 0.508)
		(layer "F.Cu")
		(net "GND")
	)
	(segment
		(start 95.047562 -123.157996)
		(end 95.047562 -122.448066)
		(width 0.4572)
		(layer "F.Cu")
		(net "GND")
	)
	(segment
		(start 109.036612 -67.099434)
		(end 109.036612 -67.162934)
		(width 0.3048)
		(layer "F.Cu")
		(net "GND")
	)
	(segment
		(start 34.418778 -107.027218)
		(end 34.418778 -106.139488)
		(width 0.4572)
		(layer "F.Cu")
		(net "GND")
	)
	(segment
		(start 73.36663 -83.70062)
		(end 73.514966 -83.552284)
		(width 0.254)
		(layer "F.Cu")
		(net "GND")
	)
	(segment
		(start 148.593302 -138.48715)
		(end 148.593302 -139.181586)
		(width 0.4572)
		(layer "F.Cu")
		(net "GND")
	)
	(segment
		(start 115.2652 -63.348616)
		(end 114.53114 -63.348616)
		(width 0.4572)
		(layer "F.Cu")
		(net "GND")
	)
	(segment
		(start 74.701908 -83.470242)
		(end 74.250042 -83.470242)
		(width 0.254)
		(layer "F.Cu")
		(net "GND")
	)
	(segment
		(start 46.915578 -65.821306)
		(end 46.946566 -65.821306)
		(width 0.3048)
		(layer "F.Cu")
		(net "GND")
	)
	(segment
		(start 55.135018 -86.243668)
		(end 55.89524 -87.00389)
		(width 0.254)
		(layer "F.Cu")
		(net "GND")
	)
	(segment
		(start 41.737534 -77.148182)
		(end 41.75125 -77.134466)
		(width 0.254)
		(layer "F.Cu")
		(net "GND")
	)
	(segment
		(start 44.530772 -71.040498)
		(end 44.656248 -71.165974)
		(width 0.3048)
		(layer "F.Cu")
		(net "GND")
	)
	(segment
		(start 41.037002 -109.860334)
		(end 41.769538 -109.860334)
		(width 0.4572)
		(layer "F.Cu")
		(net "GND")
	)
	(segment
		(start 130.537966 -136.62025)
		(end 130.537966 -135.825484)
		(width 0.1778)
		(layer "F.Cu")
		(net "GND")
	)
	(segment
		(start 51.02987 -84.779104)
		(end 51.037998 -84.770976)
		(width 0.3048)
		(layer "F.Cu")
		(net "GND")
	)
	(segment
		(start 64.514222 -175.707548)
		(end 64.363092 -175.858678)
		(width 0.4572)
		(layer "F.Cu")
		(net "GND")
	)
	(segment
		(start 70.142354 -140.05941)
		(end 70.141846 -140.05941)
		(width 0.3556)
		(layer "F.Cu")
		(net "GND")
	)
	(segment
		(start 57.740804 -128.458214)
		(end 58.14187 -128.85928)
		(width 0.3556)
		(layer "F.Cu")
		(net "GND")
	)
	(segment
		(start 72.142096 -142.059406)
		(end 71.7423 -141.65961)
		(width 0.3556)
		(layer "F.Cu")
		(net "GND")
	)
	(segment
		(start 126.661164 -165.865048)
		(end 126.05131 -166.474902)
		(width 0.508)
		(layer "F.Cu")
		(net "GND")
	)
	(segment
		(start 41.193974 -76.98105)
		(end 41.361106 -77.148182)
		(width 0.254)
		(layer "F.Cu")
		(net "GND")
	)
	(segment
		(start 72.942196 -142.059406)
		(end 72.5424 -141.65961)
		(width 0.3556)
		(layer "F.Cu")
		(net "GND")
	)
	(segment
		(start 104.299512 -64.404494)
		(end 104.73182 -64.404494)
		(width 0.3048)
		(layer "F.Cu")
		(net "GND")
	)
	(segment
		(start 64.772286 -85.956902)
		(end 64.95923 -86.143846)
		(width 0.254)
		(layer "F.Cu")
		(net "GND")
	)
	(segment
		(start 44.388278 -87.341964)
		(end 44.388278 -88.103964)
		(width 0.254)
		(layer "F.Cu")
		(net "GND")
	)
	(segment
		(start 44.231052 -61.943742)
		(end 44.231052 -62.067186)
		(width 0.381)
		(layer "F.Cu")
		(net "GND")
	)
	(segment
		(start 8.595614 -2.332482)
		(end 8.722614 -2.459482)
		(width 0.381)
		(layer "F.Cu")
		(net "GND")
	)
	(segment
		(start 91.00439 -7.667752)
		(end 91.00439 -5.41655)
		(width 0.508)
		(layer "F.Cu")
		(net "GND")
	)
	(segment
		(start 21.812504 -55.610506)
		(end 22.014434 -55.812436)
		(width 0.4572)
		(layer "F.Cu")
		(net "GND")
	)
	(segment
		(start 58.23077 -83.857846)
		(end 58.192162 -83.857846)
		(width 0.3048)
		(layer "F.Cu")
		(net "GND")
	)
	(segment
		(start 69.886068 -84.149438)
		(end 69.821044 -84.214462)
		(width 0.3556)
		(layer "F.Cu")
		(net "GND")
	)
	(segment
		(start 47.315628 -74.043286)
		(end 47.323248 -74.043286)
		(width 0.3048)
		(layer "F.Cu")
		(net "GND")
	)
	(segment
		(start 177.992278 -139.720574)
		(end 178.059842 -139.65301)
		(width 0.508)
		(layer "F.Cu")
		(net "GND")
	)
	(segment
		(start 50.910236 -119.368062)
		(end 50.243486 -119.368062)
		(width 0.508)
		(layer "F.Cu")
		(net "GND")
	)
	(segment
		(start 65.341754 -140.05941)
		(end 65.339468 -140.05941)
		(width 0.3556)
		(layer "F.Cu")
		(net "GND")
	)
	(segment
		(start 42.70248 -89.060528)
		(end 42.70248 -88.097614)
		(width 0.381)
		(layer "F.Cu")
		(net "GND")
	)
	(segment
		(start 48.085248 -69.370702)
		(end 47.323248 -69.370702)
		(width 0.254)
		(layer "F.Cu")
		(net "GND")
	)
	(segment
		(start 54.61254 -86.766146)
		(end 55.135018 -86.243668)
		(width 0.254)
		(layer "F.Cu")
		(net "GND")
	)
	(segment
		(start 49.0982 -64.25692)
		(end 49.129696 -64.25692)
		(width 0.3048)
		(layer "F.Cu")
		(net "GND")
	)
	(segment
		(start 86.242398 -107.9119)
		(end 85.399372 -107.9119)
		(width 0.508)
		(layer "F.Cu")
		(net "GND")
	)
	(segment
		(start 59.685428 -88.69934)
		(end 59.335924 -89.048844)
		(width 0.3048)
		(layer "F.Cu")
		(net "GND")
	)
	(segment
		(start 187.015628 -202.495658)
		(end 187.015628 -205.199488)
		(width 0.508)
		(layer "F.Cu")
		(net "GND")
	)
	(segment
		(start 124.55144 -163.475416)
		(end 124.10821 -163.475416)
		(width 0.508)
		(layer "F.Cu")
		(net "GND")
	)
	(segment
		(start 132.938012 -152.44191)
		(end 132.938012 -151.32558)
		(width 0.1778)
		(layer "F.Cu")
		(net "GND")
	)
	(segment
		(start 49.20869 -67.527678)
		(end 49.04105 -67.360038)
		(width 0.3048)
		(layer "F.Cu")
		(net "GND")
	)
	(segment
		(start 148.593302 -137.31875)
		(end 148.593302 -138.48715)
		(width 0.4572)
		(layer "F.Cu")
		(net "GND")
	)
	(segment
		(start 71.910448 -81.722976)
		(end 71.491094 -81.722976)
		(width 0.3048)
		(layer "F.Cu")
		(net "GND")
	)
	(segment
		(start 50.371248 -73.343262)
		(end 49.609248 -73.343262)
		(width 0.3048)
		(layer "F.Cu")
		(net "GND")
	)
	(segment
		(start 70.192138 -114.700304)
		(end 70.192138 -116.774214)
		(width 0.4572)
		(layer "F.Cu")
		(net "GND")
	)
	(segment
		(start 47.278544 -63.898526)
		(end 47.186596 -63.990474)
		(width 0.3048)
		(layer "F.Cu")
		(net "GND")
	)
	(segment
		(start 71.341996 -138.059414)
		(end 70.9422 -137.659618)
		(width 0.3556)
		(layer "F.Cu")
		(net "GND")
	)
	(segment
		(start 139.33805 -152.396952)
		(end 139.33805 -151.32558)
		(width 0.1778)
		(layer "F.Cu")
		(net "GND")
	)
	(segment
		(start 94.071186 -166.155878)
		(end 94.071186 -167.158924)
		(width 0.508)
		(layer "F.Cu")
		(net "GND")
	)
	(segment
		(start 58.864246 -67.345306)
		(end 58.470546 -67.739006)
		(width 0.254)
		(layer "F.Cu")
		(net "GND")
	)
	(segment
		(start 108.33608 -186.744864)
		(end 108.33608 -187.706254)
		(width 0.508)
		(layer "F.Cu")
		(net "GND")
	)
	(segment
		(start 59.90082 -81.641188)
		(end 59.90082 -81.300066)
		(width 0.3048)
		(layer "F.Cu")
		(net "GND")
	)
	(segment
		(start 46.032166 -134.164324)
		(end 46.032166 -134.164578)
		(width 0.3556)
		(layer "F.Cu")
		(net "GND")
	)
	(segment
		(start 191.02705 -125.095)
		(end 191.02705 -125.48235)
		(width 0.508)
		(layer "F.Cu")
		(net "GND")
	)
	(segment
		(start 42.080688 -77.134466)
		(end 41.75125 -77.134466)
		(width 0.254)
		(layer "F.Cu")
		(net "GND")
	)
	(segment
		(start 111.79429 -157.447742)
		(end 111.79429 -156.415232)
		(width 0.508)
		(layer "F.Cu")
		(net "GND")
	)
	(segment
		(start 45.037248 -70.070726)
		(end 44.840144 -70.070726)
		(width 0.254)
		(layer "F.Cu")
		(net "GND")
	)
	(segment
		(start 83.54822 -155.36672)
		(end 82.98942 -154.80792)
		(width 0.4572)
		(layer "F.Cu")
		(net "GND")
	)
	(segment
		(start 72.014334 -81.61909)
		(end 71.910448 -81.722976)
		(width 0.3048)
		(layer "F.Cu")
		(net "GND")
	)
	(segment
		(start 151.238458 -127.314452)
		(end 153.872692 -127.314452)
		(width 0.508)
		(layer "F.Cu")
		(net "GND")
	)
	(segment
		(start 55.039768 -62.110112)
		(end 55.039768 -62.55004)
		(width 0.3048)
		(layer "F.Cu")
		(net "GND")
	)
	(segment
		(start 59.19597 -86.343744)
		(end 59.044078 -86.343744)
		(width 0.254)
		(layer "F.Cu")
		(net "GND")
	)
	(segment
		(start 70.964044 -82.228182)
		(end 71.137018 -82.401156)
		(width 0.3048)
		(layer "F.Cu")
		(net "GND")
	)
	(segment
		(start 50.28565 -82.333846)
		(end 49.585626 -82.333846)
		(width 0.3048)
		(layer "F.Cu")
		(net "GND")
	)
	(segment
		(start 104.89184 -157.024578)
		(end 104.896666 -157.019752)
		(width 0.4572)
		(layer "F.Cu")
		(net "GND")
	)
	(segment
		(start 170.879008 -93.00464)
		(end 170.879008 -93.423994)
		(width 0.508)
		(layer "F.Cu")
		(net "GND")
	)
	(segment
		(start 132.93598 -184.426352)
		(end 133.08076 -184.571132)
		(width 0.508)
		(layer "F.Cu")
		(net "GND")
	)
	(segment
		(start 68.692776 -68.717922)
		(end 69.059044 -68.351654)
		(width 0.3048)
		(layer "F.Cu")
		(net "GND")
	)
	(segment
		(start 35.11423 -76.36383)
		(end 35.875468 -76.36383)
		(width 0.4572)
		(layer "F.Cu")
		(net "GND")
	)
	(segment
		(start 136.263634 -181.906672)
		(end 137.52576 -181.906672)
		(width 0.4572)
		(layer "F.Cu")
		(net "GND")
	)
	(segment
		(start 92.416376 -120.141492)
		(end 93.671898 -120.141492)
		(width 0.2032)
		(layer "F.Cu")
		(net "GND")
	)
	(segment
		(start 81.98231 -83.241134)
		(end 81.64322 -82.902044)
		(width 0.508)
		(layer "F.Cu")
		(net "GND")
	)
	(segment
		(start 165.643306 -104.839008)
		(end 165.643306 -105.761536)
		(width 0.1778)
		(layer "F.Cu")
		(net "GND")
	)
	(segment
		(start 44.32808 -62.163706)
		(end 44.32808 -62.68847)
		(width 0.381)
		(layer "F.Cu")
		(net "GND")
	)
	(segment
		(start 117.33276 -186.991498)
		(end 117.45976 -186.864498)
		(width 0.508)
		(layer "F.Cu")
		(net "GND")
	)
	(segment
		(start 152.27046 -147.041362)
		(end 151.50973 -147.041362)
		(width 0.508)
		(layer "F.Cu")
		(net "GND")
	)
	(segment
		(start 146.059652 -144.20215)
		(end 145.316702 -144.20215)
		(width 0.4572)
		(layer "F.Cu")
		(net "GND")
	)
	(segment
		(start 135.553704 -121.064528)
		(end 136.075166 -121.064528)
		(width 0.1778)
		(layer "F.Cu")
		(net "GND")
	)
	(segment
		(start 18.01495 -201.09053)
		(end 18.01495 -200.32853)
		(width 0.508)
		(layer "F.Cu")
		(net "GND")
	)
	(segment
		(start 74.610976 -84.908898)
		(end 74.250042 -84.908898)
		(width 0.254)
		(layer "F.Cu")
		(net "GND")
	)
	(segment
		(start 46.927516 -76.922122)
		(end 47.321216 -77.315822)
		(width 0.3048)
		(layer "F.Cu")
		(net "GND")
	)
	(segment
		(start 42.69994 -89.063068)
		(end 42.70248 -89.060528)
		(width 0.381)
		(layer "F.Cu")
		(net "GND")
	)
	(segment
		(start 47.819818 -105.38079)
		(end 47.818294 -105.382314)
		(width 0.4572)
		(layer "F.Cu")
		(net "GND")
	)
	(segment
		(start 156.141928 -186.868308)
		(end 156.19476 -186.92114)
		(width 0.508)
		(layer "F.Cu")
		(net "GND")
	)
	(segment
		(start 58.192162 -83.857846)
		(end 57.83834 -84.211668)
		(width 0.3048)
		(layer "F.Cu")
		(net "GND")
	)
	(segment
		(start 43.937428 -85.212428)
		(end 44.147486 -85.212428)
		(width 0.3048)
		(layer "F.Cu")
		(net "GND")
	)
	(segment
		(start 54.15026 -20.94992)
		(end 54.15026 -22.457156)
		(width 0.4572)
		(layer "F.Cu")
		(net "GND")
	)
	(segment
		(start 68.287646 -85.000846)
		(end 68.16217 -85.000846)
		(width 0.254)
		(layer "F.Cu")
		(net "GND")
	)
	(segment
		(start 125.787912 -137.775442)
		(end 126.831344 -137.775442)
		(width 0.1778)
		(layer "F.Cu")
		(net "GND")
	)
	(segment
		(start 186.55284 -202.03287)
		(end 187.015628 -202.495658)
		(width 0.508)
		(layer "F.Cu")
		(net "GND")
	)
	(segment
		(start 58.149236 -80.851502)
		(end 58.400696 -80.600042)
		(width 0.3048)
		(layer "F.Cu")
		(net "GND")
	)
	(segment
		(start 154.18308 -178.979576)
		(end 154.18308 -178.990244)
		(width 0.508)
		(layer "F.Cu")
		(net "GND")
	)
	(segment
		(start 137.65276 -186.862974)
		(end 137.65276 -187.726574)
		(width 0.508)
		(layer "F.Cu")
		(net "GND")
	)
	(segment
		(start 137.338054 -136.928352)
		(end 137.338054 -135.825484)
		(width 0.1778)
		(layer "F.Cu")
		(net "GND")
	)
	(segment
		(start 86.458552 -145.47088)
		(end 86.44763 -145.459958)
		(width 0.4572)
		(layer "F.Cu")
		(net "GND")
	)
	(segment
		(start 68.9102 -75.420474)
		(end 68.9102 -74.515218)
		(width 0.3048)
		(layer "F.Cu")
		(net "GND")
	)
	(segment
		(start 68.141088 -135.658352)
		(end 67.742308 -135.259572)
		(width 0.381)
		(layer "F.Cu")
		(net "GND")
	)
	(segment
		(start 35.987228 -68.536566)
		(end 39.992808 -68.536566)
		(width 0.254)
		(layer "F.Cu")
		(net "GND")
	)
	(segment
		(start 74.02957 -76.626212)
		(end 73.993248 -76.662534)
		(width 0.254)
		(layer "F.Cu")
		(net "GND")
	)
	(segment
		(start 45.857414 -64.047878)
		(end 45.274992 -64.047878)
		(width 0.3048)
		(layer "F.Cu")
		(net "GND")
	)
	(segment
		(start 48.555402 -170.821604)
		(end 47.8028 -170.821604)
		(width 0.508)
		(layer "F.Cu")
		(net "GND")
	)
	(segment
		(start 66.441828 -86.912196)
		(end 66.392298 -86.862666)
		(width 0.3048)
		(layer "F.Cu")
		(net "GND")
	)
	(segment
		(start 82.740246 -109.114082)
		(end 82.73796 -109.116368)
		(width 0.508)
		(layer "F.Cu")
		(net "GND")
	)
	(segment
		(start 74.80554 -71.300086)
		(end 74.705464 -71.400162)
		(width 0.3048)
		(layer "F.Cu")
		(net "GND")
	)
	(segment
		(start 68.678044 -78.255622)
		(end 68.680076 -78.255622)
		(width 0.3048)
		(layer "F.Cu")
		(net "GND")
	)
	(segment
		(start 61.279532 -81.057242)
		(end 60.822332 -80.600042)
		(width 0.3048)
		(layer "F.Cu")
		(net "GND")
	)
	(segment
		(start 54.61254 -86.879938)
		(end 54.602634 -86.889844)
		(width 0.3048)
		(layer "F.Cu")
		(net "GND")
	)
	(segment
		(start 125.790452 -154.656282)
		(end 125.536452 -154.402282)
		(width 0.4572)
		(layer "F.Cu")
		(net "GND")
	)
	(segment
		(start 60.21705 -84.238846)
		(end 59.517026 -84.238846)
		(width 0.3048)
		(layer "F.Cu")
		(net "GND")
	)
	(segment
		(start 59.015122 -205.199488)
		(end 59.015122 -201.09053)
		(width 0.508)
		(layer "F.Cu")
		(net "GND")
	)
	(segment
		(start 68.662804 -85.29193)
		(end 68.57873 -85.29193)
		(width 0.254)
		(layer "F.Cu")
		(net "GND")
	)
	(segment
		(start 47.67834 -86.813136)
		(end 47.72787 -86.862666)
		(width 0.254)
		(layer "F.Cu")
		(net "GND")
	)
	(segment
		(start 68.141088 -142.059914)
		(end 67.7418 -141.660626)
		(width 0.3556)
		(layer "F.Cu")
		(net "GND")
	)
	(segment
		(start 106.021632 -73.406254)
		(end 104.73182 -73.406254)
		(width 0.3048)
		(layer "F.Cu")
		(net "GND")
	)
	(segment
		(start 49.585626 -84.619846)
		(end 50.28565 -84.619846)
		(width 0.3048)
		(layer "F.Cu")
		(net "GND")
	)
	(segment
		(start 140.260832 -144.57553)
		(end 141.288008 -144.57553)
		(width 0.1778)
		(layer "F.Cu")
		(net "GND")
	)
	(segment
		(start 27.450542 -122.874532)
		(end 28.466288 -122.874532)
		(width 0.4572)
		(layer "F.Cu")
		(net "GND")
	)
	(segment
		(start 64.001396 -80.600042)
		(end 63.892176 -80.709262)
		(width 0.254)
		(layer "F.Cu")
		(net "GND")
	)
	(segment
		(start 15.30477 -56.881776)
		(end 14.461744 -56.881776)
		(width 0.508)
		(layer "F.Cu")
		(net "GND")
	)
	(segment
		(start 47.323248 -69.370702)
		(end 47.323248 -70.070726)
		(width 0.3048)
		(layer "F.Cu")
		(net "GND")
	)
	(segment
		(start 157.674056 -173.405038)
		(end 157.821376 -173.552358)
		(width 0.508)
		(layer "F.Cu")
		(net "GND")
	)
	(segment
		(start 66.942208 -136.059418)
		(end 66.9417 -136.059418)
		(width 0.381)
		(layer "F.Cu")
		(net "GND")
	)
	(segment
		(start 47.242222 -174.260764)
		(end 47.242222 -174.752508)
		(width 0.4572)
		(layer "F.Cu")
		(net "GND")
	)
	(segment
		(start 66.886328 -81.960466)
		(end 66.55689 -81.960466)
		(width 0.3048)
		(layer "F.Cu")
		(net "GND")
	)
	(segment
		(start 114.071908 -168.071546)
		(end 114.76736 -168.071546)
		(width 0.254)
		(layer "F.Cu")
		(net "GND")
	)
	(segment
		(start 44.530772 -70.786498)
		(end 44.530772 -71.040498)
		(width 0.3048)
		(layer "F.Cu")
		(net "GND")
	)
	(segment
		(start 140.14323 -148.975572)
		(end 141.288008 -148.975572)
		(width 0.1778)
		(layer "F.Cu")
		(net "GND")
	)
	(segment
		(start 98.550222 -20.94992)
		(end 98.550222 -22.309328)
		(width 0.381)
		(layer "F.Cu")
		(net "GND")
	)
	(segment
		(start 43.51528 -61.874654)
		(end 43.51528 -62.68847)
		(width 0.381)
		(layer "F.Cu")
		(net "GND")
	)
	(segment
		(start 67.555364 -178.510438)
		(end 68.61429 -178.510438)
		(width 0.508)
		(layer "F.Cu")
		(net "GND")
	)
	(segment
		(start 66.53276 -187.726574)
		(end 66.53276 -186.913012)
		(width 0.508)
		(layer "F.Cu")
		(net "GND")
	)
	(segment
		(start 134.98576 -110.383574)
		(end 134.98576 -109.773212)
		(width 0.381)
		(layer "F.Cu")
		(net "GND")
	)
	(segment
		(start 44.418504 -85.483446)
		(end 44.656248 -85.72119)
		(width 0.3048)
		(layer "F.Cu")
		(net "GND")
	)
	(segment
		(start 40.65016 -29.149802)
		(end 40.65016 -27.646376)
		(width 0.4572)
		(layer "F.Cu")
		(net "GND")
	)
	(segment
		(start 55.89524 -87.00389)
		(end 56.005984 -87.00389)
		(width 0.254)
		(layer "F.Cu")
		(net "GND")
	)
	(segment
		(start 115.53698 -112.143286)
		(end 115.53698 -116.074698)
		(width 0.254)
		(layer "F.Cu")
		(net "GND")
	)
	(segment
		(start 136.912604 -55.724552)
		(end 136.125966 -55.724552)
		(width 0.4572)
		(layer "F.Cu")
		(net "GND")
	)
	(segment
		(start 132.93598 -183.929274)
		(end 132.93598 -184.426352)
		(width 0.508)
		(layer "F.Cu")
		(net "GND")
	)
	(segment
		(start 54.015132 -201.09053)
		(end 54.015132 -200.32853)
		(width 0.508)
		(layer "F.Cu")
		(net "GND")
	)
	(segment
		(start 45.274992 -64.047878)
		(end 45.106082 -64.216788)
		(width 0.3048)
		(layer "F.Cu")
		(net "GND")
	)
	(segment
		(start 33.404556 -2.835148)
		(end 34.392362 -2.835148)
		(width 0.4572)
		(layer "F.Cu")
		(net "GND")
	)
	(segment
		(start 18.226532 -56.404256)
		(end 18.2245 -56.406288)
		(width 0.381)
		(layer "F.Cu")
		(net "GND")
	)
	(segment
		(start 54.805072 -170.686222)
		(end 54.861206 -170.630088)
		(width 0.4572)
		(layer "F.Cu")
		(net "GND")
	)
	(segment
		(start 151.0157 -201.034904)
		(end 151.0157 -205.199488)
		(width 0.508)
		(layer "F.Cu")
		(net "GND")
	)
	(segment
		(start 34.672524 -84.377022)
		(end 34.709862 -84.339684)
		(width 0.508)
		(layer "F.Cu")
		(net "GND")
	)
	(segment
		(start 124.063252 -26.174192)
		(end 124.063252 -25.431242)
		(width 0.508)
		(layer "F.Cu")
		(net "GND")
	)
	(segment
		(start 46.942248 -83.256882)
		(end 46.942248 -83.274662)
		(width 0.3048)
		(layer "F.Cu")
		(net "GND")
	)
	(segment
		(start 91.350084 -20.94992)
		(end 91.350084 -22.396196)
		(width 0.381)
		(layer "F.Cu")
		(net "GND")
	)
	(segment
		(start 129.403856 -114.91468)
		(end 129.403856 -114.36731)
		(width 0.1778)
		(layer "F.Cu")
		(net "GND")
	)
	(segment
		(start 72.063864 -72.263762)
		(end 72.063864 -71.910956)
		(width 0.3048)
		(layer "F.Cu")
		(net "GND")
	)
	(segment
		(start 138.211052 -134.65175)
		(end 138.53795 -134.978648)
		(width 0.1778)
		(layer "F.Cu")
		(net "GND")
	)
	(segment
		(start 26.985722 -104.315006)
		(end 26.84018 -104.460548)
		(width 0.4572)
		(layer "F.Cu")
		(net "GND")
	)
	(segment
		(start 71.7423 -141.65961)
		(end 71.741792 -141.65961)
		(width 0.3556)
		(layer "F.Cu")
		(net "GND")
	)
	(segment
		(start 73.24344 -74.694796)
		(end 73.384918 -74.553318)
		(width 0.3048)
		(layer "F.Cu")
		(net "GND")
	)
	(segment
		(start 128.53797 -136.633712)
		(end 128.53797 -135.825484)
		(width 0.1778)
		(layer "F.Cu")
		(net "GND")
	)
	(segment
		(start 138.53795 -134.978648)
		(end 138.53795 -135.825484)
		(width 0.1778)
		(layer "F.Cu")
		(net "GND")
	)
	(segment
		(start 36.531042 -174.634906)
		(end 37.5285 -174.634906)
		(width 0.508)
		(layer "F.Cu")
		(net "GND")
	)
	(segment
		(start 98.550222 -22.309328)
		(end 98.905822 -22.664928)
		(width 0.381)
		(layer "F.Cu")
		(net "GND")
	)
	(segment
		(start 8.33374 -167.373554)
		(end 7.610856 -167.373554)
		(width 0.508)
		(layer "F.Cu")
		(net "GND")
	)
	(segment
		(start 57.656222 -174.497746)
		(end 57.656222 -174.752508)
		(width 0.4572)
		(layer "F.Cu")
		(net "GND")
	)
	(segment
		(start 157.37586 -186.787282)
		(end 157.37586 -186.863228)
		(width 0.508)
		(layer "F.Cu")
		(net "GND")
	)
	(segment
		(start 52.905406 -66.964306)
		(end 52.539138 -66.598038)
		(width 0.254)
		(layer "F.Cu")
		(net "GND")
	)
	(segment
		(start 71.596504 -69.488558)
		(end 71.345044 -69.237098)
		(width 0.3048)
		(layer "F.Cu")
		(net "GND")
	)
	(segment
		(start 64.895222 -84.43849)
		(end 65.475866 -83.857846)
		(width 0.254)
		(layer "F.Cu")
		(net "GND")
	)
	(segment
		(start 66.9417 -133.657594)
		(end 66.9417 -133.659626)
		(width 0.381)
		(layer "F.Cu")
		(net "GND")
	)
	(segment
		(start 60.540392 -180.967126)
		(end 61.07176 -180.435758)
		(width 0.4572)
		(layer "F.Cu")
		(net "GND")
	)
	(segment
		(start 169.672 -171.85513)
		(end 169.57421 -171.95292)
		(width 0.508)
		(layer "F.Cu")
		(net "GND")
	)
	(segment
		(start 80.59928 -182.811674)
		(end 79.99476 -182.811674)
		(width 0.508)
		(layer "F.Cu")
		(net "GND")
	)
	(segment
		(start 28.898596 -99.573842)
		(end 29.19984 -99.573842)
		(width 0.508)
		(layer "F.Cu")
		(net "GND")
	)
	(segment
		(start 14.261592 -134.825486)
		(end 14.669516 -134.417562)
		(width 0.4572)
		(layer "F.Cu")
		(net "GND")
	)
	(segment
		(start 69.059044 -75.569318)
		(end 68.9102 -75.420474)
		(width 0.3048)
		(layer "F.Cu")
		(net "GND")
	)
	(segment
		(start 74.142092 -142.459456)
		(end 74.141838 -142.459456)
		(width 0.3556)
		(layer "F.Cu")
		(net "GND")
	)
	(segment
		(start 69.967348 -89.048844)
		(end 70.407276 -89.048844)
		(width 0.254)
		(layer "F.Cu")
		(net "GND")
	)
	(segment
		(start 44.617386 -72.893936)
		(end 44.642024 -72.918574)
		(width 0.3048)
		(layer "F.Cu")
		(net "GND")
	)
	(segment
		(start 112.305592 -70.957694)
		(end 111.754158 -70.40626)
		(width 0.3048)
		(layer "F.Cu")
		(net "GND")
	)
	(segment
		(start 49.101502 -82.674968)
		(end 49.442624 -82.333846)
		(width 0.254)
		(layer "F.Cu")
		(net "GND")
	)
	(segment
		(start 57.200546 -78.599792)
		(end 57.600596 -78.999842)
		(width 0.3556)
		(layer "F.Cu")
		(net "GND")
	)
	(segment
		(start 186.55284 -201.080116)
		(end 186.55284 -202.03287)
		(width 0.508)
		(layer "F.Cu")
		(net "GND")
	)
	(segment
		(start 74.542142 -143.659606)
		(end 74.142092 -143.259556)
		(width 0.3556)
		(layer "F.Cu")
		(net "GND")
	)
	(segment
		(start 46.032928 -134.16407)
		(end 46.03242 -134.16407)
		(width 0.3556)
		(layer "F.Cu")
		(net "GND")
	)
	(segment
		(start 69.886068 -83.579462)
		(end 69.886068 -84.149438)
		(width 0.3556)
		(layer "F.Cu")
		(net "GND")
	)
	(segment
		(start 62.928246 -86.879938)
		(end 63.618364 -86.879938)
		(width 0.254)
		(layer "F.Cu")
		(net "GND")
	)
	(segment
		(start 140.71981 -115.863624)
		(end 141.419834 -115.863624)
		(width 0.508)
		(layer "F.Cu")
		(net "GND")
	)
	(segment
		(start 73.514966 -83.552284)
		(end 73.747122 -83.552284)
		(width 0.254)
		(layer "F.Cu")
		(net "GND")
	)
	(segment
		(start 9.740646 -142.550642)
		(end 9.740646 -141.15542)
		(width 0.381)
		(layer "F.Cu")
		(net "GND")
	)
	(segment
		(start 80.740758 -166.021512)
		(end 80.55102 -166.021512)
		(width 0.254)
		(layer "F.Cu")
		(net "GND")
	)
	(segment
		(start 27.438604 -122.862594)
		(end 27.450542 -122.874532)
		(width 0.4572)
		(layer "F.Cu")
		(net "GND")
	)
	(segment
		(start 101.550216 -20.94992)
		(end 101.550216 -22.549612)
		(width 0.381)
		(layer "F.Cu")
		(net "GND")
	)
	(segment
		(start 14.48816 -20.20316)
		(end 14.48816 -18.648934)
		(width 0.381)
		(layer "F.Cu")
		(net "GND")
	)
	(segment
		(start 42.79392 -76.904088)
		(end 42.757852 -76.904088)
		(width 0.3048)
		(layer "F.Cu")
		(net "GND")
	)
	(segment
		(start 49.95799 -61.66739)
		(end 49.95799 -62.208156)
		(width 0.3048)
		(layer "F.Cu")
		(net "GND")
	)
	(segment
		(start 44.702222 -106.075734)
		(end 44.702222 -105.390696)
		(width 0.4572)
		(layer "F.Cu")
		(net "GND")
	)
	(segment
		(start 69.354954 -175.523652)
		(end 68.61556 -175.523652)
		(width 0.508)
		(layer "F.Cu")
		(net "GND")
	)
	(segment
		(start 42.82694 -76.871068)
		(end 42.79392 -76.904088)
		(width 0.3048)
		(layer "F.Cu")
		(net "GND")
	)
	(segment
		(start 142.3289 -186.894978)
		(end 142.224252 -186.999626)
		(width 0.508)
		(layer "F.Cu")
		(net "GND")
	)
	(segment
		(start 45.633132 -138.563604)
		(end 45.633132 -138.558016)
		(width 0.3556)
		(layer "F.Cu")
		(net "GND")
	)
	(segment
		(start 44.014898 -205.199488)
		(end 44.014898 -201.09053)
		(width 0.508)
		(layer "F.Cu")
		(net "GND")
	)
	(segment
		(start 126.838964 -141.375638)
		(end 125.787912 -141.375638)
		(width 0.1778)
		(layer "F.Cu")
		(net "GND")
	)
	(segment
		(start 43.447462 -145.398998)
		(end 43.41622 -145.43024)
		(width 0.508)
		(layer "F.Cu")
		(net "GND")
	)
	(segment
		(start 128.768094 -152.50795)
		(end 128.457452 -152.50795)
		(width 0.2032)
		(layer "F.Cu")
		(net "GND")
	)
	(segment
		(start 68.141088 -136.458198)
		(end 67.742308 -136.059418)
		(width 0.381)
		(layer "F.Cu")
		(net "GND")
	)
	(segment
		(start 47.452788 -89.579196)
		(end 47.452788 -89.048844)
		(width 0.254)
		(layer "F.Cu")
		(net "GND")
	)
	(segment
		(start 96.750124 -20.94992)
		(end 96.750124 -22.386036)
		(width 0.381)
		(layer "F.Cu")
		(net "GND")
	)
	(segment
		(start 79.97444 -93.384624)
		(end 79.97444 -92.609924)
		(width 0.508)
		(layer "F.Cu")
		(net "GND")
	)
	(segment
		(start 64.539876 -136.859518)
		(end 64.541908 -136.859518)
		(width 0.381)
		(layer "F.Cu")
		(net "GND")
	)
	(segment
		(start 59.317128 -64.785748)
		(end 59.4741 -64.785748)
		(width 0.3048)
		(layer "F.Cu")
		(net "GND")
	)
	(segment
		(start 148.47189 -176.29632)
		(end 149.09673 -176.29632)
		(width 0.381)
		(layer "F.Cu")
		(net "GND")
	)
	(segment
		(start 168.015666 -201.034904)
		(end 168.015666 -205.199488)
		(width 0.508)
		(layer "F.Cu")
		(net "GND")
	)
	(segment
		(start 66.14287 -142.459456)
		(end 66.141854 -142.459456)
		(width 0.3556)
		(layer "F.Cu")
		(net "GND")
	)
	(segment
		(start 66.948304 -86.588092)
		(end 66.802762 -86.588092)
		(width 0.3048)
		(layer "F.Cu")
		(net "GND")
	)
	(segment
		(start 68.141088 -129.258314)
		(end 68.074286 -129.324862)
		(width 0.3556)
		(layer "F.Cu")
		(net "GND")
	)
	(segment
		(start 35.269678 -81.036922)
		(end 34.231072 -81.036922)
		(width 0.508)
		(layer "F.Cu")
		(net "GND")
	)
	(segment
		(start 85.358478 -146.216878)
		(end 85.411818 -146.163538)
		(width 0.4572)
		(layer "F.Cu")
		(net "GND")
	)
	(segment
		(start 46.269402 -173.87697)
		(end 46.858428 -173.87697)
		(width 0.4572)
		(layer "F.Cu")
		(net "GND")
	)
	(segment
		(start 51.158648 -76.615798)
		(end 51.174904 -76.599542)
		(width 0.3048)
		(layer "F.Cu")
		(net "GND")
	)
	(segment
		(start 68.299076 -68.324222)
		(end 68.692776 -68.717922)
		(width 0.3048)
		(layer "F.Cu")
		(net "GND")
	)
	(segment
		(start 52.09032 -86.72195)
		(end 52.106068 -86.737698)
		(width 0.3048)
		(layer "F.Cu")
		(net "GND")
	)
	(segment
		(start 33.5407 -14.619986)
		(end 36.061904 -17.14119)
		(width 0.254)
		(layer "F.Cu")
		(net "GND")
	)
	(segment
		(start 49.317656 -71.356982)
		(end 49.990248 -71.356982)
		(width 0.3048)
		(layer "F.Cu")
		(net "GND")
	)
	(segment
		(start 124.627132 -147.08759)
		(end 124.915168 -147.375626)
		(width 0.1778)
		(layer "F.Cu")
		(net "GND")
	)
	(segment
		(start 64.18834 -88.438482)
		(end 63.838836 -88.787986)
		(width 0.254)
		(layer "F.Cu")
		(net "GND")
	)
	(segment
		(start 91.650058 -29.149802)
		(end 91.650058 -27.569414)
		(width 0.4572)
		(layer "F.Cu")
		(net "GND")
	)
	(segment
		(start 67.340988 -135.658352)
		(end 66.942208 -135.259572)
		(width 0.381)
		(layer "F.Cu")
		(net "GND")
	)
	(segment
		(start 79.10576 -187.726574)
		(end 79.10576 -186.901074)
		(width 0.508)
		(layer "F.Cu")
		(net "GND")
	)
	(segment
		(start 114.83721 -48.722026)
		(end 114.83721 -49.544478)
		(width 0.508)
		(layer "F.Cu")
		(net "GND")
	)
	(segment
		(start 147.245578 -56.849772)
		(end 147.245578 -56.048148)
		(width 0.508)
		(layer "F.Cu")
		(net "GND")
	)
	(segment
		(start 124.57684 -39.389812)
		(end 122.451622 -39.389812)
		(width 0.2794)
		(layer "F.Cu")
		(net "GND")
	)
	(segment
		(start 102.393496 -140.911072)
		(end 102.393496 -141.891004)
		(width 0.4572)
		(layer "F.Cu")
		(net "GND")
	)
	(segment
		(start 49.009046 -69.5325)
		(end 48.847248 -69.370702)
		(width 0.3048)
		(layer "F.Cu")
		(net "GND")
	)
	(segment
		(start 59.299856 -89.466928)
		(end 59.299856 -89.16543)
		(width 0.254)
		(layer "F.Cu")
		(net "GND")
	)
	(segment
		(start 126.01956 -154.656282)
		(end 125.790452 -154.656282)
		(width 0.4572)
		(layer "F.Cu")
		(net "GND")
	)
	(segment
		(start 44.491148 -74.659236)
		(end 45.037248 -74.113136)
		(width 0.3048)
		(layer "F.Cu")
		(net "GND")
	)
	(segment
		(start 52.285646 -83.476846)
		(end 52.27193 -83.476846)
		(width 0.3048)
		(layer "F.Cu")
		(net "GND")
	)
	(segment
		(start 127.009652 -141.20495)
		(end 126.838964 -141.375638)
		(width 0.1778)
		(layer "F.Cu")
		(net "GND")
	)
	(segment
		(start 42.757852 -72.401176)
		(end 42.052494 -72.401176)
		(width 0.254)
		(layer "F.Cu")
		(net "GND")
	)
	(segment
		(start 72.795384 -79.737458)
		(end 72.795384 -79.684626)
		(width 0.3048)
		(layer "F.Cu")
		(net "GND")
	)
	(segment
		(start 46.891956 -132.163566)
		(end 46.432978 -132.163566)
		(width 0.3556)
		(layer "F.Cu")
		(net "GND")
	)
	(segment
		(start 45.106082 -64.216788)
		(end 45.106082 -64.736218)
		(width 0.3048)
		(layer "F.Cu")
		(net "GND")
	)
	(segment
		(start 91.533218 -175.388778)
		(end 91.237308 -175.388778)
		(width 0.4572)
		(layer "F.Cu")
		(net "GND")
	)
	(segment
		(start 62.005972 -78.584298)
		(end 62.401196 -78.979522)
		(width 0.381)
		(layer "F.Cu")
		(net "GND")
	)
	(segment
		(start 89.850214 -31.114238)
		(end 89.850214 -29.149802)
		(width 0.4572)
		(layer "F.Cu")
		(net "GND")
	)
	(segment
		(start 58.800746 -78.599792)
		(end 59.200796 -78.999842)
		(width 0.3556)
		(layer "F.Cu")
		(net "GND")
	)
	(segment
		(start 51.158648 -74.74331)
		(end 50.752248 -75.14971)
		(width 0.3048)
		(layer "F.Cu")
		(net "GND")
	)
	(segment
		(start 51.9557 -89.918286)
		(end 51.9557 -89.048844)
		(width 0.254)
		(layer "F.Cu")
		(net "GND")
	)
	(segment
		(start 176.266348 -36.848034)
		(end 175.593756 -36.848034)
		(width 0.508)
		(layer "F.Cu")
		(net "GND")
	)
	(segment
		(start 60.389008 -84.066888)
		(end 60.21705 -84.238846)
		(width 0.3048)
		(layer "F.Cu")
		(net "GND")
	)
	(segment
		(start 67.109848 -62.55004)
		(end 67.07759 -62.55004)
		(width 0.254)
		(layer "F.Cu")
		(net "GND")
	)
	(segment
		(start 107.396788 -179.031646)
		(end 106.873548 -179.031646)
		(width 0.4572)
		(layer "F.Cu")
		(net "GND")
	)
	(segment
		(start 47.323248 -81.988406)
		(end 47.319184 -81.99247)
		(width 0.3048)
		(layer "F.Cu")
		(net "GND")
	)
	(segment
		(start 168.909492 -156.827474)
		(end 169.513504 -156.827474)
		(width 0.508)
		(layer "F.Cu")
		(net "GND")
	)
	(segment
		(start 98.866198 -173.467268)
		(end 97.728532 -173.467268)
		(width 0.508)
		(layer "F.Cu")
		(net "GND")
	)
	(segment
		(start 46.74235 -128.963674)
		(end 46.432978 -128.963674)
		(width 0.254)
		(layer "F.Cu")
		(net "GND")
	)
	(segment
		(start 49.990248 -75.329542)
		(end 49.228248 -75.329542)
		(width 0.3048)
		(layer "F.Cu")
		(net "GND")
	)
	(segment
		(start 67.921886 -129.477262)
		(end 67.76974 -129.629662)
		(width 0.3556)
		(layer "F.Cu")
		(net "GND")
	)
	(segment
		(start 152.979628 -69.060822)
		(end 153.612596 -69.060822)
		(width 0.508)
		(layer "F.Cu")
		(net "GND")
	)
	(segment
		(start 64.18834 -87.731854)
		(end 64.18834 -88.438482)
		(width 0.254)
		(layer "F.Cu")
		(net "GND")
	)
	(segment
		(start 46.31309 -86.143846)
		(end 46.31309 -86.226396)
		(width 0.3048)
		(layer "F.Cu")
		(net "GND")
	)
	(segment
		(start 70.964044 -78.973426)
		(end 71.08825 -78.84922)
		(width 0.3048)
		(layer "F.Cu")
		(net "GND")
	)
	(segment
		(start 51.223418 -69.733668)
		(end 50.952908 -69.733668)
		(width 0.3048)
		(layer "F.Cu")
		(net "GND")
	)
	(segment
		(start 172.279056 -102.935786)
		(end 171.14647 -102.935786)
		(width 0.1778)
		(layer "F.Cu")
		(net "GND")
	)
	(segment
		(start 128.25476 -184.805574)
		(end 128.25476 -184.225438)
		(width 0.381)
		(layer "F.Cu")
		(net "GND")
	)
	(segment
		(start 50.752248 -75.14971)
		(end 50.752248 -75.329542)
		(width 0.3048)
		(layer "F.Cu")
		(net "GND")
	)
	(segment
		(start 47.708566 -88.181688)
		(end 48.131984 -88.605106)
		(width 0.3048)
		(layer "F.Cu")
		(net "GND")
	)
	(segment
		(start 51.999896 -76.599542)
		(end 51.999896 -76.681076)
		(width 0.3048)
		(layer "F.Cu")
		(net "GND")
	)
	(segment
		(start 65.898522 -30.676342)
		(end 65.850262 -30.628082)
		(width 0.381)
		(layer "F.Cu")
		(net "GND")
	)
	(segment
		(start 9.856978 -138.946636)
		(end 9.856978 -138.058906)
		(width 0.508)
		(layer "F.Cu")
		(net "GND")
	)
	(segment
		(start 40.03167 -132.16509)
		(end 40.033194 -132.163566)
		(width 0.3556)
		(layer "F.Cu")
		(net "GND")
	)
	(segment
		(start 64.444626 -68.122038)
		(end 64.429386 -68.122038)
		(width 0.254)
		(layer "F.Cu")
		(net "GND")
	)
	(segment
		(start 95.850202 -29.149802)
		(end 95.850202 -30.761432)
		(width 0.381)
		(layer "F.Cu")
		(net "GND")
	)
	(segment
		(start 146.015456 -205.199488)
		(end 146.015456 -201.034904)
		(width 0.508)
		(layer "F.Cu")
		(net "GND")
	)
	(segment
		(start 49.658524 -64.785748)
		(end 50.311304 -64.785748)
		(width 0.3048)
		(layer "F.Cu")
		(net "GND")
	)
	(segment
		(start 11.889994 -30.178756)
		(end 11.889994 -31.223712)
		(width 0.508)
		(layer "F.Cu")
		(net "GND")
	)
	(segment
		(start 67.76974 -129.629662)
		(end 67.7418 -129.657602)
		(width 0.3556)
		(layer "F.Cu")
		(net "GND")
	)
	(segment
		(start 44.656248 -83.974686)
		(end 44.656248 -84.075524)
		(width 0.3048)
		(layer "F.Cu")
		(net "GND")
	)
	(segment
		(start 52.27193 -85.762846)
		(end 51.571906 -85.762846)
		(width 0.3048)
		(layer "F.Cu")
		(net "GND")
	)
	(segment
		(start 144.345152 -181.748938)
		(end 144.187418 -181.906672)
		(width 0.508)
		(layer "F.Cu")
		(net "GND")
	)
	(segment
		(start 64.823086 -66.202306)
		(end 64.429386 -66.596006)
		(width 0.254)
		(layer "F.Cu")
		(net "GND")
	)
	(segment
		(start 44.656248 -80.002126)
		(end 44.656248 -79.302102)
		(width 0.3048)
		(layer "F.Cu")
		(net "GND")
	)
	(segment
		(start 165.411404 -185.477404)
		(end 165.411404 -185.083196)
		(width 0.508)
		(layer "F.Cu")
		(net "GND")
	)
	(segment
		(start 64.141096 -133.258306)
		(end 64.541908 -133.659118)
		(width 0.381)
		(layer "F.Cu")
		(net "GND")
	)
	(segment
		(start 59.31281 -84.03463)
		(end 58.808366 -84.03463)
		(width 0.3048)
		(layer "F.Cu")
		(net "GND")
	)
	(segment
		(start 117.334792 -141.749526)
		(end 114.123724 -141.749526)
		(width 0.254)
		(layer "F.Cu")
		(net "GND")
	)
	(segment
		(start 44.656248 -84.075524)
		(end 45.049186 -84.468462)
		(width 0.3048)
		(layer "F.Cu")
		(net "GND")
	)
	(segment
		(start 66.443098 -66.979038)
		(end 66.415666 -66.979038)
		(width 0.3048)
		(layer "F.Cu")
		(net "GND")
	)
	(segment
		(start 165.243256 -105.869994)
		(end 165.243256 -104.839008)
		(width 0.1778)
		(layer "F.Cu")
		(net "GND")
	)
	(segment
		(start 68.940934 -141.25829)
		(end 68.542154 -140.85951)
		(width 0.3556)
		(layer "F.Cu")
		(net "GND")
	)
	(segment
		(start 68.678044 -77.555598)
		(end 68.678044 -78.255622)
		(width 0.3048)
		(layer "F.Cu")
		(net "GND")
	)
	(segment
		(start 57.450228 -30.854904)
		(end 57.450228 -29.149802)
		(width 0.4572)
		(layer "F.Cu")
		(net "GND")
	)
	(segment
		(start 70.9422 -137.659618)
		(end 70.941692 -137.659618)
		(width 0.3556)
		(layer "F.Cu")
		(net "GND")
	)
	(segment
		(start 47.323248 -78.015846)
		(end 47.323248 -77.315822)
		(width 0.3048)
		(layer "F.Cu")
		(net "GND")
	)
	(segment
		(start 18.2245 -56.406288)
		(end 18.2245 -57.085992)
		(width 0.381)
		(layer "F.Cu")
		(net "GND")
	)
	(segment
		(start 44.32808 -90.578178)
		(end 44.32808 -88.910414)
		(width 0.381)
		(layer "F.Cu")
		(net "GND")
	)
	(segment
		(start 9.056624 -129.992374)
		(end 11.8999 -132.83565)
		(width 0.254)
		(layer "F.Cu")
		(net "GND")
	)
	(segment
		(start 66.440304 -86.40826)
		(end 66.17589 -86.143846)
		(width 0.3048)
		(layer "F.Cu")
		(net "GND")
	)
	(segment
		(start 148.447252 -40.876982)
		(end 149.039326 -41.469056)
		(width 0.4572)
		(layer "F.Cu")
		(net "GND")
	)
	(segment
		(start 91.502484 -188.858398)
		(end 92.293186 -188.858398)
		(width 0.508)
		(layer "F.Cu")
		(net "GND")
	)
	(segment
		(start 143.36776 -184.556908)
		(end 143.36776 -184.805574)
		(width 0.508)
		(layer "F.Cu")
		(net "GND")
	)
	(segment
		(start 50.752248 -75.329542)
		(end 49.990248 -75.329542)
		(width 0.3048)
		(layer "F.Cu")
		(net "GND")
	)
	(segment
		(start 48.576992 -64.725804)
		(end 47.880016 -64.725804)
		(width 0.3048)
		(layer "F.Cu")
		(net "GND")
	)
	(segment
		(start 49.32426 -76.125578)
		(end 49.228248 -76.029566)
		(width 0.3048)
		(layer "F.Cu")
		(net "GND")
	)
	(segment
		(start 102.038912 -70.421754)
		(end 103.523288 -71.90613)
		(width 0.254)
		(layer "F.Cu")
		(net "GND")
	)
	(segment
		(start 66.580512 -63.047118)
		(end 66.388488 -63.047118)
		(width 0.254)
		(layer "F.Cu")
		(net "GND")
	)
	(segment
		(start 93.319346 -173.901608)
		(end 93.72473 -174.306992)
		(width 0.508)
		(layer "F.Cu")
		(net "GND")
	)
	(segment
		(start 66.141854 -134.45744)
		(end 66.141854 -134.459472)
		(width 0.381)
		(layer "F.Cu")
		(net "GND")
	)
	(segment
		(start 51.178206 -85.396578)
		(end 51.205638 -85.396578)
		(width 0.3048)
		(layer "F.Cu")
		(net "GND")
	)
	(segment
		(start 63.739522 -140.05941)
		(end 63.340996 -140.457936)
		(width 0.3556)
		(layer "F.Cu")
		(net "GND")
	)
	(segment
		(start 52.511706 -68.880736)
		(end 52.511706 -68.884038)
		(width 0.254)
		(layer "F.Cu")
		(net "GND")
	)
	(segment
		(start 47.600616 -87.375492)
		(end 47.67834 -87.297768)
		(width 0.254)
		(layer "F.Cu")
		(net "GND")
	)
	(segment
		(start 116.50091 -152.1968)
		(end 116.4844 -152.1968)
		(width 0.508)
		(layer "F.Cu")
		(net "GND")
	)
	(segment
		(start 91.968066 -98.54438)
		(end 91.686126 -98.82632)
		(width 0.508)
		(layer "F.Cu")
		(net "GND")
	)
	(segment
		(start 175.510444 -119.865648)
		(end 176.01057 -120.365774)
		(width 0.381)
		(layer "F.Cu")
		(net "GND")
	)
	(segment
		(start 51.037998 -84.770976)
		(end 50.886868 -84.619846)
		(width 0.3048)
		(layer "F.Cu")
		(net "GND")
	)
	(segment
		(start 72.205088 -69.488558)
		(end 72.205088 -68.788534)
		(width 0.3048)
		(layer "F.Cu")
		(net "GND")
	)
	(segment
		(start 65.339468 -140.05941)
		(end 64.940942 -140.457936)
		(width 0.3556)
		(layer "F.Cu")
		(net "GND")
	)
	(segment
		(start 143.310102 -133.17855)
		(end 143.310102 -133.178804)
		(width 0.4572)
		(layer "F.Cu")
		(net "GND")
	)
	(segment
		(start 66.150236 -20.94992)
		(end 66.150236 -19.609308)
		(width 0.381)
		(layer "F.Cu")
		(net "GND")
	)
	(segment
		(start 78.522068 -95.138748)
		(end 78.522068 -94.531942)
		(width 0.4572)
		(layer "F.Cu")
		(net "GND")
	)
	(segment
		(start 93.575124 -167.162734)
		(end 94.067376 -167.162734)
		(width 0.508)
		(layer "F.Cu")
		(net "GND")
	)
	(segment
		(start 60.118498 -97.850198)
		(end 60.129166 -97.83953)
		(width 0.4572)
		(layer "F.Cu")
		(net "GND")
	)
	(segment
		(start 107.30738 -164.554408)
		(end 107.30738 -164.556186)
		(width 0.4572)
		(layer "F.Cu")
		(net "GND")
	)
	(segment
		(start 139.938252 -149.18055)
		(end 140.14323 -148.975572)
		(width 0.1778)
		(layer "F.Cu")
		(net "GND")
	)
	(segment
		(start 66.809366 -65.821306)
		(end 66.443098 -65.455038)
		(width 0.254)
		(layer "F.Cu")
		(net "GND")
	)
	(segment
		(start 88.050116 -30.941518)
		(end 88.050116 -29.149802)
		(width 0.381)
		(layer "F.Cu")
		(net "GND")
	)
	(segment
		(start 59.716924 -87.095838)
		(end 59.716924 -87.700358)
		(width 0.3048)
		(layer "F.Cu")
		(net "GND")
	)
	(segment
		(start 32.920178 -175.059848)
		(end 32.920178 -174.43069)
		(width 0.4572)
		(layer "F.Cu")
		(net "GND")
	)
	(segment
		(start 124.95022 -166.167562)
		(end 124.820172 -166.167562)
		(width 0.508)
		(layer "F.Cu")
		(net "GND")
	)
	(segment
		(start 156.939488 -133.849618)
		(end 157.92704 -133.849618)
		(width 0.508)
		(layer "F.Cu")
		(net "GND")
	)
	(segment
		(start 59.200796 -78.999842)
		(end 60.000896 -79.799942)
		(width 0.3048)
		(layer "F.Cu")
		(net "GND")
	)
	(segment
		(start 95.804482 -4.518406)
		(end 96.50476 -4.518406)
		(width 0.508)
		(layer "F.Cu")
		(net "GND")
	)
	(segment
		(start 55.950104 -20.94992)
		(end 55.950104 -22.46376)
		(width 0.381)
		(layer "F.Cu")
		(net "GND")
	)
	(segment
		(start 49.594516 -78.908402)
		(end 49.988216 -79.302102)
		(width 0.254)
		(layer "F.Cu")
		(net "GND")
	)
	(segment
		(start 185.817764 -113.148872)
		(end 185.817764 -112.302544)
		(width 0.508)
		(layer "F.Cu")
		(net "GND")
	)
	(segment
		(start 151.309578 -56.849772)
		(end 151.309578 -56.13273)
		(width 0.508)
		(layer "F.Cu")
		(net "GND")
	)
	(segment
		(start 64.455802 -69.646038)
		(end 64.429386 -69.646038)
		(width 0.254)
		(layer "F.Cu")
		(net "GND")
	)
	(segment
		(start 53.146452 -171.290742)
		(end 53.144928 -171.290742)
		(width 0.508)
		(layer "F.Cu")
		(net "GND")
	)
	(segment
		(start 142.224252 -187.726574)
		(end 142.22476 -187.726574)
		(width 0.508)
		(layer "F.Cu")
		(net "GND")
	)
	(segment
		(start 41.251378 -63.491618)
		(end 41.86682 -63.491618)
		(width 0.381)
		(layer "F.Cu")
		(net "GND")
	)
	(segment
		(start 39.35603 -137.765282)
		(end 39.357554 -137.763758)
		(width 0.3556)
		(layer "F.Cu")
		(net "GND")
	)
	(segment
		(start 107.17276 -184.805574)
		(end 106.97464 -184.805574)
		(width 0.508)
		(layer "F.Cu")
		(net "GND")
	)
	(segment
		(start 142.705836 -53.513228)
		(end 141.837664 -53.513228)
		(width 0.508)
		(layer "F.Cu")
		(net "GND")
	)
	(segment
		(start 45.827188 -89.868248)
		(end 45.827188 -89.048844)
		(width 0.254)
		(layer "F.Cu")
		(net "GND")
	)
	(segment
		(start 107.987084 -170.796204)
		(end 106.740198 -170.796204)
		(width 0.508)
		(layer "F.Cu")
		(net "GND")
	)
	(segment
		(start 150.623016 -186.858148)
		(end 150.47976 -187.001404)
		(width 0.508)
		(layer "F.Cu")
		(net "GND")
	)
	(segment
		(start 44.387262 -70.380098)
		(end 44.530772 -70.380098)
		(width 0.254)
		(layer "F.Cu")
		(net "GND")
	)
	(segment
		(start 53.90515 -86.862666)
		(end 54.595268 -86.862666)
		(width 0.254)
		(layer "F.Cu")
		(net "GND")
	)
	(segment
		(start 145.316702 -145.21815)
		(end 146.186652 -145.21815)
		(width 0.4572)
		(layer "F.Cu")
		(net "GND")
	)
	(segment
		(start 46.432978 -136.963658)
		(end 46.433994 -136.963658)
		(width 0.3556)
		(layer "F.Cu")
		(net "GND")
	)
	(segment
		(start 59.756802 -69.646038)
		(end 59.756802 -68.884038)
		(width 0.3048)
		(layer "F.Cu")
		(net "GND")
	)
	(segment
		(start 68.57873 -85.29193)
		(end 68.287646 -85.000846)
		(width 0.254)
		(layer "F.Cu")
		(net "GND")
	)
	(segment
		(start 25.391872 -94.261178)
		(end 25.391872 -93.39707)
		(width 0.508)
		(layer "F.Cu")
		(net "GND")
	)
	(segment
		(start 139.68476 -181.906672)
		(end 137.52576 -181.906672)
		(width 0.508)
		(layer "F.Cu")
		(net "GND")
	)
	(segment
		(start 47.241714 -70.876414)
		(end 47.241714 -71.057516)
		(width 0.3048)
		(layer "F.Cu")
		(net "GND")
	)
	(segment
		(start 22.032976 -45.203618)
		(end 23.083012 -45.203618)
		(width 0.508)
		(layer "F.Cu")
		(net "GND")
	)
	(segment
		(start 69.059044 -80.241902)
		(end 69.059044 -79.541878)
		(width 0.3048)
		(layer "F.Cu")
		(net "GND")
	)
	(segment
		(start 137.779252 -155.194)
		(end 137.779252 -155.885642)
		(width 0.508)
		(layer "F.Cu")
		(net "GND")
	)
	(segment
		(start 62.910974 -86.862666)
		(end 62.928246 -86.879938)
		(width 0.254)
		(layer "F.Cu")
		(net "GND")
	)
	(segment
		(start 64.363092 -175.858678)
		(end 64.766444 -176.26203)
		(width 0.4572)
		(layer "F.Cu")
		(net "GND")
	)
	(segment
		(start 63.489586 -85.790278)
		(end 63.489586 -85.762846)
		(width 0.254)
		(layer "F.Cu")
		(net "GND")
	)
	(segment
		(start 68.678044 -69.610478)
		(end 68.685664 -69.610478)
		(width 0.3048)
		(layer "F.Cu")
		(net "GND")
	)
	(segment
		(start 43.986958 -74.482706)
		(end 44.314618 -74.482706)
		(width 0.254)
		(layer "F.Cu")
		(net "GND")
	)
	(segment
		(start 64.861186 -67.705478)
		(end 64.444626 -68.122038)
		(width 0.254)
		(layer "F.Cu")
		(net "GND")
	)
	(segment
		(start 44.388278 -88.103964)
		(end 43.52163 -88.103964)
		(width 0.3048)
		(layer "F.Cu")
		(net "GND")
	)
	(segment
		(start 72.014334 -67.457574)
		(end 72.014334 -68.110354)
		(width 0.3048)
		(layer "F.Cu")
		(net "GND")
	)
	(segment
		(start 39.14902 -132.16509)
		(end 40.03167 -132.16509)
		(width 0.3556)
		(layer "F.Cu")
		(net "GND")
	)
	(segment
		(start 41.718738 -69.808344)
		(end 41.718738 -69.786754)
		(width 0.254)
		(layer "F.Cu")
		(net "GND")
	)
	(segment
		(start 34.821114 -76.656946)
		(end 35.11423 -76.36383)
		(width 0.4572)
		(layer "F.Cu")
		(net "GND")
	)
	(segment
		(start 74.542142 -142.859506)
		(end 74.142092 -142.459456)
		(width 0.3556)
		(layer "F.Cu")
		(net "GND")
	)
	(segment
		(start 81.06029 -150.904448)
		(end 81.06029 -150.217378)
		(width 0.4572)
		(layer "F.Cu")
		(net "GND")
	)
	(segment
		(start 36.307522 -73.402698)
		(end 35.54095 -73.402698)
		(width 0.508)
		(layer "F.Cu")
		(net "GND")
	)
	(segment
		(start 64.724026 -84.43849)
		(end 64.895222 -84.43849)
		(width 0.254)
		(layer "F.Cu")
		(net "GND")
	)
	(segment
		(start 60.473336 -89.56294)
		(end 60.974478 -89.061798)
		(width 0.254)
		(layer "F.Cu")
		(net "GND")
	)
	(segment
		(start 82.56016 -121.951496)
		(end 82.87004 -121.641616)
		(width 0.2032)
		(layer "F.Cu")
		(net "GND")
	)
	(segment
		(start 71.759064 -182.186326)
		(end 70.698614 -182.186326)
		(width 0.508)
		(layer "F.Cu")
		(net "GND")
	)
	(segment
		(start 81.373218 -156.990034)
		(end 81.60385 -156.759402)
		(width 0.4572)
		(layer "F.Cu")
		(net "GND")
	)
	(segment
		(start 171.14647 -102.535736)
		(end 171.916598 -102.535736)
		(width 0.1778)
		(layer "F.Cu")
		(net "GND")
	)
	(segment
		(start 42.13606 -77.079094)
		(end 42.080688 -77.134466)
		(width 0.254)
		(layer "F.Cu")
		(net "GND")
	)
	(segment
		(start 76.611988 -160.223454)
		(end 79.146146 -160.223454)
		(width 0.508)
		(layer "F.Cu")
		(net "GND")
	)
	(segment
		(start 122.953272 -25.39492)
		(end 122.818652 -25.52954)
		(width 0.508)
		(layer "F.Cu")
		(net "GND")
	)
	(segment
		(start 69.039994 -77.041502)
		(end 69.059044 -77.022452)
		(width 0.3048)
		(layer "F.Cu")
		(net "GND")
	)
	(segment
		(start 64.539876 -135.259572)
		(end 64.541908 -135.259572)
		(width 0.381)
		(layer "F.Cu")
		(net "GND")
	)
	(segment
		(start 169.243248 -106.106468)
		(end 168.843198 -105.706418)
		(width 0.1778)
		(layer "F.Cu")
		(net "GND")
	)
	(segment
		(start 128.13792 -151.32558)
		(end 128.13792 -152.188418)
		(width 0.2032)
		(layer "F.Cu")
		(net "GND")
	)
	(segment
		(start 61.503306 -84.619846)
		(end 61.495686 -84.619846)
		(width 0.3048)
		(layer "F.Cu")
		(net "GND")
	)
	(segment
		(start 29.014928 -201.09053)
		(end 29.014928 -200.32853)
		(width 0.508)
		(layer "F.Cu")
		(net "GND")
	)
	(segment
		(start 104.94645 -134.697978)
		(end 105.8291 -134.697978)
		(width 0.1778)
		(layer "F.Cu")
		(net "GND")
	)
	(segment
		(start 74.111612 -64.31407)
		(end 73.298812 -64.31407)
		(width 0.3048)
		(layer "F.Cu")
		(net "GND")
	)
	(segment
		(start 56.473852 -84.041234)
		(end 56.27624 -84.238846)
		(width 0.3048)
		(layer "F.Cu")
		(net "GND")
	)
	(segment
		(start 136.250426 -47.188628)
		(end 136.261602 -47.199804)
		(width 0.2794)
		(layer "F.Cu")
		(net "GND")
	)
	(segment
		(start 52.65674 -83.84794)
		(end 52.285646 -83.476846)
		(width 0.3048)
		(layer "F.Cu")
		(net "GND")
	)
	(segment
		(start 48.891444 -89.124536)
		(end 48.891444 -89.048844)
		(width 0.254)
		(layer "F.Cu")
		(net "GND")
	)
	(segment
		(start 134.353808 -113.96472)
		(end 134.353808 -113.464086)
		(width 0.1778)
		(layer "F.Cu")
		(net "GND")
	)
	(segment
		(start 36.061904 -17.14119)
		(end 42.105326 -17.14119)
		(width 0.254)
		(layer "F.Cu")
		(net "GND")
	)
	(segment
		(start 39.346378 -140.16355)
		(end 40.033194 -140.16355)
		(width 0.3556)
		(layer "F.Cu")
		(net "GND")
	)
	(segment
		(start 89.289382 -31.673038)
		(end 89.291414 -31.673038)
		(width 0.4572)
		(layer "F.Cu")
		(net "GND")
	)
	(segment
		(start 122.66676 -187.726574)
		(end 122.66676 -187.133484)
		(width 0.508)
		(layer "F.Cu")
		(net "GND")
	)
	(segment
		(start 63.3349 -20.94992)
		(end 64.350138 -20.94992)
		(width 0.381)
		(layer "F.Cu")
		(net "GND")
	)
	(segment
		(start 49.193958 -62.454282)
		(end 49.0982 -62.55004)
		(width 0.254)
		(layer "F.Cu")
		(net "GND")
	)
	(segment
		(start 39.193978 -128.906778)
		(end 39.976298 -128.906778)
		(width 0.3556)
		(layer "F.Cu")
		(net "GND")
	)
	(segment
		(start 138.525758 -163.358576)
		(end 138.525758 -164.488876)
		(width 0.254)
		(layer "F.Cu")
		(net "GND")
	)
	(segment
		(start 52.106068 -86.737698)
		(end 52.181252 -86.813136)
		(width 0.3048)
		(layer "F.Cu")
		(net "GND")
	)
	(segment
		(start 80.528414 -155.490418)
		(end 80.298036 -155.490418)
		(width 0.254)
		(layer "F.Cu")
		(net "GND")
	)
	(segment
		(start 73.752964 -70.678802)
		(end 73.700132 -70.731634)
		(width 0.3048)
		(layer "F.Cu")
		(net "GND")
	)
	(segment
		(start 78.494636 -165.418516)
		(end 78.494636 -164.374576)
		(width 0.254)
		(layer "F.Cu")
		(net "GND")
	)
	(segment
		(start 49.990248 -76.029566)
		(end 50.752248 -76.029566)
		(width 0.3048)
		(layer "F.Cu")
		(net "GND")
	)
	(segment
		(start 67.916044 -82.63636)
		(end 67.916044 -82.228182)
		(width 0.254)
		(layer "F.Cu")
		(net "GND")
	)
	(segment
		(start 42.710608 -78.972918)
		(end 42.328592 -78.972918)
		(width 0.254)
		(layer "F.Cu")
		(net "GND")
	)
	(segment
		(start 41.86682 -63.491618)
		(end 41.88968 -63.468758)
		(width 0.381)
		(layer "F.Cu")
		(net "GND")
	)
	(segment
		(start 72.5424 -136.859518)
		(end 72.541892 -136.859518)
		(width 0.3556)
		(layer "F.Cu")
		(net "GND")
	)
	(segment
		(start 63.90132 -81.035144)
		(end 64.001396 -80.935068)
		(width 0.3048)
		(layer "F.Cu")
		(net "GND")
	)
	(segment
		(start 85.366352 -116.591588)
		(end 85.366352 -115.445794)
		(width 0.2032)
		(layer "F.Cu")
		(net "GND")
	)
	(segment
		(start 119.61876 -187.726574)
		(end 119.61876 -187.167012)
		(width 0.508)
		(layer "F.Cu")
		(net "GND")
	)
	(segment
		(start 115.29949 -157.447742)
		(end 115.29949 -158.683706)
		(width 0.508)
		(layer "F.Cu")
		(net "GND")
	)
	(segment
		(start 43.986958 -69.979794)
		(end 44.387262 -70.380098)
		(width 0.254)
		(layer "F.Cu")
		(net "GND")
	)
	(segment
		(start 41.416732 -72.631554)
		(end 41.75125 -72.631554)
		(width 0.254)
		(layer "F.Cu")
		(net "GND")
	)
	(segment
		(start 53.394356 -90.291158)
		(end 53.394356 -89.048844)
		(width 0.254)
		(layer "F.Cu")
		(net "GND")
	)
	(segment
		(start 49.163478 -74.784712)
		(end 49.163478 -75.264772)
		(width 0.3048)
		(layer "F.Cu")
		(net "GND")
	)
	(segment
		(start 66.750692 -106.915966)
		(end 66.750692 -106.143044)
		(width 0.4572)
		(layer "F.Cu")
		(net "GND")
	)
	(segment
		(start 70.181216 -62.55004)
		(end 70.174104 -62.55004)
		(width 0.254)
		(layer "F.Cu")
		(net "GND")
	)
	(segment
		(start 87.394542 -31.596838)
		(end 86.894162 -31.596838)
		(width 0.381)
		(layer "F.Cu")
		(net "GND")
	)
	(segment
		(start 52.211478 -88.793066)
		(end 52.211478 -88.04656)
		(width 0.254)
		(layer "F.Cu")
		(net "GND")
	)
	(segment
		(start 45.111416 -90.20937)
		(end 45.486066 -90.20937)
		(width 0.254)
		(layer "F.Cu")
		(net "GND")
	)
	(segment
		(start 74.852784 -66.89725)
		(end 74.250042 -66.89725)
		(width 0.254)
		(layer "F.Cu")
		(net "GND")
	)
	(segment
		(start 53.95976 -187.726574)
		(end 53.95976 -186.900566)
		(width 0.508)
		(layer "F.Cu")
		(net "GND")
	)
	(segment
		(start 51.891946 -76.789026)
		(end 51.891946 -77.291692)
		(width 0.3048)
		(layer "F.Cu")
		(net "GND")
	)
	(segment
		(start 29.050488 -130.989832)
		(end 29.050488 -131.800092)
		(width 0.508)
		(layer "F.Cu")
		(net "GND")
	)
	(segment
		(start 108.993432 -73.406254)
		(end 110.460028 -73.406254)
		(width 0.3048)
		(layer "F.Cu")
		(net "GND")
	)
	(segment
		(start 73.341992 -142.459456)
		(end 73.341738 -142.459456)
		(width 0.3556)
		(layer "F.Cu")
		(net "GND")
	)
	(segment
		(start 124.7394 -163.663376)
		(end 124.55144 -163.475416)
		(width 0.508)
		(layer "F.Cu")
		(net "GND")
	)
	(segment
		(start 46.03242 -138.16457)
		(end 46.032928 -138.164062)
		(width 0.3556)
		(layer "F.Cu")
		(net "GND")
	)
	(segment
		(start 91.502484 -183.778398)
		(end 91.5035 -183.778398)
		(width 0.508)
		(layer "F.Cu")
		(net "GND")
	)
	(segment
		(start 149.039326 -41.469056)
		(end 149.039326 -41.480994)
		(width 0.4572)
		(layer "F.Cu")
		(net "GND")
	)
	(segment
		(start 12.74318 -161.77133)
		(end 12.854178 -161.882328)
		(width 0.508)
		(layer "F.Cu")
		(net "GND")
	)
	(segment
		(start 72.014334 -72.613266)
		(end 72.014334 -72.313292)
		(width 0.3048)
		(layer "F.Cu")
		(net "GND")
	)
	(segment
		(start 142.452852 -137.24255)
		(end 142.452852 -137.39495)
		(width 0.1778)
		(layer "F.Cu")
		(net "GND")
	)
	(segment
		(start 130.904234 -167.35552)
		(end 130.657346 -167.108632)
		(width 0.254)
		(layer "F.Cu")
		(net "GND")
	)
	(segment
		(start 133.893052 -134.49935)
		(end 134.137908 -134.744206)
		(width 0.1778)
		(layer "F.Cu")
		(net "GND")
	)
	(segment
		(start 38.379654 -112.249966)
		(end 37.54628 -112.249966)
		(width 0.4572)
		(layer "F.Cu")
		(net "GND")
	)
	(segment
		(start 70.407276 -89.048844)
		(end 70.412864 -89.054432)
		(width 0.254)
		(layer "F.Cu")
		(net "GND")
	)
	(segment
		(start 14.669516 -134.417562)
		(end 15.061946 -134.417562)
		(width 0.4572)
		(layer "F.Cu")
		(net "GND")
	)
	(segment
		(start 66.392044 -79.168498)
		(end 66.765424 -79.541878)
		(width 0.3048)
		(layer "F.Cu")
		(net "GND")
	)
	(segment
		(start 51.517042 -95.738188)
		(end 51.30673 -95.527876)
		(width 0.4572)
		(layer "F.Cu")
		(net "GND")
	)
	(segment
		(start 71.673212 -62.68847)
		(end 71.673212 -61.97727)
		(width 0.3048)
		(layer "F.Cu")
		(net "GND")
	)
	(segment
		(start 48.686212 -69.209666)
		(end 48.2473 -69.209666)
		(width 0.3048)
		(layer "F.Cu")
		(net "GND")
	)
	(segment
		(start 177.51044 -118.86565)
		(end 177.010568 -119.365522)
		(width 0.381)
		(layer "F.Cu")
		(net "GND")
	)
	(segment
		(start 73.298812 -62.68847)
		(end 73.298812 -62.378082)
		(width 0.3048)
		(layer "F.Cu")
		(net "GND")
	)
	(segment
		(start 58.14187 -129.65938)
		(end 58.14187 -129.659634)
		(width 0.3556)
		(layer "F.Cu")
		(net "GND")
	)
	(segment
		(start 64.542924 -142.459456)
		(end 64.541908 -142.459456)
		(width 0.3556)
		(layer "F.Cu")
		(net "GND")
	)
	(segment
		(start 45.154596 -78.015846)
		(end 45.784516 -78.645766)
		(width 0.3048)
		(layer "F.Cu")
		(net "GND")
	)
	(segment
		(start 42.098468 -74.257154)
		(end 41.75125 -74.257154)
		(width 0.3048)
		(layer "F.Cu")
		(net "GND")
	)
	(segment
		(start 58.14187 -128.85928)
		(end 58.14187 -128.859534)
		(width 0.3556)
		(layer "F.Cu")
		(net "GND")
	)
	(segment
		(start 55.049166 -97.110042)
		(end 56.065166 -97.110042)
		(width 0.4572)
		(layer "F.Cu")
		(net "GND")
	)
	(segment
		(start 106.826558 -177.969926)
		(end 106.826558 -178.984656)
		(width 0.508)
		(layer "F.Cu")
		(net "GND")
	)
	(segment
		(start 73.700132 -70.731634)
		(end 72.795384 -70.731634)
		(width 0.3048)
		(layer "F.Cu")
		(net "GND")
	)
	(segment
		(start 106.354372 -76.499974)
		(end 106.354372 -76.497688)
		(width 0.3048)
		(layer "F.Cu")
		(net "GND")
	)
	(segment
		(start 50.109628 -86.879938)
		(end 50.092356 -86.862666)
		(width 0.254)
		(layer "F.Cu")
		(net "GND")
	)
	(segment
		(start 59.4741 -64.785748)
		(end 59.99607 -65.307718)
		(width 0.3048)
		(layer "F.Cu")
		(net "GND")
	)
	(segment
		(start 138.975592 -55.93588)
		(end 137.123932 -55.93588)
		(width 0.4572)
		(layer "F.Cu")
		(net "GND")
	)
	(segment
		(start 74.142092 -141.65961)
		(end 74.141838 -141.65961)
		(width 0.3556)
		(layer "F.Cu")
		(net "GND")
	)
	(segment
		(start 49.163478 -74.489056)
		(end 49.163478 -74.784712)
		(width 0.3048)
		(layer "F.Cu")
		(net "GND")
	)
	(segment
		(start 167.523414 -136.199372)
		(end 167.57396 -136.148826)
		(width 0.508)
		(layer "F.Cu")
		(net "GND")
	)
	(segment
		(start 43.336718 -67.900804)
		(end 43.334178 -67.898264)
		(width 0.3048)
		(layer "F.Cu")
		(net "GND")
	)
	(segment
		(start 67.328542 -68.11772)
		(end 67.328542 -67.741038)
		(width 0.3048)
		(layer "F.Cu")
		(net "GND")
	)
	(segment
		(start 42.515282 -86.691724)
		(end 42.70248 -86.878922)
		(width 0.381)
		(layer "F.Cu")
		(net "GND")
	)
	(segment
		(start 165.989 -186.076082)
		(end 165.989 -186.055)
		(width 0.508)
		(layer "F.Cu")
		(net "GND")
	)
	(segment
		(start 47.47895 -90.376248)
		(end 47.807118 -90.376248)
		(width 0.381)
		(layer "F.Cu")
		(net "GND")
	)
	(segment
		(start 146.180302 -26.193242)
		(end 147.050252 -26.193242)
		(width 0.508)
		(layer "F.Cu")
		(net "GND")
	)
	(segment
		(start 51.999896 -75.799442)
		(end 51.999896 -76.599542)
		(width 0.3048)
		(layer "F.Cu")
		(net "GND")
	)
	(segment
		(start 62.558422 -164.689282)
		(end 63.363348 -164.689282)
		(width 0.508)
		(layer "F.Cu")
		(net "GND")
	)
	(segment
		(start 72.24776 -187.726574)
		(end 72.24776 -186.798458)
		(width 0.508)
		(layer "F.Cu")
		(net "GND")
	)
	(segment
		(start 90.5637 -18.990818)
		(end 90.551762 -18.990818)
		(width 0.4572)
		(layer "F.Cu")
		(net "GND")
	)
	(segment
		(start 104.296972 -64.407034)
		(end 104.299512 -64.404494)
		(width 0.3048)
		(layer "F.Cu")
		(net "GND")
	)
	(segment
		(start 93.711522 -129.368042)
		(end 93.711522 -128.614424)
		(width 0.4572)
		(layer "F.Cu")
		(net "GND")
	)
	(segment
		(start 68.355718 -89.630504)
		(end 68.355718 -89.062814)
		(width 0.254)
		(layer "F.Cu")
		(net "GND")
	)
	(segment
		(start 63.90132 -81.300066)
		(end 63.90132 -81.035144)
		(width 0.3048)
		(layer "F.Cu")
		(net "GND")
	)
	(segment
		(start 90.354912 -18.793968)
		(end 90.354912 -17.60347)
		(width 0.4572)
		(layer "F.Cu")
		(net "GND")
	)
	(segment
		(start 42.040048 -12.945872)
		(end 42.963846 -12.945872)
		(width 0.4572)
		(layer "F.Cu")
		(net "GND")
	)
	(segment
		(start 62.59957 -86.862666)
		(end 62.405514 -86.66861)
		(width 0.254)
		(layer "F.Cu")
		(net "GND")
	)
	(segment
		(start 124.991368 -143.375634)
		(end 125.787912 -143.375634)
		(width 0.1778)
		(layer "F.Cu")
		(net "GND")
	)
	(segment
		(start 86.894162 -31.596838)
		(end 86.250272 -30.952948)
		(width 0.381)
		(layer "F.Cu")
		(net "GND")
	)
	(segment
		(start 67.154044 -70.310502)
		(end 67.156076 -70.310502)
		(width 0.3048)
		(layer "F.Cu")
		(net "GND")
	)
	(segment
		(start 49.837848 -69.276976)
		(end 49.83734 -69.276976)
		(width 0.3048)
		(layer "F.Cu")
		(net "GND")
	)
	(segment
		(start 85.96376 -187.726574)
		(end 85.96376 -187.236354)
		(width 0.508)
		(layer "F.Cu")
		(net "GND")
	)
	(segment
		(start 191.02705 -125.48235)
		(end 190.3222 -126.1872)
		(width 0.508)
		(layer "F.Cu")
		(net "GND")
	)
	(segment
		(start 67.340988 -134.058406)
		(end 66.9417 -134.457694)
		(width 0.381)
		(layer "F.Cu")
		(net "GND")
	)
	(segment
		(start 73.742042 -138.059414)
		(end 73.342246 -137.659618)
		(width 0.3556)
		(layer "F.Cu")
		(net "GND")
	)
	(segment
		(start 16.899382 -135.049514)
		(end 16.899382 -134.725918)
		(width 0.254)
		(layer "F.Cu")
		(net "GND")
	)
	(segment
		(start 48.131984 -90.051382)
		(end 48.131984 -88.605106)
		(width 0.381)
		(layer "F.Cu")
		(net "GND")
	)
	(segment
		(start 50.542698 -89.696798)
		(end 50.3301 -89.4842)
		(width 0.254)
		(layer "F.Cu")
		(net "GND")
	)
	(segment
		(start 64.429386 -66.596006)
		(end 64.429386 -66.598038)
		(width 0.254)
		(layer "F.Cu")
		(net "GND")
	)
	(segment
		(start 133.08076 -184.571132)
		(end 133.08076 -184.805574)
		(width 0.508)
		(layer "F.Cu")
		(net "GND")
	)
	(segment
		(start 41.533572 -62.332362)
		(end 41.88968 -62.68847)
		(width 0.3048)
		(layer "F.Cu")
		(net "GND")
	)
	(segment
		(start 44.530772 -70.380098)
		(end 44.530772 -70.786498)
		(width 0.254)
		(layer "F.Cu")
		(net "GND")
	)
	(segment
		(start 43.303698 -107.733084)
		(end 42.636694 -107.733084)
		(width 0.4572)
		(layer "F.Cu")
		(net "GND")
	)
	(segment
		(start 53.27904 -84.418424)
		(end 53.52034 -84.659724)
		(width 0.254)
		(layer "F.Cu")
		(net "GND")
	)
	(segment
		(start 60.150248 -20.94992)
		(end 60.150248 -22.529292)
		(width 0.4572)
		(layer "F.Cu")
		(net "GND")
	)
	(segment
		(start 157.130242 -26.594816)
		(end 157.130242 -27.665172)
		(width 0.508)
		(layer "F.Cu")
		(net "GND")
	)
	(segment
		(start 68.48348 -61.78296)
		(end 68.548504 -61.847984)
		(width 0.254)
		(layer "F.Cu")
		(net "GND")
	)
	(segment
		(start 85.96376 -187.236354)
		(end 85.59546 -186.868054)
		(width 0.508)
		(layer "F.Cu")
		(net "GND")
	)
	(segment
		(start 78.81112 -165.735)
		(end 78.494636 -165.418516)
		(width 0.254)
		(layer "F.Cu")
		(net "GND")
	)
	(segment
		(start 116.11991 -66.641472)
		(end 116.100352 -66.621914)
		(width 0.4572)
		(layer "F.Cu")
		(net "GND")
	)
	(segment
		(start 145.316702 -140.21435)
		(end 146.110452 -140.21435)
		(width 0.4572)
		(layer "F.Cu")
		(net "GND")
	)
	(segment
		(start 145.316702 -138.53795)
		(end 146.161252 -138.53795)
		(width 0.4572)
		(layer "F.Cu")
		(net "GND")
	)
	(segment
		(start 87.30742 -184.043574)
		(end 87.30742 -184.533032)
		(width 0.508)
		(layer "F.Cu")
		(net "GND")
	)
	(segment
		(start 67.340988 -136.458198)
		(end 66.942208 -136.059418)
		(width 0.381)
		(layer "F.Cu")
		(net "GND")
	)
	(segment
		(start 72.541892 -141.65961)
		(end 72.541892 -141.659102)
		(width 0.3556)
		(layer "F.Cu")
		(net "GND")
	)
	(segment
		(start 70.55485 -102.413308)
		(end 70.55485 -102.413562)
		(width 0.4572)
		(layer "F.Cu")
		(net "GND")
	)
	(segment
		(start 68.074286 -129.324862)
		(end 67.921886 -129.477262)
		(width 0.3556)
		(layer "F.Cu")
		(net "GND")
	)
	(segment
		(start 40.122602 -162.587432)
		(end 40.122602 -163.395406)
		(width 0.508)
		(layer "F.Cu")
		(net "GND")
	)
	(segment
		(start 46.834044 -140.565124)
		(end 46.833028 -140.565124)
		(width 0.3556)
		(layer "F.Cu")
		(net "GND")
	)
	(segment
		(start 71.741792 -126.459488)
		(end 71.742554 -126.459488)
		(width 0.3556)
		(layer "F.Cu")
		(net "GND")
	)
	(segment
		(start 126.966472 -148.77415)
		(end 126.76505 -148.975572)
		(width 0.1778)
		(layer "F.Cu")
		(net "GND")
	)
	(segment
		(start 64.54267 -140.85951)
		(end 64.541908 -140.85951)
		(width 0.3556)
		(layer "F.Cu")
		(net "GND")
	)
	(segment
		(start 72.541892 -141.659102)
		(end 72.142096 -141.259306)
		(width 0.3556)
		(layer "F.Cu")
		(net "GND")
	)
	(segment
		(start 108.33608 -187.706254)
		(end 108.31576 -187.726574)
		(width 0.508)
		(layer "F.Cu")
		(net "GND")
	)
	(segment
		(start 36.014914 -205.199488)
		(end 36.014914 -201.09053)
		(width 0.508)
		(layer "F.Cu")
		(net "GND")
	)
	(segment
		(start 14.29385 -115.602512)
		(end 11.18616 -115.602512)
		(width 0.254)
		(layer "F.Cu")
		(net "GND")
	)
	(segment
		(start 49.990248 -79.302102)
		(end 50.041048 -79.352902)
		(width 0.3048)
		(layer "F.Cu")
		(net "GND")
	)
	(segment
		(start 132.31876 -187.726574)
		(end 132.31876 -187.243974)
		(width 0.381)
		(layer "F.Cu")
		(net "GND")
	)
	(segment
		(start 73.394316 -66.240152)
		(end 72.77481 -66.240152)
		(width 0.3048)
		(layer "F.Cu")
		(net "GND")
	)
	(segment
		(start 91.686126 -98.82632)
		(end 91.68384 -98.82632)
		(width 0.508)
		(layer "F.Cu")
		(net "GND")
	)
	(segment
		(start 43.937428 -66.179192)
		(end 43.417998 -66.179192)
		(width 0.3048)
		(layer "F.Cu")
		(net "GND")
	)
	(segment
		(start 60.4012 -76.199492)
		(end 60.800996 -76.599288)
		(width 0.254)
		(layer "F.Cu")
		(net "GND")
	)
	(segment
		(start 35.269678 -79.893922)
		(end 34.47542 -79.893922)
		(width 0.508)
		(layer "F.Cu")
		(net "GND")
	)
	(segment
		(start 75.636628 -74.159364)
		(end 75.115674 -74.680318)
		(width 0.3048)
		(layer "F.Cu")
		(net "GND")
	)
	(segment
		(start 48.466248 -79.302102)
		(end 49.228248 -79.302102)
		(width 0.3048)
		(layer "F.Cu")
		(net "GND")
	)
	(segment
		(start 68.889372 -74.071734)
		(end 68.678044 -74.283062)
		(width 0.3048)
		(layer "F.Cu")
		(net "GND")
	)
	(segment
		(start 67.154044 -69.610478)
		(end 67.916044 -69.610478)
		(width 0.3048)
		(layer "F.Cu")
		(net "GND")
	)
	(segment
		(start 69.342254 -140.05941)
		(end 69.341746 -140.05941)
		(width 0.3556)
		(layer "F.Cu")
		(net "GND")
	)
	(segment
		(start 43.51528 -88.910414)
		(end 43.362626 -89.063068)
		(width 0.381)
		(layer "F.Cu")
		(net "GND")
	)
	(segment
		(start 64.940942 -142.857474)
		(end 64.542924 -142.459456)
		(width 0.3556)
		(layer "F.Cu")
		(net "GND")
	)
	(segment
		(start 72.142096 -143.659352)
		(end 71.7423 -143.259556)
		(width 0.3556)
		(layer "F.Cu")
		(net "GND")
	)
	(segment
		(start 137.855452 -117.633242)
		(end 137.774172 -117.714522)
		(width 0.1778)
		(layer "F.Cu")
		(net "GND")
	)
	(segment
		(start 100.950268 -20.94992)
		(end 100.950268 -23.029418)
		(width 0.381)
		(layer "F.Cu")
		(net "GND")
	)
	(segment
		(start 61.135768 -87.427816)
		(end 60.878466 -87.427816)
		(width 0.3048)
		(layer "F.Cu")
		(net "GND")
	)
	(segment
		(start 81.30794 -178.585622)
		(end 81.494884 -178.772566)
		(width 0.254)
		(layer "F.Cu")
		(net "GND")
	)
	(segment
		(start 75.361546 -76.626212)
		(end 74.02957 -76.626212)
		(width 0.254)
		(layer "F.Cu")
		(net "GND")
	)
	(segment
		(start 41.232582 -140.561314)
		(end 41.630346 -140.16355)
		(width 0.3556)
		(layer "F.Cu")
		(net "GND")
	)
	(segment
		(start 50.099722 -87.507572)
		(end 50.099722 -87.02675)
		(width 0.254)
		(layer "F.Cu")
		(net "GND")
	)
	(segment
		(start 137.398252 -120.300242)
		(end 137.212578 -120.114568)
		(width 0.1778)
		(layer "F.Cu")
		(net "GND")
	)
	(segment
		(start 160.015682 -201.034904)
		(end 160.015682 -205.199488)
		(width 0.508)
		(layer "F.Cu")
		(net "GND")
	)
	(segment
		(start 58.23077 -81.571846)
		(end 58.149236 -81.490312)
		(width 0.3048)
		(layer "F.Cu")
		(net "GND")
	)
	(segment
		(start 49.193958 -61.93917)
		(end 49.193958 -62.454282)
		(width 0.254)
		(layer "F.Cu")
		(net "GND")
	)
	(segment
		(start 44.778168 -69.370702)
		(end 45.037248 -69.370702)
		(width 0.3048)
		(layer "F.Cu")
		(net "GND")
	)
	(segment
		(start 73.39076 -184.146698)
		(end 73.46696 -184.070498)
		(width 0.508)
		(layer "F.Cu")
		(net "GND")
	)
	(segment
		(start 32.022288 -122.874532)
		(end 32.022288 -122.139456)
		(width 0.508)
		(layer "F.Cu")
		(net "GND")
	)
	(segment
		(start 142.224252 -186.999626)
		(end 142.224252 -187.726574)
		(width 0.508)
		(layer "F.Cu")
		(net "GND")
	)
	(segment
		(start 141.007592 -186.838082)
		(end 141.08176 -186.91225)
		(width 0.381)
		(layer "F.Cu")
		(net "GND")
	)
	(segment
		(start 115.3541 -63.259716)
		(end 115.2652 -63.348616)
		(width 0.4572)
		(layer "F.Cu")
		(net "GND")
	)
	(segment
		(start 67.154044 -70.310502)
		(end 66.87058 -70.027038)
		(width 0.3048)
		(layer "F.Cu")
		(net "GND")
	)
	(segment
		(start 69.741034 -140.45819)
		(end 69.342254 -140.05941)
		(width 0.3556)
		(layer "F.Cu")
		(net "GND")
	)
	(segment
		(start 142.036546 -152.705816)
		(end 140.619226 -152.705816)
		(width 0.508)
		(layer "F.Cu")
		(net "GND")
	)
	(segment
		(start 119.71274 -186.387994)
		(end 119.71274 -185.945018)
		(width 0.508)
		(layer "F.Cu")
		(net "GND")
	)
	(segment
		(start 109.343444 -67.406266)
		(end 110.460028 -67.406266)
		(width 0.3048)
		(layer "F.Cu")
		(net "GND")
	)
	(segment
		(start 78.519274 -95.141542)
		(end 78.522068 -95.138748)
		(width 0.4572)
		(layer "F.Cu")
		(net "GND")
	)
	(segment
		(start 69.0499 -168.695624)
		(end 69.354954 -168.695624)
		(width 0.508)
		(layer "F.Cu")
		(net "GND")
	)
	(segment
		(start 119.61876 -187.167012)
		(end 119.7483 -187.037472)
		(width 0.508)
		(layer "F.Cu")
		(net "GND")
	)
	(segment
		(start 53.962046 -161.030158)
		(end 54.86019 -161.030158)
		(width 0.508)
		(layer "F.Cu")
		(net "GND")
	)
	(segment
		(start 106.28376 -186.92622)
		(end 106.28376 -187.726574)
		(width 0.508)
		(layer "F.Cu")
		(net "GND")
	)
	(segment
		(start 113.486946 -167.486584)
		(end 114.071908 -168.071546)
		(width 0.254)
		(layer "F.Cu")
		(net "GND")
	)
	(segment
		(start 53.962046 -162.046158)
		(end 54.891178 -162.046158)
		(width 0.508)
		(layer "F.Cu")
		(net "GND")
	)
	(segment
		(start 124.725684 -52.716684)
		(end 125.287532 -53.278532)
		(width 0.4572)
		(layer "F.Cu")
		(net "GND")
	)
	(segment
		(start 184.015634 -200.600564)
		(end 183.53786 -200.12279)
		(width 0.508)
		(layer "F.Cu")
		(net "GND")
	)
	(segment
		(start 42.180764 -74.33945)
		(end 42.098468 -74.257154)
		(width 0.3048)
		(layer "F.Cu")
		(net "GND")
	)
	(segment
		(start 80.994758 -178.898804)
		(end 81.30794 -178.585622)
		(width 0.254)
		(layer "F.Cu")
		(net "GND")
	)
	(segment
		(start 48.29937 -84.238846)
		(end 47.599346 -84.238846)
		(width 0.3048)
		(layer "F.Cu")
		(net "GND")
	)
	(segment
		(start 46.919134 -141.45133)
		(end 46.432978 -140.965174)
		(width 0.3556)
		(layer "F.Cu")
		(net "GND")
	)
	(segment
		(start 132.978652 -152.48255)
		(end 132.938012 -152.44191)
		(width 0.1778)
		(layer "F.Cu")
		(net "GND")
	)
	(segment
		(start 109.77372 -168.55948)
		(end 109.77372 -168.015666)
		(width 0.508)
		(layer "F.Cu")
		(net "GND")
	)
	(segment
		(start 70.9422 -141.65961)
		(end 70.941692 -141.65961)
		(width 0.3556)
		(layer "F.Cu")
		(net "GND")
	)
	(segment
		(start 70.860412 -62.20587)
		(end 70.701916 -62.047374)
		(width 0.3048)
		(layer "F.Cu")
		(net "GND")
	)
	(segment
		(start 50.550064 -20.94992)
		(end 50.550064 -22.462236)
		(width 0.4572)
		(layer "F.Cu")
		(net "GND")
	)
	(segment
		(start 67.19189 -127.807466)
		(end 66.9417 -128.057402)
		(width 0.3556)
		(layer "F.Cu")
		(net "GND")
	)
	(segment
		(start 61.96076 -99.28479)
		(end 61.96076 -99.115626)
		(width 0.4572)
		(layer "F.Cu")
		(net "GND")
	)
	(segment
		(start 83.3501 -153.762456)
		(end 82.963512 -153.762456)
		(width 0.4572)
		(layer "F.Cu")
		(net "GND")
	)
	(segment
		(start 80.508602 -117.802406)
		(end 80.508602 -118.78437)
		(width 0.508)
		(layer "F.Cu")
		(net "GND")
	)
	(segment
		(start 61.96076 -99.115626)
		(end 61.628274 -98.78314)
		(width 0.4572)
		(layer "F.Cu")
		(net "GND")
	)
	(segment
		(start 73.742042 -135.659368)
		(end 73.342246 -135.259572)
		(width 0.3556)
		(layer "F.Cu")
		(net "GND")
	)
	(segment
		(start 42.78376 -78.985618)
		(end 42.753534 -79.015844)
		(width 0.254)
		(layer "F.Cu")
		(net "GND")
	)
	(segment
		(start 68.940934 -2.544064)
		(end 68.940934 -1.859026)
		(width 0.4572)
		(layer "F.Cu")
		(net "GND")
	)
	(segment
		(start 59.756802 -68.122038)
		(end 59.756802 -68.129658)
		(width 0.3048)
		(layer "F.Cu")
		(net "GND")
	)
	(segment
		(start 149.17801 -30.946344)
		(end 148.249894 -30.946344)
		(width 0.508)
		(layer "F.Cu")
		(net "GND")
	)
	(segment
		(start 49.585626 -82.333846)
		(end 49.585626 -81.571846)
		(width 0.3048)
		(layer "F.Cu")
		(net "GND")
	)
	(segment
		(start 58.525156 -86.862666)
		(end 58.408062 -86.862666)
		(width 0.254)
		(layer "F.Cu")
		(net "GND")
	)
	(segment
		(start 22.014434 -55.812436)
		(end 23.046182 -55.812436)
		(width 0.4572)
		(layer "F.Cu")
		(net "GND")
	)
	(segment
		(start 124.915168 -147.375626)
		(end 125.787912 -147.375626)
		(width 0.1778)
		(layer "F.Cu")
		(net "GND")
	)
	(segment
		(start 109.127036 -71.90613)
		(end 110.460028 -71.90613)
		(width 0.3048)
		(layer "F.Cu")
		(net "GND")
	)
	(segment
		(start 135.94842 -164.772594)
		(end 136.025636 -164.695378)
		(width 0.254)
		(layer "F.Cu")
		(net "GND")
	)
	(segment
		(start 73.742042 -141.25956)
		(end 73.341992 -140.85951)
		(width 0.3556)
		(layer "F.Cu")
		(net "GND")
	)
	(segment
		(start 172.297852 -102.91699)
		(end 172.279056 -102.935786)
		(width 0.1778)
		(layer "F.Cu")
		(net "GND")
	)
	(segment
		(start 63.892176 -80.709262)
		(end 63.310516 -80.709262)
		(width 0.254)
		(layer "F.Cu")
		(net "GND")
	)
	(segment
		(start 66.773044 -76.269342)
		(end 66.773044 -75.569318)
		(width 0.3048)
		(layer "F.Cu")
		(net "GND")
	)
	(segment
		(start 46.31309 -86.087966)
		(end 46.31309 -86.143846)
		(width 0.3048)
		(layer "F.Cu")
		(net "GND")
	)
	(segment
		(start 59.685428 -88.438482)
		(end 59.685428 -88.69934)
		(width 0.3048)
		(layer "F.Cu")
		(net "GND")
	)
	(segment
		(start 128.084072 -154.59075)
		(end 128.082802 -154.59075)
		(width 0.4572)
		(layer "F.Cu")
		(net "GND")
	)
	(segment
		(start 53.751226 -15.326868)
		(end 56.18861 -15.326868)
		(width 0.254)
		(layer "F.Cu")
		(net "GND")
	)
	(segment
		(start 113.420144 -141.045946)
		(end 113.420144 -140.593572)
		(width 0.254)
		(layer "F.Cu")
		(net "GND")
	)
	(segment
		(start 49.442624 -82.333846)
		(end 49.585626 -82.333846)
		(width 0.254)
		(layer "F.Cu")
		(net "GND")
	)
	(segment
		(start 129.33807 -136.613392)
		(end 129.33807 -135.825484)
		(width 0.1778)
		(layer "F.Cu")
		(net "GND")
	)
	(segment
		(start 49.32426 -76.60513)
		(end 49.32426 -76.125578)
		(width 0.3048)
		(layer "F.Cu")
		(net "GND")
	)
	(segment
		(start 44.656248 -71.165974)
		(end 44.656248 -71.356982)
		(width 0.3048)
		(layer "F.Cu")
		(net "GND")
	)
	(segment
		(start 152.76576 -187.726574)
		(end 152.76576 -186.862974)
		(width 0.508)
		(layer "F.Cu")
		(net "GND")
	)
	(segment
		(start 52.511706 -68.12534)
		(end 52.511706 -68.122038)
		(width 0.254)
		(layer "F.Cu")
		(net "GND")
	)
	(segment
		(start 51.178206 -86.133178)
		(end 51.561238 -86.51621)
		(width 0.3048)
		(layer "F.Cu")
		(net "GND")
	)
	(segment
		(start 61.085222 -174.752508)
		(end 61.085222 -175.940212)
		(width 0.4572)
		(layer "F.Cu")
		(net "GND")
	)
	(segment
		(start 72.24776 -186.798458)
		(end 72.13346 -186.684158)
		(width 0.508)
		(layer "F.Cu")
		(net "GND")
	)
	(segment
		(start 63.739776 -132.859526)
		(end 63.340996 -133.258306)
		(width 0.3556)
		(layer "F.Cu")
		(net "GND")
	)
	(segment
		(start 49.51857 -69.5325)
		(end 49.009046 -69.5325)
		(width 0.3048)
		(layer "F.Cu")
		(net "GND")
	)
	(segment
		(start 15.21968 -43.186604)
		(end 14.27226 -43.186604)
		(width 0.4572)
		(layer "F.Cu")
		(net "GND")
	)
	(segment
		(start 93.811344 -185.790586)
		(end 93.07322 -185.790586)
		(width 0.508)
		(layer "F.Cu")
		(net "GND")
	)
	(segment
		(start 52.905406 -66.964306)
		(end 52.511706 -67.358006)
		(width 0.254)
		(layer "F.Cu")
		(net "GND")
	)
	(segment
		(start 56.458612 -89.552018)
		(end 56.458612 -89.048844)
		(width 0.254)
		(layer "F.Cu")
		(net "GND")
	)
	(segment
		(start 64.141096 -135.658352)
		(end 64.539876 -135.259572)
		(width 0.381)
		(layer "F.Cu")
		(net "GND")
	)
	(segment
		(start 63.618364 -86.879938)
		(end 64.187832 -86.879938)
		(width 0.254)
		(layer "F.Cu")
		(net "GND")
	)
	(segment
		(start 68.941188 -142.059914)
		(end 68.540884 -141.65961)
		(width 0.3556)
		(layer "F.Cu")
		(net "GND")
	)
	(segment
		(start 42.212006 -85.16239)
		(end 42.392854 -85.343238)
		(width 0.254)
		(layer "F.Cu")
		(net "GND")
	)
	(segment
		(start 76.717144 -158.464758)
		(end 76.105766 -158.464758)
		(width 0.4572)
		(layer "F.Cu")
		(net "GND")
	)
	(segment
		(start 47.850298 -29.149802)
		(end 47.850298 -30.36443)
		(width 0.381)
		(layer "F.Cu")
		(net "GND")
	)
	(segment
		(start 72.014334 -72.313292)
		(end 72.063864 -72.263762)
		(width 0.3048)
		(layer "F.Cu")
		(net "GND")
	)
	(segment
		(start 58.540904 -128.458214)
		(end 58.941716 -128.859026)
		(width 0.3556)
		(layer "F.Cu")
		(net "GND")
	)
	(segment
		(start 124.820172 -166.167562)
		(end 124.160026 -165.507416)
		(width 0.508)
		(layer "F.Cu")
		(net "GND")
	)
	(segment
		(start 106.015536 -205.199488)
		(end 106.015536 -201.034904)
		(width 0.508)
		(layer "F.Cu")
		(net "GND")
	)
	(segment
		(start 50.311304 -64.785748)
		(end 50.502058 -64.594994)
		(width 0.3048)
		(layer "F.Cu")
		(net "GND")
	)
	(segment
		(start 80.202532 -97.669096)
		(end 80.202532 -96.975422)
		(width 0.4572)
		(layer "F.Cu")
		(net "GND")
	)
	(segment
		(start 137.559288 -64.124078)
		(end 137.559288 -64.480948)
		(width 0.4572)
		(layer "F.Cu")
		(net "GND")
	)
	(segment
		(start 120.63476 -188.526674)
		(end 120.63476 -189.786768)
		(width 0.508)
		(layer "F.Cu")
		(net "GND")
	)
	(segment
		(start 47.273972 -68.779898)
		(end 47.704248 -68.349622)
		(width 0.254)
		(layer "F.Cu")
		(net "GND")
	)
	(segment
		(start 64.940942 -133.258306)
		(end 65.341754 -133.659118)
		(width 0.381)
		(layer "F.Cu")
		(net "GND")
	)
	(segment
		(start 65.341754 -134.459218)
		(end 65.341754 -134.459472)
		(width 0.381)
		(layer "F.Cu")
		(net "GND")
	)
	(segment
		(start 69.346572 -79.287878)
		(end 69.092572 -79.541878)
		(width 0.3048)
		(layer "F.Cu")
		(net "GND")
	)
	(segment
		(start 130.79476 -184.805574)
		(end 130.79476 -183.936386)
		(width 0.508)
		(layer "F.Cu")
		(net "GND")
	)
	(segment
		(start 7.94004 -7.725156)
		(end 7.138416 -7.725156)
		(width 0.508)
		(layer "F.Cu")
		(net "GND")
	)
	(segment
		(start 51.999896 -70.998842)
		(end 51.299872 -70.298818)
		(width 0.3048)
		(layer "F.Cu")
		(net "GND")
	)
	(segment
		(start 45.784516 -78.908402)
		(end 46.178216 -79.302102)
		(width 0.254)
		(layer "F.Cu")
		(net "GND")
	)
	(segment
		(start 72.472042 -64.31407)
		(end 72.486012 -64.31407)
		(width 0.3048)
		(layer "F.Cu")
		(net "GND")
	)
	(segment
		(start 63.333376 -141.258036)
		(end 63.340996 -141.258036)
		(width 0.381)
		(layer "F.Cu")
		(net "GND")
	)
	(segment
		(start 20.15744 -10.941304)
		(end 20.15744 -11.695176)
		(width 0.508)
		(layer "F.Cu")
		(net "GND")
	)
	(segment
		(start 45.232828 -136.564624)
		(end 45.633132 -136.16432)
		(width 0.3556)
		(layer "F.Cu")
		(net "GND")
	)
	(segment
		(start 130.91795 -174.188882)
		(end 130.837686 -174.108618)
		(width 0.254)
		(layer "F.Cu")
		(net "GND")
	)
	(segment
		(start 66.142108 -136.059418)
		(end 66.141854 -136.059418)
		(width 0.381)
		(layer "F.Cu")
		(net "GND")
	)
	(segment
		(start 46.31309 -86.226396)
		(end 45.659548 -86.879938)
		(width 0.254)
		(layer "F.Cu")
		(net "GND")
	)
	(segment
		(start 66.773044 -80.241902)
		(end 66.773044 -79.541878)
		(width 0.3048)
		(layer "F.Cu")
		(net "GND")
	)
	(segment
		(start 6.33857 -151.331168)
		(end 5.557774 -151.331168)
		(width 0.508)
		(layer "F.Cu")
		(net "GND")
	)
	(segment
		(start 47.72787 -86.862666)
		(end 48.38065 -86.862666)
		(width 0.254)
		(layer "F.Cu")
		(net "GND")
	)
	(segment
		(start 67.340988 -140.45819)
		(end 66.942208 -140.05941)
		(width 0.3556)
		(layer "F.Cu")
		(net "GND")
	)
	(segment
		(start 70.194424 -69.610478)
		(end 70.202044 -69.610478)
		(width 0.3048)
		(layer "F.Cu")
		(net "GND")
	)
	(segment
		(start 73.652634 -65.12687)
		(end 74.111612 -65.12687)
		(width 0.3048)
		(layer "F.Cu")
		(net "GND")
	)
	(segment
		(start 72.04964 -63.891668)
		(end 72.440038 -63.50127)
		(width 0.3048)
		(layer "F.Cu")
		(net "GND")
	)
	(segment
		(start 165.464998 -145.43278)
		(end 165.464998 -144.697704)
		(width 0.508)
		(layer "F.Cu")
		(net "GND")
	)
	(segment
		(start 84.443062 -31.063438)
		(end 83.850226 -30.470602)
		(width 0.4572)
		(layer "F.Cu")
		(net "GND")
	)
	(segment
		(start 175.554894 -131.03987)
		(end 175.554894 -131.745736)
		(width 0.508)
		(layer "F.Cu")
		(net "GND")
	)
	(segment
		(start 68.401946 -65.836038)
		(end 68.401946 -66.598038)
		(width 0.254)
		(layer "F.Cu")
		(net "GND")
	)
	(segment
		(start 108.60786 -71.386954)
		(end 109.127036 -71.90613)
		(width 0.3048)
		(layer "F.Cu")
		(net "GND")
	)
	(segment
		(start 145.65376 -184.805574)
		(end 145.65376 -183.909462)
		(width 0.508)
		(layer "F.Cu")
		(net "GND")
	)
	(segment
		(start 41.127172 -74.642726)
		(end 41.512744 -74.257154)
		(width 0.381)
		(layer "F.Cu")
		(net "GND")
	)
	(segment
		(start 46.552866 -65.455038)
		(end 46.552866 -65.458594)
		(width 0.3048)
		(layer "F.Cu")
		(net "GND")
	)
	(segment
		(start 49.820576 -181.000908)
		(end 49.38776 -181.433724)
		(width 0.508)
		(layer "F.Cu")
		(net "GND")
	)
	(segment
		(start 176.266348 -37.991034)
		(end 175.58512 -37.991034)
		(width 0.508)
		(layer "F.Cu")
		(net "GND")
	)
	(segment
		(start 75.115674 -74.680318)
		(end 74.465942 -74.680318)
		(width 0.3048)
		(layer "F.Cu")
		(net "GND")
	)
	(segment
		(start 60.822332 -80.600042)
		(end 60.800996 -80.600042)
		(width 0.3048)
		(layer "F.Cu")
		(net "GND")
	)
	(segment
		(start 99.450144 -29.149802)
		(end 99.450144 -27.68346)
		(width 0.4572)
		(layer "F.Cu")
		(net "GND")
	)
	(segment
		(start 64.311784 -87.60841)
		(end 64.219836 -87.700358)
		(width 0.254)
		(layer "F.Cu")
		(net "GND")
	)
	(segment
		(start 126.76505 -148.975572)
		(end 125.787912 -148.975572)
		(width 0.1778)
		(layer "F.Cu")
		(net "GND")
	)
	(segment
		(start 15.499588 -45.900848)
		(end 14.543278 -45.900848)
		(width 0.4572)
		(layer "F.Cu")
		(net "GND")
	)
	(segment
		(start 60.81776 -187.726574)
		(end 60.81776 -186.97956)
		(width 0.508)
		(layer "F.Cu")
		(net "GND")
	)
	(segment
		(start 73.298812 -64.773048)
		(end 73.470516 -64.944752)
		(width 0.3048)
		(layer "F.Cu")
		(net "GND")
	)
	(segment
		(start 44.153328 -109.227874)
		(end 44.383706 -109.227874)
		(width 0.254)
		(layer "F.Cu")
		(net "GND")
	)
	(segment
		(start 125.787912 -144.97558)
		(end 124.636022 -144.97558)
		(width 0.1778)
		(layer "F.Cu")
		(net "GND")
	)
	(segment
		(start 45.037248 -77.315822)
		(end 45.037248 -78.015846)
		(width 0.3048)
		(layer "F.Cu")
		(net "GND")
	)
	(segment
		(start 62.502542 -23.418038)
		(end 63.3349 -22.58568)
		(width 0.381)
		(layer "F.Cu")
		(net "GND")
	)
	(segment
		(start 60.312554 -164.934646)
		(end 60.312554 -165.801294)
		(width 0.508)
		(layer "F.Cu")
		(net "GND")
	)
	(segment
		(start 56.284368 -63.898526)
		(end 56.315864 -63.86703)
		(width 0.3048)
		(layer "F.Cu")
		(net "GND")
	)
	(segment
		(start 56.758078 -87.551006)
		(end 57.217564 -87.551006)
		(width 0.254)
		(layer "F.Cu")
		(net "GND")
	)
	(segment
		(start 115.382802 -20.755102)
		(end 115.382802 -19.72945)
		(width 0.254)
		(layer "F.Cu")
		(net "GND")
	)
	(segment
		(start 51.561238 -86.51621)
		(end 51.884326 -86.51621)
		(width 0.3048)
		(layer "F.Cu")
		(net "GND")
	)
	(segment
		(start 64.34836 -184.080404)
		(end 64.34836 -184.703974)
		(width 0.508)
		(layer "F.Cu")
		(net "GND")
	)
	(segment
		(start 79.97444 -92.609924)
		(end 79.79791 -92.433394)
		(width 0.508)
		(layer "F.Cu")
		(net "GND")
	)
	(segment
		(start 111.74476 -187.726574)
		(end 111.74476 -186.818778)
		(width 0.508)
		(layer "F.Cu")
		(net "GND")
	)
	(segment
		(start 49.163478 -75.264772)
		(end 49.228248 -75.329542)
		(width 0.3048)
		(layer "F.Cu")
		(net "GND")
	)
	(segment
		(start 96.719644 -130.758438)
		(end 97.516696 -130.758438)
		(width 0.4572)
		(layer "F.Cu")
		(net "GND")
	)
	(segment
		(start 68.542662 -143.259556)
		(end 68.5419 -143.259556)
		(width 0.3556)
		(layer "F.Cu")
		(net "GND")
	)
	(segment
		(start 75.474068 -94.531942)
		(end 74.458068 -94.531942)
		(width 0.4572)
		(layer "F.Cu")
		(net "GND")
	)
	(segment
		(start 41.718738 -69.786754)
		(end 41.75125 -69.754242)
		(width 0.254)
		(layer "F.Cu")
		(net "GND")
	)
	(segment
		(start 176.01057 -121.365518)
		(end 175.510444 -121.865644)
		(width 0.508)
		(layer "F.Cu")
		(net "GND")
	)
	(segment
		(start 142.452852 -137.39495)
		(end 142.07236 -137.775442)
		(width 0.1778)
		(layer "F.Cu")
		(net "GND")
	)
	(segment
		(start 72.014334 -73.100692)
		(end 72.205088 -73.291446)
		(width 0.3048)
		(layer "F.Cu")
		(net "GND")
	)
	(segment
		(start 59.808872 -87.00389)
		(end 59.716924 -87.095838)
		(width 0.3048)
		(layer "F.Cu")
		(net "GND")
	)
	(segment
		(start 113.59896 -184.500774)
		(end 113.59896 -184.09412)
		(width 0.508)
		(layer "F.Cu")
		(net "GND")
	)
	(segment
		(start 51.67376 -187.726574)
		(end 51.67376 -186.862974)
		(width 0.508)
		(layer "F.Cu")
		(net "GND")
	)
	(segment
		(start 60.000896 -79.799942)
		(end 60.000896 -80.600042)
		(width 0.3048)
		(layer "F.Cu")
		(net "GND")
	)
	(segment
		(start 52.399946 -79.399892)
		(end 51.999896 -79.799942)
		(width 0.3048)
		(layer "F.Cu")
		(net "GND")
	)
	(segment
		(start 46.816772 -62.893448)
		(end 46.816772 -62.810898)
		(width 0.254)
		(layer "F.Cu")
		(net "GND")
	)
	(segment
		(start 69.059044 -77.022452)
		(end 69.059044 -76.269342)
		(width 0.3048)
		(layer "F.Cu")
		(net "GND")
	)
	(segment
		(start 124.85116 -187.726574)
		(end 124.85116 -186.96686)
		(width 0.381)
		(layer "F.Cu")
		(net "GND")
	)
	(segment
		(start 132.5372 -55.372)
		(end 131.9022 -56.007)
		(width 0.508)
		(layer "F.Cu")
		(net "GND")
	)
	(segment
		(start 45.486066 -90.20937)
		(end 45.827188 -89.868248)
		(width 0.254)
		(layer "F.Cu")
		(net "GND")
	)
	(segment
		(start 9.550146 -11.213846)
		(end 8.673846 -11.213846)
		(width 0.508)
		(layer "F.Cu")
		(net "GND")
	)
	(segment
		(start 73.39076 -184.805574)
		(end 73.39076 -184.146698)
		(width 0.508)
		(layer "F.Cu")
		(net "GND")
	)
	(segment
		(start 72.5424 -135.259572)
		(end 72.541892 -135.259572)
		(width 0.3556)
		(layer "F.Cu")
		(net "GND")
	)
	(segment
		(start 75.743308 -95.141288)
		(end 75.474068 -94.872048)
		(width 0.4572)
		(layer "F.Cu")
		(net "GND")
	)
	(segment
		(start 117.13591 -153.43124)
		(end 117.13591 -152.8318)
		(width 0.508)
		(layer "F.Cu")
		(net "GND")
	)
	(segment
		(start 51.199796 -70.298818)
		(end 51.223418 -70.275196)
		(width 0.3048)
		(layer "F.Cu")
		(net "GND")
	)
	(segment
		(start 44.656248 -68.587874)
		(end 44.656248 -68.084446)
		(width 0.3048)
		(layer "F.Cu")
		(net "GND")
	)
	(segment
		(start 44.656248 -75.329542)
		(end 44.656248 -76.029566)
		(width 0.3048)
		(layer "F.Cu")
		(net "GND")
	)
	(segment
		(start 91.502484 -187.842398)
		(end 92.243148 -187.842398)
		(width 0.508)
		(layer "F.Cu")
		(net "GND")
	)
	(segment
		(start 44.250102 -29.149802)
		(end 44.250102 -30.624526)
		(width 0.381)
		(layer "F.Cu")
		(net "GND")
	)
	(segment
		(start 50.525426 -69.265038)
		(end 49.849532 -69.265038)
		(width 0.3048)
		(layer "F.Cu")
		(net "GND")
	)
	(segment
		(start 93.450156 -29.149802)
		(end 93.450156 -30.599126)
		(width 0.381)
		(layer "F.Cu")
		(net "GND")
	)
	(segment
		(start 124.65304 -39.313612)
		(end 124.57684 -39.389812)
		(width 0.2794)
		(layer "F.Cu")
		(net "GND")
	)
	(segment
		(start 65.083436 -64.594994)
		(end 65.198244 -64.594994)
		(width 0.254)
		(layer "F.Cu")
		(net "GND")
	)
	(segment
		(start 49.38776 -181.433724)
		(end 49.38776 -181.838092)
		(width 0.508)
		(layer "F.Cu")
		(net "GND")
	)
	(segment
		(start 64.766444 -176.26203)
		(end 64.983614 -176.26203)
		(width 0.4572)
		(layer "F.Cu")
		(net "GND")
	)
	(segment
		(start 78.515718 -98.038666)
		(end 78.994254 -98.517202)
		(width 0.4572)
		(layer "F.Cu")
		(net "GND")
	)
	(segment
		(start 62.8269 -80.225646)
		(end 63.201296 -80.600042)
		(width 0.3556)
		(layer "F.Cu")
		(net "GND")
	)
	(segment
		(start 43.308524 -107.728258)
		(end 43.303698 -107.733084)
		(width 0.4572)
		(layer "F.Cu")
		(net "GND")
	)
	(segment
		(start 131.153662 -121.064528)
		(end 131.153662 -122.099832)
		(width 0.1778)
		(layer "F.Cu")
		(net "GND")
	)
	(segment
		(start 66.87058 -70.027038)
		(end 66.415666 -70.027038)
		(width 0.3048)
		(layer "F.Cu")
		(net "GND")
	)
	(segment
		(start 68.941188 -143.658082)
		(end 68.542662 -143.259556)
		(width 0.3556)
		(layer "F.Cu")
		(net "GND")
	)
	(segment
		(start 192.151 -120.65)
		(end 192.405 -120.396)
		(width 0.508)
		(layer "F.Cu")
		(net "GND")
	)
	(segment
		(start 45.07738 -74.912982)
		(end 44.66082 -75.329542)
		(width 0.254)
		(layer "F.Cu")
		(net "GND")
	)
	(segment
		(start 81.494884 -178.772566)
		(end 81.494884 -179.874672)
		(width 0.254)
		(layer "F.Cu")
		(net "GND")
	)
	(segment
		(start 115.53698 -116.074698)
		(end 116.392452 -116.93017)
		(width 0.254)
		(layer "F.Cu")
		(net "GND")
	)
	(segment
		(start 29.19984 -99.573842)
		(end 29.70784 -100.081842)
		(width 0.508)
		(layer "F.Cu")
		(net "GND")
	)
	(segment
		(start 34.842958 -185.604404)
		(end 34.842958 -184.942226)
		(width 0.508)
		(layer "F.Cu")
		(net "GND")
	)
	(segment
		(start 50.099722 -88.042242)
		(end 50.099722 -87.507572)
		(width 0.254)
		(layer "F.Cu")
		(net "GND")
	)
	(segment
		(start 49.471834 -76.752704)
		(end 49.32426 -76.60513)
		(width 0.3048)
		(layer "F.Cu")
		(net "GND")
	)
	(segment
		(start 6.862572 -4.111244)
		(end 6.200394 -4.111244)
		(width 0.4572)
		(layer "F.Cu")
		(net "GND")
	)
	(segment
		(start 48.20412 -87.551006)
		(end 47.708566 -88.04656)
		(width 0.254)
		(layer "F.Cu")
		(net "GND")
	)
	(segment
		(start 74.733912 -78.54569)
		(end 73.711816 -78.54569)
		(width 0.3048)
		(layer "F.Cu")
		(net "GND")
	)
	(segment
		(start 145.164302 -149.20595)
		(end 145.983452 -149.20595)
		(width 0.4572)
		(layer "F.Cu")
		(net "GND")
	)
	(segment
		(start 56.458612 -89.023444)
		(end 56.743092 -88.739218)
		(width 0.254)
		(layer "F.Cu")
		(net "GND")
	)
	(segment
		(start 176.238916 -35.59556)
		(end 175.551592 -35.59556)
		(width 0.508)
		(layer "F.Cu")
		(net "GND")
	)
	(segment
		(start 46.833028 -136.564624)
		(end 46.833536 -136.564624)
		(width 0.3556)
		(layer "F.Cu")
		(net "GND")
	)
	(segment
		(start 48.24476 -187.726574)
		(end 48.24476 -186.862974)
		(width 0.508)
		(layer "F.Cu")
		(net "GND")
	)
	(segment
		(start 72.77481 -66.240152)
		(end 72.752204 -66.217546)
		(width 0.3048)
		(layer "F.Cu")
		(net "GND")
	)
	(segment
		(start 68.11137 -88.042242)
		(end 68.254372 -88.185244)
		(width 0.254)
		(layer "F.Cu")
		(net "GND")
	)
	(segment
		(start 40.03294 -130.563874)
		(end 40.033194 -130.56362)
		(width 0.3556)
		(layer "F.Cu")
		(net "GND")
	)
	(segment
		(start 135.338058 -150.123144)
		(end 135.338058 -151.32558)
		(width 0.1778)
		(layer "F.Cu")
		(net "GND")
	)
	(segment
		(start 80.202532 -96.975422)
		(end 80.51292 -96.665034)
		(width 0.4572)
		(layer "F.Cu")
		(net "GND")
	)
	(segment
		(start 45.633132 -136.16432)
		(end 45.633132 -136.163558)
		(width 0.3556)
		(layer "F.Cu")
		(net "GND")
	)
	(segment
		(start 50.099722 -87.02675)
		(end 50.109628 -87.016844)
		(width 0.254)
		(layer "F.Cu")
		(net "GND")
	)
	(segment
		(start 66.17589 -81.579466)
		(end 66.17589 -81.571846)
		(width 0.3048)
		(layer "F.Cu")
		(net "GND")
	)
	(segment
		(start 50.53076 -181.846474)
		(end 50.53076 -180.974746)
		(width 0.508)
		(layer "F.Cu")
		(net "GND")
	)
	(segment
		(start 44.511722 -75.185016)
		(end 44.656248 -75.329542)
		(width 0.254)
		(layer "F.Cu")
		(net "GND")
	)
	(segment
		(start 74.874374 -78.686152)
		(end 74.733912 -78.54569)
		(width 0.3048)
		(layer "F.Cu")
		(net "GND")
	)
	(segment
		(start 68.678044 -82.228182)
		(end 67.916044 -82.228182)
		(width 0.254)
		(layer "F.Cu")
		(net "GND")
	)
	(segment
		(start 47.849282 -141.45133)
		(end 46.919134 -141.45133)
		(width 0.3556)
		(layer "F.Cu")
		(net "GND")
	)
	(segment
		(start 68.9102 -74.515218)
		(end 68.678044 -74.283062)
		(width 0.3048)
		(layer "F.Cu")
		(net "GND")
	)
	(segment
		(start 154.18308 -178.990244)
		(end 154.28214 -179.089304)
		(width 0.508)
		(layer "F.Cu")
		(net "GND")
	)
	(segment
		(start 66.141854 -132.85724)
		(end 66.141854 -132.859526)
		(width 0.381)
		(layer "F.Cu")
		(net "GND")
	)
	(segment
		(start 165.643306 -105.761536)
		(end 165.389052 -106.01579)
		(width 0.1778)
		(layer "F.Cu")
		(net "GND")
	)
	(segment
		(start 68.297044 -68.324222)
		(end 68.299076 -68.324222)
		(width 0.3048)
		(layer "F.Cu")
		(net "GND")
	)
	(segment
		(start 61.160914 -65.129918)
		(end 61.530738 -65.129918)
		(width 0.254)
		(layer "F.Cu")
		(net "GND")
	)
	(segment
		(start 56.24449 -84.238846)
		(end 55.544466 -84.238846)
		(width 0.3048)
		(layer "F.Cu")
		(net "GND")
	)
	(segment
		(start 50.675286 -70.635876)
		(end 50.752248 -70.712838)
		(width 0.3048)
		(layer "F.Cu")
		(net "GND")
	)
	(segment
		(start 141.288008 -138.175492)
		(end 142.51051 -138.175492)
		(width 0.1778)
		(layer "F.Cu")
		(net "GND")
	)
	(segment
		(start 39.357554 -136.163558)
		(end 40.033194 -136.163558)
		(width 0.3556)
		(layer "F.Cu")
		(net "GND")
	)
	(segment
		(start 67.7418 -129.657602)
		(end 67.7418 -129.659634)
		(width 0.3556)
		(layer "F.Cu")
		(net "GND")
	)
	(segment
		(start 68.254372 -88.185244)
		(end 68.254372 -88.961468)
		(width 0.254)
		(layer "F.Cu")
		(net "GND")
	)
	(segment
		(start 136.01319 -181.656228)
		(end 136.263634 -181.906672)
		(width 0.4572)
		(layer "F.Cu")
		(net "GND")
	)
	(segment
		(start 50.525426 -66.979038)
		(end 49.825402 -66.979038)
		(width 0.3048)
		(layer "F.Cu")
		(net "GND")
	)
	(segment
		(start 73.298558 -66.144394)
		(end 73.394316 -66.240152)
		(width 0.3048)
		(layer "F.Cu")
		(net "GND")
	)
	(segment
		(start 84.169504 -76.170282)
		(end 80.428592 -76.170282)
		(width 0.4572)
		(layer "F.Cu")
		(net "GND")
	)
	(segment
		(start 128.05156 -187.726574)
		(end 128.05156 -187.350146)
		(width 0.508)
		(layer "F.Cu")
		(net "GND")
	)
	(segment
		(start 43.980354 -109.0549)
		(end 44.153328 -109.227874)
		(width 0.254)
		(layer "F.Cu")
		(net "GND")
	)
	(segment
		(start 41.88968 -64.31407)
		(end 42.70248 -64.31407)
		(width 0.381)
		(layer "F.Cu")
		(net "GND")
	)
	(segment
		(start 53.83149 -61.99759)
		(end 53.601112 -62.227968)
		(width 0.3048)
		(layer "F.Cu")
		(net "GND")
	)
	(segment
		(start 32.944054 -117.535452)
		(end 32.944054 -116.518182)
		(width 0.508)
		(layer "F.Cu")
		(net "GND")
	)
	(segment
		(start 18.998184 -67.965066)
		(end 20.204176 -67.965066)
		(width 0.4572)
		(layer "F.Cu")
		(net "GND")
	)
	(segment
		(start 55.544466 -84.240878)
		(end 55.544466 -84.238846)
		(width 0.254)
		(layer "F.Cu")
		(net "GND")
	)
	(segment
		(start 40.24122 -145.43024)
		(end 40.24122 -144.382998)
		(width 0.508)
		(layer "F.Cu")
		(net "GND")
	)
	(segment
		(start 69.059044 -72.296782)
		(end 69.059044 -71.596758)
		(width 0.3048)
		(layer "F.Cu")
		(net "GND")
	)
	(segment
		(start 48.138588 -69.318378)
		(end 48.137572 -69.318378)
		(width 0.3048)
		(layer "F.Cu")
		(net "GND")
	)
	(segment
		(start 119.48922 -185.721498)
		(end 119.48922 -185.609992)
		(width 0.508)
		(layer "F.Cu")
		(net "GND")
	)
	(segment
		(start 71.341996 -136.459214)
		(end 70.9422 -136.059418)
		(width 0.3556)
		(layer "F.Cu")
		(net "GND")
	)
	(segment
		(start 49.17186 -102.119938)
		(end 49.17186 -101.66477)
		(width 0.3556)
		(layer "F.Cu")
		(net "GND")
	)
	(segment
		(start 103.498142 -158.689294)
		(end 103.498142 -158.677102)
		(width 0.4572)
		(layer "F.Cu")
		(net "GND")
	)
	(segment
		(start 76.81976 -187.091066)
		(end 76.87564 -187.035186)
		(width 0.508)
		(layer "F.Cu")
		(net "GND")
	)
	(segment
		(start 56.784494 -97.817432)
		(end 57.081166 -97.52076)
		(width 0.4572)
		(layer "F.Cu")
		(net "GND")
	)
	(segment
		(start 69.96176 -187.726574)
		(end 69.96176 -186.849004)
		(width 0.508)
		(layer "F.Cu")
		(net "GND")
	)
	(segment
		(start 72.901556 -65.102994)
		(end 72.901556 -65.491868)
		(width 0.3048)
		(layer "F.Cu")
		(net "GND")
	)
	(segment
		(start 67.742308 -135.259572)
		(end 67.7418 -135.259572)
		(width 0.381)
		(layer "F.Cu")
		(net "GND")
	)
	(segment
		(start 50.798222 -174.382176)
		(end 50.798222 -174.752508)
		(width 0.4572)
		(layer "F.Cu")
		(net "GND")
	)
	(segment
		(start 160.81502 -187.68187)
		(end 161.83102 -187.68187)
		(width 0.508)
		(layer "F.Cu")
		(net "GND")
	)
	(segment
		(start 74.70775 -68.335906)
		(end 74.250042 -68.335906)
		(width 0.254)
		(layer "F.Cu")
		(net "GND")
	)
	(segment
		(start 46.829218 -85.799168)
		(end 46.601888 -85.799168)
		(width 0.3048)
		(layer "F.Cu")
		(net "GND")
	)
	(segment
		(start 180.48859 -138.152632)
		(end 180.48859 -136.932162)
		(width 0.508)
		(layer "F.Cu")
		(net "GND")
	)
	(segment
		(start 74.465942 -74.680318)
		(end 74.250042 -74.464418)
		(width 0.3048)
		(layer "F.Cu")
		(net "GND")
	)
	(segment
		(start 21.014944 -205.199488)
		(end 21.014944 -201.09053)
		(width 0.508)
		(layer "F.Cu")
		(net "GND")
	)
	(segment
		(start 35.366452 -84.303362)
		(end 35.402774 -84.339684)
		(width 0.508)
		(layer "F.Cu")
		(net "GND")
	)
	(segment
		(start 61.9506 -184.795414)
		(end 61.96076 -184.805574)
		(width 0.508)
		(layer "F.Cu")
		(net "GND")
	)
	(segment
		(start 39.266368 -6.150864)
		(end 39.266368 -5.377942)
		(width 0.4572)
		(layer "F.Cu")
		(net "GND")
	)
	(segment
		(start 101.511862 -27.522678)
		(end 101.250242 -27.784298)
		(width 0.4572)
		(layer "F.Cu")
		(net "GND")
	)
	(segment
		(start 74.142346 -136.859518)
		(end 74.141838 -136.859518)
		(width 0.3556)
		(layer "F.Cu")
		(net "GND")
	)
	(segment
		(start 74.0283 -77.61732)
		(end 74.250042 -77.395578)
		(width 0.3048)
		(layer "F.Cu")
		(net "GND")
	)
	(segment
		(start 46.833028 -140.565124)
		(end 46.432978 -140.165074)
		(width 0.3556)
		(layer "F.Cu")
		(net "GND")
	)
	(segment
		(start 115.25885 -153.548588)
		(end 115.25885 -152.555956)
		(width 0.508)
		(layer "F.Cu")
		(net "GND")
	)
	(segment
		(start 74.901552 -77.331824)
		(end 74.259948 -77.331824)
		(width 0.254)
		(layer "F.Cu")
		(net "GND")
	)
	(segment
		(start 144.088612 -39.624)
		(end 144.3228 -39.389812)
		(width 0.3048)
		(layer "F.Cu")
		(net "GND")
	)
	(segment
		(start 43.986958 -78.985618)
		(end 42.78376 -78.985618)
		(width 0.254)
		(layer "F.Cu")
		(net "GND")
	)
	(segment
		(start 140.74521 -117.006624)
		(end 141.470634 -117.006624)
		(width 0.508)
		(layer "F.Cu")
		(net "GND")
	)
	(segment
		(start 56.458612 -89.048844)
		(end 56.458612 -89.023444)
		(width 0.254)
		(layer "F.Cu")
		(net "GND")
	)
	(segment
		(start 167.523414 -138.064494)
		(end 167.523414 -136.199372)
		(width 0.508)
		(layer "F.Cu")
		(net "GND")
	)
	(segment
		(start 132.938012 -134.43839)
		(end 132.938012 -135.825484)
		(width 0.1778)
		(layer "F.Cu")
		(net "GND")
	)
	(segment
		(start 172.701458 -12.874244)
		(end 172.701458 -13.685774)
		(width 0.508)
		(layer "F.Cu")
		(net "GND")
	)
	(segment
		(start 97.728532 -167.700706)
		(end 96.545654 -167.700706)
		(width 0.3556)
		(layer "F.Cu")
		(net "GND")
	)
	(segment
		(start 50.752248 -80.002126)
		(end 50.752248 -79.302102)
		(width 0.3048)
		(layer "F.Cu")
		(net "GND")
	)
	(segment
		(start 103.044752 -64.409574)
		(end 103.047292 -64.407034)
		(width 0.3048)
		(layer "F.Cu")
		(net "GND")
	)
	(segment
		(start 45.739812 -185.552334)
		(end 46.399196 -185.552334)
		(width 0.4572)
		(layer "F.Cu")
		(net "GND")
	)
	(segment
		(start 44.840144 -70.070726)
		(end 44.530772 -70.380098)
		(width 0.254)
		(layer "F.Cu")
		(net "GND")
	)
	(segment
		(start 131.00812 -110.92815)
		(end 131.00812 -110.245906)
		(width 0.508)
		(layer "F.Cu")
		(net "GND")
	)
	(segment
		(start 65.339214 -140.85951)
		(end 64.940942 -141.257782)
		(width 0.3556)
		(layer "F.Cu")
		(net "GND")
	)
	(segment
		(start 74.901552 -85.172804)
		(end 74.874882 -85.172804)
		(width 0.254)
		(layer "F.Cu")
		(net "GND")
	)
	(segment
		(start 59.808872 -86.956646)
		(end 59.19597 -86.343744)
		(width 0.254)
		(layer "F.Cu")
		(net "GND")
	)
	(segment
		(start 40.950134 -20.94992)
		(end 40.950134 -22.719538)
		(width 0.4572)
		(layer "F.Cu")
		(net "GND")
	)
	(segment
		(start 99.06 -175.189896)
		(end 99.06 -175.190404)
		(width 0.508)
		(layer "F.Cu")
		(net "GND")
	)
	(segment
		(start 125.07976 -185.605674)
		(end 125.07976 -185.633868)
		(width 0.508)
		(layer "F.Cu")
		(net "GND")
	)
	(segment
		(start 99.206812 -181.315106)
		(end 98.9457 -181.053994)
		(width 0.4064)
		(layer "F.Cu")
		(net "GND")
	)
	(segment
		(start 48.939704 -102.352094)
		(end 49.17186 -102.119938)
		(width 0.3556)
		(layer "F.Cu")
		(net "GND")
	)
	(segment
		(start 36.88334 -14.64564)
		(end 36.88334 -15.279116)
		(width 0.4572)
		(layer "F.Cu")
		(net "GND")
	)
	(segment
		(start 80.363568 -90.011504)
		(end 81.195164 -90.011504)
		(width 0.508)
		(layer "F.Cu")
		(net "GND")
	)
	(segment
		(start 46.048422 -29.148024)
		(end 46.0502 -29.149802)
		(width 0.4572)
		(layer "F.Cu")
		(net "GND")
	)
	(segment
		(start 43.249088 -66.010282)
		(end 43.249088 -65.451482)
		(width 0.3048)
		(layer "F.Cu")
		(net "GND")
	)
	(segment
		(start 125.07976 -185.633868)
		(end 125.6919 -186.246008)
		(width 0.508)
		(layer "F.Cu")
		(net "GND")
	)
	(segment
		(start 86.721696 -174.624746)
		(end 87.744808 -174.624746)
		(width 0.254)
		(layer "F.Cu")
		(net "GND")
	)
	(segment
		(start 64.75476 -179.922424)
		(end 64.75476 -180.944774)
		(width 0.4572)
		(layer "F.Cu")
		(net "GND")
	)
	(segment
		(start 70.54215 -142.059406)
		(end 70.142354 -141.65961)
		(width 0.3556)
		(layer "F.Cu")
		(net "GND")
	)
	(segment
		(start 72.440038 -63.50127)
		(end 72.486012 -63.50127)
		(width 0.3048)
		(layer "F.Cu")
		(net "GND")
	)
	(segment
		(start 72.795384 -79.264002)
		(end 72.795384 -79.684626)
		(width 0.3048)
		(layer "F.Cu")
		(net "GND")
	)
	(segment
		(start 61.9506 -184.064148)
		(end 61.9506 -184.795414)
		(width 0.508)
		(layer "F.Cu")
		(net "GND")
	)
	(segment
		(start 39.992808 -68.536566)
		(end 40.400732 -68.128642)
		(width 0.254)
		(layer "F.Cu")
		(net "GND")
	)
	(segment
		(start 60.717938 -65.307718)
		(end 60.850526 -65.440306)
		(width 0.3048)
		(layer "F.Cu")
		(net "GND")
	)
	(segment
		(start 107.233212 -67.790314)
		(end 106.339132 -67.790314)
		(width 0.3048)
		(layer "F.Cu")
		(net "GND")
	)
	(segment
		(start 11.8999 -132.83565)
		(end 11.8999 -134.260336)
		(width 0.254)
		(layer "F.Cu")
		(net "GND")
	)
	(segment
		(start 128.13792 -152.188418)
		(end 128.457452 -152.50795)
		(width 0.2032)
		(layer "F.Cu")
		(net "GND")
	)
	(segment
		(start 102.978204 -159.209486)
		(end 102.978204 -159.209232)
		(width 0.4572)
		(layer "F.Cu")
		(net "GND")
	)
	(segment
		(start 66.063876 -89.824814)
		(end 66.063876 -88.684862)
		(width 0.254)
		(layer "F.Cu")
		(net "GND")
	)
	(segment
		(start 52.490878 -90.453464)
		(end 51.9557 -89.918286)
		(width 0.254)
		(layer "F.Cu")
		(net "GND")
	)
	(segment
		(start 60.58154 -78.780386)
		(end 60.58154 -78.419198)
		(width 0.3556)
		(layer "F.Cu")
		(net "GND")
	)
	(segment
		(start 70.964044 -69.610478)
		(end 70.956424 -69.610478)
		(width 0.3048)
		(layer "F.Cu")
		(net "GND")
	)
	(segment
		(start 39.357554 -137.763758)
		(end 40.033194 -137.763758)
		(width 0.3556)
		(layer "F.Cu")
		(net "GND")
	)
	(segment
		(start 106.354372 -76.497688)
		(end 106.262932 -76.406248)
		(width 0.3048)
		(layer "F.Cu")
		(net "GND")
	)
	(segment
		(start 130.047238 -52.76342)
		(end 130.047238 -53.666898)
		(width 0.4572)
		(layer "F.Cu")
		(net "GND")
	)
	(segment
		(start 134.629652 -112.858042)
		(end 134.753858 -112.982248)
		(width 0.1778)
		(layer "F.Cu")
		(net "GND")
	)
	(segment
		(start 61.597286 -87.427816)
		(end 61.135768 -87.427816)
		(width 0.3048)
		(layer "F.Cu")
		(net "GND")
	)
	(segment
		(start 81.64322 -82.902044)
		(end 81.08315 -82.902044)
		(width 0.508)
		(layer "F.Cu")
		(net "GND")
	)
	(segment
		(start 36.3601 -72.335898)
		(end 36.3093 -72.386698)
		(width 0.508)
		(layer "F.Cu")
		(net "GND")
	)
	(segment
		(start 42.262552 -163.558982)
		(end 42.262552 -164.44849)
		(width 0.508)
		(layer "F.Cu")
		(net "GND")
	)
	(segment
		(start 72.063864 -71.910956)
		(end 72.063864 -71.625714)
		(width 0.3048)
		(layer "F.Cu")
		(net "GND")
	)
	(segment
		(start 44.1325 -67.90817)
		(end 43.920156 -67.90817)
		(width 0.3048)
		(layer "F.Cu")
		(net "GND")
	)
	(segment
		(start 71.08825 -78.379828)
		(end 70.964044 -78.255622)
		(width 0.3048)
		(layer "F.Cu")
		(net "GND")
	)
	(segment
		(start 61.889386 -86.862666)
		(end 61.889386 -87.382096)
		(width 0.3048)
		(layer "F.Cu")
		(net "GND")
	)
	(segment
		(start 44.708064 -90.958162)
		(end 44.32808 -90.578178)
		(width 0.381)
		(layer "F.Cu")
		(net "GND")
	)
	(segment
		(start 8.74776 -151.71039)
		(end 9.448038 -151.71039)
		(width 0.508)
		(layer "F.Cu")
		(net "GND")
	)
	(segment
		(start 65.850262 -30.628082)
		(end 65.850262 -29.149802)
		(width 0.381)
		(layer "F.Cu")
		(net "GND")
	)
	(segment
		(start 158.521654 -75.31735)
		(end 159.252412 -75.31735)
		(width 0.4572)
		(layer "F.Cu")
		(net "GND")
	)
	(segment
		(start 60.774326 -153.068782)
		(end 60.774326 -151.670512)
		(width 0.508)
		(layer "F.Cu")
		(net "GND")
	)
	(segment
		(start 141.015466 -205.199488)
		(end 141.015466 -201.034904)
		(width 0.508)
		(layer "F.Cu")
		(net "GND")
	)
	(segment
		(start 104.22001 -155.697936)
		(end 104.047036 -155.524962)
		(width 0.254)
		(layer "F.Cu")
		(net "GND")
	)
	(segment
		(start 158.48584 -186.725814)
		(end 158.48584 -187.721494)
		(width 0.508)
		(layer "F.Cu")
		(net "GND")
	)
	(segment
		(start 52.799996 -79.799942)
		(end 52.399946 -79.399892)
		(width 0.3048)
		(layer "F.Cu")
		(net "GND")
	)
	(segment
		(start 54.358032 -97.83191)
		(end 54.033166 -97.507044)
		(width 0.4572)
		(layer "F.Cu")
		(net "GND")
	)
	(segment
		(start 46.432978 -140.965174)
		(end 46.432978 -140.96365)
		(width 0.3556)
		(layer "F.Cu")
		(net "GND")
	)
	(segment
		(start 148.9837 -167.093392)
		(end 148.522944 -167.093392)
		(width 0.508)
		(layer "F.Cu")
		(net "GND")
	)
	(segment
		(start 128.93802 -151.32558)
		(end 128.93802 -152.338024)
		(width 0.2032)
		(layer "F.Cu")
		(net "GND")
	)
	(segment
		(start 46.942248 -68.084446)
		(end 47.704248 -68.084446)
		(width 0.254)
		(layer "F.Cu")
		(net "GND")
	)
	(segment
		(start 59.808872 -87.00389)
		(end 59.808872 -86.956646)
		(width 0.254)
		(layer "F.Cu")
		(net "GND")
	)
	(segment
		(start 44.153582 -83.974686)
		(end 44.656248 -83.974686)
		(width 0.3048)
		(layer "F.Cu")
		(net "GND")
	)
	(segment
		(start 91.21267 -177.578512)
		(end 91.893644 -177.578512)
		(width 0.508)
		(layer "F.Cu")
		(net "GND")
	)
	(segment
		(start 63.340996 -140.457936)
		(end 63.333376 -140.457936)
		(width 0.3556)
		(layer "F.Cu")
		(net "GND")
	)
	(segment
		(start 71.08825 -78.84922)
		(end 71.08825 -78.379828)
		(width 0.3048)
		(layer "F.Cu")
		(net "GND")
	)
	(segment
		(start 49.95799 -62.208156)
		(end 50.299874 -62.55004)
		(width 0.3048)
		(layer "F.Cu")
		(net "GND")
	)
	(segment
		(start 40.43299 -138.164062)
		(end 40.83304 -137.764012)
		(width 0.3556)
		(layer "F.Cu")
		(net "GND")
	)
	(segment
		(start 43.043094 -81.407)
		(end 42.757852 -81.407)
		(width 0.3048)
		(layer "F.Cu")
		(net "GND")
	)
	(segment
		(start 32.60344 -116.518182)
		(end 32.27324 -116.848382)
		(width 0.508)
		(layer "F.Cu")
		(net "GND")
	)
	(segment
		(start 62.910974 -86.862666)
		(end 62.59957 -86.862666)
		(width 0.254)
		(layer "F.Cu")
		(net "GND")
	)
	(segment
		(start 45.295058 -88.343994)
		(end 44.965366 -88.343994)
		(width 0.3048)
		(layer "F.Cu")
		(net "GND")
	)
	(segment
		(start 52.889404 -68.503038)
		(end 52.511706 -68.880736)
		(width 0.254)
		(layer "F.Cu")
		(net "GND")
	)
	(segment
		(start 165.411404 -183.051196)
		(end 166.246556 -183.051196)
		(width 0.508)
		(layer "F.Cu")
		(net "GND")
	)
	(segment
		(start 43.937428 -70.682104)
		(end 43.45813 -71.161402)
		(width 0.3048)
		(layer "F.Cu")
		(net "GND")
	)
	(segment
		(start 64.429386 -68.884038)
		(end 64.429386 -68.122038)
		(width 0.254)
		(layer "F.Cu")
		(net "GND")
	)
	(segment
		(start 114.123724 -141.749526)
		(end 113.420144 -141.045946)
		(width 0.254)
		(layer "F.Cu")
		(net "GND")
	)
	(segment
		(start 125.8062 -50.470562)
		(end 125.800104 -50.470562)
		(width 0.4572)
		(layer "F.Cu")
		(net "GND")
	)
	(segment
		(start 82.73796 -109.732318)
		(end 82.59572 -109.874558)
		(width 0.508)
		(layer "F.Cu")
		(net "GND")
	)
	(segment
		(start 41.822116 -72.631554)
		(end 41.75125 -72.631554)
		(width 0.254)
		(layer "F.Cu")
		(net "GND")
	)
	(segment
		(start 135.391652 -150.06955)
		(end 135.338058 -150.123144)
		(width 0.1778)
		(layer "F.Cu")
		(net "GND")
	)
	(segment
		(start 105.671366 -133.003798)
		(end 105.671366 -132.355082)
		(width 0.1778)
		(layer "F.Cu")
		(net "GND")
	)
	(segment
		(start 73.742042 -142.059406)
		(end 73.342246 -141.65961)
		(width 0.3556)
		(layer "F.Cu")
		(net "GND")
	)
	(segment
		(start 34.976816 -105.58145)
		(end 34.976816 -104.648762)
		(width 0.4572)
		(layer "F.Cu")
		(net "GND")
	)
	(segment
		(start 74.250042 -72.838818)
		(end 74.93254 -72.838818)
		(width 0.3048)
		(layer "F.Cu")
		(net "GND")
	)
	(segment
		(start 65.341754 -132.859526)
		(end 65.339722 -132.859526)
		(width 0.3556)
		(layer "F.Cu")
		(net "GND")
	)
	(segment
		(start 137.291318 -116.114576)
		(end 136.503664 -116.114576)
		(width 0.1778)
		(layer "F.Cu")
		(net "GND")
	)
	(segment
		(start 93.665548 -172.268388)
		(end 94.051882 -172.268388)
		(width 0.4572)
		(layer "F.Cu")
		(net "GND")
	)
	(segment
		(start 105.955084 -67.406266)
		(end 104.73182 -67.406266)
		(width 0.3048)
		(layer "F.Cu")
		(net "GND")
	)
	(segment
		(start 53.090318 -65.184274)
		(end 53.090318 -64.736218)
		(width 0.254)
		(layer "F.Cu")
		(net "GND")
	)
	(segment
		(start 36.3093 -72.386698)
		(end 36.307522 -72.386698)
		(width 0.508)
		(layer "F.Cu")
		(net "GND")
	)
	(segment
		(start 34.842958 -187.636404)
		(end 34.233358 -187.636404)
		(width 0.4572)
		(layer "F.Cu")
		(net "GND")
	)
	(segment
		(start 88.12276 -187.543948)
		(end 88.753188 -186.91352)
		(width 0.508)
		(layer "F.Cu")
		(net "GND")
	)
	(segment
		(start 48.539146 -66.598038)
		(end 48.539146 -67.360038)
		(width 0.3048)
		(layer "F.Cu")
		(net "GND")
	)
	(segment
		(start 72.04964 -63.891668)
		(end 72.472042 -64.31407)
		(width 0.3048)
		(layer "F.Cu")
		(net "GND")
	)
	(segment
		(start 53.52034 -84.659724)
		(end 53.558186 -84.621878)
		(width 0.254)
		(layer "F.Cu")
		(net "GND")
	)
	(segment
		(start 100.568506 -4.449826)
		(end 101.346508 -4.449826)
		(width 0.508)
		(layer "F.Cu")
		(net "GND")
	)
	(segment
		(start 69.114416 -1.685544)
		(end 69.977762 -1.685544)
		(width 0.508)
		(layer "F.Cu")
		(net "GND")
	)
	(segment
		(start 44.53382 -80.912208)
		(end 44.029122 -81.416906)
		(width 0.254)
		(layer "F.Cu")
		(net "GND")
	)
	(segment
		(start 72.142096 -138.059414)
		(end 71.7423 -137.659618)
		(width 0.3556)
		(layer "F.Cu")
		(net "GND")
	)
	(segment
		(start 45.418248 -84.058252)
		(end 45.418248 -83.974686)
		(width 0.3048)
		(layer "F.Cu")
		(net "GND")
	)
	(segment
		(start 42.836338 -69.936868)
		(end 42.763186 -70.01002)
		(width 0.3048)
		(layer "F.Cu")
		(net "GND")
	)
	(segment
		(start 67.535044 -68.324222)
		(end 67.328542 -68.11772)
		(width 0.3048)
		(layer "F.Cu")
		(net "GND")
	)
	(segment
		(start 150.589996 -63.75273)
		(end 150.384764 -63.957962)
		(width 0.1778)
		(layer "F.Cu")
		(net "GND")
	)
	(segment
		(start 45.037248 -78.015846)
		(end 45.154596 -78.015846)
		(width 0.3048)
		(layer "F.Cu")
		(net "GND")
	)
	(segment
		(start 53.558186 -84.621878)
		(end 53.558186 -84.619846)
		(width 0.254)
		(layer "F.Cu")
		(net "GND")
	)
	(segment
		(start 64.187832 -86.879938)
		(end 64.311784 -87.00389)
		(width 0.254)
		(layer "F.Cu")
		(net "GND")
	)
	(segment
		(start 104.896666 -157.019752)
		(end 105.56367 -157.019752)
		(width 0.4572)
		(layer "F.Cu")
		(net "GND")
	)
	(segment
		(start 134.353808 -113.464086)
		(end 134.437882 -113.380012)
		(width 0.1778)
		(layer "F.Cu")
		(net "GND")
	)
	(segment
		(start 149.342602 -184.799732)
		(end 149.33676 -184.805574)
		(width 0.508)
		(layer "F.Cu")
		(net "GND")
	)
	(segment
		(start 106.444034 -129.343912)
		(end 107.041188 -128.746758)
		(width 0.4572)
		(layer "F.Cu")
		(net "GND")
	)
	(segment
		(start 79.98714 -158.642558)
		(end 79.98714 -159.314388)
		(width 0.4572)
		(layer "F.Cu")
		(net "GND")
	)
	(segment
		(start 66.540888 -134.058406)
		(end 66.141854 -134.45744)
		(width 0.381)
		(layer "F.Cu")
		(net "GND")
	)
	(segment
		(start 47.807118 -90.376248)
		(end 48.131984 -90.051382)
		(width 0.381)
		(layer "F.Cu")
		(net "GND")
	)
	(segment
		(start 115.04676 -187.147708)
		(end 115.19662 -186.997848)
		(width 0.508)
		(layer "F.Cu")
		(net "GND")
	)
	(segment
		(start 63.618364 -87.472774)
		(end 63.618364 -86.879938)
		(width 0.3048)
		(layer "F.Cu")
		(net "GND")
	)
	(segment
		(start 83.63204 -153.480516)
		(end 83.3501 -153.762456)
		(width 0.4572)
		(layer "F.Cu")
		(net "GND")
	)
	(segment
		(start 47.323248 -81.288382)
		(end 47.323248 -81.988406)
		(width 0.3048)
		(layer "F.Cu")
		(net "GND")
	)
	(segment
		(start 24.014938 -205.199488)
		(end 24.014938 -201.09053)
		(width 0.508)
		(layer "F.Cu")
		(net "GND")
	)
	(segment
		(start 42.757852 -76.904088)
		(end 42.757344 -76.904088)
		(width 0.254)
		(layer "F.Cu")
		(net "GND")
	)
	(segment
		(start 42.753534 -83.518756)
		(end 43.956732 -83.518756)
		(width 0.3048)
		(layer "F.Cu")
		(net "GND")
	)
	(segment
		(start 59.716924 -87.755222)
		(end 59.740546 -87.778844)
		(width 0.3048)
		(layer "F.Cu")
		(net "GND")
	)
	(segment
		(start 45.150278 -20.94992)
		(end 45.150278 -22.420834)
		(width 0.4572)
		(layer "F.Cu")
		(net "GND")
	)
	(segment
		(start 103.093012 -74.694034)
		(end 103.305102 -74.906124)
		(width 0.254)
		(layer "F.Cu")
		(net "GND")
	)
	(segment
		(start 91.21267 -167.1066)
		(end 91.21267 -167.41902)
		(width 0.381)
		(layer "F.Cu")
		(net "GND")
	)
	(segment
		(start 62.405514 -86.66861)
		(end 62.915546 -86.158578)
		(width 0.254)
		(layer "F.Cu")
		(net "GND")
	)
	(segment
		(start 51.277012 -85.467698)
		(end 51.571906 -85.762846)
		(width 0.3048)
		(layer "F.Cu")
		(net "GND")
	)
	(segment
		(start 59.517026 -84.238846)
		(end 59.31281 -84.03463)
		(width 0.3048)
		(layer "F.Cu")
		(net "GND")
	)
	(segment
		(start 128.082802 -154.59075)
		(end 127.568452 -154.0764)
		(width 0.4572)
		(layer "F.Cu")
		(net "GND")
	)
	(segment
		(start 142.724886 -51.876706)
		(end 142.724886 -52.677822)
		(width 0.508)
		(layer "F.Cu")
		(net "GND")
	)
	(segment
		(start 65.33896 -142.459456)
		(end 64.940942 -142.857474)
		(width 0.3556)
		(layer "F.Cu")
		(net "GND")
	)
	(segment
		(start 66.142108 -136.859518)
		(end 66.141854 -136.859518)
		(width 0.381)
		(layer "F.Cu")
		(net "GND")
	)
	(segment
		(start 153.122122 -70.203822)
		(end 152.979628 -70.203822)
		(width 0.508)
		(layer "F.Cu")
		(net "GND")
	)
	(segment
		(start 115.04676 -187.726574)
		(end 115.04676 -187.147708)
		(width 0.508)
		(layer "F.Cu")
		(net "GND")
	)
	(segment
		(start 138.53795 -152.333452)
		(end 138.53795 -151.32558)
		(width 0.1778)
		(layer "F.Cu")
		(net "GND")
	)
	(segment
		(start 47.319184 -81.99247)
		(end 47.319184 -82.896964)
		(width 0.3048)
		(layer "F.Cu")
		(net "GND")
	)
	(segment
		(start 87.10676 -184.733692)
		(end 87.10676 -184.805574)
		(width 0.508)
		(layer "F.Cu")
		(net "GND")
	)
	(segment
		(start 71.848218 -71.410068)
		(end 71.848218 -71.144638)
		(width 0.3048)
		(layer "F.Cu")
		(net "GND")
	)
	(segment
		(start 35.991546 -6.475476)
		(end 34.925 -6.475476)
		(width 0.4572)
		(layer "F.Cu")
		(net "GND")
	)
	(segment
		(start 61.601096 -79.799942)
		(end 62.401196 -80.600042)
		(width 0.3556)
		(layer "F.Cu")
		(net "GND")
	)
	(segment
		(start 73.341992 -143.259556)
		(end 73.341738 -143.259556)
		(width 0.3556)
		(layer "F.Cu")
		(net "GND")
	)
	(segment
		(start 18.2245 -57.085992)
		(end 18.3261 -57.187592)
		(width 0.381)
		(layer "F.Cu")
		(net "GND")
	)
	(segment
		(start 45.633132 -137.763758)
		(end 45.633132 -137.765282)
		(width 0.3556)
		(layer "F.Cu")
		(net "GND")
	)
	(segment
		(start 42.392854 -85.600032)
		(end 42.702734 -85.909912)
		(width 0.254)
		(layer "F.Cu")
		(net "GND")
	)
	(segment
		(start 42.757344 -76.904088)
		(end 42.582338 -77.079094)
		(width 0.254)
		(layer "F.Cu")
		(net "GND")
	)
	(segment
		(start 116.249196 -111.43107)
		(end 115.53698 -112.143286)
		(width 0.254)
		(layer "F.Cu")
		(net "GND")
	)
	(segment
		(start 66.540888 -137.258298)
		(end 66.142108 -136.859518)
		(width 0.381)
		(layer "F.Cu")
		(net "GND")
	)
	(segment
		(start 15.194534 -50.68951)
		(end 14.214602 -50.68951)
		(width 0.508)
		(layer "F.Cu")
		(net "GND")
	)
	(segment
		(start 67.99199 -128.607566)
		(end 67.7418 -128.857502)
		(width 0.3556)
		(layer "F.Cu")
		(net "GND")
	)
	(segment
		(start 171.25569 -96.358456)
		(end 170.675046 -96.358456)
		(width 0.254)
		(layer "F.Cu")
		(net "GND")
	)
	(segment
		(start 57.38876 -184.805574)
		(end 57.38876 -183.911494)
		(width 0.508)
		(layer "F.Cu")
		(net "GND")
	)
	(segment
		(start 44.275248 -72.057006)
		(end 44.656248 -72.057006)
		(width 0.3048)
		(layer "F.Cu")
		(net "GND")
	)
	(segment
		(start 158.48584 -187.721494)
		(end 158.48076 -187.726574)
		(width 0.508)
		(layer "F.Cu")
		(net "GND")
	)
	(segment
		(start 57.081166 -97.52076)
		(end 57.081166 -97.110042)
		(width 0.4572)
		(layer "F.Cu")
		(net "GND")
	)
	(segment
		(start 66.942208 -136.859518)
		(end 66.9417 -136.859518)
		(width 0.381)
		(layer "F.Cu")
		(net "GND")
	)
	(segment
		(start 93.450156 -30.599126)
		(end 93.36024 -30.689042)
		(width 0.381)
		(layer "F.Cu")
		(net "GND")
	)
	(segment
		(start 64.18961 -84.238846)
		(end 64.389254 -84.43849)
		(width 0.254)
		(layer "F.Cu")
		(net "GND")
	)
	(segment
		(start 107.30738 -164.556186)
		(end 107.09402 -164.769546)
		(width 0.4572)
		(layer "F.Cu")
		(net "GND")
	)
	(segment
		(start 155.05176 -187.305696)
		(end 155.05176 -187.726574)
		(width 0.508)
		(layer "F.Cu")
		(net "GND")
	)
	(segment
		(start 107.24134 -153.757122)
		(end 107.201462 -153.797)
		(width 0.508)
		(layer "F.Cu")
		(net "GND")
	)
	(segment
		(start 41.22801 -140.561314)
		(end 41.232582 -140.561314)
		(width 0.3556)
		(layer "F.Cu")
		(net "GND")
	)
	(segment
		(start 49.609248 -78.015846)
		(end 49.601628 -78.015846)
		(width 0.3048)
		(layer "F.Cu")
		(net "GND")
	)
	(segment
		(start 27.055318 -51.858418)
		(end 27.055318 -53.542184)
		(width 0.381)
		(layer "F.Cu")
		(net "GND")
	)
	(segment
		(start 43.249088 -70.04304)
		(end 43.30954 -69.982588)
		(width 0.254)
		(layer "F.Cu")
		(net "GND")
	)
	(segment
		(start 32.796734 -169.535856)
		(end 33.895538 -169.535856)
		(width 0.508)
		(layer "F.Cu")
		(net "GND")
	)
	(segment
		(start 49.38776 -187.726574)
		(end 49.38776 -186.848242)
		(width 0.508)
		(layer "F.Cu")
		(net "GND")
	)
	(segment
		(start 80.428592 -76.170282)
		(end 80.41259 -76.186284)
		(width 0.4572)
		(layer "F.Cu")
		(net "GND")
	)
	(segment
		(start 126.50724 -167.685212)
		(end 125.887988 -167.685212)
		(width 0.508)
		(layer "F.Cu")
		(net "GND")
	)
	(segment
		(start 64.82207 -69.27977)
		(end 64.429386 -68.887086)
		(width 0.254)
		(layer "F.Cu")
		(net "GND")
	)
	(segment
		(start 61.601096 -80.735678)
		(end 61.601096 -80.600042)
		(width 0.3048)
		(layer "F.Cu")
		(net "GND")
	)
	(segment
		(start 177.3047 -56.227472)
		(end 178.052476 -56.227472)
		(width 0.508)
		(layer "F.Cu")
		(net "GND")
	)
	(segment
		(start 62.691264 -148.121624)
		(end 63.383414 -148.121624)
		(width 0.508)
		(layer "F.Cu")
		(net "GND")
	)
	(segment
		(start 135.798052 -137.11555)
		(end 136.137904 -136.775698)
		(width 0.1778)
		(layer "F.Cu")
		(net "GND")
	)
	(segment
		(start 74.015092 -205.199488)
		(end 74.015092 -201.227436)
		(width 0.508)
		(layer "F.Cu")
		(net "GND")
	)
	(segment
		(start 99.06 -175.190404)
		(end 98.69678 -175.553624)
		(width 0.508)
		(layer "F.Cu")
		(net "GND")
	)
	(segment
		(start 68.141088 -134.058406)
		(end 67.7418 -134.457694)
		(width 0.381)
		(layer "F.Cu")
		(net "GND")
	)
	(segment
		(start 91.502484 -184.794398)
		(end 91.502484 -185.628026)
		(width 0.508)
		(layer "F.Cu")
		(net "GND")
	)
	(segment
		(start 49.044606 -78.572868)
		(end 49.044606 -79.11846)
		(width 0.3048)
		(layer "F.Cu")
		(net "GND")
	)
	(segment
		(start 64.541908 -133.659118)
		(end 64.541908 -133.659626)
		(width 0.381)
		(layer "F.Cu")
		(net "GND")
	)
	(segment
		(start 135.717788 -181.95163)
		(end 136.01319 -181.656228)
		(width 0.4572)
		(layer "F.Cu")
		(net "GND")
	)
	(segment
		(start 61.924438 -64.736218)
		(end 62.096142 -64.736218)
		(width 0.254)
		(layer "F.Cu")
		(net "GND")
	)
	(segment
		(start 54.581552 -89.638886)
		(end 54.833012 -89.387426)
		(width 0.254)
		(layer "F.Cu")
		(net "GND")
	)
	(segment
		(start 71.337424 -79.541878)
		(end 70.964044 -79.168498)
		(width 0.3048)
		(layer "F.Cu")
		(net "GND")
	)
	(segment
		(start 53.601112 -62.227968)
		(end 53.601112 -62.55004)
		(width 0.3048)
		(layer "F.Cu")
		(net "GND")
	)
	(segment
		(start 69.821044 -84.739226)
		(end 69.821044 -84.214462)
		(width 0.3556)
		(layer "F.Cu")
		(net "GND")
	)
	(segment
		(start 48.75022 -181.006496)
		(end 48.24476 -181.511956)
		(width 0.508)
		(layer "F.Cu")
		(net "GND")
	)
	(segment
		(start 184.015634 -205.199488)
		(end 184.015634 -200.600564)
		(width 0.508)
		(layer "F.Cu")
		(net "GND")
	)
	(segment
		(start 191.769492 -114.562128)
		(end 192.487042 -114.562128)
		(width 0.508)
		(layer "F.Cu")
		(net "GND")
	)
	(segment
		(start 72.942196 -135.659368)
		(end 72.5424 -135.259572)
		(width 0.3556)
		(layer "F.Cu")
		(net "GND")
	)
	(segment
		(start 51.812952 -63.86703)
		(end 51.781456 -63.898526)
		(width 0.3048)
		(layer "F.Cu")
		(net "GND")
	)
	(segment
		(start 58.149236 -81.490312)
		(end 58.149236 -80.851502)
		(width 0.3048)
		(layer "F.Cu")
		(net "GND")
	)
	(segment
		(start 64.442086 -148.876512)
		(end 65.305686 -148.876512)
		(width 0.508)
		(layer "F.Cu")
		(net "GND")
	)
	(segment
		(start 74.9808 -81.654142)
		(end 74.7903 -81.844642)
		(width 0.254)
		(layer "F.Cu")
		(net "GND")
	)
	(segment
		(start 159.375602 -173.55058)
		(end 159.375602 -173.552358)
		(width 0.381)
		(layer "F.Cu")
		(net "GND")
	)
	(segment
		(start 140.68044 -112.524286)
		(end 140.670534 -112.534192)
		(width 0.4572)
		(layer "F.Cu")
		(net "GND")
	)
	(segment
		(start 108.444792 -71.386954)
		(end 108.60786 -71.386954)
		(width 0.3048)
		(layer "F.Cu")
		(net "GND")
	)
	(segment
		(start 40.83304 -134.564374)
		(end 40.83304 -134.563612)
		(width 0.3556)
		(layer "F.Cu")
		(net "GND")
	)
	(segment
		(start 89.737692 -162.060128)
		(end 89.737692 -161.011362)
		(width 0.508)
		(layer "F.Cu")
		(net "GND")
	)
	(segment
		(start 109.036612 -67.162934)
		(end 109.199172 -67.325494)
		(width 0.3048)
		(layer "F.Cu")
		(net "GND")
	)
	(segment
		(start 66.392298 -86.862666)
		(end 66.67373 -86.862666)
		(width 0.3048)
		(layer "F.Cu")
		(net "GND")
	)
	(segment
		(start 142.631668 -39.624)
		(end 144.088612 -39.624)
		(width 0.3048)
		(layer "F.Cu")
		(net "GND")
	)
	(segment
		(start 66.540888 -135.658352)
		(end 66.142108 -135.259572)
		(width 0.381)
		(layer "F.Cu")
		(net "GND")
	)
	(segment
		(start 106.349292 -70.734174)
		(end 106.021378 -70.40626)
		(width 0.3048)
		(layer "F.Cu")
		(net "GND")
	)
	(segment
		(start 45.14088 -62.68847)
		(end 44.32808 -62.68847)
		(width 0.3556)
		(layer "F.Cu")
		(net "GND")
	)
	(segment
		(start 181.01564 -205.199488)
		(end 181.01564 -200.946258)
		(width 0.508)
		(layer "F.Cu")
		(net "GND")
	)
	(segment
		(start 44.147486 -85.212428)
		(end 44.418504 -85.483446)
		(width 0.3048)
		(layer "F.Cu")
		(net "GND")
	)
	(segment
		(start 125.536452 -154.402282)
		(end 125.536452 -154.0764)
		(width 0.4572)
		(layer "F.Cu")
		(net "GND")
	)
	(segment
		(start 125.007878 -61.690758)
		(end 124.159264 -61.690758)
		(width 0.508)
		(layer "F.Cu")
		(net "GND")
	)
	(segment
		(start 47.10176 -187.726574)
		(end 47.10176 -186.862974)
		(width 0.508)
		(layer "F.Cu")
		(net "GND")
	)
	(segment
		(start 55.10276 -187.726574)
		(end 55.10276 -186.960002)
		(width 0.508)
		(layer "F.Cu")
		(net "GND")
	)
	(segment
		(start 60.129166 -97.83953)
		(end 60.129166 -97.110042)
		(width 0.4572)
		(layer "F.Cu")
		(net "GND")
	)
	(segment
		(start 72.063864 -71.625714)
		(end 71.848218 -71.410068)
		(width 0.3048)
		(layer "F.Cu")
		(net "GND")
	)
	(segment
		(start 71.7423 -140.05941)
		(end 71.741792 -140.05941)
		(width 0.3556)
		(layer "F.Cu")
		(net "GND")
	)
	(segment
		(start 176.947576 -138.95451)
		(end 177.71364 -139.720574)
		(width 0.508)
		(layer "F.Cu")
		(net "GND")
	)
	(segment
		(start 48.75022 -20.94992)
		(end 48.75022 -22.480778)
		(width 0.4572)
		(layer "F.Cu")
		(net "GND")
	)
	(segment
		(start 48.2854 -106.40695)
		(end 47.818294 -106.40695)
		(width 0.4572)
		(layer "F.Cu")
		(net "GND")
	)
	(segment
		(start 69.066664 -71.596758)
		(end 69.440044 -71.223378)
		(width 0.254)
		(layer "F.Cu")
		(net "GND")
	)
	(segment
		(start 23.230332 -129.336292)
		(end 23.230332 -130.010662)
		(width 0.4572)
		(layer "F.Cu")
		(net "GND")
	)
	(segment
		(start 124.65304 -39.311834)
		(end 124.65304 -39.313612)
		(width 0.2794)
		(layer "F.Cu")
		(net "GND")
	)
	(segment
		(start 129.403856 -116.514626)
		(end 128.382268 -116.514626)
		(width 0.1778)
		(layer "F.Cu")
		(net "GND")
	)
	(segment
		(start 42.105326 -17.14119)
		(end 43.859196 -18.89506)
		(width 0.254)
		(layer "F.Cu")
		(net "GND")
	)
	(segment
		(start 37.176456 -184.58307)
		(end 38.044374 -184.58307)
		(width 0.508)
		(layer "F.Cu")
		(net "GND")
	)
	(segment
		(start 47.850298 -30.36443)
		(end 47.42942 -30.785308)
		(width 0.381)
		(layer "F.Cu")
		(net "GND")
	)
	(segment
		(start 139.227052 -152.50795)
		(end 139.33805 -152.396952)
		(width 0.1778)
		(layer "F.Cu")
		(net "GND")
	)
	(segment
		(start 148.476208 -174.250604)
		(end 148.476208 -173.756828)
		(width 0.508)
		(layer "F.Cu")
		(net "GND")
	)
	(segment
		(start 71.410068 -102.204266)
		(end 71.201026 -102.413308)
		(width 0.4572)
		(layer "F.Cu")
		(net "GND")
	)
	(segment
		(start 103.305102 -74.906124)
		(end 104.73182 -74.906124)
		(width 0.254)
		(layer "F.Cu")
		(net "GND")
	)
	(segment
		(start 60.21705 -81.952846)
		(end 60.212478 -81.952846)
		(width 0.3048)
		(layer "F.Cu")
		(net "GND")
	)
	(segment
		(start 150.384764 -63.957962)
		(end 149.57171 -63.957962)
		(width 0.1778)
		(layer "F.Cu")
		(net "GND")
	)
	(segment
		(start 52.65674 -83.857846)
		(end 52.65674 -83.84794)
		(width 0.3048)
		(layer "F.Cu")
		(net "GND")
	)
	(segment
		(start 108.31322 -186.722004)
		(end 108.33608 -186.744864)
		(width 0.508)
		(layer "F.Cu")
		(net "GND")
	)
	(segment
		(start 68.540884 -141.65961)
		(end 68.5419 -141.65961)
		(width 0.3556)
		(layer "F.Cu")
		(net "GND")
	)
	(segment
		(start 43.827192 -70.571868)
		(end 43.937428 -70.682104)
		(width 0.3048)
		(layer "F.Cu")
		(net "GND")
	)
	(segment
		(start 100.226622 -159.571182)
		(end 100.226622 -158.52521)
		(width 0.4572)
		(layer "F.Cu")
		(net "GND")
	)
	(segment
		(start 62.915546 -86.158578)
		(end 63.121286 -86.158578)
		(width 0.254)
		(layer "F.Cu")
		(net "GND")
	)
	(segment
		(start 46.59376 -179.922424)
		(end 47.686976 -179.922424)
		(width 0.4572)
		(layer "F.Cu")
		(net "GND")
	)
	(segment
		(start 74.250042 -77.395578)
		(end 74.250042 -77.34173)
		(width 0.3048)
		(layer "F.Cu")
		(net "GND")
	)
	(segment
		(start 43.662346 -64.31407)
		(end 44.084494 -64.736218)
		(width 0.381)
		(layer "F.Cu")
		(net "GND")
	)
	(segment
		(start 68.141088 -133.258306)
		(end 67.7418 -133.657594)
		(width 0.381)
		(layer "F.Cu")
		(net "GND")
	)
	(segment
		(start 44.654216 -121.35866)
		(end 45.683678 -121.35866)
		(width 0.508)
		(layer "F.Cu")
		(net "GND")
	)
	(segment
		(start 72.250554 -100.49129)
		(end 72.82434 -100.49129)
		(width 0.508)
		(layer "F.Cu")
		(net "GND")
	)
	(segment
		(start 71.616316 -64.919352)
		(end 71.616316 -65.366646)
		(width 0.3048)
		(layer "F.Cu")
		(net "GND")
	)
	(segment
		(start 147.98548 -158.994602)
		(end 147.193 -158.994602)
		(width 0.508)
		(layer "F.Cu")
		(net "GND")
	)
	(segment
		(start 106.339132 -67.790314)
		(end 105.955084 -67.406266)
		(width 0.3048)
		(layer "F.Cu")
		(net "GND")
	)
	(segment
		(start 51.174904 -76.599542)
		(end 51.999896 -76.599542)
		(width 0.3048)
		(layer "F.Cu")
		(net "GND")
	)
	(segment
		(start 120.180862 -156.94152)
		(end 120.180862 -158.102554)
		(width 0.508)
		(layer "F.Cu")
		(net "GND")
	)
	(segment
		(start 130.137916 -151.32558)
		(end 130.137916 -150.06955)
		(width 0.1778)
		(layer "F.Cu")
		(net "GND")
	)
	(segment
		(start 17.013174 -15.860522)
		(end 17.013174 -15.08506)
		(width 0.508)
		(layer "F.Cu")
		(net "GND")
	)
	(segment
		(start 64.772286 -85.932772)
		(end 64.772286 -85.956902)
		(width 0.254)
		(layer "F.Cu")
		(net "GND")
	)
	(segment
		(start 58.400696 -79.799942)
		(end 57.600596 -78.999842)
		(width 0.3048)
		(layer "F.Cu")
		(net "GND")
	)
	(segment
		(start 71.616316 -64.919352)
		(end 71.616316 -64.260222)
		(width 0.3048)
		(layer "F.Cu")
		(net "GND")
	)
	(segment
		(start 51.222402 -181.021482)
		(end 51.67376 -181.47284)
		(width 0.508)
		(layer "F.Cu")
		(net "GND")
	)
	(segment
		(start 124.627132 -147.07235)
		(end 124.627132 -147.08759)
		(width 0.1778)
		(layer "F.Cu")
		(net "GND")
	)
	(segment
		(start 48.899826 -89.132918)
		(end 48.891444 -89.124536)
		(width 0.254)
		(layer "F.Cu")
		(net "GND")
	)
	(segment
		(start 49.990248 -72.057006)
		(end 49.990248 -71.356982)
		(width 0.3048)
		(layer "F.Cu")
		(net "GND")
	)
	(segment
		(start 69.346572 -78.922118)
		(end 69.346572 -79.287878)
		(width 0.3048)
		(layer "F.Cu")
		(net "GND")
	)
	(segment
		(start 136.015476 -201.034904)
		(end 136.015476 -205.199488)
		(width 0.508)
		(layer "F.Cu")
		(net "GND")
	)
	(segment
		(start 51.999896 -76.681076)
		(end 51.891946 -76.789026)
		(width 0.3048)
		(layer "F.Cu")
		(net "GND")
	)
	(segment
		(start 46.950122 -20.94992)
		(end 46.950122 -22.470618)
		(width 0.4572)
		(layer "F.Cu")
		(net "GND")
	)
	(segment
		(start 114.446304 -60.239148)
		(end 114.446304 -61.255148)
		(width 0.4572)
		(layer "F.Cu")
		(net "GND")
	)
	(segment
		(start 43.920156 -72.411082)
		(end 43.921172 -72.411082)
		(width 0.3048)
		(layer "F.Cu")
		(net "GND")
	)
	(segment
		(start 72.221598 -79.737458)
		(end 72.795384 -79.737458)
		(width 0.3048)
		(layer "F.Cu")
		(net "GND")
	)
	(segment
		(start 72.901556 -83.089242)
		(end 73.24344 -83.431126)
		(width 0.3048)
		(layer "F.Cu")
		(net "GND")
	)
	(segment
		(start 103.047292 -64.407034)
		(end 104.296972 -64.407034)
		(width 0.3048)
		(layer "F.Cu")
		(net "GND")
	)
	(segment
		(start 66.541142 -140.45819)
		(end 66.142362 -140.05941)
		(width 0.3556)
		(layer "F.Cu")
		(net "GND")
	)
	(segment
		(start 49.825402 -70.027038)
		(end 50.525426 -70.027038)
		(width 0.3048)
		(layer "F.Cu")
		(net "GND")
	)
	(segment
		(start 46.032166 -134.164578)
		(end 45.633132 -134.563612)
		(width 0.3556)
		(layer "F.Cu")
		(net "GND")
	)
	(segment
		(start 108.866432 -73.533254)
		(end 108.993432 -73.406254)
		(width 0.3048)
		(layer "F.Cu")
		(net "GND")
	)
	(segment
		(start 50.46599 -61.15939)
		(end 49.95799 -61.66739)
		(width 0.3048)
		(layer "F.Cu")
		(net "GND")
	)
	(segment
		(start 64.940942 -137.258298)
		(end 65.339722 -136.859518)
		(width 0.381)
		(layer "F.Cu")
		(net "GND")
	)
	(segment
		(start 72.942196 -138.059414)
		(end 72.5424 -137.659618)
		(width 0.3556)
		(layer "F.Cu")
		(net "GND")
	)
	(segment
		(start 68.548504 -61.847984)
		(end 68.548504 -62.55004)
		(width 0.254)
		(layer "F.Cu")
		(net "GND")
	)
	(segment
		(start 41.630346 -140.16355)
		(end 41.63314 -140.16355)
		(width 0.3556)
		(layer "F.Cu")
		(net "GND")
	)
	(segment
		(start 41.88968 -64.31407)
		(end 41.402 -64.31407)
		(width 0.381)
		(layer "F.Cu")
		(net "GND")
	)
	(segment
		(start 64.437514 -65.82791)
		(end 64.437514 -65.240916)
		(width 0.254)
		(layer "F.Cu")
		(net "GND")
	)
	(segment
		(start 44.607226 -177.285904)
		(end 45.282612 -177.285904)
		(width 0.4572)
		(layer "F.Cu")
		(net "GND")
	)
	(segment
		(start 106.021378 -70.40626)
		(end 104.73182 -70.40626)
		(width 0.3048)
		(layer "F.Cu")
		(net "GND")
	)
	(segment
		(start 72.205088 -64.985646)
		(end 72.784208 -64.985646)
		(width 0.3048)
		(layer "F.Cu")
		(net "GND")
	)
	(segment
		(start 41.361106 -77.148182)
		(end 41.737534 -77.148182)
		(width 0.254)
		(layer "F.Cu")
		(net "GND")
	)
	(segment
		(start 73.747122 -83.552284)
		(end 73.829164 -83.470242)
		(width 0.254)
		(layer "F.Cu")
		(net "GND")
	)
	(segment
		(start 134.137908 -134.744206)
		(end 134.137908 -135.825484)
		(width 0.1778)
		(layer "F.Cu")
		(net "GND")
	)
	(segment
		(start 130.08356 -187.726574)
		(end 130.08356 -187.084716)
		(width 0.381)
		(layer "F.Cu")
		(net "GND")
	)
	(segment
		(start 80.66532 -182.878984)
		(end 80.66532 -182.877714)
		(width 0.508)
		(layer "F.Cu")
		(net "GND")
	)
	(segment
		(start 92.10421 -166.696898)
		(end 91.622372 -166.696898)
		(width 0.381)
		(layer "F.Cu")
		(net "GND")
	)
	(segment
		(start 44.014898 -201.09053)
		(end 44.014898 -200.32853)
		(width 0.508)
		(layer "F.Cu")
		(net "GND")
	)
	(segment
		(start 144.187418 -181.906672)
		(end 143.528796 -181.906672)
		(width 0.508)
		(layer "F.Cu")
		(net "GND")
	)
	(segment
		(start 66.67373 -86.862666)
		(end 66.948304 -86.588092)
		(width 0.3048)
		(layer "F.Cu")
		(net "GND")
	)
	(segment
		(start 51.223418 -69.733668)
		(end 50.754788 -69.265038)
		(width 0.254)
		(layer "F.Cu")
		(net "GND")
	)
	(segment
		(start 107.201462 -153.797)
		(end 106.482134 -153.797)
		(width 0.508)
		(layer "F.Cu")
		(net "GND")
	)
	(segment
		(start 102.750112 -20.94992)
		(end 102.750112 -22.530308)
		(width 0.381)
		(layer "F.Cu")
		(net "GND")
	)
	(segment
		(start 88.015064 -205.199488)
		(end 88.015064 -200.734676)
		(width 0.508)
		(layer "F.Cu")
		(net "GND")
	)
	(segment
		(start 62.20333 -84.619846)
		(end 61.503306 -84.619846)
		(width 0.3048)
		(layer "F.Cu")
		(net "GND")
	)
	(segment
		(start 63.739776 -135.259572)
		(end 63.741808 -135.259572)
		(width 0.381)
		(layer "F.Cu")
		(net "GND")
	)
	(segment
		(start 50.092356 -86.862666)
		(end 49.402238 -86.862666)
		(width 0.254)
		(layer "F.Cu")
		(net "GND")
	)
	(segment
		(start 44.965366 -88.343994)
		(end 45.067982 -88.241378)
		(width 0.254)
		(layer "F.Cu")
		(net "GND")
	)
	(segment
		(start 43.447462 -144.630394)
		(end 43.447462 -145.398998)
		(width 0.508)
		(layer "F.Cu")
		(net "GND")
	)
	(segment
		(start 98.69678 -175.553624)
		(end 97.819972 -175.553624)
		(width 0.508)
		(layer "F.Cu")
		(net "GND")
	)
	(segment
		(start 63.739522 -140.85951)
		(end 63.741808 -140.85951)
		(width 0.381)
		(layer "F.Cu")
		(net "GND")
	)
	(segment
		(start 72.942196 -141.259306)
		(end 72.5424 -140.85951)
		(width 0.3556)
		(layer "F.Cu")
		(net "GND")
	)
	(segment
		(start 20.83562 -48.700182)
		(end 22.032976 -48.700182)
		(width 0.4572)
		(layer "F.Cu")
		(net "GND")
	)
	(segment
		(start 63.729362 -68.122038)
		(end 63.729362 -68.884038)
		(width 0.254)
		(layer "F.Cu")
		(net "GND")
	)
	(segment
		(start 67.328542 -67.733418)
		(end 67.328542 -67.741038)
		(width 0.3048)
		(layer "F.Cu")
		(net "GND")
	)
	(segment
		(start 99.050094 -173.283372)
		(end 98.866198 -173.467268)
		(width 0.508)
		(layer "F.Cu")
		(net "GND")
	)
	(segment
		(start 43.099736 -86.322916)
		(end 42.702734 -85.925914)
		(width 0.254)
		(layer "F.Cu")
		(net "GND")
	)
	(segment
		(start 127.035052 -137.97915)
		(end 126.83871 -138.175492)
		(width 0.1778)
		(layer "F.Cu")
		(net "GND")
	)
	(segment
		(start 34.842958 -184.942226)
		(end 34.81578 -184.915048)
		(width 0.508)
		(layer "F.Cu")
		(net "GND")
	)
	(segment
		(start 57.926478 -89.620598)
		(end 57.897268 -89.591388)
		(width 0.254)
		(layer "F.Cu")
		(net "GND")
	)
	(segment
		(start 63.340996 -135.658352)
		(end 63.739776 -135.259572)
		(width 0.381)
		(layer "F.Cu")
		(net "GND")
	)
	(segment
		(start 51.884326 -86.51621)
		(end 52.09032 -86.72195)
		(width 0.3048)
		(layer "F.Cu")
		(net "GND")
	)
	(segment
		(start 126.05131 -166.474902)
		(end 125.955552 -166.474902)
		(width 0.508)
		(layer "F.Cu")
		(net "GND")
	)
	(segment
		(start 46.433994 -136.963658)
		(end 46.833028 -136.564624)
		(width 0.3556)
		(layer "F.Cu")
		(net "GND")
	)
	(segment
		(start 134.437882 -113.049812)
		(end 134.629652 -112.858042)
		(width 0.1778)
		(layer "F.Cu")
		(net "GND")
	)
	(segment
		(start 135.391652 -149.94255)
		(end 135.391652 -150.06955)
		(width 0.1778)
		(layer "F.Cu")
		(net "GND")
	)
	(segment
		(start 66.550286 -141.262862)
		(end 66.146934 -140.85951)
		(width 0.3556)
		(layer "F.Cu")
		(net "GND")
	)
	(segment
		(start 121.2596 -119.51335)
		(end 121.2596 -137.824718)
		(width 0.254)
		(layer "F.Cu")
		(net "GND")
	)
	(segment
		(start 61.495686 -84.619846)
		(end 60.942728 -84.066888)
		(width 0.3048)
		(layer "F.Cu")
		(net "GND")
	)
	(segment
		(start 130.047238 -53.666898)
		(end 130.08864 -53.7083)
		(width 0.4572)
		(layer "F.Cu")
		(net "GND")
	)
	(segment
		(start 61.279532 -81.057242)
		(end 61.036708 -81.300066)
		(width 0.3048)
		(layer "F.Cu")
		(net "GND")
	)
	(segment
		(start 68.141088 -128.458214)
		(end 67.99199 -128.607566)
		(width 0.3556)
		(layer "F.Cu")
		(net "GND")
	)
	(segment
		(start 46.552866 -64.661288)
		(end 46.486572 -64.594994)
		(width 0.3048)
		(layer "F.Cu")
		(net "GND")
	)
	(segment
		(start 69.059044 -71.596758)
		(end 69.066664 -71.596758)
		(width 0.254)
		(layer "F.Cu")
		(net "GND")
	)
	(segment
		(start 52.95519 -84.418424)
		(end 53.27904 -84.418424)
		(width 0.254)
		(layer "F.Cu")
		(net "GND")
	)
	(segment
		(start 46.048422 -27.704542)
		(end 46.048422 -29.148024)
		(width 0.4572)
		(layer "F.Cu")
		(net "GND")
	)
	(segment
		(start 92.691712 -177.354992)
		(end 92.670376 -177.376328)
		(width 0.508)
		(layer "F.Cu")
		(net "GND")
	)
	(segment
		(start 177.51044 -119.865648)
		(end 177.010314 -120.365774)
		(width 0.381)
		(layer "F.Cu")
		(net "GND")
	)
	(segment
		(start 87.150194 -20.94992)
		(end 87.150194 -22.460966)
		(width 0.381)
		(layer "F.Cu")
		(net "GND")
	)
	(via
		(at 29.97708 -115.590066)
		(size 0.508)
		(drill 0.254)
		(layers "F.Cu" "B.Cu")
		(net "GND")
	)
	(via
		(at 117.33784 -173.836076)
		(size 0.508)
		(drill 0.254)
		(layers "F.Cu" "B.Cu")
		(net "GND")
	)
	(via
		(at 67.340988 -134.058406)
		(size 0.49022)
		(drill 0.254)
		(layers "F.Cu" "B.Cu")
		(net "GND")
	)
	(via
		(at 13.2461 -105.383584)
		(size 0.508)
		(drill 0.254)
		(layers "F.Cu" "B.Cu")
		(net "GND")
	)
	(via
		(at 147.050252 -26.193242)
		(size 0.508)
		(drill 0.254)
		(layers "F.Cu" "B.Cu")
		(net "GND")
	)
	(via
		(at 175.649128 -144.218406)
		(size 0.508)
		(drill 0.254)
		(layers "F.Cu" "B.Cu")
		(net "GND")
	)
	(via
		(at 117.77726 -114.760502)
		(size 0.508)
		(drill 0.254)
		(layers "F.Cu" "B.Cu")
		(net "GND")
	)
	(via
		(at 134.086092 -37.375084)
		(size 0.508)
		(drill 0.254)
		(layers "F.Cu" "B.Cu")
		(net "GND")
	)
	(via
		(at 150.073868 -154.460448)
		(size 0.508)
		(drill 0.254)
		(layers "F.Cu" "B.Cu")
		(net "GND")
	)
	(via
		(at 106.05008 -133.382512)
		(size 0.508)
		(drill 0.254)
		(layers "F.Cu" "B.Cu")
		(net "GND")
	)
	(via
		(at 85.59546 -186.868054)
		(size 0.508)
		(drill 0.254)
		(layers "F.Cu" "B.Cu")
		(net "GND")
	)
	(via
		(at 63.340996 -134.058406)
		(size 0.49022)
		(drill 0.254)
		(layers "F.Cu" "B.Cu")
		(net "GND")
	)
	(via
		(at 73.869042 -16.044418)
		(size 0.508)
		(drill 0.254)
		(layers "F.Cu" "B.Cu")
		(net "GND")
	)
	(via
		(at 123.799092 -146.47291)
		(size 0.508)
		(drill 0.254)
		(layers "F.Cu" "B.Cu")
		(net "GND")
	)
	(via
		(at 164.611558 -181.246526)
		(size 0.508)
		(drill 0.254)
		(layers "F.Cu" "B.Cu")
		(net "GND")
	)
	(via
		(at 107.244134 -157.447742)
		(size 0.508)
		(drill 0.254)
		(layers "F.Cu" "B.Cu")
		(net "GND")
	)
	(via
		(at 52.59578 -48.000412)
		(size 0.508)
		(drill 0.254)
		(layers "F.Cu" "B.Cu")
		(net "GND")
	)
	(via
		(at 68.940934 -141.25829)
		(size 0.49022)
		(drill 0.254)
		(layers "F.Cu" "B.Cu")
		(net "GND")
	)
	(via
		(at 133.69036 -114.889534)
		(size 0.508)
		(drill 0.254)
		(layers "F.Cu" "B.Cu")
		(net "GND")
	)
	(via
		(at 101.749606 -155.364688)
		(size 0.508)
		(drill 0.254)
		(layers "F.Cu" "B.Cu")
		(net "GND")
	)
	(via
		(at 76.924662 -22.620478)
		(size 0.508)
		(drill 0.254)
		(layers "F.Cu" "B.Cu")
		(net "GND")
	)
	(via
		(at 66.540888 -135.658352)
		(size 0.49022)
		(drill 0.254)
		(layers "F.Cu" "B.Cu")
		(net "GND")
	)
	(via
		(at 54.358032 -97.83191)
		(size 0.508)
		(drill 0.254)
		(layers "F.Cu" "B.Cu")
		(net "GND")
	)
	(via
		(at 167.375586 -42.06875)
		(size 0.508)
		(drill 0.254)
		(layers "F.Cu" "B.Cu")
		(net "GND")
	)
	(via
		(at 21.19757 -125.59919)
		(size 0.508)
		(drill 0.254)
		(layers "F.Cu" "B.Cu")
		(net "GND")
	)
	(via
		(at 73.37552 -175.124618)
		(size 0.508)
		(drill 0.254)
		(layers "F.Cu" "B.Cu")
		(net "GND")
	)
	(via
		(at 47.10176 -186.862974)
		(size 0.508)
		(drill 0.254)
		(layers "F.Cu" "B.Cu")
		(net "GND")
	)
	(via
		(at 148.738336 -78.455774)
		(size 0.508)
		(drill 0.254)
		(layers "F.Cu" "B.Cu")
		(net "GND")
	)
	(via
		(at 116.899944 -147.746466)
		(size 0.508)
		(drill 0.254)
		(layers "F.Cu" "B.Cu")
		(net "GND")
	)
	(via
		(at 127.73406 -187.032646)
		(size 0.508)
		(drill 0.254)
		(layers "F.Cu" "B.Cu")
		(net "GND")
	)
	(via
		(at 56.784494 -97.817432)
		(size 0.508)
		(drill 0.254)
		(layers "F.Cu" "B.Cu")
		(net "GND")
	)
	(via
		(at 130.33756 -120.147334)
		(size 0.508)
		(drill 0.254)
		(layers "F.Cu" "B.Cu")
		(net "GND")
	)
	(via
		(at 151.580596 -63.44793)
		(size 0.508)
		(drill 0.254)
		(layers "F.Cu" "B.Cu")
		(net "GND")
	)
	(via
		(at 166.870634 -167.764968)
		(size 0.508)
		(drill 0.254)
		(layers "F.Cu" "B.Cu")
		(net "GND")
	)
	(via
		(at 30.15488 -119.885206)
		(size 0.508)
		(drill 0.254)
		(layers "F.Cu" "B.Cu")
		(net "GND")
	)
	(via
		(at 46.16069 -1.871726)
		(size 0.508)
		(drill 0.254)
		(layers "F.Cu" "B.Cu")
		(net "GND")
	)
	(via
		(at 86.262464 -153.908252)
		(size 0.508)
		(drill 0.254)
		(layers "F.Cu" "B.Cu")
		(net "GND")
	)
	(via
		(at 89.281 -76.65593)
		(size 0.508)
		(drill 0.254)
		(layers "F.Cu" "B.Cu")
		(net "GND")
	)
	(via
		(at 11.26744 -110.167166)
		(size 0.508)
		(drill 0.254)
		(layers "F.Cu" "B.Cu")
		(net "GND")
	)
	(via
		(at 179.29098 -183.345328)
		(size 0.508)
		(drill 0.254)
		(layers "F.Cu" "B.Cu")
		(net "GND")
	)
	(via
		(at 120.46966 -143.14551)
		(size 0.508)
		(drill 0.254)
		(layers "F.Cu" "B.Cu")
		(net "GND")
	)
	(via
		(at 34.81578 -184.915048)
		(size 0.508)
		(drill 0.254)
		(layers "F.Cu" "B.Cu")
		(net "GND")
	)
	(via
		(at 139.98956 -113.230406)
		(size 0.508)
		(drill 0.254)
		(layers "F.Cu" "B.Cu")
		(net "GND")
	)
	(via
		(at 57.474104 -117.018816)
		(size 0.508)
		(drill 0.254)
		(layers "F.Cu" "B.Cu")
		(net "GND")
	)
	(via
		(at 76.015088 -201.09053)
		(size 0.508)
		(drill 0.254)
		(layers "F.Cu" "B.Cu")
		(net "GND")
	)
	(via
		(at 134.59714 -106.547412)
		(size 0.508)
		(drill 0.254)
		(layers "F.Cu" "B.Cu")
		(net "GND")
	)
	(via
		(at 56.38546 -5.389626)
		(size 0.508)
		(drill 0.254)
		(layers "F.Cu" "B.Cu")
		(net "GND")
	)
	(via
		(at 119.42826 -164.768022)
		(size 0.508)
		(drill 0.254)
		(layers "F.Cu" "B.Cu")
		(net "GND")
	)
	(via
		(at 32.93364 -71.09206)
		(size 0.508)
		(drill 0.254)
		(layers "F.Cu" "B.Cu")
		(net "GND")
	)
	(via
		(at 55.701184 -153.621994)
		(size 0.508)
		(drill 0.254)
		(layers "F.Cu" "B.Cu")
		(net "GND")
	)
	(via
		(at 72.942196 -141.259306)
		(size 0.49022)
		(drill 0.254)
		(layers "F.Cu" "B.Cu")
		(net "GND")
	)
	(via
		(at 62.3824 -16.844518)
		(size 0.508)
		(drill 0.254)
		(layers "F.Cu" "B.Cu")
		(net "GND")
	)
	(via
		(at 114.11966 -70.161658)
		(size 0.508)
		(drill 0.254)
		(layers "F.Cu" "B.Cu")
		(net "GND")
	)
	(via
		(at 38.06444 -184.563004)
		(size 0.508)
		(drill 0.254)
		(layers "F.Cu" "B.Cu")
		(net "GND")
	)
	(via
		(at 54.354476 -118.377716)
		(size 0.508)
		(drill 0.254)
		(layers "F.Cu" "B.Cu")
		(net "GND")
	)
	(via
		(at 184.80278 -196.920612)
		(size 0.508)
		(drill 0.254)
		(layers "F.Cu" "B.Cu")
		(net "GND")
	)
	(via
		(at 47.918116 -145.64233)
		(size 0.508)
		(drill 0.254)
		(layers "F.Cu" "B.Cu")
		(net "GND")
	)
	(via
		(at 145.983452 -147.19935)
		(size 0.508)
		(drill 0.254)
		(layers "F.Cu" "B.Cu")
		(net "GND")
	)
	(via
		(at 38.5826 -149.975316)
		(size 0.508)
		(drill 0.254)
		(layers "F.Cu" "B.Cu")
		(net "GND")
	)
	(via
		(at 168.41216 -174.766478)
		(size 0.508)
		(drill 0.254)
		(layers "F.Cu" "B.Cu")
		(net "GND")
	)
	(via
		(at 118.537228 -26.01214)
		(size 0.508)
		(drill 0.254)
		(layers "F.Cu" "B.Cu")
		(net "GND")
	)
	(via
		(at 20.121118 -59.146694)
		(size 0.508)
		(drill 0.254)
		(layers "F.Cu" "B.Cu")
		(net "GND")
	)
	(via
		(at 104.272588 -150.862538)
		(size 0.508)
		(drill 0.254)
		(layers "F.Cu" "B.Cu")
		(net "GND")
	)
	(via
		(at 66.540888 -132.458206)
		(size 0.49022)
		(drill 0.254)
		(layers "F.Cu" "B.Cu")
		(net "GND")
	)
	(via
		(at 97.55886 -25.080722)
		(size 0.508)
		(drill 0.254)
		(layers "F.Cu" "B.Cu")
		(net "GND")
	)
	(via
		(at 102.929436 -155.369768)
		(size 0.508)
		(drill 0.254)
		(layers "F.Cu" "B.Cu")
		(net "GND")
	)
	(via
		(at 103.124 -112.96777)
		(size 0.508)
		(drill 0.254)
		(layers "F.Cu" "B.Cu")
		(net "GND")
	)
	(via
		(at 98.9076 -22.664928)
		(size 0.508)
		(drill 0.254)
		(layers "F.Cu" "B.Cu")
		(net "GND")
	)
	(via
		(at 185.817764 -112.302544)
		(size 0.508)
		(drill 0.254)
		(layers "F.Cu" "B.Cu")
		(net "GND")
	)
	(via
		(at 179.622704 -12.845796)
		(size 0.508)
		(drill 0.254)
		(layers "F.Cu" "B.Cu")
		(net "GND")
	)
	(via
		(at 130.33756 -114.965734)
		(size 0.508)
		(drill 0.254)
		(layers "F.Cu" "B.Cu")
		(net "GND")
	)
	(via
		(at 85.7377 -141.253972)
		(size 0.508)
		(drill 0.254)
		(layers "F.Cu" "B.Cu")
		(net "GND")
	)
	(via
		(at 170.00728 -54.606444)
		(size 0.508)
		(drill 0.254)
		(layers "F.Cu" "B.Cu")
		(net "GND")
	)
	(via
		(at 75.607672 -76.380086)
		(size 0.508)
		(drill 0.254)
		(layers "F.Cu" "B.Cu")
		(net "GND")
	)
	(via
		(at 127.633476 -110.92815)
		(size 0.508)
		(drill 0.254)
		(layers "F.Cu" "B.Cu")
		(net "GND")
	)
	(via
		(at 103.564182 -124.658374)
		(size 0.508)
		(drill 0.254)
		(layers "F.Cu" "B.Cu")
		(net "GND")
	)
	(via
		(at 146.2151 -119.378984)
		(size 0.508)
		(drill 0.254)
		(layers "F.Cu" "B.Cu")
		(net "GND")
	)
	(via
		(at 169.015664 -201.034904)
		(size 0.508)
		(drill 0.254)
		(layers "F.Cu" "B.Cu")
		(net "GND")
	)
	(via
		(at 76.570078 -130.514598)
		(size 0.508)
		(drill 0.254)
		(layers "F.Cu" "B.Cu")
		(net "GND")
	)
	(via
		(at 93.36024 -30.689042)
		(size 0.508)
		(drill 0.254)
		(layers "F.Cu" "B.Cu")
		(net "GND")
	)
	(via
		(at 60.150248 -22.529292)
		(size 0.508)
		(drill 0.254)
		(layers "F.Cu" "B.Cu")
		(net "GND")
	)
	(via
		(at 62.95898 -26.878534)
		(size 0.508)
		(drill 0.254)
		(layers "F.Cu" "B.Cu")
		(net "GND")
	)
	(via
		(at 12.04468 -110.16615)
		(size 0.508)
		(drill 0.254)
		(layers "F.Cu" "B.Cu")
		(net "GND")
	)
	(via
		(at 74.827384 -83.344766)
		(size 0.508)
		(drill 0.254)
		(layers "F.Cu" "B.Cu")
		(net "GND")
	)
	(via
		(at 68.940934 -1.859026)
		(size 0.508)
		(drill 0.254)
		(layers "F.Cu" "B.Cu")
		(net "GND")
	)
	(via
		(at 79.529432 -141.365224)
		(size 0.508)
		(drill 0.254)
		(layers "F.Cu" "B.Cu")
		(net "GND")
	)
	(via
		(at 72.768968 -65.624456)
		(size 0.508)
		(drill 0.254)
		(layers "F.Cu" "B.Cu")
		(net "GND")
	)
	(via
		(at 89.248742 -34.129218)
		(size 0.508)
		(drill 0.254)
		(layers "F.Cu" "B.Cu")
		(net "GND")
	)
	(via
		(at 47.849282 -141.45133)
		(size 0.49022)
		(drill 0.254)
		(layers "F.Cu" "B.Cu")
		(net "GND")
	)
	(via
		(at 54.787546 -158.998158)
		(size 0.508)
		(drill 0.254)
		(layers "F.Cu" "B.Cu")
		(net "GND")
	)
	(via
		(at 42.659554 -96.659954)
		(size 0.508)
		(drill 0.254)
		(layers "F.Cu" "B.Cu")
		(net "GND")
	)
	(via
		(at 99.567492 -65.595754)
		(size 0.508)
		(drill 0.254)
		(layers "F.Cu" "B.Cu")
		(net "GND")
	)
	(via
		(at 187.60948 -27.775154)
		(size 0.508)
		(drill 0.254)
		(layers "F.Cu" "B.Cu")
		(net "GND")
	)
	(via
		(at 47.179738 -123.866656)
		(size 0.508)
		(drill 0.254)
		(layers "F.Cu" "B.Cu")
		(net "GND")
	)
	(via
		(at 52.59578 -45.654976)
		(size 0.508)
		(drill 0.254)
		(layers "F.Cu" "B.Cu")
		(net "GND")
	)
	(via
		(at 28.0416 -127.564642)
		(size 0.508)
		(drill 0.254)
		(layers "F.Cu" "B.Cu")
		(net "GND")
	)
	(via
		(at 175.58512 -37.991034)
		(size 0.508)
		(drill 0.254)
		(layers "F.Cu" "B.Cu")
		(net "GND")
	)
	(via
		(at 80.11414 -65.698624)
		(size 0.508)
		(drill 0.254)
		(layers "F.Cu" "B.Cu")
		(net "GND")
	)
	(via
		(at 72.220328 -120.099836)
		(size 0.508)
		(drill 0.254)
		(layers "F.Cu" "B.Cu")
		(net "GND")
	)
	(via
		(at 101.511862 -27.522678)
		(size 0.508)
		(drill 0.254)
		(layers "F.Cu" "B.Cu")
		(net "GND")
	)
	(via
		(at 12.60983 -124.283216)
		(size 0.508)
		(drill 0.254)
		(layers "F.Cu" "B.Cu")
		(net "GND")
	)
	(via
		(at 29.014928 -200.32853)
		(size 0.508)
		(drill 0.254)
		(layers "F.Cu" "B.Cu")
		(net "GND")
	)
	(via
		(at 171.25569 -96.358456)
		(size 0.508)
		(drill 0.254)
		(layers "F.Cu" "B.Cu")
		(net "GND")
	)
	(via
		(at 66.550286 -141.262862)
		(size 0.49022)
		(drill 0.254)
		(layers "F.Cu" "B.Cu")
		(net "GND")
	)
	(via
		(at 115.910868 -164.956744)
		(size 0.508)
		(drill 0.254)
		(layers "F.Cu" "B.Cu")
		(net "GND")
	)
	(via
		(at 101.30028 -24.339042)
		(size 0.508)
		(drill 0.254)
		(layers "F.Cu" "B.Cu")
		(net "GND")
	)
	(via
		(at 76.87564 -187.035186)
		(size 0.508)
		(drill 0.254)
		(layers "F.Cu" "B.Cu")
		(net "GND")
	)
	(via
		(at 70.358 -22.434042)
		(size 0.508)
		(drill 0.254)
		(layers "F.Cu" "B.Cu")
		(net "GND")
	)
	(via
		(at 124.627132 -147.07235)
		(size 0.508)
		(drill 0.254)
		(layers "F.Cu" "B.Cu")
		(net "GND")
	)
	(via
		(at 56.400446 -78.599792)
		(size 0.508)
		(drill 0.254)
		(layers "F.Cu" "B.Cu")
		(net "GND")
	)
	(via
		(at 14.636496 -92.99067)
		(size 0.508)
		(drill 0.254)
		(layers "F.Cu" "B.Cu")
		(net "GND")
	)
	(via
		(at 122.27052 -140.51534)
		(size 0.508)
		(drill 0.254)
		(layers "F.Cu" "B.Cu")
		(net "GND")
	)
	(via
		(at 170.879008 -93.00464)
		(size 0.508)
		(drill 0.254)
		(layers "F.Cu" "B.Cu")
		(net "GND")
	)
	(via
		(at 145.180304 -62.660022)
		(size 0.508)
		(drill 0.254)
		(layers "F.Cu" "B.Cu")
		(net "GND")
	)
	(via
		(at 80.66532 -182.878984)
		(size 0.508)
		(drill 0.254)
		(layers "F.Cu" "B.Cu")
		(net "GND")
	)
	(via
		(at 101.2952 -116.346732)
		(size 0.508)
		(drill 0.254)
		(layers "F.Cu" "B.Cu")
		(net "GND")
	)
	(via
		(at 45.97146 -27.62758)
		(size 0.508)
		(drill 0.254)
		(layers "F.Cu" "B.Cu")
		(net "GND")
	)
	(via
		(at 123.28652 -151.51227)
		(size 0.508)
		(drill 0.254)
		(layers "F.Cu" "B.Cu")
		(net "GND")
	)
	(via
		(at 65.169542 -23.900638)
		(size 0.508)
		(drill 0.254)
		(layers "F.Cu" "B.Cu")
		(net "GND")
	)
	(via
		(at 64.141096 -134.058406)
		(size 0.49022)
		(drill 0.254)
		(layers "F.Cu" "B.Cu")
		(net "GND")
	)
	(via
		(at 79.57185 -142.13586)
		(size 0.508)
		(drill 0.254)
		(layers "F.Cu" "B.Cu")
		(net "GND")
	)
	(via
		(at 179.42052 -19.172428)
		(size 0.508)
		(drill 0.254)
		(layers "F.Cu" "B.Cu")
		(net "GND")
	)
	(via
		(at 20.73529 -131.344416)
		(size 0.508)
		(drill 0.254)
		(layers "F.Cu" "B.Cu")
		(net "GND")
	)
	(via
		(at 128.457452 -152.50795)
		(size 0.508)
		(drill 0.254)
		(layers "F.Cu" "B.Cu")
		(net "GND")
	)
	(via
		(at 143.427704 -62.660022)
		(size 0.508)
		(drill 0.254)
		(layers "F.Cu" "B.Cu")
		(net "GND")
	)
	(via
		(at 83.2993 -25.668478)
		(size 0.508)
		(drill 0.254)
		(layers "F.Cu" "B.Cu")
		(net "GND")
	)
	(via
		(at 52.393342 -24.984456)
		(size 0.508)
		(drill 0.254)
		(layers "F.Cu" "B.Cu")
		(net "GND")
	)
	(via
		(at 139.227052 -152.50795)
		(size 0.508)
		(drill 0.254)
		(layers "F.Cu" "B.Cu")
		(net "GND")
	)
	(via
		(at 46.972728 -152.536398)
		(size 0.508)
		(drill 0.254)
		(layers "F.Cu" "B.Cu")
		(net "GND")
	)
	(via
		(at 99.050094 -173.283372)
		(size 0.508)
		(drill 0.254)
		(layers "F.Cu" "B.Cu")
		(net "GND")
	)
	(via
		(at 101.3587 -114.545872)
		(size 0.508)
		(drill 0.254)
		(layers "F.Cu" "B.Cu")
		(net "GND")
	)
	(via
		(at 153.587196 -60.95873)
		(size 0.508)
		(drill 0.254)
		(layers "F.Cu" "B.Cu")
		(net "GND")
	)
	(via
		(at 55.150766 -82.348578)
		(size 0.508)
		(drill 0.254)
		(layers "F.Cu" "B.Cu")
		(net "GND")
	)
	(via
		(at 58.864246 -67.345306)
		(size 0.508)
		(drill 0.254)
		(layers "F.Cu" "B.Cu")
		(net "GND")
	)
	(via
		(at 49.784 -24.274272)
		(size 0.508)
		(drill 0.254)
		(layers "F.Cu" "B.Cu")
		(net "GND")
	)
	(via
		(at 63.383414 -149.137624)
		(size 0.508)
		(drill 0.254)
		(layers "F.Cu" "B.Cu")
		(net "GND")
	)
	(via
		(at 67.52082 -26.051764)
		(size 0.508)
		(drill 0.254)
		(layers "F.Cu" "B.Cu")
		(net "GND")
	)
	(via
		(at 165.335712 -162.37966)
		(size 0.508)
		(drill 0.254)
		(layers "F.Cu" "B.Cu")
		(net "GND")
	)
	(via
		(at 101.36124 -115.397788)
		(size 0.508)
		(drill 0.254)
		(layers "F.Cu" "B.Cu")
		(net "GND")
	)
	(via
		(at 75.976734 -151.775668)
		(size 0.508)
		(drill 0.254)
		(layers "F.Cu" "B.Cu")
		(net "GND")
	)
	(via
		(at 41.152318 -82.394806)
		(size 0.508)
		(drill 0.254)
		(layers "F.Cu" "B.Cu")
		(net "GND")
	)
	(via
		(at 72.942196 -142.059406)
		(size 0.49022)
		(drill 0.254)
		(layers "F.Cu" "B.Cu")
		(net "GND")
	)
	(via
		(at 47.42942 -30.785308)
		(size 0.508)
		(drill 0.254)
		(layers "F.Cu" "B.Cu")
		(net "GND")
	)
	(via
		(at 31.28264 -72.91324)
		(size 0.508)
		(drill 0.254)
		(layers "F.Cu" "B.Cu")
		(net "GND")
	)
	(via
		(at 106.444034 -129.357882)
		(size 0.508)
		(drill 0.254)
		(layers "F.Cu" "B.Cu")
		(net "GND")
	)
	(via
		(at 146.186652 -145.21815)
		(size 0.508)
		(drill 0.254)
		(layers "F.Cu" "B.Cu")
		(net "GND")
	)
	(via
		(at 117.018308 -120.77192)
		(size 0.508)
		(drill 0.254)
		(layers "F.Cu" "B.Cu")
		(net "GND")
	)
	(via
		(at 72.142096 -142.059406)
		(size 0.49022)
		(drill 0.254)
		(layers "F.Cu" "B.Cu")
		(net "GND")
	)
	(via
		(at 131.00812 -110.245906)
		(size 0.508)
		(drill 0.254)
		(layers "F.Cu" "B.Cu")
		(net "GND")
	)
	(via
		(at 44.051728 -152.510998)
		(size 0.508)
		(drill 0.254)
		(layers "F.Cu" "B.Cu")
		(net "GND")
	)
	(via
		(at 20.48002 -175.179228)
		(size 0.508)
		(drill 0.254)
		(layers "F.Cu" "B.Cu")
		(net "GND")
	)
	(via
		(at 43.980354 -108.598208)
		(size 0.508)
		(drill 0.254)
		(layers "F.Cu" "B.Cu")
		(net "GND")
	)
	(via
		(at 163.466272 -152.283414)
		(size 0.508)
		(drill 0.254)
		(layers "F.Cu" "B.Cu")
		(net "GND")
	)
	(via
		(at 69.062092 -66.845942)
		(size 0.508)
		(drill 0.254)
		(layers "F.Cu" "B.Cu")
		(net "GND")
	)
	(via
		(at 53.345842 -181.061868)
		(size 0.508)
		(drill 0.254)
		(layers "F.Cu" "B.Cu")
		(net "GND")
	)
	(via
		(at 155.839414 -138.878056)
		(size 0.508)
		(drill 0.254)
		(layers "F.Cu" "B.Cu")
		(net "GND")
	)
	(via
		(at 80.107282 -98.517202)
		(size 0.508)
		(drill 0.254)
		(layers "F.Cu" "B.Cu")
		(net "GND")
	)
	(via
		(at 59.015122 -200.32853)
		(size 0.508)
		(drill 0.254)
		(layers "F.Cu" "B.Cu")
		(net "GND")
	)
	(via
		(at 78.61554 -87.408258)
		(size 0.508)
		(drill 0.254)
		(layers "F.Cu" "B.Cu")
		(net "GND")
	)
	(via
		(at 66.750692 -106.143044)
		(size 0.508)
		(drill 0.254)
		(layers "F.Cu" "B.Cu")
		(net "GND")
	)
	(via
		(at 108.653072 -64.406526)
		(size 0.508)
		(drill 0.254)
		(layers "F.Cu" "B.Cu")
		(net "GND")
	)
	(via
		(at 56.400446 -79.399892)
		(size 0.508)
		(drill 0.254)
		(layers "F.Cu" "B.Cu")
		(net "GND")
	)
	(via
		(at 115.137692 -31.052516)
		(size 0.508)
		(drill 0.254)
		(layers "F.Cu" "B.Cu")
		(net "GND")
	)
	(via
		(at 55.135018 -86.243668)
		(size 0.508)
		(drill 0.254)
		(layers "F.Cu" "B.Cu")
		(net "GND")
	)
	(via
		(at 153.612596 -69.060822)
		(size 0.508)
		(drill 0.254)
		(layers "F.Cu" "B.Cu")
		(net "GND")
	)
	(via
		(at 127.682498 -106.033062)
		(size 0.508)
		(drill 0.254)
		(layers "F.Cu" "B.Cu")
		(net "GND")
	)
	(via
		(at 107.987084 -170.796204)
		(size 0.508)
		(drill 0.254)
		(layers "F.Cu" "B.Cu")
		(net "GND")
	)
	(via
		(at 39.3446 -140.165328)
		(size 0.49022)
		(drill 0.254)
		(layers "F.Cu" "B.Cu")
		(net "GND")
	)
	(via
		(at 45.14088 -89.540588)
		(size 0.508)
		(drill 0.254)
		(layers "F.Cu" "B.Cu")
		(net "GND")
	)
	(via
		(at 174.510446 -122.865642)
		(size 0.49022)
		(drill 0.254)
		(layers "F.Cu" "B.Cu")
		(net "GND")
	)
	(via
		(at 125.887988 -167.685212)
		(size 0.508)
		(drill 0.254)
		(layers "F.Cu" "B.Cu")
		(net "GND")
	)
	(via
		(at 37.529262 -159.399478)
		(size 0.508)
		(drill 0.254)
		(layers "F.Cu" "B.Cu")
		(net "GND")
	)
	(via
		(at 7.610856 -167.373554)
		(size 0.508)
		(drill 0.254)
		(layers "F.Cu" "B.Cu")
		(net "GND")
	)
	(via
		(at 114.456972 -17.527016)
		(size 0.508)
		(drill 0.254)
		(layers "F.Cu" "B.Cu")
		(net "GND")
	)
	(via
		(at 151.437086 -149.073362)
		(size 0.508)
		(drill 0.254)
		(layers "F.Cu" "B.Cu")
		(net "GND")
	)
	(via
		(at 19.967956 -58.39968)
		(size 0.508)
		(drill 0.254)
		(layers "F.Cu" "B.Cu")
		(net "GND")
	)
	(via
		(at 67.340988 -132.458206)
		(size 0.49022)
		(drill 0.254)
		(layers "F.Cu" "B.Cu")
		(net "GND")
	)
	(via
		(at 86.49335 -174.3964)
		(size 0.508)
		(drill 0.254)
		(layers "F.Cu" "B.Cu")
		(net "GND")
	)
	(via
		(at 20.0279 -40.097964)
		(size 0.508)
		(drill 0.254)
		(layers "F.Cu" "B.Cu")
		(net "GND")
	)
	(via
		(at 52.905406 -66.964306)
		(size 0.508)
		(drill 0.254)
		(layers "F.Cu" "B.Cu")
		(net "GND")
	)
	(via
		(at 52.617116 -44.503848)
		(size 0.508)
		(drill 0.254)
		(layers "F.Cu" "B.Cu")
		(net "GND")
	)
	(via
		(at 124.65304 -39.311834)
		(size 0.508)
		(drill 0.254)
		(layers "F.Cu" "B.Cu")
		(net "GND")
	)
	(via
		(at 64.940942 -143.65732)
		(size 0.49022)
		(drill 0.254)
		(layers "F.Cu" "B.Cu")
		(net "GND")
	)
	(via
		(at 142.51051 -138.175492)
		(size 0.508)
		(drill 0.254)
		(layers "F.Cu" "B.Cu")
		(net "GND")
	)
	(via
		(at 72.04964 -63.891668)
		(size 0.508)
		(drill 0.254)
		(layers "F.Cu" "B.Cu")
		(net "GND")
	)
	(via
		(at 8.673846 -11.213846)
		(size 0.508)
		(drill 0.254)
		(layers "F.Cu" "B.Cu")
		(net "GND")
	)
	(via
		(at 16.7386 -143.866362)
		(size 0.508)
		(drill 0.254)
		(layers "F.Cu" "B.Cu")
		(net "GND")
	)
	(via
		(at 72.64654 -70.114668)
		(size 0.508)
		(drill 0.254)
		(layers "F.Cu" "B.Cu")
		(net "GND")
	)
	(via
		(at 54.15026 -22.457156)
		(size 0.508)
		(drill 0.254)
		(layers "F.Cu" "B.Cu")
		(net "GND")
	)
	(via
		(at 61.3664 -16.844518)
		(size 0.508)
		(drill 0.254)
		(layers "F.Cu" "B.Cu")
		(net "GND")
	)
	(via
		(at 92.670376 -177.376328)
		(size 0.508)
		(drill 0.254)
		(layers "F.Cu" "B.Cu")
		(net "GND")
	)
	(via
		(at 141.015466 -201.034904)
		(size 0.508)
		(drill 0.254)
		(layers "F.Cu" "B.Cu")
		(net "GND")
	)
	(via
		(at 102.750112 -22.530308)
		(size 0.508)
		(drill 0.254)
		(layers "F.Cu" "B.Cu")
		(net "GND")
	)
	(via
		(at 128.45796 -125.95352)
		(size 0.508)
		(drill 0.254)
		(layers "F.Cu" "B.Cu")
		(net "GND")
	)
	(via
		(at 105.088182 -126.182374)
		(size 0.508)
		(drill 0.254)
		(layers "F.Cu" "B.Cu")
		(net "GND")
	)
	(via
		(at 76.229972 -63.750698)
		(size 0.508)
		(drill 0.254)
		(layers "F.Cu" "B.Cu")
		(net "GND")
	)
	(via
		(at 53.146452 -171.290742)
		(size 0.508)
		(drill 0.254)
		(layers "F.Cu" "B.Cu")
		(net "GND")
	)
	(via
		(at 44.379896 -13.741654)
		(size 0.508)
		(drill 0.254)
		(layers "F.Cu" "B.Cu")
		(net "GND")
	)
	(via
		(at 116.7511 -174.242222)
		(size 0.508)
		(drill 0.254)
		(layers "F.Cu" "B.Cu")
		(net "GND")
	)
	(via
		(at 25.026874 -30.82036)
		(size 0.508)
		(drill 0.254)
		(layers "F.Cu" "B.Cu")
		(net "GND")
	)
	(via
		(at 41.05656 -102.434644)
		(size 0.508)
		(drill 0.254)
		(layers "F.Cu" "B.Cu")
		(net "GND")
	)
	(via
		(at 97.685352 -133.621526)
		(size 0.508)
		(drill 0.254)
		(layers "F.Cu" "B.Cu")
		(net "GND")
	)
	(via
		(at 73.04913 -26.951686)
		(size 0.508)
		(drill 0.254)
		(layers "F.Cu" "B.Cu")
		(net "GND")
	)
	(via
		(at 166.246556 -183.051196)
		(size 0.508)
		(drill 0.254)
		(layers "F.Cu" "B.Cu")
		(net "GND")
	)
	(via
		(at 7.1755 -119.907304)
		(size 0.508)
		(drill 0.254)
		(layers "F.Cu" "B.Cu")
		(net "GND")
	)
	(via
		(at 175.649128 -147.266406)
		(size 0.508)
		(drill 0.254)
		(layers "F.Cu" "B.Cu")
		(net "GND")
	)
	(via
		(at 44.53382 -80.912208)
		(size 0.508)
		(drill 0.254)
		(layers "F.Cu" "B.Cu")
		(net "GND")
	)
	(via
		(at 102.978204 -159.209486)
		(size 0.508)
		(drill 0.254)
		(layers "F.Cu" "B.Cu")
		(net "GND")
	)
	(via
		(at 60.774326 -151.670512)
		(size 0.508)
		(drill 0.254)
		(layers "F.Cu" "B.Cu")
		(net "GND")
	)
	(via
		(at 62.001146 -74.599292)
		(size 0.508)
		(drill 0.254)
		(layers "F.Cu" "B.Cu")
		(net "GND")
	)
	(via
		(at 93.437964 -172.040804)
		(size 0.508)
		(drill 0.254)
		(layers "F.Cu" "B.Cu")
		(net "GND")
	)
	(via
		(at 117.422676 -22.925786)
		(size 0.508)
		(drill 0.254)
		(layers "F.Cu" "B.Cu")
		(net "GND")
	)
	(via
		(at 160.65119 -51.327558)
		(size 0.508)
		(drill 0.254)
		(layers "F.Cu" "B.Cu")
		(net "GND")
	)
	(via
		(at 49.228248 -78.389226)
		(size 0.508)
		(drill 0.254)
		(layers "F.Cu" "B.Cu")
		(net "GND")
	)
	(via
		(at 195.7959 -149.10435)
		(size 0.508)
		(drill 0.254)
		(layers "F.Cu" "B.Cu")
		(net "GND")
	)
	(via
		(at 68.81876 -186.853068)
		(size 0.508)
		(drill 0.254)
		(layers "F.Cu" "B.Cu")
		(net "GND")
	)
	(via
		(at 148.19376 -186.907424)
		(size 0.508)
		(drill 0.254)
		(layers "F.Cu" "B.Cu")
		(net "GND")
	)
	(via
		(at 43.823128 -157.362398)
		(size 0.508)
		(drill 0.254)
		(layers "F.Cu" "B.Cu")
		(net "GND")
	)
	(via
		(at 150.024084 -157.162754)
		(size 0.508)
		(drill 0.254)
		(layers "F.Cu" "B.Cu")
		(net "GND")
	)
	(via
		(at 45.267118 -110.570518)
		(size 0.508)
		(drill 0.254)
		(layers "F.Cu" "B.Cu")
		(net "GND")
	)
	(via
		(at 73.394316 -66.240152)
		(size 0.508)
		(drill 0.254)
		(layers "F.Cu" "B.Cu")
		(net "GND")
	)
	(via
		(at 28.933648 -137.450576)
		(size 0.508)
		(drill 0.254)
		(layers "F.Cu" "B.Cu")
		(net "GND")
	)
	(via
		(at 53.78704 -155.17241)
		(size 0.508)
		(drill 0.254)
		(layers "F.Cu" "B.Cu")
		(net "GND")
	)
	(via
		(at 45.51172 -171.50207)
		(size 0.508)
		(drill 0.254)
		(layers "F.Cu" "B.Cu")
		(net "GND")
	)
	(via
		(at 93.015054 -200.907904)
		(size 0.508)
		(drill 0.254)
		(layers "F.Cu" "B.Cu")
		(net "GND")
	)
	(via
		(at 122.844814 -121.825512)
		(size 0.508)
		(drill 0.254)
		(layers "F.Cu" "B.Cu")
		(net "GND")
	)
	(via
		(at 101.77653 -157.053534)
		(size 0.508)
		(drill 0.254)
		(layers "F.Cu" "B.Cu")
		(net "GND")
	)
	(via
		(at 74.93254 -72.838818)
		(size 0.508)
		(drill 0.254)
		(layers "F.Cu" "B.Cu")
		(net "GND")
	)
	(via
		(at 28.59405 -135.365236)
		(size 0.508)
		(drill 0.254)
		(layers "F.Cu" "B.Cu")
		(net "GND")
	)
	(via
		(at 173.514512 -114.638328)
		(size 0.508)
		(drill 0.254)
		(layers "F.Cu" "B.Cu")
		(net "GND")
	)
	(via
		(at 107.015534 -201.034904)
		(size 0.508)
		(drill 0.254)
		(layers "F.Cu" "B.Cu")
		(net "GND")
	)
	(via
		(at 91.81846 -180.97627)
		(size 0.508)
		(drill 0.254)
		(layers "F.Cu" "B.Cu")
		(net "GND")
	)
	(via
		(at 116.539772 -31.857188)
		(size 0.508)
		(drill 0.254)
		(layers "F.Cu" "B.Cu")
		(net "GND")
	)
	(via
		(at 67.547236 -4.196588)
		(size 0.508)
		(drill 0.254)
		(layers "F.Cu" "B.Cu")
		(net "GND")
	)
	(via
		(at 51.222402 -181.024276)
		(size 0.508)
		(drill 0.254)
		(layers "F.Cu" "B.Cu")
		(net "GND")
	)
	(via
		(at 74.80554 -71.300086)
		(size 0.508)
		(drill 0.254)
		(layers "F.Cu" "B.Cu")
		(net "GND")
	)
	(via
		(at 118.050818 -19.84883)
		(size 0.508)
		(drill 0.254)
		(layers "F.Cu" "B.Cu")
		(net "GND")
	)
	(via
		(at 122.27814 -145.685002)
		(size 0.508)
		(drill 0.254)
		(layers "F.Cu" "B.Cu")
		(net "GND")
	)
	(via
		(at 82.53476 -186.961018)
		(size 0.508)
		(drill 0.254)
		(layers "F.Cu" "B.Cu")
		(net "GND")
	)
	(via
		(at 107.42676 -183.845708)
		(size 0.508)
		(drill 0.254)
		(layers "F.Cu" "B.Cu")
		(net "GND")
	)
	(via
		(at 124.596652 -144.22755)
		(size 0.508)
		(drill 0.254)
		(layers "F.Cu" "B.Cu")
		(net "GND")
	)
	(via
		(at 131.22275 -58.43905)
		(size 0.508)
		(drill 0.254)
		(layers "F.Cu" "B.Cu")
		(net "GND")
	)
	(via
		(at 69.774054 -84.786216)
		(size 0.508)
		(drill 0.254)
		(layers "F.Cu" "B.Cu")
		(net "GND")
	)
	(via
		(at 142.452852 -137.24255)
		(size 0.508)
		(drill 0.254)
		(layers "F.Cu" "B.Cu")
		(net "GND")
	)
	(via
		(at 68.662804 -85.29193)
		(size 0.508)
		(drill 0.254)
		(layers "F.Cu" "B.Cu")
		(net "GND")
	)
	(via
		(at 71.835772 -89.582498)
		(size 0.508)
		(drill 0.254)
		(layers "F.Cu" "B.Cu")
		(net "GND")
	)
	(via
		(at 63.3984 -16.844518)
		(size 0.508)
		(drill 0.254)
		(layers "F.Cu" "B.Cu")
		(net "GND")
	)
	(via
		(at 106.349292 -71.026274)
		(size 0.508)
		(drill 0.254)
		(layers "F.Cu" "B.Cu")
		(net "GND")
	)
	(via
		(at 24.014938 -200.32853)
		(size 0.508)
		(drill 0.254)
		(layers "F.Cu" "B.Cu")
		(net "GND")
	)
	(via
		(at 41.127172 -74.642726)
		(size 0.508)
		(drill 0.254)
		(layers "F.Cu" "B.Cu")
		(net "GND")
	)
	(via
		(at 37.54628 -112.249966)
		(size 0.508)
		(drill 0.254)
		(layers "F.Cu" "B.Cu")
		(net "GND")
	)
	(via
		(at 53.812948 -156.898086)
		(size 0.508)
		(drill 0.254)
		(layers "F.Cu" "B.Cu")
		(net "GND")
	)
	(via
		(at 136.015476 -201.034904)
		(size 0.508)
		(drill 0.254)
		(layers "F.Cu" "B.Cu")
		(net "GND")
	)
	(via
		(at 170.25112 -47.780448)
		(size 0.508)
		(drill 0.254)
		(layers "F.Cu" "B.Cu")
		(net "GND")
	)
	(via
		(at 45.049186 -84.468462)
		(size 0.508)
		(drill 0.254)
		(layers "F.Cu" "B.Cu")
		(net "GND")
	)
	(via
		(at 170.466766 -77.617066)
		(size 0.508)
		(drill 0.254)
		(layers "F.Cu" "B.Cu")
		(net "GND")
	)
	(via
		(at 153.841196 -60.01893)
		(size 0.508)
		(drill 0.254)
		(layers "F.Cu" "B.Cu")
		(net "GND")
	)
	(via
		(at 113.53292 -162.248596)
		(size 0.508)
		(drill 0.254)
		(layers "F.Cu" "B.Cu")
		(net "GND")
	)
	(via
		(at 56.015128 -201.09053)
		(size 0.508)
		(drill 0.254)
		(layers "F.Cu" "B.Cu")
		(net "GND")
	)
	(via
		(at 65.34658 -7.450836)
		(size 0.508)
		(drill 0.254)
		(layers "F.Cu" "B.Cu")
		(net "GND")
	)
	(via
		(at 76.630784 -177.635154)
		(size 0.508)
		(drill 0.254)
		(layers "F.Cu" "B.Cu")
		(net "GND")
	)
	(via
		(at 15.494762 -130.83794)
		(size 0.508)
		(drill 0.254)
		(layers "F.Cu" "B.Cu")
		(net "GND")
	)
	(via
		(at 95.047562 -122.448066)
		(size 0.508)
		(drill 0.254)
		(layers "F.Cu" "B.Cu")
		(net "GND")
	)
	(via
		(at 89.004394 -5.404358)
		(size 0.508)
		(drill 0.254)
		(layers "F.Cu" "B.Cu")
		(net "GND")
	)
	(via
		(at 115.68938 -42.408602)
		(size 0.508)
		(drill 0.254)
		(layers "F.Cu" "B.Cu")
		(net "GND")
	)
	(via
		(at 81.89976 -177.83302)
		(size 0.508)
		(drill 0.254)
		(layers "F.Cu" "B.Cu")
		(net "GND")
	)
	(via
		(at 20.58162 -43.84167)
		(size 0.508)
		(drill 0.254)
		(layers "F.Cu" "B.Cu")
		(net "GND")
	)
	(via
		(at 8.595614 -2.332482)
		(size 0.508)
		(drill 0.254)
		(layers "F.Cu" "B.Cu")
		(net "GND")
	)
	(via
		(at 56.757062 -146.834098)
		(size 0.508)
		(drill 0.254)
		(layers "F.Cu" "B.Cu")
		(net "GND")
	)
	(via
		(at 149.09673 -176.29632)
		(size 0.508)
		(drill 0.254)
		(layers "F.Cu" "B.Cu")
		(net "GND")
	)
	(via
		(at 45.52569 -1.871726)
		(size 0.508)
		(drill 0.254)
		(layers "F.Cu" "B.Cu")
		(net "GND")
	)
	(via
		(at 39.247318 -130.538474)
		(size 0.49022)
		(drill 0.254)
		(layers "F.Cu" "B.Cu")
		(net "GND")
	)
	(via
		(at 146.018504 -146.20875)
		(size 0.508)
		(drill 0.254)
		(layers "F.Cu" "B.Cu")
		(net "GND")
	)
	(via
		(at 37.885878 -15.24254)
		(size 0.508)
		(drill 0.254)
		(layers "F.Cu" "B.Cu")
		(net "GND")
	)
	(via
		(at 13.619988 -129.356104)
		(size 0.508)
		(drill 0.254)
		(layers "F.Cu" "B.Cu")
		(net "GND")
	)
	(via
		(at 46.96968 -129.191004)
		(size 0.49022)
		(drill 0.254)
		(layers "F.Cu" "B.Cu")
		(net "GND")
	)
	(via
		(at 77.77988 -121.18975)
		(size 0.508)
		(drill 0.254)
		(layers "F.Cu" "B.Cu")
		(net "GND")
	)
	(via
		(at 63.618364 -87.472774)
		(size 0.508)
		(drill 0.254)
		(layers "F.Cu" "B.Cu")
		(net "GND")
	)
	(via
		(at 119.7483 -187.037472)
		(size 0.508)
		(drill 0.254)
		(layers "F.Cu" "B.Cu")
		(net "GND")
	)
	(via
		(at 135.584438 -45.914056)
		(size 0.508)
		(drill 0.254)
		(layers "F.Cu" "B.Cu")
		(net "GND")
	)
	(via
		(at 68.006214 -124.868432)
		(size 0.508)
		(drill 0.254)
		(layers "F.Cu" "B.Cu")
		(net "GND")
	)
	(via
		(at 16.953738 -118.456202)
		(size 0.508)
		(drill 0.254)
		(layers "F.Cu" "B.Cu")
		(net "GND")
	)
	(via
		(at 71.91756 -87.904828)
		(size 0.508)
		(drill 0.254)
		(layers "F.Cu" "B.Cu")
		(net "GND")
	)
	(via
		(at 156.186886 -170.672252)
		(size 0.508)
		(drill 0.254)
		(layers "F.Cu" "B.Cu")
		(net "GND")
	)
	(via
		(at 55.600346 -78.599792)
		(size 0.508)
		(drill 0.254)
		(layers "F.Cu" "B.Cu")
		(net "GND")
	)
	(via
		(at 74.874374 -78.686152)
		(size 0.508)
		(drill 0.254)
		(layers "F.Cu" "B.Cu")
		(net "GND")
	)
	(via
		(at 170.06316 -102.306882)
		(size 0.508)
		(drill 0.254)
		(layers "F.Cu" "B.Cu")
		(net "GND")
	)
	(via
		(at 137.017252 -63.582042)
		(size 0.508)
		(drill 0.254)
		(layers "F.Cu" "B.Cu")
		(net "GND")
	)
	(via
		(at 134.782052 -137.03935)
		(size 0.508)
		(drill 0.254)
		(layers "F.Cu" "B.Cu")
		(net "GND")
	)
	(via
		(at 66.540888 -137.258298)
		(size 0.49022)
		(drill 0.254)
		(layers "F.Cu" "B.Cu")
		(net "GND")
	)
	(via
		(at 141.419834 -115.863624)
		(size 0.508)
		(drill 0.254)
		(layers "F.Cu" "B.Cu")
		(net "GND")
	)
	(via
		(at 41.533572 -61.972698)
		(size 0.508)
		(drill 0.254)
		(layers "F.Cu" "B.Cu")
		(net "GND")
	)
	(via
		(at 60.850526 -65.440306)
		(size 0.508)
		(drill 0.254)
		(layers "F.Cu" "B.Cu")
		(net "GND")
	)
	(via
		(at 21.19757 -124.96419)
		(size 0.508)
		(drill 0.254)
		(layers "F.Cu" "B.Cu")
		(net "GND")
	)
	(via
		(at 103.10622 -104.492044)
		(size 0.508)
		(drill 0.254)
		(layers "F.Cu" "B.Cu")
		(net "GND")
	)
	(via
		(at 102.3366 -112.989868)
		(size 0.508)
		(drill 0.254)
		(layers "F.Cu" "B.Cu")
		(net "GND")
	)
	(via
		(at 117.23116 -114.257582)
		(size 0.508)
		(drill 0.254)
		(layers "F.Cu" "B.Cu")
		(net "GND")
	)
	(via
		(at 72.142096 -126.85903)
		(size 0.49022)
		(drill 0.254)
		(layers "F.Cu" "B.Cu")
		(net "GND")
	)
	(via
		(at 80.506824 -121.623582)
		(size 0.508)
		(drill 0.254)
		(layers "F.Cu" "B.Cu")
		(net "GND")
	)
	(via
		(at 123.60656 -138.096498)
		(size 0.508)
		(drill 0.254)
		(layers "F.Cu" "B.Cu")
		(net "GND")
	)
	(via
		(at 81.98231 -83.241134)
		(size 0.508)
		(drill 0.254)
		(layers "F.Cu" "B.Cu")
		(net "GND")
	)
	(via
		(at 70.662546 -3.532632)
		(size 0.508)
		(drill 0.254)
		(layers "F.Cu" "B.Cu")
		(net "GND")
	)
	(via
		(at 101.14153 -157.053534)
		(size 0.508)
		(drill 0.254)
		(layers "F.Cu" "B.Cu")
		(net "GND")
	)
	(via
		(at 43.47972 -165.610286)
		(size 0.508)
		(drill 0.254)
		(layers "F.Cu" "B.Cu")
		(net "GND")
	)
	(via
		(at 142.48384 -129.578354)
		(size 0.508)
		(drill 0.254)
		(layers "F.Cu" "B.Cu")
		(net "GND")
	)
	(via
		(at 120.42902 -140.629386)
		(size 0.508)
		(drill 0.254)
		(layers "F.Cu" "B.Cu")
		(net "GND")
	)
	(via
		(at 124.725684 -52.706524)
		(size 0.508)
		(drill 0.254)
		(layers "F.Cu" "B.Cu")
		(net "GND")
	)
	(via
		(at 86.166706 -6.815328)
		(size 0.508)
		(drill 0.254)
		(layers "F.Cu" "B.Cu")
		(net "GND")
	)
	(via
		(at 107.30738 -164.554408)
		(size 0.508)
		(drill 0.254)
		(layers "F.Cu" "B.Cu")
		(net "GND")
	)
	(via
		(at 119.94134 -114.367818)
		(size 0.508)
		(drill 0.254)
		(layers "F.Cu" "B.Cu")
		(net "GND")
	)
	(via
		(at 116.539772 -31.00451)
		(size 0.508)
		(drill 0.254)
		(layers "F.Cu" "B.Cu")
		(net "GND")
	)
	(via
		(at 195.86194 -146.975322)
		(size 0.508)
		(drill 0.254)
		(layers "F.Cu" "B.Cu")
		(net "GND")
	)
	(via
		(at 93.671898 -120.141492)
		(size 0.508)
		(drill 0.254)
		(layers "F.Cu" "B.Cu")
		(net "GND")
	)
	(via
		(at 172.701458 -13.685774)
		(size 0.508)
		(drill 0.254)
		(layers "F.Cu" "B.Cu")
		(net "GND")
	)
	(via
		(at 66.540888 -142.857474)
		(size 0.49022)
		(drill 0.254)
		(layers "F.Cu" "B.Cu")
		(net "GND")
	)
	(via
		(at 57.3024 -16.844518)
		(size 0.508)
		(drill 0.254)
		(layers "F.Cu" "B.Cu")
		(net "GND")
	)
	(via
		(at 150.623016 -186.858148)
		(size 0.508)
		(drill 0.254)
		(layers "F.Cu" "B.Cu")
		(net "GND")
	)
	(via
		(at 103.1748 -106.10977)
		(size 0.508)
		(drill 0.254)
		(layers "F.Cu" "B.Cu")
		(net "GND")
	)
	(via
		(at 169.4942 -47.780448)
		(size 0.508)
		(drill 0.254)
		(layers "F.Cu" "B.Cu")
		(net "GND")
	)
	(via
		(at 74.542142 -142.859506)
		(size 0.49022)
		(drill 0.254)
		(layers "F.Cu" "B.Cu")
		(net "GND")
	)
	(via
		(at 65.38976 -186.954414)
		(size 0.508)
		(drill 0.254)
		(layers "F.Cu" "B.Cu")
		(net "GND")
	)
	(via
		(at 59.359038 -89.906094)
		(size 0.508)
		(drill 0.254)
		(layers "F.Cu" "B.Cu")
		(net "GND")
	)
	(via
		(at 20.15744 -11.695176)
		(size 0.508)
		(drill 0.254)
		(layers "F.Cu" "B.Cu")
		(net "GND")
	)
	(via
		(at 68.68922 -169.056304)
		(size 0.508)
		(drill 0.254)
		(layers "F.Cu" "B.Cu")
		(net "GND")
	)
	(via
		(at 44.479972 -69.668898)
		(size 0.508)
		(drill 0.254)
		(layers "F.Cu" "B.Cu")
		(net "GND")
	)
	(via
		(at 45.282612 -179.317904)
		(size 0.508)
		(drill 0.254)
		(layers "F.Cu" "B.Cu")
		(net "GND")
	)
	(via
		(at 67.340988 -127.658114)
		(size 0.49022)
		(drill 0.254)
		(layers "F.Cu" "B.Cu")
		(net "GND")
	)
	(via
		(at 149.10816 -174.807372)
		(size 0.508)
		(drill 0.254)
		(layers "F.Cu" "B.Cu")
		(net "GND")
	)
	(via
		(at 44.323 -97.379282)
		(size 0.508)
		(drill 0.254)
		(layers "F.Cu" "B.Cu")
		(net "GND")
	)
	(via
		(at 143.367252 -186.906662)
		(size 0.508)
		(drill 0.254)
		(layers "F.Cu" "B.Cu")
		(net "GND")
	)
	(via
		(at 46.423834 -107.699302)
		(size 0.508)
		(drill 0.254)
		(layers "F.Cu" "B.Cu")
		(net "GND")
	)
	(via
		(at 129.403856 -114.36731)
		(size 0.508)
		(drill 0.254)
		(layers "F.Cu" "B.Cu")
		(net "GND")
	)
	(via
		(at 136.075166 -121.064528)
		(size 0.508)
		(drill 0.254)
		(layers "F.Cu" "B.Cu")
		(net "GND")
	)
	(via
		(at 42.450258 -30.633162)
		(size 0.508)
		(drill 0.254)
		(layers "F.Cu" "B.Cu")
		(net "GND")
	)
	(via
		(at 14.48816 -18.648934)
		(size 0.508)
		(drill 0.254)
		(layers "F.Cu" "B.Cu")
		(net "GND")
	)
	(via
		(at 155.105354 -171.489624)
		(size 0.508)
		(drill 0.254)
		(layers "F.Cu" "B.Cu")
		(net "GND")
	)
	(via
		(at 27.75204 -164.843206)
		(size 0.508)
		(drill 0.254)
		(layers "F.Cu" "B.Cu")
		(net "GND")
	)
	(via
		(at 129.93624 -130.503168)
		(size 0.508)
		(drill 0.254)
		(layers "F.Cu" "B.Cu")
		(net "GND")
	)
	(via
		(at 56.245252 -99.22637)
		(size 0.508)
		(drill 0.254)
		(layers "F.Cu" "B.Cu")
		(net "GND")
	)
	(via
		(at 140.090652 -144.40535)
		(size 0.508)
		(drill 0.254)
		(layers "F.Cu" "B.Cu")
		(net "GND")
	)
	(via
		(at 144.502632 -186.914282)
		(size 0.508)
		(drill 0.254)
		(layers "F.Cu" "B.Cu")
		(net "GND")
	)
	(via
		(at 158.614872 -150.683214)
		(size 0.508)
		(drill 0.254)
		(layers "F.Cu" "B.Cu")
		(net "GND")
	)
	(via
		(at 153.561796 -68.27393)
		(size 0.508)
		(drill 0.254)
		(layers "F.Cu" "B.Cu")
		(net "GND")
	)
	(via
		(at 48.06569 -1.871726)
		(size 0.508)
		(drill 0.254)
		(layers "F.Cu" "B.Cu")
		(net "GND")
	)
	(via
		(at 182.893208 -157.60192)
		(size 0.508)
		(drill 0.254)
		(layers "F.Cu" "B.Cu")
		(net "GND")
	)
	(via
		(at 34.346896 -82.179922)
		(size 0.508)
		(drill 0.254)
		(layers "F.Cu" "B.Cu")
		(net "GND")
	)
	(via
		(at 141.470634 -117.006624)
		(size 0.508)
		(drill 0.254)
		(layers "F.Cu" "B.Cu")
		(net "GND")
	)
	(via
		(at 74.542142 -135.659368)
		(size 0.49022)
		(drill 0.254)
		(layers "F.Cu" "B.Cu")
		(net "GND")
	)
	(via
		(at 70.583044 -69.237098)
		(size 0.508)
		(drill 0.254)
		(layers "F.Cu" "B.Cu")
		(net "GND")
	)
	(via
		(at 35.86226 -151.81199)
		(size 0.508)
		(drill 0.254)
		(layers "F.Cu" "B.Cu")
		(net "GND")
	)
	(via
		(at 115.25885 -152.555956)
		(size 0.508)
		(drill 0.254)
		(layers "F.Cu" "B.Cu")
		(net "GND")
	)
	(via
		(at 133.893052 -134.49935)
		(size 0.508)
		(drill 0.254)
		(layers "F.Cu" "B.Cu")
		(net "GND")
	)
	(via
		(at 40.24122 -144.382998)
		(size 0.508)
		(drill 0.254)
		(layers "F.Cu" "B.Cu")
		(net "GND")
	)
	(via
		(at 13.93444 -4.305808)
		(size 0.508)
		(drill 0.254)
		(layers "F.Cu" "B.Cu")
		(net "GND")
	)
	(via
		(at 174.429674 -104.990646)
		(size 0.508)
		(drill 0.254)
		(layers "F.Cu" "B.Cu")
		(net "GND")
	)
	(via
		(at 157.130242 -27.665172)
		(size 0.508)
		(drill 0.254)
		(layers "F.Cu" "B.Cu")
		(net "GND")
	)
	(via
		(at 90.01506 -200.734676)
		(size 0.508)
		(drill 0.254)
		(layers "F.Cu" "B.Cu")
		(net "GND")
	)
	(via
		(at 73.930764 -150.644352)
		(size 0.508)
		(drill 0.254)
		(layers "F.Cu" "B.Cu")
		(net "GND")
	)
	(via
		(at 169.243248 -106.106468)
		(size 0.508)
		(drill 0.254)
		(layers "F.Cu" "B.Cu")
		(net "GND")
	)
	(via
		(at 180.561742 -143.06042)
		(size 0.508)
		(drill 0.254)
		(layers "F.Cu" "B.Cu")
		(net "GND")
	)
	(via
		(at 35.408108 -130.481578)
		(size 0.508)
		(drill 0.254)
		(layers "F.Cu" "B.Cu")
		(net "GND")
	)
	(via
		(at 93.435932 -167.023542)
		(size 0.508)
		(drill 0.254)
		(layers "F.Cu" "B.Cu")
		(net "GND")
	)
	(via
		(at 55.988712 -147.388834)
		(size 0.508)
		(drill 0.254)
		(layers "F.Cu" "B.Cu")
		(net "GND")
	)
	(via
		(at 30.82544 -119.895112)
		(size 0.508)
		(drill 0.254)
		(layers "F.Cu" "B.Cu")
		(net "GND")
	)
	(via
		(at 120.180862 -158.102554)
		(size 0.508)
		(drill 0.254)
		(layers "F.Cu" "B.Cu")
		(net "GND")
	)
	(via
		(at 170.110912 -118.880128)
		(size 0.508)
		(drill 0.254)
		(layers "F.Cu" "B.Cu")
		(net "GND")
	)
	(via
		(at 21.19757 -124.32919)
		(size 0.508)
		(drill 0.254)
		(layers "F.Cu" "B.Cu")
		(net "GND")
	)
	(via
		(at 117.422676 -21.655786)
		(size 0.508)
		(drill 0.254)
		(layers "F.Cu" "B.Cu")
		(net "GND")
	)
	(via
		(at 131.937252 -137.92835)
		(size 0.508)
		(drill 0.254)
		(layers "F.Cu" "B.Cu")
		(net "GND")
	)
	(via
		(at 69.039994 -77.041502)
		(size 0.508)
		(drill 0.254)
		(layers "F.Cu" "B.Cu")
		(net "GND")
	)
	(via
		(at 46.834044 -140.565124)
		(size 0.49022)
		(drill 0.254)
		(layers "F.Cu" "B.Cu")
		(net "GND")
	)
	(via
		(at 194.79768 -143.27632)
		(size 0.508)
		(drill 0.254)
		(layers "F.Cu" "B.Cu")
		(net "GND")
	)
	(via
		(at 32.569404 -105.13695)
		(size 0.508)
		(drill 0.254)
		(layers "F.Cu" "B.Cu")
		(net "GND")
	)
	(via
		(at 50.675286 -70.635876)
		(size 0.508)
		(drill 0.254)
		(layers "F.Cu" "B.Cu")
		(net "GND")
	)
	(via
		(at 120.492774 -31.82874)
		(size 0.508)
		(drill 0.254)
		(layers "F.Cu" "B.Cu")
		(net "GND")
	)
	(via
		(at 143.427704 -64.438022)
		(size 0.508)
		(drill 0.254)
		(layers "F.Cu" "B.Cu")
		(net "GND")
	)
	(via
		(at 11.26744 -105.38841)
		(size 0.508)
		(drill 0.254)
		(layers "F.Cu" "B.Cu")
		(net "GND")
	)
	(via
		(at 122.85599 -120.274588)
		(size 0.508)
		(drill 0.254)
		(layers "F.Cu" "B.Cu")
		(net "GND")
	)
	(via
		(at 148.937726 -148.793454)
		(size 0.508)
		(drill 0.254)
		(layers "F.Cu" "B.Cu")
		(net "GND")
	)
	(via
		(at 94.9579 -126.13259)
		(size 0.508)
		(drill 0.254)
		(layers "F.Cu" "B.Cu")
		(net "GND")
	)
	(via
		(at 48.054768 -61.737494)
		(size 0.508)
		(drill 0.254)
		(layers "F.Cu" "B.Cu")
		(net "GND")
	)
	(via
		(at 92.0242 -25.063196)
		(size 0.508)
		(drill 0.254)
		(layers "F.Cu" "B.Cu")
		(net "GND")
	)
	(via
		(at 179.9463 -176.654206)
		(size 0.508)
		(drill 0.254)
		(layers "F.Cu" "B.Cu")
		(net "GND")
	)
	(via
		(at 80.701388 -156.120084)
		(size 0.508)
		(drill 0.254)
		(layers "F.Cu" "B.Cu")
		(net "GND")
	)
	(via
		(at 167.279828 -56.543956)
		(size 0.508)
		(drill 0.254)
		(layers "F.Cu" "B.Cu")
		(net "GND")
	)
	(via
		(at 145.95983 -148.21535)
		(size 0.508)
		(drill 0.254)
		(layers "F.Cu" "B.Cu")
		(net "GND")
	)
	(via
		(at 168.015666 -201.034904)
		(size 0.508)
		(drill 0.254)
		(layers "F.Cu" "B.Cu")
		(net "GND")
	)
	(via
		(at 130.047238 -52.76342)
		(size 0.508)
		(drill 0.254)
		(layers "F.Cu" "B.Cu")
		(net "GND")
	)
	(via
		(at 109.25556 -169.07764)
		(size 0.508)
		(drill 0.254)
		(layers "F.Cu" "B.Cu")
		(net "GND")
	)
	(via
		(at 56.784494 -142.61465)
		(size 0.508)
		(drill 0.254)
		(layers "F.Cu" "B.Cu")
		(net "GND")
	)
	(via
		(at 4.336034 -167.373554)
		(size 0.508)
		(drill 0.254)
		(layers "F.Cu" "B.Cu")
		(net "GND")
	)
	(via
		(at 67.3862 -178.341274)
		(size 0.508)
		(drill 0.254)
		(layers "F.Cu" "B.Cu")
		(net "GND")
	)
	(via
		(at 73.449434 -168.124632)
		(size 0.508)
		(drill 0.254)
		(layers "F.Cu" "B.Cu")
		(net "GND")
	)
	(via
		(at 104.22001 -156.154628)
		(size 0.508)
		(drill 0.254)
		(layers "F.Cu" "B.Cu")
		(net "GND")
	)
	(via
		(at 42.536618 -61.783468)
		(size 0.508)
		(drill 0.254)
		(layers "F.Cu" "B.Cu")
		(net "GND")
	)
	(via
		(at 74.643742 -33.110678)
		(size 0.508)
		(drill 0.254)
		(layers "F.Cu" "B.Cu")
		(net "GND")
	)
	(via
		(at 61.015118 -200.32853)
		(size 0.508)
		(drill 0.254)
		(layers "F.Cu" "B.Cu")
		(net "GND")
	)
	(via
		(at 31.808166 -101.092254)
		(size 0.508)
		(drill 0.254)
		(layers "F.Cu" "B.Cu")
		(net "GND")
	)
	(via
		(at 20.62734 -66.379598)
		(size 0.508)
		(drill 0.254)
		(layers "F.Cu" "B.Cu")
		(net "GND")
	)
	(via
		(at 167.93464 -59.81319)
		(size 0.508)
		(drill 0.254)
		(layers "F.Cu" "B.Cu")
		(net "GND")
	)
	(via
		(at 60.312554 -165.801294)
		(size 0.508)
		(drill 0.254)
		(layers "F.Cu" "B.Cu")
		(net "GND")
	)
	(via
		(at 64.141096 -137.258298)
		(size 0.49022)
		(drill 0.254)
		(layers "F.Cu" "B.Cu")
		(net "GND")
	)
	(via
		(at 75.07224 -13.438378)
		(size 0.508)
		(drill 0.254)
		(layers "F.Cu" "B.Cu")
		(net "GND")
	)
	(via
		(at 45.128688 -90.958162)
		(size 0.508)
		(drill 0.254)
		(layers "F.Cu" "B.Cu")
		(net "GND")
	)
	(via
		(at 146.271996 -71.72833)
		(size 0.508)
		(drill 0.254)
		(layers "F.Cu" "B.Cu")
		(net "GND")
	)
	(via
		(at 77.142086 -124.295662)
		(size 0.508)
		(drill 0.254)
		(layers "F.Cu" "B.Cu")
		(net "GND")
	)
	(via
		(at 146.831304 -62.660022)
		(size 0.508)
		(drill 0.254)
		(layers "F.Cu" "B.Cu")
		(net "GND")
	)
	(via
		(at 106.425492 -73.627234)
		(size 0.508)
		(drill 0.254)
		(layers "F.Cu" "B.Cu")
		(net "GND")
	)
	(via
		(at 43.744896 -13.106654)
		(size 0.508)
		(drill 0.254)
		(layers "F.Cu" "B.Cu")
		(net "GND")
	)
	(via
		(at 151.506936 -148.057362)
		(size 0.508)
		(drill 0.254)
		(layers "F.Cu" "B.Cu")
		(net "GND")
	)
	(via
		(at 59.73826 -24.61387)
		(size 0.508)
		(drill 0.254)
		(layers "F.Cu" "B.Cu")
		(net "GND")
	)
	(via
		(at 45.84954 -59.259978)
		(size 0.508)
		(drill 0.254)
		(layers "F.Cu" "B.Cu")
		(net "GND")
	)
	(via
		(at 64.940942 -142.057628)
		(size 0.49022)
		(drill 0.254)
		(layers "F.Cu" "B.Cu")
		(net "GND")
	)
	(via
		(at 103.044752 -64.409574)
		(size 0.508)
		(drill 0.254)
		(layers "F.Cu" "B.Cu")
		(net "GND")
	)
	(via
		(at 113.306352 -22.900386)
		(size 0.508)
		(drill 0.254)
		(layers "F.Cu" "B.Cu")
		(net "GND")
	)
	(via
		(at 79.10068 -63.55842)
		(size 0.508)
		(drill 0.254)
		(layers "F.Cu" "B.Cu")
		(net "GND")
	)
	(via
		(at 67.340988 -137.258298)
		(size 0.49022)
		(drill 0.254)
		(layers "F.Cu" "B.Cu")
		(net "GND")
	)
	(via
		(at 154.197558 -143.99641)
		(size 0.508)
		(drill 0.254)
		(layers "F.Cu" "B.Cu")
		(net "GND")
	)
	(via
		(at 12.60475 -122.166888)
		(size 0.508)
		(drill 0.254)
		(layers "F.Cu" "B.Cu")
		(net "GND")
	)
	(via
		(at 175.95088 -170.31716)
		(size 0.508)
		(drill 0.254)
		(layers "F.Cu" "B.Cu")
		(net "GND")
	)
	(via
		(at 104.391206 -165.851078)
		(size 0.508)
		(drill 0.254)
		(layers "F.Cu" "B.Cu")
		(net "GND")
	)
	(via
		(at 146.161252 -138.53795)
		(size 0.508)
		(drill 0.254)
		(layers "F.Cu" "B.Cu")
		(net "GND")
	)
	(via
		(at 25.391872 -93.39707)
		(size 0.508)
		(drill 0.254)
		(layers "F.Cu" "B.Cu")
		(net "GND")
	)
	(via
		(at 104.71404 -122.651774)
		(size 0.508)
		(drill 0.254)
		(layers "F.Cu" "B.Cu")
		(net "GND")
	)
	(via
		(at 92.72778 -167.14851)
		(size 0.508)
		(drill 0.254)
		(layers "F.Cu" "B.Cu")
		(net "GND")
	)
	(via
		(at 76.80198 -24.18461)
		(size 0.508)
		(drill 0.254)
		(layers "F.Cu" "B.Cu")
		(net "GND")
	)
	(via
		(at 103.564182 -126.182374)
		(size 0.508)
		(drill 0.254)
		(layers "F.Cu" "B.Cu")
		(net "GND")
	)
	(via
		(at 57.40146 -5.389626)
		(size 0.508)
		(drill 0.254)
		(layers "F.Cu" "B.Cu")
		(net "GND")
	)
	(via
		(at 153.761948 -154.790902)
		(size 0.508)
		(drill 0.254)
		(layers "F.Cu" "B.Cu")
		(net "GND")
	)
	(via
		(at 45.784516 -78.908402)
		(size 0.508)
		(drill 0.254)
		(layers "F.Cu" "B.Cu")
		(net "GND")
	)
	(via
		(at 51.014884 -201.09053)
		(size 0.508)
		(drill 0.254)
		(layers "F.Cu" "B.Cu")
		(net "GND")
	)
	(via
		(at 97.188528 -134.701788)
		(size 0.508)
		(drill 0.254)
		(layers "F.Cu" "B.Cu")
		(net "GND")
	)
	(via
		(at 43.000422 -142.838932)
		(size 0.508)
		(drill 0.254)
		(layers "F.Cu" "B.Cu")
		(net "GND")
	)
	(via
		(at 46.750732 -95.625666)
		(size 0.508)
		(drill 0.254)
		(layers "F.Cu" "B.Cu")
		(net "GND")
	)
	(via
		(at 167.326818 -38.357302)
		(size 0.508)
		(drill 0.254)
		(layers "F.Cu" "B.Cu")
		(net "GND")
	)
	(via
		(at 107.365292 -62.052454)
		(size 0.508)
		(drill 0.254)
		(layers "F.Cu" "B.Cu")
		(net "GND")
	)
	(via
		(at 151.309578 -56.13273)
		(size 0.508)
		(drill 0.254)
		(layers "F.Cu" "B.Cu")
		(net "GND")
	)
	(via
		(at 33.1089 -34.078418)
		(size 0.508)
		(drill 0.254)
		(layers "F.Cu" "B.Cu")
		(net "GND")
	)
	(via
		(at 113.352072 -17.544796)
		(size 0.508)
		(drill 0.254)
		(layers "F.Cu" "B.Cu")
		(net "GND")
	)
	(via
		(at 79.414624 -154.147774)
		(size 0.508)
		(drill 0.254)
		(layers "F.Cu" "B.Cu")
		(net "GND")
	)
	(via
		(at 139.075922 -36.42741)
		(size 0.508)
		(drill 0.254)
		(layers "F.Cu" "B.Cu")
		(net "GND")
	)
	(via
		(at 52.531518 -91.153996)
		(size 0.508)
		(drill 0.254)
		(layers "F.Cu" "B.Cu")
		(net "GND")
	)
	(via
		(at 85.678264 -93.410532)
		(size 0.508)
		(drill 0.254)
		(layers "F.Cu" "B.Cu")
		(net "GND")
	)
	(via
		(at 48.24476 -186.862974)
		(size 0.508)
		(drill 0.254)
		(layers "F.Cu" "B.Cu")
		(net "GND")
	)
	(via
		(at 165.120066 -109.293406)
		(size 0.508)
		(drill 0.254)
		(layers "F.Cu" "B.Cu")
		(net "GND")
	)
	(via
		(at 115.3541 -63.259462)
		(size 0.508)
		(drill 0.254)
		(layers "F.Cu" "B.Cu")
		(net "GND")
	)
	(via
		(at 46.269402 -173.87697)
		(size 0.508)
		(drill 0.254)
		(layers "F.Cu" "B.Cu")
		(net "GND")
	)
	(via
		(at 28.607258 -136.321038)
		(size 0.508)
		(drill 0.254)
		(layers "F.Cu" "B.Cu")
		(net "GND")
	)
	(via
		(at 141.927072 -48.570642)
		(size 0.508)
		(drill 0.254)
		(layers "F.Cu" "B.Cu")
		(net "GND")
	)
	(via
		(at 104.326182 -126.944374)
		(size 0.508)
		(drill 0.254)
		(layers "F.Cu" "B.Cu")
		(net "GND")
	)
	(via
		(at 151.10968 -31.33598)
		(size 0.508)
		(drill 0.254)
		(layers "F.Cu" "B.Cu")
		(net "GND")
	)
	(via
		(at 102.933246 -154.182318)
		(size 0.508)
		(drill 0.254)
		(layers "F.Cu" "B.Cu")
		(net "GND")
	)
	(via
		(at 68.355718 -89.630504)
		(size 0.508)
		(drill 0.254)
		(layers "F.Cu" "B.Cu")
		(net "GND")
	)
	(via
		(at 63.40856 -153.039826)
		(size 0.508)
		(drill 0.254)
		(layers "F.Cu" "B.Cu")
		(net "GND")
	)
	(via
		(at 39.35603 -136.165082)
		(size 0.49022)
		(drill 0.254)
		(layers "F.Cu" "B.Cu")
		(net "GND")
	)
	(via
		(at 21.83257 -125.59919)
		(size 0.508)
		(drill 0.254)
		(layers "F.Cu" "B.Cu")
		(net "GND")
	)
	(via
		(at 158.521654 -75.31735)
		(size 0.508)
		(drill 0.254)
		(layers "F.Cu" "B.Cu")
		(net "GND")
	)
	(via
		(at 55.12816 -26.192734)
		(size 0.508)
		(drill 0.254)
		(layers "F.Cu" "B.Cu")
		(net "GND")
	)
	(via
		(at 52.8447 -134.336282)
		(size 0.49022)
		(drill 0.254)
		(layers "F.Cu" "B.Cu")
		(net "GND")
	)
	(via
		(at 21.83257 -124.96419)
		(size 0.508)
		(drill 0.254)
		(layers "F.Cu" "B.Cu")
		(net "GND")
	)
	(via
		(at 61.279532 -81.057242)
		(size 0.508)
		(drill 0.254)
		(layers "F.Cu" "B.Cu")
		(net "GND")
	)
	(via
		(at 35.39871 -131.225544)
		(size 0.508)
		(drill 0.254)
		(layers "F.Cu" "B.Cu")
		(net "GND")
	)
	(via
		(at 72.142096 -140.459206)
		(size 0.49022)
		(drill 0.254)
		(layers "F.Cu" "B.Cu")
		(net "GND")
	)
	(via
		(at 141.007592 -186.838082)
		(size 0.508)
		(drill 0.254)
		(layers "F.Cu" "B.Cu")
		(net "GND")
	)
	(via
		(at 118.376446 -171.533058)
		(size 0.508)
		(drill 0.254)
		(layers "F.Cu" "B.Cu")
		(net "GND")
	)
	(via
		(at 62.646306 -153.867612)
		(size 0.508)
		(drill 0.254)
		(layers "F.Cu" "B.Cu")
		(net "GND")
	)
	(via
		(at 45.150278 -22.420834)
		(size 0.508)
		(drill 0.254)
		(layers "F.Cu" "B.Cu")
		(net "GND")
	)
	(via
		(at 167.94226 -62.50559)
		(size 0.508)
		(drill 0.254)
		(layers "F.Cu" "B.Cu")
		(net "GND")
	)
	(via
		(at 81.06029 -150.217378)
		(size 0.508)
		(drill 0.254)
		(layers "F.Cu" "B.Cu")
		(net "GND")
	)
	(via
		(at 49.20869 -67.527678)
		(size 0.508)
		(drill 0.254)
		(layers "F.Cu" "B.Cu")
		(net "GND")
	)
	(via
		(at 145.65376 -183.909462)
		(size 0.508)
		(drill 0.254)
		(layers "F.Cu" "B.Cu")
		(net "GND")
	)
	(via
		(at 151.60244 -183.749188)
		(size 0.508)
		(drill 0.254)
		(layers "F.Cu" "B.Cu")
		(net "GND")
	)
	(via
		(at 105.397046 -19.123914)
		(size 0.508)
		(drill 0.254)
		(layers "F.Cu" "B.Cu")
		(net "GND")
	)
	(via
		(at 138.338052 -152.53335)
		(size 0.508)
		(drill 0.254)
		(layers "F.Cu" "B.Cu")
		(net "GND")
	)
	(via
		(at 71.616316 -64.919352)
		(size 0.508)
		(drill 0.254)
		(layers "F.Cu" "B.Cu")
		(net "GND")
	)
	(via
		(at 62.003686 -70.610984)
		(size 0.508)
		(drill 0.254)
		(layers "F.Cu" "B.Cu")
		(net "GND")
	)
	(via
		(at 118.29542 -114.257582)
		(size 0.508)
		(drill 0.254)
		(layers "F.Cu" "B.Cu")
		(net "GND")
	)
	(via
		(at 68.042282 -82.762598)
		(size 0.508)
		(drill 0.254)
		(layers "F.Cu" "B.Cu")
		(net "GND")
	)
	(via
		(at 170.03776 -103.754682)
		(size 0.508)
		(drill 0.254)
		(layers "F.Cu" "B.Cu")
		(net "GND")
	)
	(via
		(at 76.975462 -16.044418)
		(size 0.508)
		(drill 0.254)
		(layers "F.Cu" "B.Cu")
		(net "GND")
	)
	(via
		(at 118.542308 -120.77192)
		(size 0.508)
		(drill 0.254)
		(layers "F.Cu" "B.Cu")
		(net "GND")
	)
	(via
		(at 80.55102 -166.021512)
		(size 0.508)
		(drill 0.254)
		(layers "F.Cu" "B.Cu")
		(net "GND")
	)
	(via
		(at 103.564182 -126.944374)
		(size 0.508)
		(drill 0.254)
		(layers "F.Cu" "B.Cu")
		(net "GND")
	)
	(via
		(at 83.54822 -155.369514)
		(size 0.508)
		(drill 0.254)
		(layers "F.Cu" "B.Cu")
		(net "GND")
	)
	(via
		(at 48.785526 -112.992408)
		(size 0.508)
		(drill 0.254)
		(layers "F.Cu" "B.Cu")
		(net "GND")
	)
	(via
		(at 72.142096 -143.659352)
		(size 0.49022)
		(drill 0.254)
		(layers "F.Cu" "B.Cu")
		(net "GND")
	)
	(via
		(at 23.230332 -130.010662)
		(size 0.508)
		(drill 0.254)
		(layers "F.Cu" "B.Cu")
		(net "GND")
	)
	(via
		(at 82.56016 -121.952766)
		(size 0.508)
		(drill 0.254)
		(layers "F.Cu" "B.Cu")
		(net "GND")
	)
	(via
		(at 46.032928 -134.16407)
		(size 0.49022)
		(drill 0.254)
		(layers "F.Cu" "B.Cu")
		(net "GND")
	)
	(via
		(at 166.205408 -82.280252)
		(size 0.508)
		(drill 0.254)
		(layers "F.Cu" "B.Cu")
		(net "GND")
	)
	(via
		(at 77.900022 -16.044418)
		(size 0.508)
		(drill 0.254)
		(layers "F.Cu" "B.Cu")
		(net "GND")
	)
	(via
		(at 170.63974 -27.043888)
		(size 0.508)
		(drill 0.254)
		(layers "F.Cu" "B.Cu")
		(net "GND")
	)
	(via
		(at 54.891178 -162.046158)
		(size 0.508)
		(drill 0.254)
		(layers "F.Cu" "B.Cu")
		(net "GND")
	)
	(via
		(at 18.58772 -155.240736)
		(size 0.508)
		(drill 0.254)
		(layers "F.Cu" "B.Cu")
		(net "GND")
	)
	(via
		(at 115.26012 -74.272394)
		(size 0.508)
		(drill 0.254)
		(layers "F.Cu" "B.Cu")
		(net "GND")
	)
	(via
		(at 136.255252 -152.50795)
		(size 0.508)
		(drill 0.254)
		(layers "F.Cu" "B.Cu")
		(net "GND")
	)
	(via
		(at 81.015078 -201.09053)
		(size 0.508)
		(drill 0.254)
		(layers "F.Cu" "B.Cu")
		(net "GND")
	)
	(via
		(at 66.55689 -81.960466)
		(size 0.508)
		(drill 0.254)
		(layers "F.Cu" "B.Cu")
		(net "GND")
	)
	(via
		(at 51.178206 -85.396578)
		(size 0.508)
		(drill 0.254)
		(layers "F.Cu" "B.Cu")
		(net "GND")
	)
	(via
		(at 195.76034 -148.349716)
		(size 0.508)
		(drill 0.254)
		(layers "F.Cu" "B.Cu")
		(net "GND")
	)
	(via
		(at 73.742042 -141.25956)
		(size 0.49022)
		(drill 0.254)
		(layers "F.Cu" "B.Cu")
		(net "GND")
	)
	(via
		(at 67.996562 -22.706838)
		(size 0.508)
		(drill 0.254)
		(layers "F.Cu" "B.Cu")
		(net "GND")
	)
	(via
		(at 98.8949 -180.667152)
		(size 0.508)
		(drill 0.254)
		(layers "F.Cu" "B.Cu")
		(net "GND")
	)
	(via
		(at 126.661164 -165.865048)
		(size 0.508)
		(drill 0.254)
		(layers "F.Cu" "B.Cu")
		(net "GND")
	)
	(via
		(at 75.916282 -16.044418)
		(size 0.508)
		(drill 0.254)
		(layers "F.Cu" "B.Cu")
		(net "GND")
	)
	(via
		(at 103.15956 -107.890564)
		(size 0.508)
		(drill 0.254)
		(layers "F.Cu" "B.Cu")
		(net "GND")
	)
	(via
		(at 109.45876 -186.91733)
		(size 0.508)
		(drill 0.254)
		(layers "F.Cu" "B.Cu")
		(net "GND")
	)
	(via
		(at 41.762172 -88.439498)
		(size 0.508)
		(drill 0.254)
		(layers "F.Cu" "B.Cu")
		(net "GND")
	)
	(via
		(at 152.015698 -201.034904)
		(size 0.508)
		(drill 0.254)
		(layers "F.Cu" "B.Cu")
		(net "GND")
	)
	(via
		(at 114.502692 -31.052516)
		(size 0.508)
		(drill 0.254)
		(layers "F.Cu" "B.Cu")
		(net "GND")
	)
	(via
		(at 28.787598 -127.52832)
		(size 0.508)
		(drill 0.254)
		(layers "F.Cu" "B.Cu")
		(net "GND")
	)
	(via
		(at 170.06316 -98.115882)
		(size 0.508)
		(drill 0.254)
		(layers "F.Cu" "B.Cu")
		(net "GND")
	)
	(via
		(at 97.369376 -150.028148)
		(size 0.508)
		(drill 0.254)
		(layers "F.Cu" "B.Cu")
		(net "GND")
	)
	(via
		(at 36.3601 -71.405242)
		(size 0.508)
		(drill 0.254)
		(layers "F.Cu" "B.Cu")
		(net "GND")
	)
	(via
		(at 157.92704 -133.849618)
		(size 0.508)
		(drill 0.254)
		(layers "F.Cu" "B.Cu")
		(net "GND")
	)
	(via
		(at 82.081116 -141.952218)
		(size 0.508)
		(drill 0.254)
		(layers "F.Cu" "B.Cu")
		(net "GND")
	)
	(via
		(at 136.290304 -62.736222)
		(size 0.508)
		(drill 0.254)
		(layers "F.Cu" "B.Cu")
		(net "GND")
	)
	(via
		(at 86.2584 -157.808422)
		(size 0.508)
		(drill 0.254)
		(layers "F.Cu" "B.Cu")
		(net "GND")
	)
	(via
		(at 90.70594 -83.61934)
		(size 0.508)
		(drill 0.254)
		(layers "F.Cu" "B.Cu")
		(net "GND")
	)
	(via
		(at 58.35015 -22.534626)
		(size 0.508)
		(drill 0.254)
		(layers "F.Cu" "B.Cu")
		(net "GND")
	)
	(via
		(at 56.2864 -16.844518)
		(size 0.508)
		(drill 0.254)
		(layers "F.Cu" "B.Cu")
		(net "GND")
	)
	(via
		(at 55.15229 -61.99759)
		(size 0.508)
		(drill 0.254)
		(layers "F.Cu" "B.Cu")
		(net "GND")
	)
	(via
		(at 33.77184 -139.70127)
		(size 0.508)
		(drill 0.254)
		(layers "F.Cu" "B.Cu")
		(net "GND")
	)
	(via
		(at 90.06332 -75.717654)
		(size 0.508)
		(drill 0.254)
		(layers "F.Cu" "B.Cu")
		(net "GND")
	)
	(via
		(at 93.711522 -128.614424)
		(size 0.508)
		(drill 0.254)
		(layers "F.Cu" "B.Cu")
		(net "GND")
	)
	(via
		(at 46.451266 -110.569248)
		(size 0.508)
		(drill 0.254)
		(layers "F.Cu" "B.Cu")
		(net "GND")
	)
	(via
		(at 24.84882 -16.893032)
		(size 0.508)
		(drill 0.254)
		(layers "F.Cu" "B.Cu")
		(net "GND")
	)
	(via
		(at 29.008578 -105.38714)
		(size 0.508)
		(drill 0.254)
		(layers "F.Cu" "B.Cu")
		(net "GND")
	)
	(via
		(at 32.12084 -63.54064)
		(size 0.508)
		(drill 0.254)
		(layers "F.Cu" "B.Cu")
		(net "GND")
	)
	(via
		(at 180.908706 -114.882422)
		(size 0.508)
		(drill 0.254)
		(layers "F.Cu" "B.Cu")
		(net "GND")
	)
	(via
		(at 141.837664 -53.513228)
		(size 0.508)
		(drill 0.254)
		(layers "F.Cu" "B.Cu")
		(net "GND")
	)
	(via
		(at 96.50476 -4.518406)
		(size 0.508)
		(drill 0.254)
		(layers "F.Cu" "B.Cu")
		(net "GND")
	)
	(via
		(at 43.609006 -185.14568)
		(size 0.508)
		(drill 0.254)
		(layers "F.Cu" "B.Cu")
		(net "GND")
	)
	(via
		(at 163.36518 -74.747628)
		(size 0.508)
		(drill 0.254)
		(layers "F.Cu" "B.Cu")
		(net "GND")
	)
	(via
		(at 18.381472 -73.128124)
		(size 0.508)
		(drill 0.254)
		(layers "F.Cu" "B.Cu")
		(net "GND")
	)
	(via
		(at 42.08526 -25.10409)
		(size 0.508)
		(drill 0.254)
		(layers "F.Cu" "B.Cu")
		(net "GND")
	)
	(via
		(at 156.741622 -180.128418)
		(size 0.508)
		(drill 0.254)
		(layers "F.Cu" "B.Cu")
		(net "GND")
	)
	(via
		(at 54.6354 -81.9658)
		(size 0.508)
		(drill 0.254)
		(layers "F.Cu" "B.Cu")
		(net "GND")
	)
	(via
		(at 42.750232 -22.456648)
		(size 0.508)
		(drill 0.254)
		(layers "F.Cu" "B.Cu")
		(net "GND")
	)
	(via
		(at 180.919374 -133.54939)
		(size 0.508)
		(drill 0.254)
		(layers "F.Cu" "B.Cu")
		(net "GND")
	)
	(via
		(at 9.108948 -156.731208)
		(size 0.508)
		(drill 0.254)
		(layers "F.Cu" "B.Cu")
		(net "GND")
	)
	(via
		(at 133.71576 -109.747558)
		(size 0.508)
		(drill 0.254)
		(layers "F.Cu" "B.Cu")
		(net "GND")
	)
	(via
		(at 117.015514 -201.034904)
		(size 0.508)
		(drill 0.254)
		(layers "F.Cu" "B.Cu")
		(net "GND")
	)
	(via
		(at 89.04732 -184.004458)
		(size 0.508)
		(drill 0.254)
		(layers "F.Cu" "B.Cu")
		(net "GND")
	)
	(via
		(at 34.57702 -77.63256)
		(size 0.508)
		(drill 0.254)
		(layers "F.Cu" "B.Cu")
		(net "GND")
	)
	(via
		(at 30.75432 -116.85524)
		(size 0.508)
		(drill 0.254)
		(layers "F.Cu" "B.Cu")
		(net "GND")
	)
	(via
		(at 14.261592 -134.825486)
		(size 0.508)
		(drill 0.254)
		(layers "F.Cu" "B.Cu")
		(net "GND")
	)
	(via
		(at 70.68947 -5.856478)
		(size 0.508)
		(drill 0.254)
		(layers "F.Cu" "B.Cu")
		(net "GND")
	)
	(via
		(at 72.824594 -89.577672)
		(size 0.508)
		(drill 0.254)
		(layers "F.Cu" "B.Cu")
		(net "GND")
	)
	(via
		(at 76.105766 -158.464758)
		(size 0.508)
		(drill 0.254)
		(layers "F.Cu" "B.Cu")
		(net "GND")
	)
	(via
		(at 178.228498 -53.881528)
		(size 0.508)
		(drill 0.254)
		(layers "F.Cu" "B.Cu")
		(net "GND")
	)
	(via
		(at 127.015494 -201.034904)
		(size 0.508)
		(drill 0.254)
		(layers "F.Cu" "B.Cu")
		(net "GND")
	)
	(via
		(at 133.969252 -152.48255)
		(size 0.508)
		(drill 0.254)
		(layers "F.Cu" "B.Cu")
		(net "GND")
	)
	(via
		(at 67.67576 -186.95162)
		(size 0.508)
		(drill 0.254)
		(layers "F.Cu" "B.Cu")
		(net "GND")
	)
	(via
		(at 29.008578 -106.14914)
		(size 0.508)
		(drill 0.254)
		(layers "F.Cu" "B.Cu")
		(net "GND")
	)
	(via
		(at 41.228518 -63.468758)
		(size 0.508)
		(drill 0.254)
		(layers "F.Cu" "B.Cu")
		(net "GND")
	)
	(via
		(at 112.76076 -186.862974)
		(size 0.508)
		(drill 0.254)
		(layers "F.Cu" "B.Cu")
		(net "GND")
	)
	(via
		(at 156.77769 -175.015144)
		(size 0.508)
		(drill 0.254)
		(layers "F.Cu" "B.Cu")
		(net "GND")
	)
	(via
		(at 190.37808 -167.226488)
		(size 0.508)
		(drill 0.254)
		(layers "F.Cu" "B.Cu")
		(net "GND")
	)
	(via
		(at 19.86026 -54.519068)
		(size 0.508)
		(drill 0.254)
		(layers "F.Cu" "B.Cu")
		(net "GND")
	)
	(via
		(at 170.42892 -19.573494)
		(size 0.508)
		(drill 0.254)
		(layers "F.Cu" "B.Cu")
		(net "GND")
	)
	(via
		(at 71.015098 -201.09053)
		(size 0.508)
		(drill 0.254)
		(layers "F.Cu" "B.Cu")
		(net "GND")
	)
	(via
		(at 43.51528 -61.874654)
		(size 0.508)
		(drill 0.254)
		(layers "F.Cu" "B.Cu")
		(net "GND")
	)
	(via
		(at 175.510444 -121.865644)
		(size 0.49022)
		(drill 0.254)
		(layers "F.Cu" "B.Cu")
		(net "GND")
	)
	(via
		(at 62.646306 -158.592012)
		(size 0.508)
		(drill 0.254)
		(layers "F.Cu" "B.Cu")
		(net "GND")
	)
	(via
		(at 130.33756 -116.769134)
		(size 0.508)
		(drill 0.254)
		(layers "F.Cu" "B.Cu")
		(net "GND")
	)
	(via
		(at 135.56996 -118.115334)
		(size 0.508)
		(drill 0.254)
		(layers "F.Cu" "B.Cu")
		(net "GND")
	)
	(via
		(at 177.51044 -118.86565)
		(size 0.49022)
		(drill 0.254)
		(layers "F.Cu" "B.Cu")
		(net "GND")
	)
	(via
		(at 131.93776 -114.889534)
		(size 0.508)
		(drill 0.254)
		(layers "F.Cu" "B.Cu")
		(net "GND")
	)
	(via
		(at 161.535872 -155.509214)
		(size 0.508)
		(drill 0.254)
		(layers "F.Cu" "B.Cu")
		(net "GND")
	)
	(via
		(at 67.531488 -10.358628)
		(size 0.508)
		(drill 0.254)
		(layers "F.Cu" "B.Cu")
		(net "GND")
	)
	(via
		(at 61.70041 -146.440906)
		(size 0.508)
		(drill 0.254)
		(layers "F.Cu" "B.Cu")
		(net "GND")
	)
	(via
		(at 142.64894 -127.98679)
		(size 0.508)
		(drill 0.254)
		(layers "F.Cu" "B.Cu")
		(net "GND")
	)
	(via
		(at 32.920178 -174.43069)
		(size 0.508)
		(drill 0.254)
		(layers "F.Cu" "B.Cu")
		(net "GND")
	)
	(via
		(at 32.27324 -116.85016)
		(size 0.508)
		(drill 0.254)
		(layers "F.Cu" "B.Cu")
		(net "GND")
	)
	(via
		(at 65.289684 -71.020178)
		(size 0.508)
		(drill 0.254)
		(layers "F.Cu" "B.Cu")
		(net "GND")
	)
	(via
		(at 110.85576 -184.07634)
		(size 0.508)
		(drill 0.254)
		(layers "F.Cu" "B.Cu")
		(net "GND")
	)
	(via
		(at 51.223418 -69.733668)
		(size 0.508)
		(drill 0.254)
		(layers "F.Cu" "B.Cu")
		(net "GND")
	)
	(via
		(at 126.71425 -55.161688)
		(size 0.508)
		(drill 0.254)
		(layers "F.Cu" "B.Cu")
		(net "GND")
	)
	(via
		(at 52.360576 -64.129158)
		(size 0.508)
		(drill 0.254)
		(layers "F.Cu" "B.Cu")
		(net "GND")
	)
	(via
		(at 64.34836 -184.080404)
		(size 0.508)
		(drill 0.254)
		(layers "F.Cu" "B.Cu")
		(net "GND")
	)
	(via
		(at 56.949086 -125.711712)
		(size 0.508)
		(drill 0.254)
		(layers "F.Cu" "B.Cu")
		(net "GND")
	)
	(via
		(at 167.284654 -58.36158)
		(size 0.508)
		(drill 0.254)
		(layers "F.Cu" "B.Cu")
		(net "GND")
	)
	(via
		(at 67.340988 -135.658352)
		(size 0.49022)
		(drill 0.254)
		(layers "F.Cu" "B.Cu")
		(net "GND")
	)
	(via
		(at 50.550064 -22.462236)
		(size 0.508)
		(drill 0.254)
		(layers "F.Cu" "B.Cu")
		(net "GND")
	)
	(via
		(at 89.737692 -161.011362)
		(size 0.508)
		(drill 0.254)
		(layers "F.Cu" "B.Cu")
		(net "GND")
	)
	(via
		(at 133.82625 -41.106852)
		(size 0.508)
		(drill 0.254)
		(layers "F.Cu" "B.Cu")
		(net "GND")
	)
	(via
		(at 164.11067 -124.97054)
		(size 0.508)
		(drill 0.254)
		(layers "F.Cu" "B.Cu")
		(net "GND")
	)
	(via
		(at 71.410068 -102.204266)
		(size 0.508)
		(drill 0.254)
		(layers "F.Cu" "B.Cu")
		(net "GND")
	)
	(via
		(at 110.276132 -31.057088)
		(size 0.508)
		(drill 0.254)
		(layers "F.Cu" "B.Cu")
		(net "GND")
	)
	(via
		(at 130.76428 -106.074718)
		(size 0.508)
		(drill 0.254)
		(layers "F.Cu" "B.Cu")
		(net "GND")
	)
	(via
		(at 179.47005 -188.06795)
		(size 0.508)
		(drill 0.254)
		(layers "F.Cu" "B.Cu")
		(net "GND")
	)
	(via
		(at 55.01386 -144.9959)
		(size 0.508)
		(drill 0.254)
		(layers "F.Cu" "B.Cu")
		(net "GND")
	)
	(via
		(at 50.542698 -89.696798)
		(size 0.508)
		(drill 0.254)
		(layers "F.Cu" "B.Cu")
		(net "GND")
	)
	(via
		(at 56.585358 -89.678764)
		(size 0.508)
		(drill 0.254)
		(layers "F.Cu" "B.Cu")
		(net "GND")
	)
	(via
		(at 52.58054 -153.027888)
		(size 0.508)
		(drill 0.254)
		(layers "F.Cu" "B.Cu")
		(net "GND")
	)
	(via
		(at 77.145388 -97.883218)
		(size 0.508)
		(drill 0.254)
		(layers "F.Cu" "B.Cu")
		(net "GND")
	)
	(via
		(at 44.491148 -74.659236)
		(size 0.508)
		(drill 0.254)
		(layers "F.Cu" "B.Cu")
		(net "GND")
	)
	(via
		(at 37.455094 -9.671812)
		(size 0.508)
		(drill 0.254)
		(layers "F.Cu" "B.Cu")
		(net "GND")
	)
	(via
		(at 128.084072 -154.59075)
		(size 0.508)
		(drill 0.254)
		(layers "F.Cu" "B.Cu")
		(net "GND")
	)
	(via
		(at 11.53414 -109.332776)
		(size 0.508)
		(drill 0.254)
		(layers "F.Cu" "B.Cu")
		(net "GND")
	)
	(via
		(at 118.19382 -103.712772)
		(size 0.508)
		(drill 0.254)
		(layers "F.Cu" "B.Cu")
		(net "GND")
	)
	(via
		(at 167.83558 -54.597554)
		(size 0.508)
		(drill 0.254)
		(layers "F.Cu" "B.Cu")
		(net "GND")
	)
	(via
		(at 97.17913 -140.758164)
		(size 0.508)
		(drill 0.254)
		(layers "F.Cu" "B.Cu")
		(net "GND")
	)
	(via
		(at 68.199508 -87.421974)
		(size 0.508)
		(drill 0.254)
		(layers "F.Cu" "B.Cu")
		(net "GND")
	)
	(via
		(at 66.015108 -201.09053)
		(size 0.508)
		(drill 0.254)
		(layers "F.Cu" "B.Cu")
		(net "GND")
	)
	(via
		(at 118.47576 -186.940698)
		(size 0.508)
		(drill 0.254)
		(layers "F.Cu" "B.Cu")
		(net "GND")
	)
	(via
		(at 41.088818 -72.959468)
		(size 0.508)
		(drill 0.254)
		(layers "F.Cu" "B.Cu")
		(net "GND")
	)
	(via
		(at 54.86019 -161.030158)
		(size 0.508)
		(drill 0.254)
		(layers "F.Cu" "B.Cu")
		(net "GND")
	)
	(via
		(at 128.243838 -99.182174)
		(size 0.508)
		(drill 0.254)
		(layers "F.Cu" "B.Cu")
		(net "GND")
	)
	(via
		(at 24.99614 -172.857414)
		(size 0.508)
		(drill 0.254)
		(layers "F.Cu" "B.Cu")
		(net "GND")
	)
	(via
		(at 42.121328 -157.336998)
		(size 0.508)
		(drill 0.254)
		(layers "F.Cu" "B.Cu")
		(net "GND")
	)
	(via
		(at 45.282612 -180.333904)
		(size 0.508)
		(drill 0.254)
		(layers "F.Cu" "B.Cu")
		(net "GND")
	)
	(via
		(at 93.07322 -185.790586)
		(size 0.508)
		(drill 0.254)
		(layers "F.Cu" "B.Cu")
		(net "GND")
	)
	(via
		(at 67.549776 -70.704202)
		(size 0.508)
		(drill 0.254)
		(layers "F.Cu" "B.Cu")
		(net "GND")
	)
	(via
		(at 175.0314 -172.793914)
		(size 0.508)
		(drill 0.254)
		(layers "F.Cu" "B.Cu")
		(net "GND")
	)
	(via
		(at 123.631452 -53.450236)
		(size 0.508)
		(drill 0.254)
		(layers "F.Cu" "B.Cu")
		(net "GND")
	)
	(via
		(at 120.17756 -111.752634)
		(size 0.508)
		(drill 0.254)
		(layers "F.Cu" "B.Cu")
		(net "GND")
	)
	(via
		(at 87.705438 -72.351646)
		(size 0.508)
		(drill 0.254)
		(layers "F.Cu" "B.Cu")
		(net "GND")
	)
	(via
		(at 15.997174 -15.09776)
		(size 0.508)
		(drill 0.254)
		(layers "F.Cu" "B.Cu")
		(net "GND")
	)
	(via
		(at 56.98744 -173.828964)
		(size 0.508)
		(drill 0.254)
		(layers "F.Cu" "B.Cu")
		(net "GND")
	)
	(via
		(at 148.269198 -81.585816)
		(size 0.508)
		(drill 0.254)
		(layers "F.Cu" "B.Cu")
		(net "GND")
	)
	(via
		(at 139.16152 -130.998722)
		(size 0.508)
		(drill 0.254)
		(layers "F.Cu" "B.Cu")
		(net "GND")
	)
	(via
		(at 12.60856 -109.280198)
		(size 0.508)
		(drill 0.254)
		(layers "F.Cu" "B.Cu")
		(net "GND")
	)
	(via
		(at 37.0205 -160.084516)
		(size 0.508)
		(drill 0.254)
		(layers "F.Cu" "B.Cu")
		(net "GND")
	)
	(via
		(at 88.94572 -186.91352)
		(size 0.508)
		(drill 0.254)
		(layers "F.Cu" "B.Cu")
		(net "GND")
	)
	(via
		(at 47.704248 -72.733408)
		(size 0.508)
		(drill 0.254)
		(layers "F.Cu" "B.Cu")
		(net "GND")
	)
	(via
		(at 44.702222 -105.390696)
		(size 0.508)
		(drill 0.254)
		(layers "F.Cu" "B.Cu")
		(net "GND")
	)
	(via
		(at 62.025784 -108.61294)
		(size 0.508)
		(drill 0.254)
		(layers "F.Cu" "B.Cu")
		(net "GND")
	)
	(via
		(at 105.088182 -126.944374)
		(size 0.508)
		(drill 0.254)
		(layers "F.Cu" "B.Cu")
		(net "GND")
	)
	(via
		(at 116.226082 -16.861536)
		(size 0.508)
		(drill 0.254)
		(layers "F.Cu" "B.Cu")
		(net "GND")
	)
	(via
		(at 150.119842 -152.497536)
		(size 0.508)
		(drill 0.254)
		(layers "F.Cu" "B.Cu")
		(net "GND")
	)
	(via
		(at 61.015118 -201.09053)
		(size 0.508)
		(drill 0.254)
		(layers "F.Cu" "B.Cu")
		(net "GND")
	)
	(via
		(at 73.018904 -9.42975)
		(size 0.508)
		(drill 0.254)
		(layers "F.Cu" "B.Cu")
		(net "GND")
	)
	(via
		(at 32.57296 -169.312082)
		(size 0.508)
		(drill 0.254)
		(layers "F.Cu" "B.Cu")
		(net "GND")
	)
	(via
		(at 37.05352 -148.36775)
		(size 0.508)
		(drill 0.254)
		(layers "F.Cu" "B.Cu")
		(net "GND")
	)
	(via
		(at 170.02506 -176.633124)
		(size 0.508)
		(drill 0.254)
		(layers "F.Cu" "B.Cu")
		(net "GND")
	)
	(via
		(at 20.921472 -75.47229)
		(size 0.508)
		(drill 0.254)
		(layers "F.Cu" "B.Cu")
		(net "GND")
	)
	(via
		(at 68.141088 -137.258298)
		(size 0.49022)
		(drill 0.254)
		(layers "F.Cu" "B.Cu")
		(net "GND")
	)
	(via
		(at 129.625852 -145.11655)
		(size 0.508)
		(drill 0.254)
		(layers "F.Cu" "B.Cu")
		(net "GND")
	)
	(via
		(at 61.90742 -26.176478)
		(size 0.508)
		(drill 0.254)
		(layers "F.Cu" "B.Cu")
		(net "GND")
	)
	(via
		(at 71.341996 -142.859252)
		(size 0.49022)
		(drill 0.254)
		(layers "F.Cu" "B.Cu")
		(net "GND")
	)
	(via
		(at 47.349918 -131.705604)
		(size 0.49022)
		(drill 0.254)
		(layers "F.Cu" "B.Cu")
		(net "GND")
	)
	(via
		(at 116.11991 -66.641472)
		(size 0.508)
		(drill 0.254)
		(layers "F.Cu" "B.Cu")
		(net "GND")
	)
	(via
		(at 12.03452 -125.638052)
		(size 0.508)
		(drill 0.254)
		(layers "F.Cu" "B.Cu")
		(net "GND")
	)
	(via
		(at 91.68384 -98.82632)
		(size 0.508)
		(drill 0.254)
		(layers "F.Cu" "B.Cu")
		(net "GND")
	)
	(via
		(at 74.11466 -186.937904)
		(size 0.508)
		(drill 0.254)
		(layers "F.Cu" "B.Cu")
		(net "GND")
	)
	(via
		(at 56.284114 -143.096234)
		(size 0.508)
		(drill 0.254)
		(layers "F.Cu" "B.Cu")
		(net "GND")
	)
	(via
		(at 35.987228 -68.536566)
		(size 0.508)
		(drill 0.254)
		(layers "F.Cu" "B.Cu")
		(net "GND")
	)
	(via
		(at 91.650058 -27.569414)
		(size 0.508)
		(drill 0.254)
		(layers "F.Cu" "B.Cu")
		(net "GND")
	)
	(via
		(at 154.501596 -68.27393)
		(size 0.508)
		(drill 0.254)
		(layers "F.Cu" "B.Cu")
		(net "GND")
	)
	(via
		(at 137.398252 -120.300242)
		(size 0.508)
		(drill 0.254)
		(layers "F.Cu" "B.Cu")
		(net "GND")
	)
	(via
		(at 71.633842 -16.044418)
		(size 0.508)
		(drill 0.254)
		(layers "F.Cu" "B.Cu")
		(net "GND")
	)
	(via
		(at 166.27983 -159.274256)
		(size 0.508)
		(drill 0.254)
		(layers "F.Cu" "B.Cu")
		(net "GND")
	)
	(via
		(at 140.692886 -52.679854)
		(size 0.508)
		(drill 0.254)
		(layers "F.Cu" "B.Cu")
		(net "GND")
	)
	(via
		(at 64.141096 -136.458198)
		(size 0.49022)
		(drill 0.254)
		(layers "F.Cu" "B.Cu")
		(net "GND")
	)
	(via
		(at 29.050488 -131.800092)
		(size 0.508)
		(drill 0.254)
		(layers "F.Cu" "B.Cu")
		(net "GND")
	)
	(via
		(at 118.17858 -104.508554)
		(size 0.508)
		(drill 0.254)
		(layers "F.Cu" "B.Cu")
		(net "GND")
	)
	(via
		(at 57.200546 -76.199492)
		(size 0.508)
		(drill 0.254)
		(layers "F.Cu" "B.Cu")
		(net "GND")
	)
	(via
		(at 52.647596 -89.693496)
		(size 0.508)
		(drill 0.254)
		(layers "F.Cu" "B.Cu")
		(net "GND")
	)
	(via
		(at 123.62688 -143.18742)
		(size 0.508)
		(drill 0.254)
		(layers "F.Cu" "B.Cu")
		(net "GND")
	)
	(via
		(at 51.45024 -27.380438)
		(size 0.508)
		(drill 0.254)
		(layers "F.Cu" "B.Cu")
		(net "GND")
	)
	(via
		(at 79.727552 -143.764762)
		(size 0.508)
		(drill 0.254)
		(layers "F.Cu" "B.Cu")
		(net "GND")
	)
	(via
		(at 45.270928 -109.383068)
		(size 0.508)
		(drill 0.254)
		(layers "F.Cu" "B.Cu")
		(net "GND")
	)
	(via
		(at 85.366352 -115.445794)
		(size 0.508)
		(drill 0.254)
		(layers "F.Cu" "B.Cu")
		(net "GND")
	)
	(via
		(at 148.249894 -30.946344)
		(size 0.508)
		(drill 0.254)
		(layers "F.Cu" "B.Cu")
		(net "GND")
	)
	(via
		(at 107.054142 -40.019224)
		(size 0.508)
		(drill 0.254)
		(layers "F.Cu" "B.Cu")
		(net "GND")
	)
	(via
		(at 85.043264 -93.417898)
		(size 0.508)
		(drill 0.254)
		(layers "F.Cu" "B.Cu")
		(net "GND")
	)
	(via
		(at 134.22376 -186.862974)
		(size 0.508)
		(drill 0.254)
		(layers "F.Cu" "B.Cu")
		(net "GND")
	)
	(via
		(at 36.88334 -15.279116)
		(size 0.508)
		(drill 0.254)
		(layers "F.Cu" "B.Cu")
		(net "GND")
	)
	(via
		(at 72.942196 -140.459206)
		(size 0.49022)
		(drill 0.254)
		(layers "F.Cu" "B.Cu")
		(net "GND")
	)
	(via
		(at 29.96692 -114.803174)
		(size 0.508)
		(drill 0.254)
		(layers "F.Cu" "B.Cu")
		(net "GND")
	)
	(via
		(at 162.673792 -74.783188)
		(size 0.508)
		(drill 0.254)
		(layers "F.Cu" "B.Cu")
		(net "GND")
	)
	(via
		(at 151.0157 -201.034904)
		(size 0.508)
		(drill 0.254)
		(layers "F.Cu" "B.Cu")
		(net "GND")
	)
	(via
		(at 63.340996 -135.658352)
		(size 0.49022)
		(drill 0.254)
		(layers "F.Cu" "B.Cu")
		(net "GND")
	)
	(via
		(at 62.384686 -131.364228)
		(size 0.508)
		(drill 0.254)
		(layers "F.Cu" "B.Cu")
		(net "GND")
	)
	(via
		(at 90.7796 -78.132432)
		(size 0.508)
		(drill 0.254)
		(layers "F.Cu" "B.Cu")
		(net "GND")
	)
	(via
		(at 170.847512 -118.880128)
		(size 0.508)
		(drill 0.254)
		(layers "F.Cu" "B.Cu")
		(net "GND")
	)
	(via
		(at 138.3538 -54.8894)
		(size 0.508)
		(drill 0.254)
		(layers "F.Cu" "B.Cu")
		(net "GND")
	)
	(via
		(at 129.92608 -126.04877)
		(size 0.508)
		(drill 0.254)
		(layers "F.Cu" "B.Cu")
		(net "GND")
	)
	(via
		(at 127.035052 -137.97915)
		(size 0.508)
		(drill 0.254)
		(layers "F.Cu" "B.Cu")
		(net "GND")
	)
	(via
		(at 94.337378 -162.942778)
		(size 0.508)
		(drill 0.254)
		(layers "F.Cu" "B.Cu")
		(net "GND")
	)
	(via
		(at 149.33676 -186.862974)
		(size 0.508)
		(drill 0.254)
		(layers "F.Cu" "B.Cu")
		(net "GND")
	)
	(via
		(at 43.50258 -166.5351)
		(size 0.508)
		(drill 0.254)
		(layers "F.Cu" "B.Cu")
		(net "GND")
	)
	(via
		(at 93.648276 -138.724386)
		(size 0.508)
		(drill 0.254)
		(layers "F.Cu" "B.Cu")
		(net "GND")
	)
	(via
		(at 144.09928 -105.432352)
		(size 0.508)
		(drill 0.254)
		(layers "F.Cu" "B.Cu")
		(net "GND")
	)
	(via
		(at 128.478026 -106.038142)
		(size 0.508)
		(drill 0.254)
		(layers "F.Cu" "B.Cu")
		(net "GND")
	)
	(via
		(at 47.700692 -178.946302)
		(size 0.508)
		(drill 0.254)
		(layers "F.Cu" "B.Cu")
		(net "GND")
	)
	(via
		(at 74.95794 -66.792094)
		(size 0.508)
		(drill 0.254)
		(layers "F.Cu" "B.Cu")
		(net "GND")
	)
	(via
		(at 44.52112 -3.149854)
		(size 0.508)
		(drill 0.254)
		(layers "F.Cu" "B.Cu")
		(net "GND")
	)
	(via
		(at 112.986312 -31.021528)
		(size 0.508)
		(drill 0.254)
		(layers "F.Cu" "B.Cu")
		(net "GND")
	)
	(via
		(at 114.83721 -49.544478)
		(size 0.508)
		(drill 0.254)
		(layers "F.Cu" "B.Cu")
		(net "GND")
	)
	(via
		(at 25.01138 -106.383836)
		(size 0.508)
		(drill 0.254)
		(layers "F.Cu" "B.Cu")
		(net "GND")
	)
	(via
		(at 169.9895 -51.642518)
		(size 0.508)
		(drill 0.254)
		(layers "F.Cu" "B.Cu")
		(net "GND")
	)
	(via
		(at 50.809906 -113.9825)
		(size 0.508)
		(drill 0.254)
		(layers "F.Cu" "B.Cu")
		(net "GND")
	)
	(via
		(at 138.525758 -164.488876)
		(size 0.508)
		(drill 0.254)
		(layers "F.Cu" "B.Cu")
		(net "GND")
	)
	(via
		(at 74.905362 -16.044418)
		(size 0.508)
		(drill 0.254)
		(layers "F.Cu" "B.Cu")
		(net "GND")
	)
	(via
		(at 58.540904 -128.458214)
		(size 0.49022)
		(drill 0.254)
		(layers "F.Cu" "B.Cu")
		(net "GND")
	)
	(via
		(at 34.418778 -107.027218)
		(size 0.508)
		(drill 0.254)
		(layers "F.Cu" "B.Cu")
		(net "GND")
	)
	(via
		(at 160.950402 -104.396286)
		(size 0.508)
		(drill 0.254)
		(layers "F.Cu" "B.Cu")
		(net "GND")
	)
	(via
		(at 131.98856 -120.147334)
		(size 0.508)
		(drill 0.254)
		(layers "F.Cu" "B.Cu")
		(net "GND")
	)
	(via
		(at 51.02987 -84.779104)
		(size 0.508)
		(drill 0.254)
		(layers "F.Cu" "B.Cu")
		(net "GND")
	)
	(via
		(at 14.461744 -56.881776)
		(size 0.508)
		(drill 0.254)
		(layers "F.Cu" "B.Cu")
		(net "GND")
	)
	(via
		(at 41.22801 -140.561314)
		(size 0.49022)
		(drill 0.254)
		(layers "F.Cu" "B.Cu")
		(net "GND")
	)
	(via
		(at 179.817268 -113.963704)
		(size 0.508)
		(drill 0.254)
		(layers "F.Cu" "B.Cu")
		(net "GND")
	)
	(via
		(at 50.910236 -121.49963)
		(size 0.508)
		(drill 0.254)
		(layers "F.Cu" "B.Cu")
		(net "GND")
	)
	(via
		(at 62.801246 -76.999592)
		(size 0.508)
		(drill 0.254)
		(layers "F.Cu" "B.Cu")
		(net "GND")
	)
	(via
		(at 162.17138 -162.37966)
		(size 0.508)
		(drill 0.254)
		(layers "F.Cu" "B.Cu")
		(net "GND")
	)
	(via
		(at 28.546044 -18.255996)
		(size 0.508)
		(drill 0.254)
		(layers "F.Cu" "B.Cu")
		(net "GND")
	)
	(via
		(at 20.698714 -135.430514)
		(size 0.508)
		(drill 0.254)
		(layers "F.Cu" "B.Cu")
		(net "GND")
	)
	(via
		(at 64.82207 -69.27977)
		(size 0.508)
		(drill 0.254)
		(layers "F.Cu" "B.Cu")
		(net "GND")
	)
	(via
		(at 123.93676 -186.862974)
		(size 0.508)
		(drill 0.254)
		(layers "F.Cu" "B.Cu")
		(net "GND")
	)
	(via
		(at 61.96076 -99.28479)
		(size 0.508)
		(drill 0.254)
		(layers "F.Cu" "B.Cu")
		(net "GND")
	)
	(via
		(at 71.67372 -2.604262)
		(size 0.508)
		(drill 0.254)
		(layers "F.Cu" "B.Cu")
		(net "GND")
	)
	(via
		(at 21.014944 -201.09053)
		(size 0.508)
		(drill 0.254)
		(layers "F.Cu" "B.Cu")
		(net "GND")
	)
	(via
		(at 49.193958 -61.93917)
		(size 0.508)
		(drill 0.254)
		(layers "F.Cu" "B.Cu")
		(net "GND")
	)
	(via
		(at 68.506086 -170.83405)
		(size 0.508)
		(drill 0.254)
		(layers "F.Cu" "B.Cu")
		(net "GND")
	)
	(via
		(at 117.63248 -173.225968)
		(size 0.508)
		(drill 0.254)
		(layers "F.Cu" "B.Cu")
		(net "GND")
	)
	(via
		(at 111.223298 -119.652542)
		(size 0.508)
		(drill 0.254)
		(layers "F.Cu" "B.Cu")
		(net "GND")
	)
	(via
		(at 99.53752 -33.449768)
		(size 0.508)
		(drill 0.254)
		(layers "F.Cu" "B.Cu")
		(net "GND")
	)
	(via
		(at 147.108672 -79.664814)
		(size 0.508)
		(drill 0.254)
		(layers "F.Cu" "B.Cu")
		(net "GND")
	)
	(via
		(at 86.34222 -167.949626)
		(size 0.508)
		(drill 0.254)
		(layers "F.Cu" "B.Cu")
		(net "GND")
	)
	(via
		(at 80.24876 -186.924696)
		(size 0.508)
		(drill 0.254)
		(layers "F.Cu" "B.Cu")
		(net "GND")
	)
	(via
		(at 168.87698 -156.093922)
		(size 0.508)
		(drill 0.254)
		(layers "F.Cu" "B.Cu")
		(net "GND")
	)
	(via
		(at 67.154044 -75.195938)
		(size 0.508)
		(drill 0.254)
		(layers "F.Cu" "B.Cu")
		(net "GND")
	)
	(via
		(at 52.81676 -186.862974)
		(size 0.508)
		(drill 0.254)
		(layers "F.Cu" "B.Cu")
		(net "GND")
	)
	(via
		(at 72.142096 -141.259306)
		(size 0.49022)
		(drill 0.254)
		(layers "F.Cu" "B.Cu")
		(net "GND")
	)
	(via
		(at 56.166766 -163.160202)
		(size 0.508)
		(drill 0.254)
		(layers "F.Cu" "B.Cu")
		(net "GND")
	)
	(via
		(at 126.01956 -154.656282)
		(size 0.508)
		(drill 0.254)
		(layers "F.Cu" "B.Cu")
		(net "GND")
	)
	(via
		(at 80.464152 -145.517362)
		(size 0.508)
		(drill 0.254)
		(layers "F.Cu" "B.Cu")
		(net "GND")
	)
	(via
		(at 122.72772 -187.072524)
		(size 0.508)
		(drill 0.254)
		(layers "F.Cu" "B.Cu")
		(net "GND")
	)
	(via
		(at 82.740246 -106.350054)
		(size 0.508)
		(drill 0.254)
		(layers "F.Cu" "B.Cu")
		(net "GND")
	)
	(via
		(at 52.399946 -79.399892)
		(size 0.508)
		(drill 0.254)
		(layers "F.Cu" "B.Cu")
		(net "GND")
	)
	(via
		(at 112.878362 -169.154602)
		(size 0.508)
		(drill 0.254)
		(layers "F.Cu" "B.Cu")
		(net "GND")
	)
	(via
		(at 145.154904 -66.063622)
		(size 0.508)
		(drill 0.254)
		(layers "F.Cu" "B.Cu")
		(net "GND")
	)
	(via
		(at 64.940942 -134.058406)
		(size 0.49022)
		(drill 0.254)
		(layers "F.Cu" "B.Cu")
		(net "GND")
	)
	(via
		(at 74.8792 -25.550622)
		(size 0.508)
		(drill 0.254)
		(layers "F.Cu" "B.Cu")
		(net "GND")
	)
	(via
		(at 188.665866 -123.860306)
		(size 0.508)
		(drill 0.254)
		(layers "F.Cu" "B.Cu")
		(net "GND")
	)
	(via
		(at 58.3184 -16.844518)
		(size 0.508)
		(drill 0.254)
		(layers "F.Cu" "B.Cu")
		(net "GND")
	)
	(via
		(at 73.742042 -142.059406)
		(size 0.49022)
		(drill 0.254)
		(layers "F.Cu" "B.Cu")
		(net "GND")
	)
	(via
		(at 93.072204 -135.311388)
		(size 0.508)
		(drill 0.254)
		(layers "F.Cu" "B.Cu")
		(net "GND")
	)
	(via
		(at 50.53076 -180.974746)
		(size 0.508)
		(drill 0.254)
		(layers "F.Cu" "B.Cu")
		(net "GND")
	)
	(via
		(at 80.438752 -144.679162)
		(size 0.508)
		(drill 0.254)
		(layers "F.Cu" "B.Cu")
		(net "GND")
	)
	(via
		(at 91.502484 -185.628026)
		(size 0.508)
		(drill 0.254)
		(layers "F.Cu" "B.Cu")
		(net "GND")
	)
	(via
		(at 43.927776 -113.890298)
		(size 0.508)
		(drill 0.254)
		(layers "F.Cu" "B.Cu")
		(net "GND")
	)
	(via
		(at 113.306352 -21.630386)
		(size 0.508)
		(drill 0.254)
		(layers "F.Cu" "B.Cu")
		(net "GND")
	)
	(via
		(at 119.27586 -103.712772)
		(size 0.508)
		(drill 0.254)
		(layers "F.Cu" "B.Cu")
		(net "GND")
	)
	(via
		(at 47.03953 -84.544408)
		(size 0.508)
		(drill 0.254)
		(layers "F.Cu" "B.Cu")
		(net "GND")
	)
	(via
		(at 175.225456 -99.60102)
		(size 0.508)
		(drill 0.254)
		(layers "F.Cu" "B.Cu")
		(net "GND")
	)
	(via
		(at 164.180774 -121.584466)
		(size 0.508)
		(drill 0.254)
		(layers "F.Cu" "B.Cu")
		(net "GND")
	)
	(via
		(at 107.993942 -174.901352)
		(size 0.508)
		(drill 0.254)
		(layers "F.Cu" "B.Cu")
		(net "GND")
	)
	(via
		(at 70.192138 -116.774214)
		(size 0.508)
		(drill 0.254)
		(layers "F.Cu" "B.Cu")
		(net "GND")
	)
	(via
		(at 128.452372 -137.88771)
		(size 0.508)
		(drill 0.254)
		(layers "F.Cu" "B.Cu")
		(net "GND")
	)
	(via
		(at 20.400772 -137.420604)
		(size 0.508)
		(drill 0.254)
		(layers "F.Cu" "B.Cu")
		(net "GND")
	)
	(via
		(at 114.977926 -39.91356)
		(size 0.508)
		(drill 0.254)
		(layers "F.Cu" "B.Cu")
		(net "GND")
	)
	(via
		(at 78.519274 -95.141542)
		(size 0.508)
		(drill 0.254)
		(layers "F.Cu" "B.Cu")
		(net "GND")
	)
	(via
		(at 131.872482 -56.939942)
		(size 0.508)
		(drill 0.254)
		(layers "F.Cu" "B.Cu")
		(net "GND")
	)
	(via
		(at 39.266368 -5.377942)
		(size 0.508)
		(drill 0.254)
		(layers "F.Cu" "B.Cu")
		(net "GND")
	)
	(via
		(at 28.059888 -126.209552)
		(size 0.508)
		(drill 0.254)
		(layers "F.Cu" "B.Cu")
		(net "GND")
	)
	(via
		(at 36.75634 -151.92629)
		(size 0.508)
		(drill 0.254)
		(layers "F.Cu" "B.Cu")
		(net "GND")
	)
	(via
		(at 48.75022 -181.006496)
		(size 0.508)
		(drill 0.254)
		(layers "F.Cu" "B.Cu")
		(net "GND")
	)
	(via
		(at 165.989 -186.076082)
		(size 0.508)
		(drill 0.254)
		(layers "F.Cu" "B.Cu")
		(net "GND")
	)
	(via
		(at 70.54215 -141.25829)
		(size 0.49022)
		(drill 0.254)
		(layers "F.Cu" "B.Cu")
		(net "GND")
	)
	(via
		(at 15.14856 -40.989504)
		(size 0.508)
		(drill 0.254)
		(layers "F.Cu" "B.Cu")
		(net "GND")
	)
	(via
		(at 115.644168 -41.350438)
		(size 0.508)
		(drill 0.254)
		(layers "F.Cu" "B.Cu")
		(net "GND")
	)
	(via
		(at 62.793372 -84.594446)
		(size 0.508)
		(drill 0.254)
		(layers "F.Cu" "B.Cu")
		(net "GND")
	)
	(via
		(at 124.063252 -25.431242)
		(size 0.508)
		(drill 0.254)
		(layers "F.Cu" "B.Cu")
		(net "GND")
	)
	(via
		(at 88.015064 -200.734676)
		(size 0.508)
		(drill 0.254)
		(layers "F.Cu" "B.Cu")
		(net "GND")
	)
	(via
		(at 131.699 -183.660542)
		(size 0.508)
		(drill 0.254)
		(layers "F.Cu" "B.Cu")
		(net "GND")
	)
	(via
		(at 112.635792 -31.636208)
		(size 0.508)
		(drill 0.254)
		(layers "F.Cu" "B.Cu")
		(net "GND")
	)
	(via
		(at 55.65013 -27.60345)
		(size 0.508)
		(drill 0.254)
		(layers "F.Cu" "B.Cu")
		(net "GND")
	)
	(via
		(at 58.727086 -143.835628)
		(size 0.49022)
		(drill 0.254)
		(layers "F.Cu" "B.Cu")
		(net "GND")
	)
	(via
		(at 79.015082 -201.135234)
		(size 0.508)
		(drill 0.254)
		(layers "F.Cu" "B.Cu")
		(net "GND")
	)
	(via
		(at 55.950104 -22.46376)
		(size 0.508)
		(drill 0.254)
		(layers "F.Cu" "B.Cu")
		(net "GND")
	)
	(via
		(at 139.938252 -149.18055)
		(size 0.508)
		(drill 0.254)
		(layers "F.Cu" "B.Cu")
		(net "GND")
	)
	(via
		(at 41.270936 -70.256146)
		(size 0.508)
		(drill 0.254)
		(layers "F.Cu" "B.Cu")
		(net "GND")
	)
	(via
		(at 44.967652 -164.37229)
		(size 0.508)
		(drill 0.254)
		(layers "F.Cu" "B.Cu")
		(net "GND")
	)
	(via
		(at 165.951408 -74.012552)
		(size 0.508)
		(drill 0.254)
		(layers "F.Cu" "B.Cu")
		(net "GND")
	)
	(via
		(at 93.150182 -22.473158)
		(size 0.508)
		(drill 0.254)
		(layers "F.Cu" "B.Cu")
		(net "GND")
	)
	(via
		(at 63.340996 -133.258306)
		(size 0.49022)
		(drill 0.254)
		(layers "F.Cu" "B.Cu")
		(net "GND")
	)
	(via
		(at 154.7622 -135.036052)
		(size 0.508)
		(drill 0.254)
		(layers "F.Cu" "B.Cu")
		(net "GND")
	)
	(via
		(at 97.188528 -135.336788)
		(size 0.508)
		(drill 0.254)
		(layers "F.Cu" "B.Cu")
		(net "GND")
	)
	(via
		(at 160.619948 -143.647922)
		(size 0.508)
		(drill 0.254)
		(layers "F.Cu" "B.Cu")
		(net "GND")
	)
	(via
		(at 9.856978 -138.058906)
		(size 0.508)
		(drill 0.254)
		(layers "F.Cu" "B.Cu")
		(net "GND")
	)
	(via
		(at 18.342864 -137.285222)
		(size 0.508)
		(drill 0.254)
		(layers "F.Cu" "B.Cu")
		(net "GND")
	)
	(via
		(at 174.83836 -157.808676)
		(size 0.508)
		(drill 0.254)
		(layers "F.Cu" "B.Cu")
		(net "GND")
	)
	(via
		(at 40.43299 -138.164062)
		(size 0.49022)
		(drill 0.254)
		(layers "F.Cu" "B.Cu")
		(net "GND")
	)
	(via
		(at 101.835712 -74.460354)
		(size 0.508)
		(drill 0.254)
		(layers "F.Cu" "B.Cu")
		(net "GND")
	)
	(via
		(at 47.308516 -74.935842)
		(size 0.508)
		(drill 0.254)
		(layers "F.Cu" "B.Cu")
		(net "GND")
	)
	(via
		(at 20.83562 -48.700182)
		(size 0.508)
		(drill 0.254)
		(layers "F.Cu" "B.Cu")
		(net "GND")
	)
	(via
		(at 101.749098 -154.183588)
		(size 0.508)
		(drill 0.254)
		(layers "F.Cu" "B.Cu")
		(net "GND")
	)
	(via
		(at 91.350084 -22.396196)
		(size 0.508)
		(drill 0.254)
		(layers "F.Cu" "B.Cu")
		(net "GND")
	)
	(via
		(at 131.95046 -126.14783)
		(size 0.508)
		(drill 0.254)
		(layers "F.Cu" "B.Cu")
		(net "GND")
	)
	(via
		(at 31.83636 -141.75486)
		(size 0.508)
		(drill 0.254)
		(layers "F.Cu" "B.Cu")
		(net "GND")
	)
	(via
		(at 44.014898 -200.32853)
		(size 0.508)
		(drill 0.254)
		(layers "F.Cu" "B.Cu")
		(net "GND")
	)
	(via
		(at 52.350162 -22.404578)
		(size 0.508)
		(drill 0.254)
		(layers "F.Cu" "B.Cu")
		(net "GND")
	)
	(via
		(at 63.363348 -164.689282)
		(size 0.508)
		(drill 0.254)
		(layers "F.Cu" "B.Cu")
		(net "GND")
	)
	(via
		(at 169.526712 -117.711728)
		(size 0.508)
		(drill 0.254)
		(layers "F.Cu" "B.Cu")
		(net "GND")
	)
	(via
		(at 17.08404 -138.858752)
		(size 0.508)
		(drill 0.254)
		(layers "F.Cu" "B.Cu")
		(net "GND")
	)
	(via
		(at 52.588414 -46.863508)
		(size 0.508)
		(drill 0.254)
		(layers "F.Cu" "B.Cu")
		(net "GND")
	)
	(via
		(at 46.659292 -72.566022)
		(size 0.508)
		(drill 0.254)
		(layers "F.Cu" "B.Cu")
		(net "GND")
	)
	(via
		(at 94.95028 -22.4536)
		(size 0.508)
		(drill 0.254)
		(layers "F.Cu" "B.Cu")
		(net "GND")
	)
	(via
		(at 140.619226 -152.705816)
		(size 0.508)
		(drill 0.254)
		(layers "F.Cu" "B.Cu")
		(net "GND")
	)
	(via
		(at 52.490878 -90.453464)
		(size 0.508)
		(drill 0.254)
		(layers "F.Cu" "B.Cu")
		(net "GND")
	)
	(via
		(at 95.5421 -109.32287)
		(size 0.508)
		(drill 0.254)
		(layers "F.Cu" "B.Cu")
		(net "GND")
	)
	(via
		(at 192.588642 -113.419128)
		(size 0.508)
		(drill 0.254)
		(layers "F.Cu" "B.Cu")
		(net "GND")
	)
	(via
		(at 82.042 -23.961598)
		(size 0.508)
		(drill 0.254)
		(layers "F.Cu" "B.Cu")
		(net "GND")
	)
	(via
		(at 68.527422 -16.044418)
		(size 0.508)
		(drill 0.254)
		(layers "F.Cu" "B.Cu")
		(net "GND")
	)
	(via
		(at 131.693158 -35.915854)
		(size 0.508)
		(drill 0.254)
		(layers "F.Cu" "B.Cu")
		(net "GND")
	)
	(via
		(at 111.129064 -149.245066)
		(size 0.508)
		(drill 0.254)
		(layers "F.Cu" "B.Cu")
		(net "GND")
	)
	(via
		(at 62.005972 -78.584298)
		(size 0.508)
		(drill 0.254)
		(layers "F.Cu" "B.Cu")
		(net "GND")
	)
	(via
		(at 138.534902 -139.1793)
		(size 0.508)
		(drill 0.254)
		(layers "F.Cu" "B.Cu")
		(net "GND")
	)
	(via
		(at 108.764832 -66.575686)
		(size 0.508)
		(drill 0.254)
		(layers "F.Cu" "B.Cu")
		(net "GND")
	)
	(via
		(at 154.501596 -63.44793)
		(size 0.508)
		(drill 0.254)
		(layers "F.Cu" "B.Cu")
		(net "GND")
	)
	(via
		(at 58.90514 -26.855674)
		(size 0.508)
		(drill 0.254)
		(layers "F.Cu" "B.Cu")
		(net "GND")
	)
	(via
		(at 5.557774 -151.331168)
		(size 0.508)
		(drill 0.254)
		(layers "F.Cu" "B.Cu")
		(net "GND")
	)
	(via
		(at 137.52576 -109.673898)
		(size 0.508)
		(drill 0.254)
		(layers "F.Cu" "B.Cu")
		(net "GND")
	)
	(via
		(at 21.831554 -104.206802)
		(size 0.508)
		(drill 0.254)
		(layers "F.Cu" "B.Cu")
		(net "GND")
	)
	(via
		(at 22.495002 -125.598936)
		(size 0.508)
		(drill 0.254)
		(layers "F.Cu" "B.Cu")
		(net "GND")
	)
	(via
		(at 82.59572 -109.874558)
		(size 0.508)
		(drill 0.254)
		(layers "F.Cu" "B.Cu")
		(net "GND")
	)
	(via
		(at 155.86456 -85.594444)
		(size 0.508)
		(drill 0.254)
		(layers "F.Cu" "B.Cu")
		(net "GND")
	)
	(via
		(at 168.809162 -152.901904)
		(size 0.508)
		(drill 0.254)
		(layers "F.Cu" "B.Cu")
		(net "GND")
	)
	(via
		(at 80.145382 -97.726246)
		(size 0.508)
		(drill 0.254)
		(layers "F.Cu" "B.Cu")
		(net "GND")
	)
	(via
		(at 154.652726 -100.827586)
		(size 0.508)
		(drill 0.254)
		(layers "F.Cu" "B.Cu")
		(net "GND")
	)
	(via
		(at 139.192 -129.411222)
		(size 0.508)
		(drill 0.254)
		(layers "F.Cu" "B.Cu")
		(net "GND")
	)
	(via
		(at 126.966472 -148.77415)
		(size 0.508)
		(drill 0.254)
		(layers "F.Cu" "B.Cu")
		(net "GND")
	)
	(via
		(at 22.495002 -124.328936)
		(size 0.508)
		(drill 0.254)
		(layers "F.Cu" "B.Cu")
		(net "GND")
	)
	(via
		(at 147.015708 -201.034904)
		(size 0.508)
		(drill 0.254)
		(layers "F.Cu" "B.Cu")
		(net "GND")
	)
	(via
		(at 115.494308 -120.77192)
		(size 0.508)
		(drill 0.254)
		(layers "F.Cu" "B.Cu")
		(net "GND")
	)
	(via
		(at 146.015456 -201.034904)
		(size 0.508)
		(drill 0.254)
		(layers "F.Cu" "B.Cu")
		(net "GND")
	)
	(via
		(at 70.01764 -86.069678)
		(size 0.508)
		(drill 0.254)
		(layers "F.Cu" "B.Cu")
		(net "GND")
	)
	(via
		(at 66.787776 -78.649322)
		(size 0.508)
		(drill 0.254)
		(layers "F.Cu" "B.Cu")
		(net "GND")
	)
	(via
		(at 146.4818 -166.520876)
		(size 0.508)
		(drill 0.254)
		(layers "F.Cu" "B.Cu")
		(net "GND")
	)
	(via
		(at 49.163478 -74.784712)
		(size 0.508)
		(drill 0.254)
		(layers "F.Cu" "B.Cu")
		(net "GND")
	)
	(via
		(at 46.927516 -76.922122)
		(size 0.508)
		(drill 0.254)
		(layers "F.Cu" "B.Cu")
		(net "GND")
	)
	(via
		(at 159.60852 -186.810904)
		(size 0.508)
		(drill 0.254)
		(layers "F.Cu" "B.Cu")
		(net "GND")
	)
	(via
		(at 45.418248 -82.361786)
		(size 0.508)
		(drill 0.254)
		(layers "F.Cu" "B.Cu")
		(net "GND")
	)
	(via
		(at 74.901552 -85.172804)
		(size 0.508)
		(drill 0.254)
		(layers "F.Cu" "B.Cu")
		(net "GND")
	)
	(via
		(at 46.946566 -65.821306)
		(size 0.508)
		(drill 0.254)
		(layers "F.Cu" "B.Cu")
		(net "GND")
	)
	(via
		(at 112.145572 -31.049468)
		(size 0.508)
		(drill 0.254)
		(layers "F.Cu" "B.Cu")
		(net "GND")
	)
	(via
		(at 53.1622 -81.9912)
		(size 0.508)
		(drill 0.254)
		(layers "F.Cu" "B.Cu")
		(net "GND")
	)
	(via
		(at 39.38524 -138.563604)
		(size 0.49022)
		(drill 0.254)
		(layers "F.Cu" "B.Cu")
		(net "GND")
	)
	(via
		(at 72.82434 -24.312118)
		(size 0.508)
		(drill 0.254)
		(layers "F.Cu" "B.Cu")
		(net "GND")
	)
	(via
		(at 95.830136 -120.236996)
		(size 0.508)
		(drill 0.254)
		(layers "F.Cu" "B.Cu")
		(net "GND")
	)
	(via
		(at 60.3504 -16.844518)
		(size 0.508)
		(drill 0.254)
		(layers "F.Cu" "B.Cu")
		(net "GND")
	)
	(via
		(at 81.30794 -178.585622)
		(size 0.508)
		(drill 0.254)
		(layers "F.Cu" "B.Cu")
		(net "GND")
	)
	(via
		(at 162.29838 -33.589214)
		(size 0.508)
		(drill 0.254)
		(layers "F.Cu" "B.Cu")
		(net "GND")
	)
	(via
		(at 95.74784 -200.29932)
		(size 0.508)
		(drill 0.254)
		(layers "F.Cu" "B.Cu")
		(net "GND")
	)
	(via
		(at 137.172192 -159.928814)
		(size 0.508)
		(drill 0.254)
		(layers "F.Cu" "B.Cu")
		(net "GND")
	)
	(via
		(at 131.988052 -152.50795)
		(size 0.508)
		(drill 0.254)
		(layers "F.Cu" "B.Cu")
		(net "GND")
	)
	(via
		(at 63.667894 -97.73412)
		(size 0.508)
		(drill 0.254)
		(layers "F.Cu" "B.Cu")
		(net "GND")
	)
	(via
		(at 38.700964 -10.917682)
		(size 0.508)
		(drill 0.254)
		(layers "F.Cu" "B.Cu")
		(net "GND")
	)
	(via
		(at 181.518306 -115.537488)
		(size 0.508)
		(drill 0.254)
		(layers "F.Cu" "B.Cu")
		(net "GND")
	)
	(via
		(at 105.14076 -186.85891)
		(size 0.508)
		(drill 0.254)
		(layers "F.Cu" "B.Cu")
		(net "GND")
	)
	(via
		(at 29.91866 -169.47769)
		(size 0.508)
		(drill 0.254)
		(layers "F.Cu" "B.Cu")
		(net "GND")
	)
	(via
		(at 142.015464 -201.034904)
		(size 0.508)
		(drill 0.254)
		(layers "F.Cu" "B.Cu")
		(net "GND")
	)
	(via
		(at 177.51044 -119.865648)
		(size 0.49022)
		(drill 0.254)
		(layers "F.Cu" "B.Cu")
		(net "GND")
	)
	(via
		(at 43.308524 -107.728258)
		(size 0.508)
		(drill 0.254)
		(layers "F.Cu" "B.Cu")
		(net "GND")
	)
	(via
		(at 117.12702 -103.712772)
		(size 0.508)
		(drill 0.254)
		(layers "F.Cu" "B.Cu")
		(net "GND")
	)
	(via
		(at 85.399372 -107.9119)
		(size 0.508)
		(drill 0.254)
		(layers "F.Cu" "B.Cu")
		(net "GND")
	)
	(via
		(at 169.672 -171.85513)
		(size 0.508)
		(drill 0.254)
		(layers "F.Cu" "B.Cu")
		(net "GND")
	)
	(via
		(at 18.51406 -39.204646)
		(size 0.508)
		(drill 0.254)
		(layers "F.Cu" "B.Cu")
		(net "GND")
	)
	(via
		(at 32.92094 -72.92721)
		(size 0.508)
		(drill 0.254)
		(layers "F.Cu" "B.Cu")
		(net "GND")
	)
	(via
		(at 34.1503 -173.476412)
		(size 0.508)
		(drill 0.254)
		(layers "F.Cu" "B.Cu")
		(net "GND")
	)
	(via
		(at 71.341996 -135.659368)
		(size 0.49022)
		(drill 0.254)
		(layers "F.Cu" "B.Cu")
		(net "GND")
	)
	(via
		(at 71.341996 -140.459206)
		(size 0.49022)
		(drill 0.254)
		(layers "F.Cu" "B.Cu")
		(net "GND")
	)
	(via
		(at 193.69786 -27.058366)
		(size 0.508)
		(drill 0.254)
		(layers "F.Cu" "B.Cu")
		(net "GND")
	)
	(via
		(at 18.3261 -57.187592)
		(size 0.508)
		(drill 0.254)
		(layers "F.Cu" "B.Cu")
		(net "GND")
	)
	(via
		(at 7.138416 -7.725156)
		(size 0.508)
		(drill 0.254)
		(layers "F.Cu" "B.Cu")
		(net "GND")
	)
	(via
		(at 89.355422 -26.772616)
		(size 0.508)
		(drill 0.254)
		(layers "F.Cu" "B.Cu")
		(net "GND")
	)
	(via
		(at 93.072204 -134.676388)
		(size 0.508)
		(drill 0.254)
		(layers "F.Cu" "B.Cu")
		(net "GND")
	)
	(via
		(at 62.646306 -155.899612)
		(size 0.508)
		(drill 0.254)
		(layers "F.Cu" "B.Cu")
		(net "GND")
	)
	(via
		(at 65.77711 -133.720078)
		(size 0.6604)
		(drill 0.3302)
		(layers "F.Cu" "B.Cu")
		(net "GND")
	)
	(via
		(at 140.423646 -160.439608)
		(size 0.508)
		(drill 0.254)
		(layers "F.Cu" "B.Cu")
		(net "GND")
	)
	(via
		(at 170.288712 -117.737128)
		(size 0.508)
		(drill 0.254)
		(layers "F.Cu" "B.Cu")
		(net "GND")
	)
	(via
		(at 175.593756 -36.848034)
		(size 0.508)
		(drill 0.254)
		(layers "F.Cu" "B.Cu")
		(net "GND")
	)
	(via
		(at 18.774918 -97.973388)
		(size 0.508)
		(drill 0.254)
		(layers "F.Cu" "B.Cu")
		(net "GND")
	)
	(via
		(at 69.563742 -16.044418)
		(size 0.508)
		(drill 0.254)
		(layers "F.Cu" "B.Cu")
		(net "GND")
	)
	(via
		(at 48.4378 -106.25455)
		(size 0.508)
		(drill 0.254)
		(layers "F.Cu" "B.Cu")
		(net "GND")
	)
	(via
		(at 25.456642 -186.234578)
		(size 0.508)
		(drill 0.254)
		(layers "F.Cu" "B.Cu")
		(net "GND")
	)
	(via
		(at 41.040558 -110.955836)
		(size 0.508)
		(drill 0.254)
		(layers "F.Cu" "B.Cu")
		(net "GND")
	)
	(via
		(at 91.00439 -5.41655)
		(size 0.508)
		(drill 0.254)
		(layers "F.Cu" "B.Cu")
		(net "GND")
	)
	(via
		(at 177.51044 -121.865644)
		(size 0.49022)
		(drill 0.254)
		(layers "F.Cu" "B.Cu")
		(net "GND")
	)
	(via
		(at 137.855452 -115.779042)
		(size 0.508)
		(drill 0.254)
		(layers "F.Cu" "B.Cu")
		(net "GND")
	)
	(via
		(at 48.75022 -22.480778)
		(size 0.508)
		(drill 0.254)
		(layers "F.Cu" "B.Cu")
		(net "GND")
	)
	(via
		(at 172.29201 -137.351008)
		(size 0.508)
		(drill 0.254)
		(layers "F.Cu" "B.Cu")
		(net "GND")
	)
	(via
		(at 46.998128 -155.685998)
		(size 0.508)
		(drill 0.254)
		(layers "F.Cu" "B.Cu")
		(net "GND")
	)
	(via
		(at 30.570678 -187.677806)
		(size 0.508)
		(drill 0.254)
		(layers "F.Cu" "B.Cu")
		(net "GND")
	)
	(via
		(at 131.634992 -34.973768)
		(size 0.508)
		(drill 0.254)
		(layers "F.Cu" "B.Cu")
		(net "GND")
	)
	(via
		(at 53.690266 -127.483616)
		(size 0.508)
		(drill 0.254)
		(layers "F.Cu" "B.Cu")
		(net "GND")
	)
	(via
		(at 75.743308 -95.141288)
		(size 0.508)
		(drill 0.254)
		(layers "F.Cu" "B.Cu")
		(net "GND")
	)
	(via
		(at 72.142096 -138.059414)
		(size 0.49022)
		(drill 0.254)
		(layers "F.Cu" "B.Cu")
		(net "GND")
	)
	(via
		(at 142.3289 -186.894978)
		(size 0.508)
		(drill 0.254)
		(layers "F.Cu" "B.Cu")
		(net "GND")
	)
	(via
		(at 87.30742 -184.043574)
		(size 0.508)
		(drill 0.254)
		(layers "F.Cu" "B.Cu")
		(net "GND")
	)
	(via
		(at 27.055318 -53.542184)
		(size 0.508)
		(drill 0.254)
		(layers "F.Cu" "B.Cu")
		(net "GND")
	)
	(via
		(at 86.225634 -4.920742)
		(size 0.508)
		(drill 0.254)
		(layers "F.Cu" "B.Cu")
		(net "GND")
	)
	(via
		(at 40.529256 -83.315302)
		(size 0.508)
		(drill 0.254)
		(layers "F.Cu" "B.Cu")
		(net "GND")
	)
	(via
		(at 52.889404 -68.503038)
		(size 0.508)
		(drill 0.254)
		(layers "F.Cu" "B.Cu")
		(net "GND")
	)
	(via
		(at 55.007256 -134.341108)
		(size 0.49022)
		(drill 0.254)
		(layers "F.Cu" "B.Cu")
		(net "GND")
	)
	(via
		(at 43.292776 -113.890298)
		(size 0.508)
		(drill 0.254)
		(layers "F.Cu" "B.Cu")
		(net "GND")
	)
	(via
		(at 55.150766 -85.396578)
		(size 0.508)
		(drill 0.254)
		(layers "F.Cu" "B.Cu")
		(net "GND")
	)
	(via
		(at 59.19597 -86.343744)
		(size 0.508)
		(drill 0.254)
		(layers "F.Cu" "B.Cu")
		(net "GND")
	)
	(via
		(at 101.77653 -157.688534)
		(size 0.508)
		(drill 0.254)
		(layers "F.Cu" "B.Cu")
		(net "GND")
	)
	(via
		(at 77.622908 -157.01899)
		(size 0.508)
		(drill 0.254)
		(layers "F.Cu" "B.Cu")
		(net "GND")
	)
	(via
		(at 183.1594 -193.777362)
		(size 0.508)
		(drill 0.254)
		(layers "F.Cu" "B.Cu")
		(net "GND")
	)
	(via
		(at 68.941188 -142.059914)
		(size 0.49022)
		(drill 0.254)
		(layers "F.Cu" "B.Cu")
		(net "GND")
	)
	(via
		(at 60.4012 -76.199492)
		(size 0.508)
		(drill 0.254)
		(layers "F.Cu" "B.Cu")
		(net "GND")
	)
	(via
		(at 139.285218 -34.39541)
		(size 0.508)
		(drill 0.254)
		(layers "F.Cu" "B.Cu")
		(net "GND")
	)
	(via
		(at 124.444252 -143.10995)
		(size 0.508)
		(drill 0.254)
		(layers "F.Cu" "B.Cu")
		(net "GND")
	)
	(via
		(at 42.963846 -12.945872)
		(size 0.508)
		(drill 0.254)
		(layers "F.Cu" "B.Cu")
		(net "GND")
	)
	(via
		(at 39.193978 -128.906778)
		(size 0.49022)
		(drill 0.254)
		(layers "F.Cu" "B.Cu")
		(net "GND")
	)
	(via
		(at 164.44976 -98.141282)
		(size 0.508)
		(drill 0.254)
		(layers "F.Cu" "B.Cu")
		(net "GND")
	)
	(via
		(at 126.015496 -201.034904)
		(size 0.508)
		(drill 0.254)
		(layers "F.Cu" "B.Cu")
		(net "GND")
	)
	(via
		(at 142.84833 -184.037478)
		(size 0.508)
		(drill 0.254)
		(layers "F.Cu" "B.Cu")
		(net "GND")
	)
	(via
		(at 107.512612 -133.39064)
		(size 0.508)
		(drill 0.254)
		(layers "F.Cu" "B.Cu")
		(net "GND")
	)
	(via
		(at 85.043264 -94.642686)
		(size 0.508)
		(drill 0.254)
		(layers "F.Cu" "B.Cu")
		(net "GND")
	)
	(via
		(at 135.56996 -116.337334)
		(size 0.508)
		(drill 0.254)
		(layers "F.Cu" "B.Cu")
		(net "GND")
	)
	(via
		(at 66.541142 -140.45819)
		(size 0.49022)
		(drill 0.254)
		(layers "F.Cu" "B.Cu")
		(net "GND")
	)
	(via
		(at 12.78382 -127.969518)
		(size 0.508)
		(drill 0.254)
		(layers "F.Cu" "B.Cu")
		(net "GND")
	)
	(via
		(at 69.741034 -140.45819)
		(size 0.49022)
		(drill 0.254)
		(layers "F.Cu" "B.Cu")
		(net "GND")
	)
	(via
		(at 148.06168 -49.33188)
		(size 0.508)
		(drill 0.254)
		(layers "F.Cu" "B.Cu")
		(net "GND")
	)
	(via
		(at 46.450758 -109.388148)
		(size 0.508)
		(drill 0.254)
		(layers "F.Cu" "B.Cu")
		(net "GND")
	)
	(via
		(at 11.71956 -137.594848)
		(size 0.508)
		(drill 0.254)
		(layers "F.Cu" "B.Cu")
		(net "GND")
	)
	(via
		(at 27.75204 -163.750498)
		(size 0.508)
		(drill 0.254)
		(layers "F.Cu" "B.Cu")
		(net "GND")
	)
	(via
		(at 44.52366 -98.953828)
		(size 0.508)
		(drill 0.254)
		(layers "F.Cu" "B.Cu")
		(net "GND")
	)
	(via
		(at 45.784516 -74.935842)
		(size 0.508)
		(drill 0.254)
		(layers "F.Cu" "B.Cu")
		(net "GND")
	)
	(via
		(at 50.099722 -87.507572)
		(size 0.508)
		(drill 0.254)
		(layers "F.Cu" "B.Cu")
		(net "GND")
	)
	(via
		(at 97.369376 -150.688548)
		(size 0.508)
		(drill 0.254)
		(layers "F.Cu" "B.Cu")
		(net "GND")
	)
	(via
		(at 180.48859 -136.932162)
		(size 0.508)
		(drill 0.254)
		(layers "F.Cu" "B.Cu")
		(net "GND")
	)
	(via
		(at 102.549706 -18.486882)
		(size 0.508)
		(drill 0.254)
		(layers "F.Cu" "B.Cu")
		(net "GND")
	)
	(via
		(at 37.5285 -174.634906)
		(size 0.508)
		(drill 0.254)
		(layers "F.Cu" "B.Cu")
		(net "GND")
	)
	(via
		(at 106.354372 -76.499974)
		(size 0.508)
		(drill 0.254)
		(layers "F.Cu" "B.Cu")
		(net "GND")
	)
	(via
		(at 36.590732 -95.51035)
		(size 0.508)
		(drill 0.254)
		(layers "F.Cu" "B.Cu")
		(net "GND")
	)
	(via
		(at 73.742042 -137.259314)
		(size 0.49022)
		(drill 0.254)
		(layers "F.Cu" "B.Cu")
		(net "GND")
	)
	(via
		(at 68.61556 -175.523652)
		(size 0.508)
		(drill 0.254)
		(layers "F.Cu" "B.Cu")
		(net "GND")
	)
	(via
		(at 74.832972 -88.464898)
		(size 0.508)
		(drill 0.254)
		(layers "F.Cu" "B.Cu")
		(net "GND")
	)
	(via
		(at 21.83257 -124.32919)
		(size 0.508)
		(drill 0.254)
		(layers "F.Cu" "B.Cu")
		(net "GND")
	)
	(via
		(at 35.03295 -73.910698)
		(size 0.508)
		(drill 0.254)
		(layers "F.Cu" "B.Cu")
		(net "GND")
	)
	(via
		(at 133.51256 -120.147334)
		(size 0.508)
		(drill 0.254)
		(layers "F.Cu" "B.Cu")
		(net "GND")
	)
	(via
		(at 162.541712 -187.68187)
		(size 0.508)
		(drill 0.254)
		(layers "F.Cu" "B.Cu")
		(net "GND")
	)
	(via
		(at 165.141148 -80.873092)
		(size 0.508)
		(drill 0.254)
		(layers "F.Cu" "B.Cu")
		(net "GND")
	)
	(via
		(at 131.93776 -186.862974)
		(size 0.508)
		(drill 0.254)
		(layers "F.Cu" "B.Cu")
		(net "GND")
	)
	(via
		(at 14.543278 -45.900848)
		(size 0.508)
		(drill 0.254)
		(layers "F.Cu" "B.Cu")
		(net "GND")
	)
	(via
		(at 91.858084 -175.063912)
		(size 0.508)
		(drill 0.254)
		(layers "F.Cu" "B.Cu")
		(net "GND")
	)
	(via
		(at 157.798516 -181.302152)
		(size 0.508)
		(drill 0.254)
		(layers "F.Cu" "B.Cu")
		(net "GND")
	)
	(via
		(at 107.526328 -136.337802)
		(size 0.508)
		(drill 0.254)
		(layers "F.Cu" "B.Cu")
		(net "GND")
	)
	(via
		(at 102.02418 -23.826978)
		(size 0.508)
		(drill 0.254)
		(layers "F.Cu" "B.Cu")
		(net "GND")
	)
	(via
		(at 47.600616 -87.375492)
		(size 0.508)
		(drill 0.254)
		(layers "F.Cu" "B.Cu")
		(net "GND")
	)
	(via
		(at 66.773044 -73.209658)
		(size 0.508)
		(drill 0.254)
		(layers "F.Cu" "B.Cu")
		(net "GND")
	)
	(via
		(at 172.237146 -99.03841)
		(size 0.508)
		(drill 0.254)
		(layers "F.Cu" "B.Cu")
		(net "GND")
	)
	(via
		(at 62.405514 -86.66861)
		(size 0.508)
		(drill 0.254)
		(layers "F.Cu" "B.Cu")
		(net "GND")
	)
	(via
		(at 49.594516 -78.908402)
		(size 0.508)
		(drill 0.254)
		(layers "F.Cu" "B.Cu")
		(net "GND")
	)
	(via
		(at 103.899716 -122.703336)
		(size 0.508)
		(drill 0.254)
		(layers "F.Cu" "B.Cu")
		(net "GND")
	)
	(via
		(at 170.03776 -100.376482)
		(size 0.508)
		(drill 0.254)
		(layers "F.Cu" "B.Cu")
		(net "GND")
	)
	(via
		(at 20.73529 -130.328416)
		(size 0.508)
		(drill 0.254)
		(layers "F.Cu" "B.Cu")
		(net "GND")
	)
	(via
		(at 73.742042 -143.659606)
		(size 0.49022)
		(drill 0.254)
		(layers "F.Cu" "B.Cu")
		(net "GND")
	)
	(via
		(at 52.864766 -65.409826)
		(size 0.508)
		(drill 0.254)
		(layers "F.Cu" "B.Cu")
		(net "GND")
	)
	(via
		(at 72.942196 -135.659368)
		(size 0.49022)
		(drill 0.254)
		(layers "F.Cu" "B.Cu")
		(net "GND")
	)
	(via
		(at 64.940942 -133.258306)
		(size 0.49022)
		(drill 0.254)
		(layers "F.Cu" "B.Cu")
		(net "GND")
	)
	(via
		(at 108.31322 -186.722004)
		(size 0.508)
		(drill 0.254)
		(layers "F.Cu" "B.Cu")
		(net "GND")
	)
	(via
		(at 101.421692 -65.336674)
		(size 0.508)
		(drill 0.254)
		(layers "F.Cu" "B.Cu")
		(net "GND")
	)
	(via
		(at 64.24676 -187.024772)
		(size 0.508)
		(drill 0.254)
		(layers "F.Cu" "B.Cu")
		(net "GND")
	)
	(via
		(at 94.64548 -24.98217)
		(size 0.508)
		(drill 0.254)
		(layers "F.Cu" "B.Cu")
		(net "GND")
	)
	(via
		(at 47.960534 -59.127136)
		(size 0.508)
		(drill 0.254)
		(layers "F.Cu" "B.Cu")
		(net "GND")
	)
	(via
		(at 34.672524 -84.377022)
		(size 0.508)
		(drill 0.254)
		(layers "F.Cu" "B.Cu")
		(net "GND")
	)
	(via
		(at 92.293186 -188.858398)
		(size 0.508)
		(drill 0.254)
		(layers "F.Cu" "B.Cu")
		(net "GND")
	)
	(via
		(at 70.540372 -89.582498)
		(size 0.508)
		(drill 0.254)
		(layers "F.Cu" "B.Cu")
		(net "GND")
	)
	(via
		(at 42.121328 -153.933398)
		(size 0.508)
		(drill 0.254)
		(layers "F.Cu" "B.Cu")
		(net "GND")
	)
	(via
		(at 181.33314 -173.05782)
		(size 0.508)
		(drill 0.254)
		(layers "F.Cu" "B.Cu")
		(net "GND")
	)
	(via
		(at 54.63159 -82.714846)
		(size 0.508)
		(drill 0.254)
		(layers "F.Cu" "B.Cu")
		(net "GND")
	)
	(via
		(at 138.425936 -177.652426)
		(size 0.508)
		(drill 0.254)
		(layers "F.Cu" "B.Cu")
		(net "GND")
	)
	(via
		(at 14.668246 -51.898804)
		(size 0.508)
		(drill 0.254)
		(layers "F.Cu" "B.Cu")
		(net "GND")
	)
	(via
		(at 61.05017 -27.624278)
		(size 0.508)
		(drill 0.254)
		(layers "F.Cu" "B.Cu")
		(net "GND")
	)
	(via
		(at 43.30954 -69.982588)
		(size 0.508)
		(drill 0.254)
		(layers "F.Cu" "B.Cu")
		(net "GND")
	)
	(via
		(at 148.565362 -168.612312)
		(size 0.508)
		(drill 0.254)
		(layers "F.Cu" "B.Cu")
		(net "GND")
	)
	(via
		(at 180.09616 -200.026778)
		(size 0.508)
		(drill 0.254)
		(layers "F.Cu" "B.Cu")
		(net "GND")
	)
	(via
		(at 67.535044 -69.016372)
		(size 0.508)
		(drill 0.254)
		(layers "F.Cu" "B.Cu")
		(net "GND")
	)
	(via
		(at 18.803874 -100.039678)
		(size 0.508)
		(drill 0.254)
		(layers "F.Cu" "B.Cu")
		(net "GND")
	)
	(via
		(at 81.84134 -85.520784)
		(size 0.508)
		(drill 0.254)
		(layers "F.Cu" "B.Cu")
		(net "GND")
	)
	(via
		(at 106.482134 -155.512262)
		(size 0.508)
		(drill 0.254)
		(layers "F.Cu" "B.Cu")
		(net "GND")
	)
	(via
		(at 74.542142 -142.05966)
		(size 0.49022)
		(drill 0.254)
		(layers "F.Cu" "B.Cu")
		(net "GND")
	)
	(via
		(at 153.815542 -100.05568)
		(size 0.508)
		(drill 0.254)
		(layers "F.Cu" "B.Cu")
		(net "GND")
	)
	(via
		(at 25.8191 -110.76305)
		(size 0.508)
		(drill 0.254)
		(layers "F.Cu" "B.Cu")
		(net "GND")
	)
	(via
		(at 49.101502 -82.674968)
		(size 0.508)
		(drill 0.254)
		(layers "F.Cu" "B.Cu")
		(net "GND")
	)
	(via
		(at 99.584002 -158.523686)
		(size 0.508)
		(drill 0.254)
		(layers "F.Cu" "B.Cu")
		(net "GND")
	)
	(via
		(at 58.53176 -187.048648)
		(size 0.508)
		(drill 0.254)
		(layers "F.Cu" "B.Cu")
		(net "GND")
	)
	(via
		(at 74.004678 -148.876512)
		(size 0.508)
		(drill 0.254)
		(layers "F.Cu" "B.Cu")
		(net "GND")
	)
	(via
		(at 12.507976 -91.529408)
		(size 0.508)
		(drill 0.254)
		(layers "F.Cu" "B.Cu")
		(net "GND")
	)
	(via
		(at 44.389294 -168.609264)
		(size 0.508)
		(drill 0.254)
		(layers "F.Cu" "B.Cu")
		(net "GND")
	)
	(via
		(at 101.2952 -117.410992)
		(size 0.508)
		(drill 0.254)
		(layers "F.Cu" "B.Cu")
		(net "GND")
	)
	(via
		(at 73.997058 -118.569994)
		(size 0.508)
		(drill 0.254)
		(layers "F.Cu" "B.Cu")
		(net "GND")
	)
	(via
		(at 107.522518 -179.157376)
		(size 0.508)
		(drill 0.254)
		(layers "F.Cu" "B.Cu")
		(net "GND")
	)
	(via
		(at 25.8191 -112.531652)
		(size 0.508)
		(drill 0.254)
		(layers "F.Cu" "B.Cu")
		(net "GND")
	)
	(via
		(at 116.4844 -152.1968)
		(size 0.508)
		(drill 0.254)
		(layers "F.Cu" "B.Cu")
		(net "GND")
	)
	(via
		(at 49.820576 -181.000908)
		(size 0.508)
		(drill 0.254)
		(layers "F.Cu" "B.Cu")
		(net "GND")
	)
	(via
		(at 151.51862 -146.025362)
		(size 0.508)
		(drill 0.254)
		(layers "F.Cu" "B.Cu")
		(net "GND")
	)
	(via
		(at 57.200546 -71.398892)
		(size 0.508)
		(drill 0.254)
		(layers "F.Cu" "B.Cu")
		(net "GND")
	)
	(via
		(at 73.46696 -184.070498)
		(size 0.508)
		(drill 0.254)
		(layers "F.Cu" "B.Cu")
		(net "GND")
	)
	(via
		(at 13.54582 -127.969518)
		(size 0.508)
		(drill 0.254)
		(layers "F.Cu" "B.Cu")
		(net "GND")
	)
	(via
		(at 24.014938 -201.09053)
		(size 0.508)
		(drill 0.254)
		(layers "F.Cu" "B.Cu")
		(net "GND")
	)
	(via
		(at 34.233358 -187.636404)
		(size 0.508)
		(drill 0.254)
		(layers "F.Cu" "B.Cu")
		(net "GND")
	)
	(via
		(at 64.46774 -16.063976)
		(size 0.508)
		(drill 0.254)
		(layers "F.Cu" "B.Cu")
		(net "GND")
	)
	(via
		(at 93.09354 -183.799988)
		(size 0.508)
		(drill 0.254)
		(layers "F.Cu" "B.Cu")
		(net "GND")
	)
	(via
		(at 108.933996 -134.779258)
		(size 0.508)
		(drill 0.254)
		(layers "F.Cu" "B.Cu")
		(net "GND")
	)
	(via
		(at 45.683678 -121.35866)
		(size 0.508)
		(drill 0.254)
		(layers "F.Cu" "B.Cu")
		(net "GND")
	)
	(via
		(at 153.908252 -186.85891)
		(size 0.508)
		(drill 0.254)
		(layers "F.Cu" "B.Cu")
		(net "GND")
	)
	(via
		(at 57.097676 -65.215516)
		(size 0.508)
		(drill 0.254)
		(layers "F.Cu" "B.Cu")
		(net "GND")
	)
	(via
		(at 15.502382 -129.71907)
		(size 0.508)
		(drill 0.254)
		(layers "F.Cu" "B.Cu")
		(net "GND")
	)
	(via
		(at 118.47576 -184.01411)
		(size 0.508)
		(drill 0.254)
		(layers "F.Cu" "B.Cu")
		(net "GND")
	)
	(via
		(at 41.193974 -76.98105)
		(size 0.508)
		(drill 0.254)
		(layers "F.Cu" "B.Cu")
		(net "GND")
	)
	(via
		(at 31.173166 -101.092254)
		(size 0.508)
		(drill 0.254)
		(layers "F.Cu" "B.Cu")
		(net "GND")
	)
	(via
		(at 24.426672 -58.830972)
		(size 0.508)
		(drill 0.254)
		(layers "F.Cu" "B.Cu")
		(net "GND")
	)
	(via
		(at 93.532452 -132.758942)
		(size 0.508)
		(drill 0.254)
		(layers "F.Cu" "B.Cu")
		(net "GND")
	)
	(via
		(at 64.940942 -140.457936)
		(size 0.49022)
		(drill 0.254)
		(layers "F.Cu" "B.Cu")
		(net "GND")
	)
	(via
		(at 175.551592 -35.59556)
		(size 0.508)
		(drill 0.254)
		(layers "F.Cu" "B.Cu")
		(net "GND")
	)
	(via
		(at 99.450144 -27.68346)
		(size 0.508)
		(drill 0.254)
		(layers "F.Cu" "B.Cu")
		(net "GND")
	)
	(via
		(at 126.76505 -59.83605)
		(size 0.508)
		(drill 0.254)
		(layers "F.Cu" "B.Cu")
		(net "GND")
	)
	(via
		(at 92.11564 -80.514444)
		(size 0.508)
		(drill 0.254)
		(layers "F.Cu" "B.Cu")
		(net "GND")
	)
	(via
		(at 49.471834 -76.752704)
		(size 0.508)
		(drill 0.254)
		(layers "F.Cu" "B.Cu")
		(net "GND")
	)
	(via
		(at 120.41632 -104.508554)
		(size 0.508)
		(drill 0.254)
		(layers "F.Cu" "B.Cu")
		(net "GND")
	)
	(via
		(at 164.314124 -128.32334)
		(size 0.508)
		(drill 0.254)
		(layers "F.Cu" "B.Cu")
		(net "GND")
	)
	(via
		(at 138.975592 -55.93588)
		(size 0.508)
		(drill 0.254)
		(layers "F.Cu" "B.Cu")
		(net "GND")
	)
	(via
		(at 164.087302 -90.95994)
		(size 0.508)
		(drill 0.254)
		(layers "F.Cu" "B.Cu")
		(net "GND")
	)
	(via
		(at 148.292566 -29.903928)
		(size 0.508)
		(drill 0.254)
		(layers "F.Cu" "B.Cu")
		(net "GND")
	)
	(via
		(at 161.27603 -117.319552)
		(size 0.508)
		(drill 0.254)
		(layers "F.Cu" "B.Cu")
		(net "GND")
	)
	(via
		(at 134.98576 -109.773212)
		(size 0.508)
		(drill 0.254)
		(layers "F.Cu" "B.Cu")
		(net "GND")
	)
	(via
		(at 78.230476 -154.149044)
		(size 0.508)
		(drill 0.254)
		(layers "F.Cu" "B.Cu")
		(net "GND")
	)
	(via
		(at 33.967674 -125.45314)
		(size 0.508)
		(drill 0.254)
		(layers "F.Cu" "B.Cu")
		(net "GND")
	)
	(via
		(at 45.806868 -80.383126)
		(size 0.508)
		(drill 0.254)
		(layers "F.Cu" "B.Cu")
		(net "GND")
	)
	(via
		(at 69.015102 -201.09053)
		(size 0.508)
		(drill 0.254)
		(layers "F.Cu" "B.Cu")
		(net "GND")
	)
	(via
		(at 101.667818 -173.743366)
		(size 0.508)
		(drill 0.254)
		(layers "F.Cu" "B.Cu")
		(net "GND")
	)
	(via
		(at 66.809366 -65.821306)
		(size 0.508)
		(drill 0.254)
		(layers "F.Cu" "B.Cu")
		(net "GND")
	)
	(via
		(at 34.821114 -76.656946)
		(size 0.508)
		(drill 0.254)
		(layers "F.Cu" "B.Cu")
		(net "GND")
	)
	(via
		(at 135.08863 -183.92013)
		(size 0.508)
		(drill 0.254)
		(layers "F.Cu" "B.Cu")
		(net "GND")
	)
	(via
		(at 100.608892 -72.118474)
		(size 0.508)
		(drill 0.254)
		(layers "F.Cu" "B.Cu")
		(net "GND")
	)
	(via
		(at 96.310958 -129.488692)
		(size 0.508)
		(drill 0.254)
		(layers "F.Cu" "B.Cu")
		(net "GND")
	)
	(via
		(at 44.238164 -1.892046)
		(size 0.508)
		(drill 0.254)
		(layers "F.Cu" "B.Cu")
		(net "GND")
	)
	(via
		(at 52.95519 -84.418424)
		(size 0.508)
		(drill 0.254)
		(layers "F.Cu" "B.Cu")
		(net "GND")
	)
	(via
		(at 150.47976 -183.837072)
		(size 0.508)
		(drill 0.254)
		(layers "F.Cu" "B.Cu")
		(net "GND")
	)
	(via
		(at 158.586932 -44.72686)
		(size 0.508)
		(drill 0.254)
		(layers "F.Cu" "B.Cu")
		(net "GND")
	)
	(via
		(at 151.574754 -135.155432)
		(size 0.508)
		(drill 0.254)
		(layers "F.Cu" "B.Cu")
		(net "GND")
	)
	(via
		(at 32.022288 -122.139456)
		(size 0.508)
		(drill 0.254)
		(layers "F.Cu" "B.Cu")
		(net "GND")
	)
	(via
		(at 9.38022 -155.214828)
		(size 0.508)
		(drill 0.254)
		(layers "F.Cu" "B.Cu")
		(net "GND")
	)
	(via
		(at 54.015132 -201.09053)
		(size 0.508)
		(drill 0.254)
		(layers "F.Cu" "B.Cu")
		(net "GND")
	)
	(via
		(at 54.515004 -131.188968)
		(size 0.49022)
		(drill 0.254)
		(layers "F.Cu" "B.Cu")
		(net "GND")
	)
	(via
		(at 62.48146 -5.389626)
		(size 0.508)
		(drill 0.254)
		(layers "F.Cu" "B.Cu")
		(net "GND")
	)
	(via
		(at 66.540888 -133.258306)
		(size 0.49022)
		(drill 0.254)
		(layers "F.Cu" "B.Cu")
		(net "GND")
	)
	(via
		(at 124.753878 -171.603416)
		(size 0.508)
		(drill 0.254)
		(layers "F.Cu" "B.Cu")
		(net "GND")
	)
	(via
		(at 177.51044 -122.865642)
		(size 0.49022)
		(drill 0.254)
		(layers "F.Cu" "B.Cu")
		(net "GND")
	)
	(via
		(at 60.81776 -186.97956)
		(size 0.508)
		(drill 0.254)
		(layers "F.Cu" "B.Cu")
		(net "GND")
	)
	(via
		(at 103.11892 -105.31602)
		(size 0.508)
		(drill 0.254)
		(layers "F.Cu" "B.Cu")
		(net "GND")
	)
	(via
		(at 56.969406 -172.740574)
		(size 0.508)
		(drill 0.254)
		(layers "F.Cu" "B.Cu")
		(net "GND")
	)
	(via
		(at 34.227262 -184.444894)
		(size 0.508)
		(drill 0.254)
		(layers "F.Cu" "B.Cu")
		(net "GND")
	)
	(via
		(at 130.137916 -150.06955)
		(size 0.508)
		(drill 0.254)
		(layers "F.Cu" "B.Cu")
		(net "GND")
	)
	(via
		(at 112.033304 -74.906124)
		(size 0.508)
		(drill 0.254)
		(layers "F.Cu" "B.Cu")
		(net "GND")
	)
	(via
		(at 110.60176 -186.925712)
		(size 0.508)
		(drill 0.254)
		(layers "F.Cu" "B.Cu")
		(net "GND")
	)
	(via
		(at 57.740804 -128.458214)
		(size 0.49022)
		(drill 0.254)
		(layers "F.Cu" "B.Cu")
		(net "GND")
	)
	(via
		(at 50.923952 -100.69195)
		(size 0.508)
		(drill 0.254)
		(layers "F.Cu" "B.Cu")
		(net "GND")
	)
	(via
		(at 194.77736 -142.56766)
		(size 0.508)
		(drill 0.254)
		(layers "F.Cu" "B.Cu")
		(net "GND")
	)
	(via
		(at 138.79576 -186.862974)
		(size 0.508)
		(drill 0.254)
		(layers "F.Cu" "B.Cu")
		(net "GND")
	)
	(via
		(at 170.84802 -183.071008)
		(size 0.508)
		(drill 0.254)
		(layers "F.Cu" "B.Cu")
		(net "GND")
	)
	(via
		(at 166.629334 -108.677456)
		(size 0.508)
		(drill 0.254)
		(layers "F.Cu" "B.Cu")
		(net "GND")
	)
	(via
		(at 79.96682 -23.584154)
		(size 0.508)
		(drill 0.254)
		(layers "F.Cu" "B.Cu")
		(net "GND")
	)
	(via
		(at 154.632914 -186.88685)
		(size 0.508)
		(drill 0.254)
		(layers "F.Cu" "B.Cu")
		(net "GND")
	)
	(via
		(at 53.85308 -59.527186)
		(size 0.508)
		(drill 0.254)
		(layers "F.Cu" "B.Cu")
		(net "GND")
	)
	(via
		(at 168.13276 -103.729282)
		(size 0.508)
		(drill 0.254)
		(layers "F.Cu" "B.Cu")
		(net "GND")
	)
	(via
		(at 64.940942 -136.458198)
		(size 0.49022)
		(drill 0.254)
		(layers "F.Cu" "B.Cu")
		(net "GND")
	)
	(via
		(at 63.121286 -86.158578)
		(size 0.508)
		(drill 0.254)
		(layers "F.Cu" "B.Cu")
		(net "GND")
	)
	(via
		(at 72.942196 -138.059414)
		(size 0.49022)
		(drill 0.254)
		(layers "F.Cu" "B.Cu")
		(net "GND")
	)
	(via
		(at 72.142096 -142.859252)
		(size 0.49022)
		(drill 0.254)
		(layers "F.Cu" "B.Cu")
		(net "GND")
	)
	(via
		(at 140.065252 -142.55115)
		(size 0.508)
		(drill 0.254)
		(layers "F.Cu" "B.Cu")
		(net "GND")
	)
	(via
		(at 160.015682 -201.034904)
		(size 0.508)
		(drill 0.254)
		(layers "F.Cu" "B.Cu")
		(net "GND")
	)
	(via
		(at 69.073776 -78.649322)
		(size 0.508)
		(drill 0.254)
		(layers "F.Cu" "B.Cu")
		(net "GND")
	)
	(via
		(at 11.576812 -12.821412)
		(size 0.508)
		(drill 0.254)
		(layers "F.Cu" "B.Cu")
		(net "GND")
	)
	(via
		(at 68.141088 -136.458198)
		(size 0.49022)
		(drill 0.254)
		(layers "F.Cu" "B.Cu")
		(net "GND")
	)
	(via
		(at 70.232778 -75.137264)
		(size 0.508)
		(drill 0.254)
		(layers "F.Cu" "B.Cu")
		(net "GND")
	)
	(via
		(at -9.107932 -185.771282)
		(size 0.508)
		(drill 0.254)
		(layers "F.Cu" "B.Cu")
		(net "GND")
	)
	(via
		(at 32.98444 -3.701034)
		(size 0.508)
		(drill 0.254)
		(layers "F.Cu" "B.Cu")
		(net "GND")
	)
	(via
		(at 121.857516 -117.598952)
		(size 0.508)
		(drill 0.254)
		(layers "F.Cu" "B.Cu")
		(net "GND")
	)
	(via
		(at 68.141088 -134.058406)
		(size 0.49022)
		(drill 0.254)
		(layers "F.Cu" "B.Cu")
		(net "GND")
	)
	(via
		(at 43.603672 -65.096898)
		(size 0.508)
		(drill 0.254)
		(layers "F.Cu" "B.Cu")
		(net "GND")
	)
	(via
		(at 166.41318 -162.415728)
		(size 0.508)
		(drill 0.254)
		(layers "F.Cu" "B.Cu")
		(net "GND")
	)
	(via
		(at 188.315854 -115.527328)
		(size 0.508)
		(drill 0.254)
		(layers "F.Cu" "B.Cu")
		(net "GND")
	)
	(via
		(at 61.135768 -87.427816)
		(size 0.508)
		(drill 0.254)
		(layers "F.Cu" "B.Cu")
		(net "GND")
	)
	(via
		(at 146.271996 -73.63333)
		(size 0.508)
		(drill 0.254)
		(layers "F.Cu" "B.Cu")
		(net "GND")
	)
	(via
		(at 16.621252 -129.709164)
		(size 0.508)
		(drill 0.254)
		(layers "F.Cu" "B.Cu")
		(net "GND")
	)
	(via
		(at 121.64187 -167.494204)
		(size 0.508)
		(drill 0.254)
		(layers "F.Cu" "B.Cu")
		(net "GND")
	)
	(via
		(at 169.57294 -156.768038)
		(size 0.508)
		(drill 0.254)
		(layers "F.Cu" "B.Cu")
		(net "GND")
	)
	(via
		(at 58.971688 -98.758756)
		(size 0.508)
		(drill 0.254)
		(layers "F.Cu" "B.Cu")
		(net "GND")
	)
	(via
		(at 145.65376 -186.862974)
		(size 0.508)
		(drill 0.254)
		(layers "F.Cu" "B.Cu")
		(net "GND")
	)
	(via
		(at 84.443062 -31.063438)
		(size 0.508)
		(drill 0.254)
		(layers "F.Cu" "B.Cu")
		(net "GND")
	)
	(via
		(at 182.50154 -173.107604)
		(size 0.508)
		(drill 0.254)
		(layers "F.Cu" "B.Cu")
		(net "GND")
	)
	(via
		(at 71.703692 -122.885962)
		(size 0.508)
		(drill 0.254)
		(layers "F.Cu" "B.Cu")
		(net "GND")
	)
	(via
		(at 154.728672 -140.932154)
		(size 0.508)
		(drill 0.254)
		(layers "F.Cu" "B.Cu")
		(net "GND")
	)
	(via
		(at 40.280082 -72.529192)
		(size 0.508)
		(drill 0.254)
		(layers "F.Cu" "B.Cu")
		(net "GND")
	)
	(via
		(at 133.946646 -38.670484)
		(size 0.508)
		(drill 0.254)
		(layers "F.Cu" "B.Cu")
		(net "GND")
	)
	(via
		(at 75.02906 -11.180318)
		(size 0.508)
		(drill 0.254)
		(layers "F.Cu" "B.Cu")
		(net "GND")
	)
	(via
		(at 174.528734 -103.379016)
		(size 0.508)
		(drill 0.254)
		(layers "F.Cu" "B.Cu")
		(net "GND")
	)
	(via
		(at 40.177974 -3.042412)
		(size 0.508)
		(drill 0.254)
		(layers "F.Cu" "B.Cu")
		(net "GND")
	)
	(via
		(at 14.27226 -43.186604)
		(size 0.508)
		(drill 0.254)
		(layers "F.Cu" "B.Cu")
		(net "GND")
	)
	(via
		(at 50.726086 -140.119862)
		(size 0.49022)
		(drill 0.254)
		(layers "F.Cu" "B.Cu")
		(net "GND")
	)
	(via
		(at 165.443408 -82.280252)
		(size 0.508)
		(drill 0.254)
		(layers "F.Cu" "B.Cu")
		(net "GND")
	)
	(via
		(at 48.939704 -102.352094)
		(size 0.508)
		(drill 0.254)
		(layers "F.Cu" "B.Cu")
		(net "GND")
	)
	(via
		(at 95.00362 -24.13)
		(size 0.508)
		(drill 0.254)
		(layers "F.Cu" "B.Cu")
		(net "GND")
	)
	(via
		(at 118.85168 -114.723418)
		(size 0.508)
		(drill 0.254)
		(layers "F.Cu" "B.Cu")
		(net "GND")
	)
	(via
		(at 53.83149 -61.99759)
		(size 0.508)
		(drill 0.254)
		(layers "F.Cu" "B.Cu")
		(net "GND")
	)
	(via
		(at 48.70069 -1.871726)
		(size 0.508)
		(drill 0.254)
		(layers "F.Cu" "B.Cu")
		(net "GND")
	)
	(via
		(at 118.528338 -23.170896)
		(size 0.508)
		(drill 0.254)
		(layers "F.Cu" "B.Cu")
		(net "GND")
	)
	(via
		(at 106.05008 -134.918958)
		(size 0.508)
		(drill 0.254)
		(layers "F.Cu" "B.Cu")
		(net "GND")
	)
	(via
		(at 82.081116 -140.682218)
		(size 0.508)
		(drill 0.254)
		(layers "F.Cu" "B.Cu")
		(net "GND")
	)
	(via
		(at 75.207622 -22.473158)
		(size 0.508)
		(drill 0.254)
		(layers "F.Cu" "B.Cu")
		(net "GND")
	)
	(via
		(at 47.241714 -70.876414)
		(size 0.508)
		(drill 0.254)
		(layers "F.Cu" "B.Cu")
		(net "GND")
	)
	(via
		(at 46.423834 -107.064302)
		(size 0.508)
		(drill 0.254)
		(layers "F.Cu" "B.Cu")
		(net "GND")
	)
	(via
		(at 125.8062 -51.2064)
		(size 0.508)
		(drill 0.254)
		(layers "F.Cu" "B.Cu")
		(net "GND")
	)
	(via
		(at 46.032928 -138.164062)
		(size 0.49022)
		(drill 0.254)
		(layers "F.Cu" "B.Cu")
		(net "GND")
	)
	(via
		(at 90.5637 -18.990818)
		(size 0.508)
		(drill 0.254)
		(layers "F.Cu" "B.Cu")
		(net "GND")
	)
	(via
		(at 13.54582 -128.629918)
		(size 0.508)
		(drill 0.254)
		(layers "F.Cu" "B.Cu")
		(net "GND")
	)
	(via
		(at 100.705412 -168.028366)
		(size 0.508)
		(drill 0.254)
		(layers "F.Cu" "B.Cu")
		(net "GND")
	)
	(via
		(at 103.1621 -110.033562)
		(size 0.508)
		(drill 0.254)
		(layers "F.Cu" "B.Cu")
		(net "GND")
	)
	(via
		(at 133.080252 -134.29615)
		(size 0.508)
		(drill 0.254)
		(layers "F.Cu" "B.Cu")
		(net "GND")
	)
	(via
		(at 107.054142 -40.781224)
		(size 0.508)
		(drill 0.254)
		(layers "F.Cu" "B.Cu")
		(net "GND")
	)
	(via
		(at 99.36226 -26.459942)
		(size 0.508)
		(drill 0.254)
		(layers "F.Cu" "B.Cu")
		(net "GND")
	)
	(via
		(at 68.941188 -142.858236)
		(size 0.49022)
		(drill 0.254)
		(layers "F.Cu" "B.Cu")
		(net "GND")
	)
	(via
		(at 148.447252 -40.876982)
		(size 0.508)
		(drill 0.254)
		(layers "F.Cu" "B.Cu")
		(net "GND")
	)
	(via
		(at 57.200546 -78.599792)
		(size 0.508)
		(drill 0.254)
		(layers "F.Cu" "B.Cu")
		(net "GND")
	)
	(via
		(at 75.636628 -74.159364)
		(size 0.508)
		(drill 0.254)
		(layers "F.Cu" "B.Cu")
		(net "GND")
	)
	(via
		(at 167.994584 -149.5806)
		(size 0.508)
		(drill 0.254)
		(layers "F.Cu" "B.Cu")
		(net "GND")
	)
	(via
		(at 141.467586 -112.524286)
		(size 0.508)
		(drill 0.254)
		(layers "F.Cu" "B.Cu")
		(net "GND")
	)
	(via
		(at 33.1089 -33.1216)
		(size 0.508)
		(drill 0.254)
		(layers "F.Cu" "B.Cu")
		(net "GND")
	)
	(via
		(at 108.933996 -133.399022)
		(size 0.508)
		(drill 0.254)
		(layers "F.Cu" "B.Cu")
		(net "GND")
	)
	(via
		(at 152.76576 -186.862974)
		(size 0.508)
		(drill 0.254)
		(layers "F.Cu" "B.Cu")
		(net "GND")
	)
	(via
		(at 59.250072 -30.922468)
		(size 0.508)
		(drill 0.254)
		(layers "F.Cu" "B.Cu")
		(net "GND")
	)
	(via
		(at 79.10576 -186.901074)
		(size 0.508)
		(drill 0.254)
		(layers "F.Cu" "B.Cu")
		(net "GND")
	)
	(via
		(at 186.55284 -200.318116)
		(size 0.508)
		(drill 0.254)
		(layers "F.Cu" "B.Cu")
		(net "GND")
	)
	(via
		(at 170.5356 -169.202354)
		(size 0.508)
		(drill 0.254)
		(layers "F.Cu" "B.Cu")
		(net "GND")
	)
	(via
		(at 21.014944 -200.32853)
		(size 0.508)
		(drill 0.254)
		(layers "F.Cu" "B.Cu")
		(net "GND")
	)
	(via
		(at 134.629652 -112.858042)
		(size 0.508)
		(drill 0.254)
		(layers "F.Cu" "B.Cu")
		(net "GND")
	)
	(via
		(at 102.39502 -106.195114)
		(size 0.508)
		(drill 0.254)
		(layers "F.Cu" "B.Cu")
		(net "GND")
	)
	(via
		(at 174.79264 -16.372586)
		(size 0.508)
		(drill 0.254)
		(layers "F.Cu" "B.Cu")
		(net "GND")
	)
	(via
		(at 87.150194 -22.460966)
		(size 0.508)
		(drill 0.254)
		(layers "F.Cu" "B.Cu")
		(net "GND")
	)
	(via
		(at 48.493172 -70.532498)
		(size 0.508)
		(drill 0.254)
		(layers "F.Cu" "B.Cu")
		(net "GND")
	)
	(via
		(at 114.532918 -24.781764)
		(size 0.508)
		(drill 0.254)
		(layers "F.Cu" "B.Cu")
		(net "GND")
	)
	(via
		(at 163.325048 -143.571722)
		(size 0.508)
		(drill 0.254)
		(layers "F.Cu" "B.Cu")
		(net "GND")
	)
	(via
		(at 46.399196 -185.552334)
		(size 0.508)
		(drill 0.254)
		(layers "F.Cu" "B.Cu")
		(net "GND")
	)
	(via
		(at 130.91795 -174.188882)
		(size 0.508)
		(drill 0.254)
		(layers "F.Cu" "B.Cu")
		(net "GND")
	)
	(via
		(at 27.84856 -155.42006)
		(size 0.508)
		(drill 0.254)
		(layers "F.Cu" "B.Cu")
		(net "GND")
	)
	(via
		(at 153.612596 -63.44793)
		(size 0.508)
		(drill 0.254)
		(layers "F.Cu" "B.Cu")
		(net "GND")
	)
	(via
		(at 117.24386 -113.4618)
		(size 0.508)
		(drill 0.254)
		(layers "F.Cu" "B.Cu")
		(net "GND")
	)
	(via
		(at 30.561788 -188.515498)
		(size 0.508)
		(drill 0.254)
		(layers "F.Cu" "B.Cu")
		(net "GND")
	)
	(via
		(at 64.940942 -135.658352)
		(size 0.49022)
		(drill 0.254)
		(layers "F.Cu" "B.Cu")
		(net "GND")
	)
	(via
		(at 58.800746 -72.999092)
		(size 0.508)
		(drill 0.254)
		(layers "F.Cu" "B.Cu")
		(net "GND")
	)
	(via
		(at 40.43299 -134.964424)
		(size 0.49022)
		(drill 0.254)
		(layers "F.Cu" "B.Cu")
		(net "GND")
	)
	(via
		(at 132.015484 -201.034904)
		(size 0.508)
		(drill 0.254)
		(layers "F.Cu" "B.Cu")
		(net "GND")
	)
	(via
		(at 28.974288 -122.164856)
		(size 0.508)
		(drill 0.254)
		(layers "F.Cu" "B.Cu")
		(net "GND")
	)
	(via
		(at 161.764472 -150.657814)
		(size 0.508)
		(drill 0.254)
		(layers "F.Cu" "B.Cu")
		(net "GND")
	)
	(via
		(at 117.11432 -104.508554)
		(size 0.508)
		(drill 0.254)
		(layers "F.Cu" "B.Cu")
		(net "GND")
	)
	(via
		(at 81.062322 -81.769712)
		(size 0.508)
		(drill 0.254)
		(layers "F.Cu" "B.Cu")
		(net "GND")
	)
	(via
		(at 78.257908 -157.01899)
		(size 0.508)
		(drill 0.254)
		(layers "F.Cu" "B.Cu")
		(net "GND")
	)
	(via
		(at 169.104564 -108.678472)
		(size 0.508)
		(drill 0.254)
		(layers "F.Cu" "B.Cu")
		(net "GND")
	)
	(via
		(at 63.10376 -186.985402)
		(size 0.508)
		(drill 0.254)
		(layers "F.Cu" "B.Cu")
		(net "GND")
	)
	(via
		(at 24.375872 -93.424756)
		(size 0.508)
		(drill 0.254)
		(layers "F.Cu" "B.Cu")
		(net "GND")
	)
	(via
		(at 60.03544 -23.858474)
		(size 0.508)
		(drill 0.254)
		(layers "F.Cu" "B.Cu")
		(net "GND")
	)
	(via
		(at 76.507086 -124.168662)
		(size 0.508)
		(drill 0.254)
		(layers "F.Cu" "B.Cu")
		(net "GND")
	)
	(via
		(at 93.319346 -173.901608)
		(size 0.508)
		(drill 0.254)
		(layers "F.Cu" "B.Cu")
		(net "GND")
	)
	(via
		(at 28.778454 -126.891796)
		(size 0.508)
		(drill 0.254)
		(layers "F.Cu" "B.Cu")
		(net "GND")
	)
	(via
		(at 106.015536 -201.034904)
		(size 0.508)
		(drill 0.254)
		(layers "F.Cu" "B.Cu")
		(net "GND")
	)
	(via
		(at 16.18488 -58.085482)
		(size 0.508)
		(drill 0.254)
		(layers "F.Cu" "B.Cu")
		(net "GND")
	)
	(via
		(at 6.200394 -4.111244)
		(size 0.508)
		(drill 0.254)
		(layers "F.Cu" "B.Cu")
		(net "GND")
	)
	(via
		(at 47.474632 -89.60104)
		(size 0.508)
		(drill 0.254)
		(layers "F.Cu" "B.Cu")
		(net "GND")
	)
	(via
		(at 61.873384 -170.630088)
		(size 0.508)
		(drill 0.254)
		(layers "F.Cu" "B.Cu")
		(net "GND")
	)
	(via
		(at 70.54215 -140.459206)
		(size 0.49022)
		(drill 0.254)
		(layers "F.Cu" "B.Cu")
		(net "GND")
	)
	(via
		(at 64.823086 -66.202306)
		(size 0.508)
		(drill 0.254)
		(layers "F.Cu" "B.Cu")
		(net "GND")
	)
	(via
		(at 31.50616 -116.775484)
		(size 0.508)
		(drill 0.254)
		(layers "F.Cu" "B.Cu")
		(net "GND")
	)
	(via
		(at 46.998128 -154.111198)
		(size 0.508)
		(drill 0.254)
		(layers "F.Cu" "B.Cu")
		(net "GND")
	)
	(via
		(at 26.84018 -104.460548)
		(size 0.508)
		(drill 0.254)
		(layers "F.Cu" "B.Cu")
		(net "GND")
	)
	(via
		(at 114.528346 -122.796808)
		(size 0.508)
		(drill 0.254)
		(layers "F.Cu" "B.Cu")
		(net "GND")
	)
	(via
		(at 57.38876 -183.911494)
		(size 0.508)
		(drill 0.254)
		(layers "F.Cu" "B.Cu")
		(net "GND")
	)
	(via
		(at 126.552452 -106.12755)
		(size 0.508)
		(drill 0.254)
		(layers "F.Cu" "B.Cu")
		(net "GND")
	)
	(via
		(at 104.89184 -157.024578)
		(size 0.508)
		(drill 0.254)
		(layers "F.Cu" "B.Cu")
		(net "GND")
	)
	(via
		(at 132.93598 -183.929274)
		(size 0.508)
		(drill 0.254)
		(layers "F.Cu" "B.Cu")
		(net "GND")
	)
	(via
		(at 161.01568 -201.034904)
		(size 0.508)
		(drill 0.254)
		(layers "F.Cu" "B.Cu")
		(net "GND")
	)
	(via
		(at 74.542142 -137.259314)
		(size 0.49022)
		(drill 0.254)
		(layers "F.Cu" "B.Cu")
		(net "GND")
	)
	(via
		(at 57.55894 -181.224428)
		(size 0.508)
		(drill 0.254)
		(layers "F.Cu" "B.Cu")
		(net "GND")
	)
	(via
		(at 130.42392 -137.540746)
		(size 0.508)
		(drill 0.254)
		(layers "F.Cu" "B.Cu")
		(net "GND")
	)
	(via
		(at 16.830548 -140.549376)
		(size 0.508)
		(drill 0.254)
		(layers "F.Cu" "B.Cu")
		(net "GND")
	)
	(via
		(at 124.762006 -172.632624)
		(size 0.508)
		(drill 0.254)
		(layers "F.Cu" "B.Cu")
		(net "GND")
	)
	(via
		(at 148.298662 -79.700882)
		(size 0.508)
		(drill 0.254)
		(layers "F.Cu" "B.Cu")
		(net "GND")
	)
	(via
		(at 19.141186 -51.081686)
		(size 0.508)
		(drill 0.254)
		(layers "F.Cu" "B.Cu")
		(net "GND")
	)
	(via
		(at 70.278498 -97.8154)
		(size 0.508)
		(drill 0.254)
		(layers "F.Cu" "B.Cu")
		(net "GND")
	)
	(via
		(at 68.141088 -128.458214)
		(size 0.49022)
		(drill 0.254)
		(layers "F.Cu" "B.Cu")
		(net "GND")
	)
	(via
		(at 81.39176 -186.951874)
		(size 0.508)
		(drill 0.254)
		(layers "F.Cu" "B.Cu")
		(net "GND")
	)
	(via
		(at 149.527768 -48.973486)
		(size 0.508)
		(drill 0.254)
		(layers "F.Cu" "B.Cu")
		(net "GND")
	)
	(via
		(at 42.121328 -155.736798)
		(size 0.508)
		(drill 0.254)
		(layers "F.Cu" "B.Cu")
		(net "GND")
	)
	(via
		(at 61.46546 -5.389626)
		(size 0.508)
		(drill 0.254)
		(layers "F.Cu" "B.Cu")
		(net "GND")
	)
	(via
		(at 120.63476 -189.786768)
		(size 0.508)
		(drill 0.254)
		(layers "F.Cu" "B.Cu")
		(net "GND")
	)
	(via
		(at 34.47542 -79.893922)
		(size 0.508)
		(drill 0.254)
		(layers "F.Cu" "B.Cu")
		(net "GND")
	)
	(via
		(at 119.71274 -186.387994)
		(size 0.508)
		(drill 0.254)
		(layers "F.Cu" "B.Cu")
		(net "GND")
	)
	(via
		(at 101.3841 -33.470342)
		(size 0.508)
		(drill 0.254)
		(layers "F.Cu" "B.Cu")
		(net "GND")
	)
	(via
		(at 74.901552 -77.331824)
		(size 0.508)
		(drill 0.254)
		(layers "F.Cu" "B.Cu")
		(net "GND")
	)
	(via
		(at 157.015688 -201.034904)
		(size 0.508)
		(drill 0.254)
		(layers "F.Cu" "B.Cu")
		(net "GND")
	)
	(via
		(at 64.940942 -137.258298)
		(size 0.49022)
		(drill 0.254)
		(layers "F.Cu" "B.Cu")
		(net "GND")
	)
	(via
		(at 56.24576 -186.927236)
		(size 0.508)
		(drill 0.254)
		(layers "F.Cu" "B.Cu")
		(net "GND")
	)
	(via
		(at 43.6753 -26.69667)
		(size 0.508)
		(drill 0.254)
		(layers "F.Cu" "B.Cu")
		(net "GND")
	)
	(via
		(at 185.67146 -196.934836)
		(size 0.508)
		(drill 0.254)
		(layers "F.Cu" "B.Cu")
		(net "GND")
	)
	(via
		(at 60.400946 -72.198992)
		(size 0.508)
		(drill 0.254)
		(layers "F.Cu" "B.Cu")
		(net "GND")
	)
	(via
		(at 40.654732 -95.457772)
		(size 0.508)
		(drill 0.254)
		(layers "F.Cu" "B.Cu")
		(net "GND")
	)
	(via
		(at 79.91856 -16.044418)
		(size 0.508)
		(drill 0.254)
		(layers "F.Cu" "B.Cu")
		(net "GND")
	)
	(via
		(at 111.74476 -186.818778)
		(size 0.508)
		(drill 0.254)
		(layers "F.Cu" "B.Cu")
		(net "GND")
	)
	(via
		(at 52.698904 -154.669744)
		(size 0.508)
		(drill 0.254)
		(layers "F.Cu" "B.Cu")
		(net "GND")
	)
	(via
		(at 31.373572 -188.47562)
		(size 0.508)
		(drill 0.254)
		(layers "F.Cu" "B.Cu")
		(net "GND")
	)
	(via
		(at 47.10176 -180.974746)
		(size 0.508)
		(drill 0.254)
		(layers "F.Cu" "B.Cu")
		(net "GND")
	)
	(via
		(at 42.69994 -89.063068)
		(size 0.508)
		(drill 0.254)
		(layers "F.Cu" "B.Cu")
		(net "GND")
	)
	(via
		(at 34.21888 -188.565028)
		(size 0.508)
		(drill 0.254)
		(layers "F.Cu" "B.Cu")
		(net "GND")
	)
	(via
		(at 163.604702 -75.456034)
		(size 0.508)
		(drill 0.254)
		(layers "F.Cu" "B.Cu")
		(net "GND")
	)
	(via
		(at 75.415902 -130.67284)
		(size 0.508)
		(drill 0.254)
		(layers "F.Cu" "B.Cu")
		(net "GND")
	)
	(via
		(at 45.07738 -74.912982)
		(size 0.508)
		(drill 0.254)
		(layers "F.Cu" "B.Cu")
		(net "GND")
	)
	(via
		(at 125.984 -186.982608)
		(size 0.508)
		(drill 0.254)
		(layers "F.Cu" "B.Cu")
		(net "GND")
	)
	(via
		(at 102.879652 -67.950334)
		(size 0.508)
		(drill 0.254)
		(layers "F.Cu" "B.Cu")
		(net "GND")
	)
	(via
		(at 12.63142 -104.768142)
		(size 0.508)
		(drill 0.254)
		(layers "F.Cu" "B.Cu")
		(net "GND")
	)
	(via
		(at 179.86502 -27.022806)
		(size 0.508)
		(drill 0.254)
		(layers "F.Cu" "B.Cu")
		(net "GND")
	)
	(via
		(at 62.646306 -156.560012)
		(size 0.508)
		(drill 0.254)
		(layers "F.Cu" "B.Cu")
		(net "GND")
	)
	(via
		(at 20.204176 -67.965066)
		(size 0.508)
		(drill 0.254)
		(layers "F.Cu" "B.Cu")
		(net "GND")
	)
	(via
		(at 158.589472 -153.909014)
		(size 0.508)
		(drill 0.254)
		(layers "F.Cu" "B.Cu")
		(net "GND")
	)
	(via
		(at 166.688516 -173.552358)
		(size 0.508)
		(drill 0.254)
		(layers "F.Cu" "B.Cu")
		(net "GND")
	)
	(via
		(at 145.932398 -150.19655)
		(size 0.508)
		(drill 0.254)
		(layers "F.Cu" "B.Cu")
		(net "GND")
	)
	(via
		(at 41.164002 -83.29676)
		(size 0.508)
		(drill 0.254)
		(layers "F.Cu" "B.Cu")
		(net "GND")
	)
	(via
		(at 97.188528 -134.066788)
		(size 0.508)
		(drill 0.254)
		(layers "F.Cu" "B.Cu")
		(net "GND")
	)
	(via
		(at 176.6824 -150.060152)
		(size 0.508)
		(drill 0.254)
		(layers "F.Cu" "B.Cu")
		(net "GND")
	)
	(via
		(at 44.617386 -72.893936)
		(size 0.508)
		(drill 0.254)
		(layers "F.Cu" "B.Cu")
		(net "GND")
	)
	(via
		(at 181.681628 -157.551628)
		(size 0.508)
		(drill 0.254)
		(layers "F.Cu" "B.Cu")
		(net "GND")
	)
	(via
		(at 158.614872 -155.483814)
		(size 0.508)
		(drill 0.254)
		(layers "F.Cu" "B.Cu")
		(net "GND")
	)
	(via
		(at 69.039994 -65.198498)
		(size 0.508)
		(drill 0.254)
		(layers "F.Cu" "B.Cu")
		(net "GND")
	)
	(via
		(at 55.410862 -66.979038)
		(size 0.508)
		(drill 0.254)
		(layers "F.Cu" "B.Cu")
		(net "GND")
	)
	(via
		(at 16.773144 -146.024854)
		(size 0.508)
		(drill 0.254)
		(layers "F.Cu" "B.Cu")
		(net "GND")
	)
	(via
		(at 99.916234 -18.521426)
		(size 0.508)
		(drill 0.254)
		(layers "F.Cu" "B.Cu")
		(net "GND")
	)
	(via
		(at 83.63204 -153.258774)
		(size 0.508)
		(drill 0.254)
		(layers "F.Cu" "B.Cu")
		(net "GND")
	)
	(via
		(at 54.501542 -23.817834)
		(size 0.508)
		(drill 0.254)
		(layers "F.Cu" "B.Cu")
		(net "GND")
	)
	(via
		(at 138.922252 -155.912312)
		(size 0.508)
		(drill 0.254)
		(layers "F.Cu" "B.Cu")
		(net "GND")
	)
	(via
		(at 60.473336 -90.421968)
		(size 0.508)
		(drill 0.254)
		(layers "F.Cu" "B.Cu")
		(net "GND")
	)
	(via
		(at 44.965366 -88.343994)
		(size 0.508)
		(drill 0.254)
		(layers "F.Cu" "B.Cu")
		(net "GND")
	)
	(via
		(at 107.261152 -63.667894)
		(size 0.508)
		(drill 0.254)
		(layers "F.Cu" "B.Cu")
		(net "GND")
	)
	(via
		(at 121.9327 -106.567224)
		(size 0.508)
		(drill 0.254)
		(layers "F.Cu" "B.Cu")
		(net "GND")
	)
	(via
		(at 138.018774 -113.900712)
		(size 0.508)
		(drill 0.254)
		(layers "F.Cu" "B.Cu")
		(net "GND")
	)
	(via
		(at 106.435652 -61.623194)
		(size 0.508)
		(drill 0.254)
		(layers "F.Cu" "B.Cu")
		(net "GND")
	)
	(via
		(at 74.540618 -89.520268)
		(size 0.508)
		(drill 0.254)
		(layers "F.Cu" "B.Cu")
		(net "GND")
	)
	(via
		(at 120.43156 -103.712772)
		(size 0.508)
		(drill 0.254)
		(layers "F.Cu" "B.Cu")
		(net "GND")
	)
	(via
		(at 23.6728 -76.386436)
		(size 0.508)
		(drill 0.254)
		(layers "F.Cu" "B.Cu")
		(net "GND")
	)
	(via
		(at 146.110452 -140.21435)
		(size 0.508)
		(drill 0.254)
		(layers "F.Cu" "B.Cu")
		(net "GND")
	)
	(via
		(at 65.79362 -31.426658)
		(size 0.508)
		(drill 0.254)
		(layers "F.Cu" "B.Cu")
		(net "GND")
	)
	(via
		(at 101.14153 -157.688534)
		(size 0.508)
		(drill 0.254)
		(layers "F.Cu" "B.Cu")
		(net "GND")
	)
	(via
		(at 100.82276 -167.151812)
		(size 0.508)
		(drill 0.254)
		(layers "F.Cu" "B.Cu")
		(net "GND")
	)
	(via
		(at 30.992572 -131.153662)
		(size 0.508)
		(drill 0.254)
		(layers "F.Cu" "B.Cu")
		(net "GND")
	)
	(via
		(at 124.94006 -186.87796)
		(size 0.508)
		(drill 0.254)
		(layers "F.Cu" "B.Cu")
		(net "GND")
	)
	(via
		(at 9.64946 -132.135372)
		(size 0.508)
		(drill 0.254)
		(layers "F.Cu" "B.Cu")
		(net "GND")
	)
	(via
		(at 167.327326 -36.48202)
		(size 0.508)
		(drill 0.254)
		(layers "F.Cu" "B.Cu")
		(net "GND")
	)
	(via
		(at 70.964044 -79.168498)
		(size 0.508)
		(drill 0.254)
		(layers "F.Cu" "B.Cu")
		(net "GND")
	)
	(via
		(at 17.464024 -42.59453)
		(size 0.508)
		(drill 0.254)
		(layers "F.Cu" "B.Cu")
		(net "GND")
	)
	(via
		(at 72.627236 -61.958474)
		(size 0.508)
		(drill 0.254)
		(layers "F.Cu" "B.Cu")
		(net "GND")
	)
	(via
		(at 12.78382 -126.47676)
		(size 0.508)
		(drill 0.254)
		(layers "F.Cu" "B.Cu")
		(net "GND")
	)
	(via
		(at 87.394542 -31.596838)
		(size 0.508)
		(drill 0.254)
		(layers "F.Cu" "B.Cu")
		(net "GND")
	)
	(via
		(at 162.93592 -109.293406)
		(size 0.508)
		(drill 0.254)
		(layers "F.Cu" "B.Cu")
		(net "GND")
	)
	(via
		(at 59.3344 -16.844518)
		(size 0.508)
		(drill 0.254)
		(layers "F.Cu" "B.Cu")
		(net "GND")
	)
	(via
		(at 54.000146 -76.199492)
		(size 0.508)
		(drill 0.254)
		(layers "F.Cu" "B.Cu")
		(net "GND")
	)
	(via
		(at 160.215072 -150.683214)
		(size 0.508)
		(drill 0.254)
		(layers "F.Cu" "B.Cu")
		(net "GND")
	)
	(via
		(at 111.015526 -201.034904)
		(size 0.508)
		(drill 0.254)
		(layers "F.Cu" "B.Cu")
		(net "GND")
	)
	(via
		(at 70.851522 -88.116156)
		(size 0.508)
		(drill 0.254)
		(layers "F.Cu" "B.Cu")
		(net "GND")
	)
	(via
		(at 141.149578 -98.843084)
		(size 0.508)
		(drill 0.254)
		(layers "F.Cu" "B.Cu")
		(net "GND")
	)
	(via
		(at 86.147148 -3.023616)
		(size 0.508)
		(drill 0.254)
		(layers "F.Cu" "B.Cu")
		(net "GND")
	)
	(via
		(at 70.689978 -7.037578)
		(size 0.508)
		(drill 0.254)
		(layers "F.Cu" "B.Cu")
		(net "GND")
	)
	(via
		(at 42.686732 -95.51289)
		(size 0.508)
		(drill 0.254)
		(layers "F.Cu" "B.Cu")
		(net "GND")
	)
	(via
		(at 170.476164 -76.8477)
		(size 0.508)
		(drill 0.254)
		(layers "F.Cu" "B.Cu")
		(net "GND")
	)
	(via
		(at 153.872692 -127.314452)
		(size 0.508)
		(drill 0.254)
		(layers "F.Cu" "B.Cu")
		(net "GND")
	)
	(via
		(at 40.950134 -22.719538)
		(size 0.508)
		(drill 0.254)
		(layers "F.Cu" "B.Cu")
		(net "GND")
	)
	(via
		(at 54.850792 -160.014158)
		(size 0.508)
		(drill 0.254)
		(layers "F.Cu" "B.Cu")
		(net "GND")
	)
	(via
		(at 114.446304 -59.545474)
		(size 0.508)
		(drill 0.254)
		(layers "F.Cu" "B.Cu")
		(net "GND")
	)
	(via
		(at 161.08426 -136.719818)
		(size 0.508)
		(drill 0.254)
		(layers "F.Cu" "B.Cu")
		(net "GND")
	)
	(via
		(at 8.74776 -151.71039)
		(size 0.508)
		(drill 0.254)
		(layers "F.Cu" "B.Cu")
		(net "GND")
	)
	(via
		(at 107.233212 -67.790314)
		(size 0.508)
		(drill 0.254)
		(layers "F.Cu" "B.Cu")
		(net "GND")
	)
	(via
		(at 67.340988 -133.258306)
		(size 0.49022)
		(drill 0.254)
		(layers "F.Cu" "B.Cu")
		(net "GND")
	)
	(via
		(at 54.805072 -170.686222)
		(size 0.508)
		(drill 0.254)
		(layers "F.Cu" "B.Cu")
		(net "GND")
	)
	(via
		(at 19.109944 -47.992284)
		(size 0.508)
		(drill 0.254)
		(layers "F.Cu" "B.Cu")
		(net "GND")
	)
	(via
		(at 139.193778 -35.41141)
		(size 0.508)
		(drill 0.254)
		(layers "F.Cu" "B.Cu")
		(net "GND")
	)
	(via
		(at 54.0004 -81.0514)
		(size 0.508)
		(drill 0.254)
		(layers "F.Cu" "B.Cu")
		(net "GND")
	)
	(via
		(at 70.86854 -26.641806)
		(size 0.508)
		(drill 0.254)
		(layers "F.Cu" "B.Cu")
		(net "GND")
	)
	(via
		(at 88.950292 -22.422358)
		(size 0.508)
		(drill 0.254)
		(layers "F.Cu" "B.Cu")
		(net "GND")
	)
	(via
		(at 61.112146 -111.773462)
		(size 0.508)
		(drill 0.254)
		(layers "F.Cu" "B.Cu")
		(net "GND")
	)
	(via
		(at 69.50583 -7.038848)
		(size 0.508)
		(drill 0.254)
		(layers "F.Cu" "B.Cu")
		(net "GND")
	)
	(via
		(at 86.147148 -2.363216)
		(size 0.508)
		(drill 0.254)
		(layers "F.Cu" "B.Cu")
		(net "GND")
	)
	(via
		(at 69.073776 -70.704202)
		(size 0.508)
		(drill 0.254)
		(layers "F.Cu" "B.Cu")
		(net "GND")
	)
	(via
		(at 136.576308 -186.858148)
		(size 0.508)
		(drill 0.254)
		(layers "F.Cu" "B.Cu")
		(net "GND")
	)
	(via
		(at 184.44464 -28.577032)
		(size 0.508)
		(drill 0.254)
		(layers "F.Cu" "B.Cu")
		(net "GND")
	)
	(via
		(at 64.015112 -201.09053)
		(size 0.508)
		(drill 0.254)
		(layers "F.Cu" "B.Cu")
		(net "GND")
	)
	(via
		(at 41.037002 -109.860334)
		(size 0.508)
		(drill 0.254)
		(layers "F.Cu" "B.Cu")
		(net "GND")
	)
	(via
		(at 158.48076 -183.769762)
		(size 0.508)
		(drill 0.254)
		(layers "F.Cu" "B.Cu")
		(net "GND")
	)
	(via
		(at 150.419054 -78.482952)
		(size 0.508)
		(drill 0.254)
		(layers "F.Cu" "B.Cu")
		(net "GND")
	)
	(via
		(at 99.737672 -69.217794)
		(size 0.508)
		(drill 0.254)
		(layers "F.Cu" "B.Cu")
		(net "GND")
	)
	(via
		(at 62.502542 -23.418038)
		(size 0.508)
		(drill 0.254)
		(layers "F.Cu" "B.Cu")
		(net "GND")
	)
	(via
		(at 109.441742 -173.872144)
		(size 0.508)
		(drill 0.254)
		(layers "F.Cu" "B.Cu")
		(net "GND")
	)
	(via
		(at 46.942248 -74.416666)
		(size 0.508)
		(drill 0.254)
		(layers "F.Cu" "B.Cu")
		(net "GND")
	)
	(via
		(at 87.060786 -152.195022)
		(size 0.508)
		(drill 0.254)
		(layers "F.Cu" "B.Cu")
		(net "GND")
	)
	(via
		(at 96.545654 -167.700706)
		(size 0.508)
		(drill 0.254)
		(layers "F.Cu" "B.Cu")
		(net "GND")
	)
	(via
		(at 16.631412 -130.83794)
		(size 0.508)
		(drill 0.254)
		(layers "F.Cu" "B.Cu")
		(net "GND")
	)
	(via
		(at 192.487042 -114.562128)
		(size 0.508)
		(drill 0.254)
		(layers "F.Cu" "B.Cu")
		(net "GND")
	)
	(via
		(at 44.379896 -13.106654)
		(size 0.508)
		(drill 0.254)
		(layers "F.Cu" "B.Cu")
		(net "GND")
	)
	(via
		(at 104.326182 -126.182374)
		(size 0.508)
		(drill 0.254)
		(layers "F.Cu" "B.Cu")
		(net "GND")
	)
	(via
		(at 45.01134 -24.804878)
		(size 0.508)
		(drill 0.254)
		(layers "F.Cu" "B.Cu")
		(net "GND")
	)
	(via
		(at 108.90123 -136.397746)
		(size 0.508)
		(drill 0.254)
		(layers "F.Cu" "B.Cu")
		(net "GND")
	)
	(via
		(at 71.297546 -4.167632)
		(size 0.508)
		(drill 0.254)
		(layers "F.Cu" "B.Cu")
		(net "GND")
	)
	(via
		(at 147.2184 -129.255012)
		(size 0.508)
		(drill 0.254)
		(layers "F.Cu" "B.Cu")
		(net "GND")
	)
	(via
		(at 153.859484 -98.510598)
		(size 0.508)
		(drill 0.254)
		(layers "F.Cu" "B.Cu")
		(net "GND")
	)
	(via
		(at 49.901602 -173.999144)
		(size 0.508)
		(drill 0.254)
		(layers "F.Cu" "B.Cu")
		(net "GND")
	)
	(via
		(at 117.780308 -120.77192)
		(size 0.508)
		(drill 0.254)
		(layers "F.Cu" "B.Cu")
		(net "GND")
	)
	(via
		(at 146.059652 -144.20215)
		(size 0.508)
		(drill 0.254)
		(layers "F.Cu" "B.Cu")
		(net "GND")
	)
	(via
		(at 175.649128 -143.202406)
		(size 0.508)
		(drill 0.254)
		(layers "F.Cu" "B.Cu")
		(net "GND")
	)
	(via
		(at 141.94663 -40.309038)
		(size 0.508)
		(drill 0.254)
		(layers "F.Cu" "B.Cu")
		(net "GND")
	)
	(via
		(at 191.25184 -166.107618)
		(size 0.508)
		(drill 0.254)
		(layers "F.Cu" "B.Cu")
		(net "GND")
	)
	(via
		(at 112.015524 -201.034904)
		(size 0.508)
		(drill 0.254)
		(layers "F.Cu" "B.Cu")
		(net "GND")
	)
	(via
		(at 152.621996 -63.44793)
		(size 0.508)
		(drill 0.254)
		(layers "F.Cu" "B.Cu")
		(net "GND")
	)
	(via
		(at 46.829218 -85.799168)
		(size 0.508)
		(drill 0.254)
		(layers "F.Cu" "B.Cu")
		(net "GND")
	)
	(via
		(at 119.26062 -104.508554)
		(size 0.508)
		(drill 0.254)
		(layers "F.Cu" "B.Cu")
		(net "GND")
	)
	(via
		(at 82.081116 -141.317218)
		(size 0.508)
		(drill 0.254)
		(layers "F.Cu" "B.Cu")
		(net "GND")
	)
	(via
		(at 29.014928 -201.09053)
		(size 0.508)
		(drill 0.254)
		(layers "F.Cu" "B.Cu")
		(net "GND")
	)
	(via
		(at 55.410862 -66.217038)
		(size 0.508)
		(drill 0.254)
		(layers "F.Cu" "B.Cu")
		(net "GND")
	)
	(via
		(at 20.72259 -136.241028)
		(size 0.508)
		(drill 0.254)
		(layers "F.Cu" "B.Cu")
		(net "GND")
	)
	(via
		(at 18.01495 -200.32853)
		(size 0.508)
		(drill 0.254)
		(layers "F.Cu" "B.Cu")
		(net "GND")
	)
	(via
		(at 63.340996 -137.258298)
		(size 0.49022)
		(drill 0.254)
		(layers "F.Cu" "B.Cu")
		(net "GND")
	)
	(via
		(at 52.859686 -139.967462)
		(size 0.49022)
		(drill 0.254)
		(layers "F.Cu" "B.Cu")
		(net "GND")
	)
	(via
		(at 81.651602 -22.483318)
		(size 0.508)
		(drill 0.254)
		(layers "F.Cu" "B.Cu")
		(net "GND")
	)
	(via
		(at 78.007464 -98.038666)
		(size 0.508)
		(drill 0.254)
		(layers "F.Cu" "B.Cu")
		(net "GND")
	)
	(via
		(at 62.001146 -72.198992)
		(size 0.508)
		(drill 0.254)
		(layers "F.Cu" "B.Cu")
		(net "GND")
	)
	(via
		(at 166.20236 -98.115882)
		(size 0.508)
		(drill 0.254)
		(layers "F.Cu" "B.Cu")
		(net "GND")
	)
	(via
		(at 135.798052 -137.11555)
		(size 0.508)
		(drill 0.254)
		(layers "F.Cu" "B.Cu")
		(net "GND")
	)
	(via
		(at 156.103066 -163.848288)
		(size 0.508)
		(drill 0.254)
		(layers "F.Cu" "B.Cu")
		(net "GND")
	)
	(via
		(at 103.25862 -111.929418)
		(size 0.508)
		(drill 0.254)
		(layers "F.Cu" "B.Cu")
		(net "GND")
	)
	(via
		(at 68.166488 -10.358628)
		(size 0.508)
		(drill 0.254)
		(layers "F.Cu" "B.Cu")
		(net "GND")
	)
	(via
		(at 153.651204 -70.732904)
		(size 0.508)
		(drill 0.254)
		(layers "F.Cu" "B.Cu")
		(net "GND")
	)
	(via
		(at 13.54582 -126.47676)
		(size 0.508)
		(drill 0.254)
		(layers "F.Cu" "B.Cu")
		(net "GND")
	)
	(via
		(at 177.50282 -170.345608)
		(size 0.508)
		(drill 0.254)
		(layers "F.Cu" "B.Cu")
		(net "GND")
	)
	(via
		(at 38.808406 -13.493496)
		(size 0.508)
		(drill 0.254)
		(layers "F.Cu" "B.Cu")
		(net "GND")
	)
	(via
		(at 69.96176 -186.849004)
		(size 0.508)
		(drill 0.254)
		(layers "F.Cu" "B.Cu")
		(net "GND")
	)
	(via
		(at 172.606208 -94.709742)
		(size 0.508)
		(drill 0.254)
		(layers "F.Cu" "B.Cu")
		(net "GND")
	)
	(via
		(at 51.014884 -200.32853)
		(size 0.508)
		(drill 0.254)
		(layers "F.Cu" "B.Cu")
		(net "GND")
	)
	(via
		(at 104.907588 -150.862538)
		(size 0.508)
		(drill 0.254)
		(layers "F.Cu" "B.Cu")
		(net "GND")
	)
	(via
		(at 79.792322 -81.769712)
		(size 0.508)
		(drill 0.254)
		(layers "F.Cu" "B.Cu")
		(net "GND")
	)
	(via
		(at 62.646306 -154.528012)
		(size 0.508)
		(drill 0.254)
		(layers "F.Cu" "B.Cu")
		(net "GND")
	)
	(via
		(at 22.028404 -127.507238)
		(size 0.508)
		(drill 0.254)
		(layers "F.Cu" "B.Cu")
		(net "GND")
	)
	(via
		(at 144.32661 -178.395122)
		(size 0.508)
		(drill 0.254)
		(layers "F.Cu" "B.Cu")
		(net "GND")
	)
	(via
		(at 113.5126 -181.520592)
		(size 0.508)
		(drill 0.254)
		(layers "F.Cu" "B.Cu")
		(net "GND")
	)
	(via
		(at 63.333376 -140.457936)
		(size 0.49022)
		(drill 0.254)
		(layers "F.Cu" "B.Cu")
		(net "GND")
	)
	(via
		(at 175.510444 -119.865648)
		(size 0.49022)
		(drill 0.254)
		(layers "F.Cu" "B.Cu")
		(net "GND")
	)
	(via
		(at 160.650682 -48.966374)
		(size 0.508)
		(drill 0.254)
		(layers "F.Cu" "B.Cu")
		(net "GND")
	)
	(via
		(at 163.466272 -154.086814)
		(size 0.508)
		(drill 0.254)
		(layers "F.Cu" "B.Cu")
		(net "GND")
	)
	(via
		(at 68.48348 -61.78296)
		(size 0.508)
		(drill 0.254)
		(layers "F.Cu" "B.Cu")
		(net "GND")
	)
	(via
		(at 16.17218 -146.31416)
		(size 0.508)
		(drill 0.254)
		(layers "F.Cu" "B.Cu")
		(net "GND")
	)
	(via
		(at 25.8191 -110.057184)
		(size 0.508)
		(drill 0.254)
		(layers "F.Cu" "B.Cu")
		(net "GND")
	)
	(via
		(at 101.550216 -22.549612)
		(size 0.508)
		(drill 0.254)
		(layers "F.Cu" "B.Cu")
		(net "GND")
	)
	(via
		(at 47.058834 -107.064302)
		(size 0.508)
		(drill 0.254)
		(layers "F.Cu" "B.Cu")
		(net "GND")
	)
	(via
		(at 68.141088 -132.458206)
		(size 0.49022)
		(drill 0.254)
		(layers "F.Cu" "B.Cu")
		(net "GND")
	)
	(via
		(at 71.848218 -71.410068)
		(size 0.508)
		(drill 0.254)
		(layers "F.Cu" "B.Cu")
		(net "GND")
	)
	(via
		(at 168.99128 -51.624738)
		(size 0.508)
		(drill 0.254)
		(layers "F.Cu" "B.Cu")
		(net "GND")
	)
	(via
		(at 16.809974 -142.785846)
		(size 0.508)
		(drill 0.254)
		(layers "F.Cu" "B.Cu")
		(net "GND")
	)
	(via
		(at 33.09874 -68.370196)
		(size 0.508)
		(drill 0.254)
		(layers "F.Cu" "B.Cu")
		(net "GND")
	)
	(via
		(at 84.169504 -76.170282)
		(size 0.508)
		(drill 0.254)
		(layers "F.Cu" "B.Cu")
		(net "GND")
	)
	(via
		(at 53.95976 -186.900566)
		(size 0.508)
		(drill 0.254)
		(layers "F.Cu" "B.Cu")
		(net "GND")
	)
	(via
		(at 184.45226 -26.75255)
		(size 0.508)
		(drill 0.254)
		(layers "F.Cu" "B.Cu")
		(net "GND")
	)
	(via
		(at 55.150766 -84.634578)
		(size 0.508)
		(drill 0.254)
		(layers "F.Cu" "B.Cu")
		(net "GND")
	)
	(via
		(at 42.515282 -86.691724)
		(size 0.508)
		(drill 0.254)
		(layers "F.Cu" "B.Cu")
		(net "GND")
	)
	(via
		(at 73.742042 -135.659368)
		(size 0.49022)
		(drill 0.254)
		(layers "F.Cu" "B.Cu")
		(net "GND")
	)
	(via
		(at 139.025884 -177.185574)
		(size 0.508)
		(drill 0.254)
		(layers "F.Cu" "B.Cu")
		(net "GND")
	)
	(via
		(at 34.43986 -33.134046)
		(size 0.508)
		(drill 0.254)
		(layers "F.Cu" "B.Cu")
		(net "GND")
	)
	(via
		(at 72.142096 -135.659368)
		(size 0.49022)
		(drill 0.254)
		(layers "F.Cu" "B.Cu")
		(net "GND")
	)
	(via
		(at 126.885954 -109.127544)
		(size 0.508)
		(drill 0.254)
		(layers "F.Cu" "B.Cu")
		(net "GND")
	)
	(via
		(at 124.636022 -144.97558)
		(size 0.508)
		(drill 0.254)
		(layers "F.Cu" "B.Cu")
		(net "GND")
	)
	(via
		(at 47.362618 -130.565144)
		(size 0.49022)
		(drill 0.254)
		(layers "F.Cu" "B.Cu")
		(net "GND")
	)
	(via
		(at 116.26342 -173.23054)
		(size 0.508)
		(drill 0.254)
		(layers "F.Cu" "B.Cu")
		(net "GND")
	)
	(via
		(at 136.7536 -155.906216)
		(size 0.508)
		(drill 0.254)
		(layers "F.Cu" "B.Cu")
		(net "GND")
	)
	(via
		(at 14.214602 -50.68951)
		(size 0.508)
		(drill 0.254)
		(layers "F.Cu" "B.Cu")
		(net "GND")
	)
	(via
		(at 68.141088 -133.258306)
		(size 0.49022)
		(drill 0.254)
		(layers "F.Cu" "B.Cu")
		(net "GND")
	)
	(via
		(at 82.893662 -16.044418)
		(size 0.508)
		(drill 0.254)
		(layers "F.Cu" "B.Cu")
		(net "GND")
	)
	(via
		(at 62.025784 -107.95254)
		(size 0.508)
		(drill 0.254)
		(layers "F.Cu" "B.Cu")
		(net "GND")
	)
	(via
		(at 54.803294 -64.219582)
		(size 0.508)
		(drill 0.254)
		(layers "F.Cu" "B.Cu")
		(net "GND")
	)
	(via
		(at 38.622732 -95.508064)
		(size 0.508)
		(drill 0.254)
		(layers "F.Cu" "B.Cu")
		(net "GND")
	)
	(via
		(at 50.243486 -119.368062)
		(size 0.508)
		(drill 0.254)
		(layers "F.Cu" "B.Cu")
		(net "GND")
	)
	(via
		(at 67.82308 -65.298066)
		(size 0.508)
		(drill 0.254)
		(layers "F.Cu" "B.Cu")
		(net "GND")
	)
	(via
		(at 103.093012 -74.694034)
		(size 0.508)
		(drill 0.254)
		(layers "F.Cu" "B.Cu")
		(net "GND")
	)
	(via
		(at 97.6503 -27.64282)
		(size 0.508)
		(drill 0.254)
		(layers "F.Cu" "B.Cu")
		(net "GND")
	)
	(via
		(at 42.262552 -164.44849)
		(size 0.508)
		(drill 0.254)
		(layers "F.Cu" "B.Cu")
		(net "GND")
	)
	(via
		(at 57.585102 -30.989778)
		(size 0.508)
		(drill 0.254)
		(layers "F.Cu" "B.Cu")
		(net "GND")
	)
	(via
		(at 32.14878 -65.073276)
		(size 0.508)
		(drill 0.254)
		(layers "F.Cu" "B.Cu")
		(net "GND")
	)
	(via
		(at 124.30252 -150.073106)
		(size 0.508)
		(drill 0.254)
		(layers "F.Cu" "B.Cu")
		(net "GND")
	)
	(via
		(at 63.49746 -5.389626)
		(size 0.508)
		(drill 0.254)
		(layers "F.Cu" "B.Cu")
		(net "GND")
	)
	(via
		(at 56.015128 -200.32853)
		(size 0.508)
		(drill 0.254)
		(layers "F.Cu" "B.Cu")
		(net "GND")
	)
	(via
		(at 102.038912 -70.421754)
		(size 0.508)
		(drill 0.254)
		(layers "F.Cu" "B.Cu")
		(net "GND")
	)
	(via
		(at 44.231052 -61.943742)
		(size 0.508)
		(drill 0.254)
		(layers "F.Cu" "B.Cu")
		(net "GND")
	)
	(via
		(at 125.6919 -186.246008)
		(size 0.508)
		(drill 0.254)
		(layers "F.Cu" "B.Cu")
		(net "GND")
	)
	(via
		(at 77.5208 -165.832282)
		(size 0.508)
		(drill 0.254)
		(layers "F.Cu" "B.Cu")
		(net "GND")
	)
	(via
		(at 130.514852 -141.45895)
		(size 0.508)
		(drill 0.254)
		(layers "F.Cu" "B.Cu")
		(net "GND")
	)
	(via
		(at 183.53786 -200.12279)
		(size 0.508)
		(drill 0.254)
		(layers "F.Cu" "B.Cu")
		(net "GND")
	)
	(via
		(at 175.225456 -101.127814)
		(size 0.508)
		(drill 0.254)
		(layers "F.Cu" "B.Cu")
		(net "GND")
	)
	(via
		(at 166.32936 -103.754682)
		(size 0.508)
		(drill 0.254)
		(layers "F.Cu" "B.Cu")
		(net "GND")
	)
	(via
		(at 68.219066 -4.91871)
		(size 0.508)
		(drill 0.254)
		(layers "F.Cu" "B.Cu")
		(net "GND")
	)
	(via
		(at 68.297044 -69.237098)
		(size 0.508)
		(drill 0.254)
		(layers "F.Cu" "B.Cu")
		(net "GND")
	)
	(via
		(at 154.18308 -178.979576)
		(size 0.508)
		(drill 0.254)
		(layers "F.Cu" "B.Cu")
		(net "GND")
	)
	(via
		(at 159.986472 -155.509214)
		(size 0.508)
		(drill 0.254)
		(layers "F.Cu" "B.Cu")
		(net "GND")
	)
	(via
		(at 53.601112 -64.946784)
		(size 0.508)
		(drill 0.254)
		(layers "F.Cu" "B.Cu")
		(net "GND")
	)
	(via
		(at 86.203536 -155.992576)
		(size 0.508)
		(drill 0.254)
		(layers "F.Cu" "B.Cu")
		(net "GND")
	)
	(via
		(at 44.718732 -95.648272)
		(size 0.508)
		(drill 0.254)
		(layers "F.Cu" "B.Cu")
		(net "GND")
	)
	(via
		(at 79.95666 -165.620446)
		(size 0.508)
		(drill 0.254)
		(layers "F.Cu" "B.Cu")
		(net "GND")
	)
	(via
		(at 58.60415 -84.238846)
		(size 0.508)
		(drill 0.254)
		(layers "F.Cu" "B.Cu")
		(net "GND")
	)
	(via
		(at 72.09028 -100.651564)
		(size 0.508)
		(drill 0.254)
		(layers "F.Cu" "B.Cu")
		(net "GND")
	)
	(via
		(at 132.978652 -152.48255)
		(size 0.508)
		(drill 0.254)
		(layers "F.Cu" "B.Cu")
		(net "GND")
	)
	(via
		(at 41.024302 -80.554322)
		(size 0.508)
		(drill 0.254)
		(layers "F.Cu" "B.Cu")
		(net "GND")
	)
	(via
		(at 174.09414 -157.7975)
		(size 0.508)
		(drill 0.254)
		(layers "F.Cu" "B.Cu")
		(net "GND")
	)
	(via
		(at 36.531042 -173.458378)
		(size 0.508)
		(drill 0.254)
		(layers "F.Cu" "B.Cu")
		(net "GND")
	)
	(via
		(at 92.793566 -138.714734)
		(size 0.508)
		(drill 0.254)
		(layers "F.Cu" "B.Cu")
		(net "GND")
	)
	(via
		(at 37.225732 -19.015202)
		(size 0.508)
		(drill 0.254)
		(layers "F.Cu" "B.Cu")
		(net "GND")
	)
	(via
		(at 132.03682 -161.204402)
		(size 0.508)
		(drill 0.254)
		(layers "F.Cu" "B.Cu")
		(net "GND")
	)
	(via
		(at 97.27946 -4.449826)
		(size 0.508)
		(drill 0.254)
		(layers "F.Cu" "B.Cu")
		(net "GND")
	)
	(via
		(at 104.326182 -125.420374)
		(size 0.508)
		(drill 0.254)
		(layers "F.Cu" "B.Cu")
		(net "GND")
	)
	(via
		(at 45.372528 -157.336998)
		(size 0.508)
		(drill 0.254)
		(layers "F.Cu" "B.Cu")
		(net "GND")
	)
	(via
		(at 167.868346 -79.12481)
		(size 0.508)
		(drill 0.254)
		(layers "F.Cu" "B.Cu")
		(net "GND")
	)
	(via
		(at 115.29949 -158.683706)
		(size 0.508)
		(drill 0.254)
		(layers "F.Cu" "B.Cu")
		(net "GND")
	)
	(via
		(at 112.41532 -60.060586)
		(size 0.508)
		(drill 0.254)
		(layers "F.Cu" "B.Cu")
		(net "GND")
	)
	(via
		(at 178.70678 -170.951144)
		(size 0.508)
		(drill 0.254)
		(layers "F.Cu" "B.Cu")
		(net "GND")
	)
	(via
		(at 54.000146 -76.999592)
		(size 0.508)
		(drill 0.254)
		(layers "F.Cu" "B.Cu")
		(net "GND")
	)
	(via
		(at 161.42843 -118.335552)
		(size 0.508)
		(drill 0.254)
		(layers "F.Cu" "B.Cu")
		(net "GND")
	)
	(via
		(at 60.540392 -180.967126)
		(size 0.508)
		(drill 0.254)
		(layers "F.Cu" "B.Cu")
		(net "GND")
	)
	(via
		(at 93.79712 -105.5624)
		(size 0.508)
		(drill 0.254)
		(layers "F.Cu" "B.Cu")
		(net "GND")
	)
	(via
		(at 90.68816 -84.57438)
		(size 0.508)
		(drill 0.254)
		(layers "F.Cu" "B.Cu")
		(net "GND")
	)
	(via
		(at 164.42436 -101.621082)
		(size 0.508)
		(drill 0.254)
		(layers "F.Cu" "B.Cu")
		(net "GND")
	)
	(via
		(at 83.729322 -22.831298)
		(size 0.508)
		(drill 0.254)
		(layers "F.Cu" "B.Cu")
		(net "GND")
	)
	(via
		(at 63.601346 -72.198992)
		(size 0.508)
		(drill 0.254)
		(layers "F.Cu" "B.Cu")
		(net "GND")
	)
	(via
		(at 39.081202 -3.854704)
		(size 0.508)
		(drill 0.254)
		(layers "F.Cu" "B.Cu")
		(net "GND")
	)
	(via
		(at 12.60983 -124.918216)
		(size 0.508)
		(drill 0.254)
		(layers "F.Cu" "B.Cu")
		(net "GND")
	)
	(via
		(at 71.10476 -183.928004)
		(size 0.508)
		(drill 0.254)
		(layers "F.Cu" "B.Cu")
		(net "GND")
	)
	(via
		(at 16.12646 -160.196022)
		(size 0.508)
		(drill 0.254)
		(layers "F.Cu" "B.Cu")
		(net "GND")
	)
	(via
		(at 11.889994 -31.223712)
		(size 0.508)
		(drill 0.254)
		(layers "F.Cu" "B.Cu")
		(net "GND")
	)
	(via
		(at 81.195164 -90.011504)
		(size 0.508)
		(drill 0.254)
		(layers "F.Cu" "B.Cu")
		(net "GND")
	)
	(via
		(at 54.015132 -200.32853)
		(size 0.508)
		(drill 0.254)
		(layers "F.Cu" "B.Cu")
		(net "GND")
	)
	(via
		(at 33.394396 -11.033506)
		(size 0.508)
		(drill 0.254)
		(layers "F.Cu" "B.Cu")
		(net "GND")
	)
	(via
		(at 127.009652 -139.88415)
		(size 0.508)
		(drill 0.254)
		(layers "F.Cu" "B.Cu")
		(net "GND")
	)
	(via
		(at 168.79824 -48.626522)
		(size 0.508)
		(drill 0.254)
		(layers "F.Cu" "B.Cu")
		(net "GND")
	)
	(via
		(at 91.893644 -177.578512)
		(size 0.508)
		(drill 0.254)
		(layers "F.Cu" "B.Cu")
		(net "GND")
	)
	(via
		(at 68.311776 -70.704202)
		(size 0.508)
		(drill 0.254)
		(layers "F.Cu" "B.Cu")
		(net "GND")
	)
	(via
		(at 108.444792 -71.386954)
		(size 0.508)
		(drill 0.254)
		(layers "F.Cu" "B.Cu")
		(net "GND")
	)
	(via
		(at 14.321282 -55.509922)
		(size 0.508)
		(drill 0.254)
		(layers "F.Cu" "B.Cu")
		(net "GND")
	)
	(via
		(at 44.713398 -78.70063)
		(size 0.508)
		(drill 0.254)
		(layers "F.Cu" "B.Cu")
		(net "GND")
	)
	(via
		(at 41.068498 -78.83017)
		(size 0.508)
		(drill 0.254)
		(layers "F.Cu" "B.Cu")
		(net "GND")
	)
	(via
		(at 110.046262 -40.827198)
		(size 0.508)
		(drill 0.254)
		(layers "F.Cu" "B.Cu")
		(net "GND")
	)
	(via
		(at 81.697322 -81.769712)
		(size 0.508)
		(drill 0.254)
		(layers "F.Cu" "B.Cu")
		(net "GND")
	)
	(via
		(at 91.7829 -183.06288)
		(size 0.508)
		(drill 0.254)
		(layers "F.Cu" "B.Cu")
		(net "GND")
	)
	(via
		(at 41.691306 -3.308858)
		(size 0.508)
		(drill 0.254)
		(layers "F.Cu" "B.Cu")
		(net "GND")
	)
	(via
		(at 54.19471 -175.806354)
		(size 0.508)
		(drill 0.254)
		(layers "F.Cu" "B.Cu")
		(net "GND")
	)
	(via
		(at 124.95022 -166.167562)
		(size 0.508)
		(drill 0.254)
		(layers "F.Cu" "B.Cu")
		(net "GND")
	)
	(via
		(at 112.30991 -68.906136)
		(size 0.508)
		(drill 0.254)
		(layers "F.Cu" "B.Cu")
		(net "GND")
	)
	(via
		(at 34.45256 -34.078418)
		(size 0.508)
		(drill 0.254)
		(layers "F.Cu" "B.Cu")
		(net "GND")
	)
	(via
		(at 36.83508 -146.304254)
		(size 0.508)
		(drill 0.254)
		(layers "F.Cu" "B.Cu")
		(net "GND")
	)
	(via
		(at 121.434352 -31.805626)
		(size 0.508)
		(drill 0.254)
		(layers "F.Cu" "B.Cu")
		(net "GND")
	)
	(via
		(at 175.133 -30.592014)
		(size 0.508)
		(drill 0.254)
		(layers "F.Cu" "B.Cu")
		(net "GND")
	)
	(via
		(at 150.088092 -151.678132)
		(size 0.508)
		(drill 0.254)
		(layers "F.Cu" "B.Cu")
		(net "GND")
	)
	(via
		(at 122.015504 -201.034904)
		(size 0.508)
		(drill 0.254)
		(layers "F.Cu" "B.Cu")
		(net "GND")
	)
	(via
		(at 101.577394 -167.97655)
		(size 0.508)
		(drill 0.254)
		(layers "F.Cu" "B.Cu")
		(net "GND")
	)
	(via
		(at 182.4101 -193.80581)
		(size 0.508)
		(drill 0.254)
		(layers "F.Cu" "B.Cu")
		(net "GND")
	)
	(via
		(at 7.1755 -111.43996)
		(size 0.508)
		(drill 0.254)
		(layers "F.Cu" "B.Cu")
		(net "GND")
	)
	(via
		(at 66.392044 -79.168498)
		(size 0.508)
		(drill 0.254)
		(layers "F.Cu" "B.Cu")
		(net "GND")
	)
	(via
		(at 40.45839 -85.39988)
		(size 0.508)
		(drill 0.254)
		(layers "F.Cu" "B.Cu")
		(net "GND")
	)
	(via
		(at 54.891686 -69.631306)
		(size 0.508)
		(drill 0.254)
		(layers "F.Cu" "B.Cu")
		(net "GND")
	)
	(via
		(at 69.50964 -5.851398)
		(size 0.508)
		(drill 0.254)
		(layers "F.Cu" "B.Cu")
		(net "GND")
	)
	(via
		(at 86.203536 -155.332176)
		(size 0.508)
		(drill 0.254)
		(layers "F.Cu" "B.Cu")
		(net "GND")
	)
	(via
		(at 156.01569 -201.034904)
		(size 0.508)
		(drill 0.254)
		(layers "F.Cu" "B.Cu")
		(net "GND")
	)
	(via
		(at 75.67676 -183.991758)
		(size 0.508)
		(drill 0.254)
		(layers "F.Cu" "B.Cu")
		(net "GND")
	)
	(via
		(at 60.118498 -97.849436)
		(size 0.508)
		(drill 0.254)
		(layers "F.Cu" "B.Cu")
		(net "GND")
	)
	(via
		(at 101.346508 -4.449826)
		(size 0.508)
		(drill 0.254)
		(layers "F.Cu" "B.Cu")
		(net "GND")
	)
	(via
		(at 128.55067 -183.929528)
		(size 0.508)
		(drill 0.254)
		(layers "F.Cu" "B.Cu")
		(net "GND")
	)
	(via
		(at 116.015516 -201.034904)
		(size 0.508)
		(drill 0.254)
		(layers "F.Cu" "B.Cu")
		(net "GND")
	)
	(via
		(at 41.18102 -32.853376)
		(size 0.508)
		(drill 0.254)
		(layers "F.Cu" "B.Cu")
		(net "GND")
	)
	(via
		(at 71.317104 -82.908648)
		(size 0.508)
		(drill 0.254)
		(layers "F.Cu" "B.Cu")
		(net "GND")
	)
	(via
		(at 50.53076 -186.862974)
		(size 0.508)
		(drill 0.254)
		(layers "F.Cu" "B.Cu")
		(net "GND")
	)
	(via
		(at 107.31754 -172.170344)
		(size 0.508)
		(drill 0.254)
		(layers "F.Cu" "B.Cu")
		(net "GND")
	)
	(via
		(at 178.040538 -55.084472)
		(size 0.508)
		(drill 0.254)
		(layers "F.Cu" "B.Cu")
		(net "GND")
	)
	(via
		(at 44.014898 -201.09053)
		(size 0.508)
		(drill 0.254)
		(layers "F.Cu" "B.Cu")
		(net "GND")
	)
	(via
		(at 126.015242 -59.309)
		(size 0.508)
		(drill 0.254)
		(layers "F.Cu" "B.Cu")
		(net "GND")
	)
	(via
		(at 29.70784 -100.081842)
		(size 0.508)
		(drill 0.254)
		(layers "F.Cu" "B.Cu")
		(net "GND")
	)
	(via
		(at 40.754046 -65.93967)
		(size 0.508)
		(drill 0.254)
		(layers "F.Cu" "B.Cu")
		(net "GND")
	)
	(via
		(at 155.255976 -180.29682)
		(size 0.508)
		(drill 0.254)
		(layers "F.Cu" "B.Cu")
		(net "GND")
	)
	(via
		(at 71.673212 -61.97727)
		(size 0.508)
		(drill 0.254)
		(layers "F.Cu" "B.Cu")
		(net "GND")
	)
	(via
		(at 71.341996 -142.059406)
		(size 0.49022)
		(drill 0.254)
		(layers "F.Cu" "B.Cu")
		(net "GND")
	)
	(via
		(at 48.899826 -89.601294)
		(size 0.508)
		(drill 0.254)
		(layers "F.Cu" "B.Cu")
		(net "GND")
	)
	(via
		(at 115.801902 -45.389292)
		(size 0.508)
		(drill 0.254)
		(layers "F.Cu" "B.Cu")
		(net "GND")
	)
	(via
		(at 62.025784 -109.98454)
		(size 0.508)
		(drill 0.254)
		(layers "F.Cu" "B.Cu")
		(net "GND")
	)
	(via
		(at 39.047674 -132.266436)
		(size 0.49022)
		(drill 0.254)
		(layers "F.Cu" "B.Cu")
		(net "GND")
	)
	(via
		(at 85.7377 -141.888972)
		(size 0.508)
		(drill 0.254)
		(layers "F.Cu" "B.Cu")
		(net "GND")
	)
	(via
		(at 175.649128 -148.282406)
		(size 0.508)
		(drill 0.254)
		(layers "F.Cu" "B.Cu")
		(net "GND")
	)
	(via
		(at 20.84451 -18.598896)
		(size 0.508)
		(drill 0.254)
		(layers "F.Cu" "B.Cu")
		(net "GND")
	)
	(via
		(at 28.95727 -138.266932)
		(size 0.508)
		(drill 0.254)
		(layers "F.Cu" "B.Cu")
		(net "GND")
	)
	(via
		(at 110.074202 -40.032178)
		(size 0.508)
		(drill 0.254)
		(layers "F.Cu" "B.Cu")
		(net "GND")
	)
	(via
		(at 50.809906 -114.6429)
		(size 0.508)
		(drill 0.254)
		(layers "F.Cu" "B.Cu")
		(net "GND")
	)
	(via
		(at 60.400946 -73.799192)
		(size 0.508)
		(drill 0.254)
		(layers "F.Cu" "B.Cu")
		(net "GND")
	)
	(via
		(at 15.119096 -6.584188)
		(size 0.508)
		(drill 0.254)
		(layers "F.Cu" "B.Cu")
		(net "GND")
	)
	(via
		(at 158.7373 -48.209454)
		(size 0.508)
		(drill 0.254)
		(layers "F.Cu" "B.Cu")
		(net "GND")
	)
	(via
		(at 151.062182 -165.95979)
		(size 0.508)
		(drill 0.254)
		(layers "F.Cu" "B.Cu")
		(net "GND")
	)
	(via
		(at 20.400772 -138.254994)
		(size 0.508)
		(drill 0.254)
		(layers "F.Cu" "B.Cu")
		(net "GND")
	)
	(via
		(at 95.74784 -201.06132)
		(size 0.508)
		(drill 0.254)
		(layers "F.Cu" "B.Cu")
		(net "GND")
	)
	(via
		(at 76.630784 -178.270154)
		(size 0.508)
		(drill 0.254)
		(layers "F.Cu" "B.Cu")
		(net "GND")
	)
	(via
		(at 135.56996 -120.147334)
		(size 0.508)
		(drill 0.254)
		(layers "F.Cu" "B.Cu")
		(net "GND")
	)
	(via
		(at 136.01319 -181.656228)
		(size 0.508)
		(drill 0.254)
		(layers "F.Cu" "B.Cu")
		(net "GND")
	)
	(via
		(at 59.383422 -68.503038)
		(size 0.508)
		(drill 0.254)
		(layers "F.Cu" "B.Cu")
		(net "GND")
	)
	(via
		(at 12.60475 -121.531888)
		(size 0.508)
		(drill 0.254)
		(layers "F.Cu" "B.Cu")
		(net "GND")
	)
	(via
		(at 163.60267 -79.23911)
		(size 0.508)
		(drill 0.254)
		(layers "F.Cu" "B.Cu")
		(net "GND")
	)
	(via
		(at 45.014896 -13.106654)
		(size 0.508)
		(drill 0.254)
		(layers "F.Cu" "B.Cu")
		(net "GND")
	)
	(via
		(at 136.315704 -59.688222)
		(size 0.508)
		(drill 0.254)
		(layers "F.Cu" "B.Cu")
		(net "GND")
	)
	(via
		(at 146.831304 -66.063622)
		(size 0.508)
		(drill 0.254)
		(layers "F.Cu" "B.Cu")
		(net "GND")
	)
	(via
		(at 45.282612 -177.285904)
		(size 0.508)
		(drill 0.254)
		(layers "F.Cu" "B.Cu")
		(net "GND")
	)
	(via
		(at 70.701916 -62.047374)
		(size 0.508)
		(drill 0.254)
		(layers "F.Cu" "B.Cu")
		(net "GND")
	)
	(via
		(at 67.10934 -24.616156)
		(size 0.508)
		(drill 0.254)
		(layers "F.Cu" "B.Cu")
		(net "GND")
	)
	(via
		(at 183.33466 -201.017632)
		(size 0.508)
		(drill 0.254)
		(layers "F.Cu" "B.Cu")
		(net "GND")
	)
	(via
		(at 69.821044 -69.237098)
		(size 0.508)
		(drill 0.254)
		(layers "F.Cu" "B.Cu")
		(net "GND")
	)
	(via
		(at 29.369512 -26.51887)
		(size 0.508)
		(drill 0.254)
		(layers "F.Cu" "B.Cu")
		(net "GND")
	)
	(via
		(at 169.399712 -118.905528)
		(size 0.508)
		(drill 0.254)
		(layers "F.Cu" "B.Cu")
		(net "GND")
	)
	(via
		(at 90.2081 -123.636532)
		(size 0.508)
		(drill 0.254)
		(layers "F.Cu" "B.Cu")
		(net "GND")
	)
	(via
		(at 45.014896 -13.741654)
		(size 0.508)
		(drill 0.254)
		(layers "F.Cu" "B.Cu")
		(net "GND")
	)
	(via
		(at 9.740646 -141.15542)
		(size 0.508)
		(drill 0.254)
		(layers "F.Cu" "B.Cu")
		(net "GND")
	)
	(via
		(at 71.345044 -69.237098)
		(size 0.508)
		(drill 0.254)
		(layers "F.Cu" "B.Cu")
		(net "GND")
	)
	(via
		(at 131.153662 -122.099832)
		(size 0.508)
		(drill 0.254)
		(layers "F.Cu" "B.Cu")
		(net "GND")
	)
	(via
		(at 156.141928 -186.821318)
		(size 0.508)
		(drill 0.254)
		(layers "F.Cu" "B.Cu")
		(net "GND")
	)
	(via
		(at 103.90124 -23.39213)
		(size 0.508)
		(drill 0.254)
		(layers "F.Cu" "B.Cu")
		(net "GND")
	)
	(via
		(at 175.649128 -142.186406)
		(size 0.508)
		(drill 0.254)
		(layers "F.Cu" "B.Cu")
		(net "GND")
	)
	(via
		(at 75.96886 -161.142934)
		(size 0.508)
		(drill 0.254)
		(layers "F.Cu" "B.Cu")
		(net "GND")
	)
	(via
		(at 72.710802 -22.523958)
		(size 0.508)
		(drill 0.254)
		(layers "F.Cu" "B.Cu")
		(net "GND")
	)
	(via
		(at 113.7666 -67.384168)
		(size 0.508)
		(drill 0.254)
		(layers "F.Cu" "B.Cu")
		(net "GND")
	)
	(via
		(at 75.16114 -67.743324)
		(size 0.508)
		(drill 0.254)
		(layers "F.Cu" "B.Cu")
		(net "GND")
	)
	(via
		(at 49.334674 -99.127818)
		(size 0.508)
		(drill 0.254)
		(layers "F.Cu" "B.Cu")
		(net "GND")
	)
	(via
		(at 66.540888 -134.058406)
		(size 0.49022)
		(drill 0.254)
		(layers "F.Cu" "B.Cu")
		(net "GND")
	)
	(via
		(at 50.46599 -61.15939)
		(size 0.508)
		(drill 0.254)
		(layers "F.Cu" "B.Cu")
		(net "GND")
	)
	(via
		(at 132.6515 -130.477768)
		(size 0.508)
		(drill 0.254)
		(layers "F.Cu" "B.Cu")
		(net "GND")
	)
	(via
		(at 91.21648 -84.115656)
		(size 0.508)
		(drill 0.254)
		(layers "F.Cu" "B.Cu")
		(net "GND")
	)
	(via
		(at 16.761206 -146.84121)
		(size 0.508)
		(drill 0.254)
		(layers "F.Cu" "B.Cu")
		(net "GND")
	)
	(via
		(at 70.574662 -16.044418)
		(size 0.508)
		(drill 0.254)
		(layers "F.Cu" "B.Cu")
		(net "GND")
	)
	(via
		(at 119.77116 -111.052356)
		(size 0.508)
		(drill 0.254)
		(layers "F.Cu" "B.Cu")
		(net "GND")
	)
	(via
		(at 185.405268 -131.002278)
		(size 0.508)
		(drill 0.254)
		(layers "F.Cu" "B.Cu")
		(net "GND")
	)
	(via
		(at 84.82076 -186.91733)
		(size 0.508)
		(drill 0.254)
		(layers "F.Cu" "B.Cu")
		(net "GND")
	)
	(via
		(at 93.072204 -134.041388)
		(size 0.508)
		(drill 0.254)
		(layers "F.Cu" "B.Cu")
		(net "GND")
	)
	(via
		(at 75.05446 -24.691086)
		(size 0.508)
		(drill 0.254)
		(layers "F.Cu" "B.Cu")
		(net "GND")
	)
	(via
		(at 157.37586 -186.787282)
		(size 0.508)
		(drill 0.254)
		(layers "F.Cu" "B.Cu")
		(net "GND")
	)
	(via
		(at 54.000146 -71.398892)
		(size 0.508)
		(drill 0.254)
		(layers "F.Cu" "B.Cu")
		(net "GND")
	)
	(via
		(at 21.043138 -181.881272)
		(size 0.508)
		(drill 0.254)
		(layers "F.Cu" "B.Cu")
		(net "GND")
	)
	(via
		(at 116.3447 -184.163462)
		(size 0.508)
		(drill 0.254)
		(layers "F.Cu" "B.Cu")
		(net "GND")
	)
	(via
		(at 73.742042 -142.859506)
		(size 0.49022)
		(drill 0.254)
		(layers "F.Cu" "B.Cu")
		(net "GND")
	)
	(via
		(at 76.51496 -119.60479)
		(size 0.508)
		(drill 0.254)
		(layers "F.Cu" "B.Cu")
		(net "GND")
	)
	(via
		(at 54.000146 -73.799192)
		(size 0.508)
		(drill 0.254)
		(layers "F.Cu" "B.Cu")
		(net "GND")
	)
	(via
		(at 27.79014 -157.84195)
		(size 0.508)
		(drill 0.254)
		(layers "F.Cu" "B.Cu")
		(net "GND")
	)
	(via
		(at 78.123796 -160.975548)
		(size 0.508)
		(drill 0.254)
		(layers "F.Cu" "B.Cu")
		(net "GND")
	)
	(via
		(at 43.51274 -3.1623)
		(size 0.508)
		(drill 0.254)
		(layers "F.Cu" "B.Cu")
		(net "GND")
	)
	(via
		(at 56.64454 -87.437468)
		(size 0.508)
		(drill 0.254)
		(layers "F.Cu" "B.Cu")
		(net "GND")
	)
	(via
		(at 130.784854 -183.92648)
		(size 0.508)
		(drill 0.254)
		(layers "F.Cu" "B.Cu")
		(net "GND")
	)
	(via
		(at 46.950122 -22.470618)
		(size 0.508)
		(drill 0.254)
		(layers "F.Cu" "B.Cu")
		(net "GND")
	)
	(via
		(at 37.464238 -10.917682)
		(size 0.508)
		(drill 0.254)
		(layers "F.Cu" "B.Cu")
		(net "GND")
	)
	(via
		(at 70.187312 -67.230498)
		(size 0.508)
		(drill 0.254)
		(layers "F.Cu" "B.Cu")
		(net "GND")
	)
	(via
		(at 71.341996 -136.459214)
		(size 0.49022)
		(drill 0.254)
		(layers "F.Cu" "B.Cu")
		(net "GND")
	)
	(via
		(at 61.19114 -69.784468)
		(size 0.508)
		(drill 0.254)
		(layers "F.Cu" "B.Cu")
		(net "GND")
	)
	(via
		(at 55.150766 -83.110578)
		(size 0.508)
		(drill 0.254)
		(layers "F.Cu" "B.Cu")
		(net "GND")
	)
	(via
		(at 81.017872 -136.157208)
		(size 0.508)
		(drill 0.254)
		(layers "F.Cu" "B.Cu")
		(net "GND")
	)
	(via
		(at 70.54215 -142.059406)
		(size 0.49022)
		(drill 0.254)
		(layers "F.Cu" "B.Cu")
		(net "GND")
	)
	(via
		(at 105.088182 -124.658374)
		(size 0.508)
		(drill 0.254)
		(layers "F.Cu" "B.Cu")
		(net "GND")
	)
	(via
		(at 123.41606 -150.003002)
		(size 0.508)
		(drill 0.254)
		(layers "F.Cu" "B.Cu")
		(net "GND")
	)
	(via
		(at 192.405 -120.396)
		(size 0.508)
		(drill 0.254)
		(layers "F.Cu" "B.Cu")
		(net "GND")
	)
	(via
		(at 60.141104 -129.258314)
		(size 0.49022)
		(drill 0.254)
		(layers "F.Cu" "B.Cu")
		(net "GND")
	)
	(via
		(at 87.57158 -25.836372)
		(size 0.508)
		(drill 0.254)
		(layers "F.Cu" "B.Cu")
		(net "GND")
	)
	(via
		(at 128.171702 -132.6007)
		(size 0.508)
		(drill 0.254)
		(layers "F.Cu" "B.Cu")
		(net "GND")
	)
	(via
		(at 68.692776 -68.717922)
		(size 0.508)
		(drill 0.254)
		(layers "F.Cu" "B.Cu")
		(net "GND")
	)
	(via
		(at 18.01495 -201.09053)
		(size 0.508)
		(drill 0.254)
		(layers "F.Cu" "B.Cu")
		(net "GND")
	)
	(via
		(at 56.400446 -73.799192)
		(size 0.508)
		(drill 0.254)
		(layers "F.Cu" "B.Cu")
		(net "GND")
	)
	(via
		(at 149.615144 -139.40155)
		(size 0.508)
		(drill 0.254)
		(layers "F.Cu" "B.Cu")
		(net "GND")
	)
	(via
		(at 144.218914 -134.19455)
		(size 0.508)
		(drill 0.254)
		(layers "F.Cu" "B.Cu")
		(net "GND")
	)
	(via
		(at 57.926478 -89.620598)
		(size 0.508)
		(drill 0.254)
		(layers "F.Cu" "B.Cu")
		(net "GND")
	)
	(via
		(at 164.44976 -103.729282)
		(size 0.508)
		(drill 0.254)
		(layers "F.Cu" "B.Cu")
		(net "GND")
	)
	(via
		(at 57.200546 -72.999092)
		(size 0.508)
		(drill 0.254)
		(layers "F.Cu" "B.Cu")
		(net "GND")
	)
	(via
		(at 23.083012 -45.203618)
		(size 0.508)
		(drill 0.254)
		(layers "F.Cu" "B.Cu")
		(net "GND")
	)
	(via
		(at 17.013174 -15.08506)
		(size 0.508)
		(drill 0.254)
		(layers "F.Cu" "B.Cu")
		(net "GND")
	)
	(via
		(at 49.405032 -178.936904)
		(size 0.508)
		(drill 0.254)
		(layers "F.Cu" "B.Cu")
		(net "GND")
	)
	(via
		(at 174.510446 -118.86565)
		(size 0.49022)
		(drill 0.254)
		(layers "F.Cu" "B.Cu")
		(net "GND")
	)
	(via
		(at 190.0682 -126.1872)
		(size 0.508)
		(drill 0.254)
		(layers "F.Cu" "B.Cu")
		(net "GND")
	)
	(via
		(at 49.35982 -100.69195)
		(size 0.508)
		(drill 0.254)
		(layers "F.Cu" "B.Cu")
		(net "GND")
	)
	(via
		(at 31.934404 -105.13695)
		(size 0.508)
		(drill 0.254)
		(layers "F.Cu" "B.Cu")
		(net "GND")
	)
	(via
		(at 92.243148 -187.842398)
		(size 0.508)
		(drill 0.254)
		(layers "F.Cu" "B.Cu")
		(net "GND")
	)
	(via
		(at 47.864268 -64.171322)
		(size 0.508)
		(drill 0.254)
		(layers "F.Cu" "B.Cu")
		(net "GND")
	)
	(via
		(at 128.382268 -116.514626)
		(size 0.508)
		(drill 0.254)
		(layers "F.Cu" "B.Cu")
		(net "GND")
	)
	(via
		(at 54.581552 -89.638886)
		(size 0.508)
		(drill 0.254)
		(layers "F.Cu" "B.Cu")
		(net "GND")
	)
	(via
		(at 144.51076 -183.91886)
		(size 0.508)
		(drill 0.254)
		(layers "F.Cu" "B.Cu")
		(net "GND")
	)
	(via
		(at 32.443166 -101.092254)
		(size 0.508)
		(drill 0.254)
		(layers "F.Cu" "B.Cu")
		(net "GND")
	)
	(via
		(at 79.52105 -140.65377)
		(size 0.508)
		(drill 0.254)
		(layers "F.Cu" "B.Cu")
		(net "GND")
	)
	(via
		(at 70.309486 -119.850662)
		(size 0.508)
		(drill 0.254)
		(layers "F.Cu" "B.Cu")
		(net "GND")
	)
	(via
		(at 117.45976 -186.864498)
		(size 0.508)
		(drill 0.254)
		(layers "F.Cu" "B.Cu")
		(net "GND")
	)
	(via
		(at 131.9022 -56.007)
		(size 0.508)
		(drill 0.254)
		(layers "F.Cu" "B.Cu")
		(net "GND")
	)
	(via
		(at 64.940942 -141.257782)
		(size 0.49022)
		(drill 0.254)
		(layers "F.Cu" "B.Cu")
		(net "GND")
	)
	(via
		(at 30.710886 -171.32046)
		(size 0.508)
		(drill 0.254)
		(layers "F.Cu" "B.Cu")
		(net "GND")
	)
	(via
		(at 112.305592 -70.957694)
		(size 0.508)
		(drill 0.254)
		(layers "F.Cu" "B.Cu")
		(net "GND")
	)
	(via
		(at 72.13346 -186.684158)
		(size 0.508)
		(drill 0.254)
		(layers "F.Cu" "B.Cu")
		(net "GND")
	)
	(via
		(at 89.289382 -31.673038)
		(size 0.508)
		(drill 0.254)
		(layers "F.Cu" "B.Cu")
		(net "GND")
	)
	(via
		(at 86.225634 -4.260342)
		(size 0.508)
		(drill 0.254)
		(layers "F.Cu" "B.Cu")
		(net "GND")
	)
	(via
		(at 43.447462 -144.630394)
		(size 0.508)
		(drill 0.254)
		(layers "F.Cu" "B.Cu")
		(net "GND")
	)
	(via
		(at 80.508602 -118.78437)
		(size 0.508)
		(drill 0.254)
		(layers "F.Cu" "B.Cu")
		(net "GND")
	)
	(via
		(at 119.253 -113.72342)
		(size 0.508)
		(drill 0.254)
		(layers "F.Cu" "B.Cu")
		(net "GND")
	)
	(via
		(at 169.00906 -54.588664)
		(size 0.508)
		(drill 0.254)
		(layers "F.Cu" "B.Cu")
		(net "GND")
	)
	(via
		(at 158.589472 -152.334214)
		(size 0.508)
		(drill 0.254)
		(layers "F.Cu" "B.Cu")
		(net "GND")
	)
	(via
		(at 129.261616 -31.512002)
		(size 0.508)
		(drill 0.254)
		(layers "F.Cu" "B.Cu")
		(net "GND")
	)
	(via
		(at 163.466272 -150.683214)
		(size 0.508)
		(drill 0.254)
		(layers "F.Cu" "B.Cu")
		(net "GND")
	)
	(via
		(at 46.972728 -157.336998)
		(size 0.508)
		(drill 0.254)
		(layers "F.Cu" "B.Cu")
		(net "GND")
	)
	(via
		(at 118.92534 -101.98227)
		(size 0.508)
		(drill 0.254)
		(layers "F.Cu" "B.Cu")
		(net "GND")
	)
	(via
		(at 67.328542 -67.741038)
		(size 0.508)
		(drill 0.254)
		(layers "F.Cu" "B.Cu")
		(net "GND")
	)
	(via
		(at 43.603164 -1.892046)
		(size 0.508)
		(drill 0.254)
		(layers "F.Cu" "B.Cu")
		(net "GND")
	)
	(via
		(at 147.245578 -56.048148)
		(size 0.508)
		(drill 0.254)
		(layers "F.Cu" "B.Cu")
		(net "GND")
	)
	(via
		(at 63.340996 -136.458198)
		(size 0.49022)
		(drill 0.254)
		(layers "F.Cu" "B.Cu")
		(net "GND")
	)
	(via
		(at 135.365236 -124.811536)
		(size 0.508)
		(drill 0.254)
		(layers "F.Cu" "B.Cu")
		(net "GND")
	)
	(via
		(at 45.282612 -178.301904)
		(size 0.508)
		(drill 0.254)
		(layers "F.Cu" "B.Cu")
		(net "GND")
	)
	(via
		(at 89.338912 -166.08044)
		(size 0.508)
		(drill 0.254)
		(layers "F.Cu" "B.Cu")
		(net "GND")
	)
	(via
		(at 49.650142 -27.626818)
		(size 0.508)
		(drill 0.254)
		(layers "F.Cu" "B.Cu")
		(net "GND")
	)
	(via
		(at 158.48584 -186.725814)
		(size 0.508)
		(drill 0.254)
		(layers "F.Cu" "B.Cu")
		(net "GND")
	)
	(via
		(at 51.178206 -86.133178)
		(size 0.508)
		(drill 0.254)
		(layers "F.Cu" "B.Cu")
		(net "GND")
	)
	(via
		(at 194.77228 -144.753838)
		(size 0.508)
		(drill 0.254)
		(layers "F.Cu" "B.Cu")
		(net "GND")
	)
	(via
		(at 18.57502 -152.806146)
		(size 0.508)
		(drill 0.254)
		(layers "F.Cu" "B.Cu")
		(net "GND")
	)
	(via
		(at 66.540888 -136.458198)
		(size 0.49022)
		(drill 0.254)
		(layers "F.Cu" "B.Cu")
		(net "GND")
	)
	(via
		(at 24.99614 -107.164632)
		(size 0.508)
		(drill 0.254)
		(layers "F.Cu" "B.Cu")
		(net "GND")
	)
	(via
		(at 148.85924 -173.375828)
		(size 0.508)
		(drill 0.254)
		(layers "F.Cu" "B.Cu")
		(net "GND")
	)
	(via
		(at 106.72064 -183.974486)
		(size 0.508)
		(drill 0.254)
		(layers "F.Cu" "B.Cu")
		(net "GND")
	)
	(via
		(at 39.35603 -137.765282)
		(size 0.49022)
		(drill 0.254)
		(layers "F.Cu" "B.Cu")
		(net "GND")
	)
	(via
		(at 74.731372 -87.271098)
		(size 0.508)
		(drill 0.254)
		(layers "F.Cu" "B.Cu")
		(net "GND")
	)
	(via
		(at 165.464998 -144.697704)
		(size 0.508)
		(drill 0.254)
		(layers "F.Cu" "B.Cu")
		(net "GND")
	)
	(via
		(at 62.646306 -157.931612)
		(size 0.508)
		(drill 0.254)
		(layers "F.Cu" "B.Cu")
		(net "GND")
	)
	(via
		(at 41.127172 -64.588898)
		(size 0.508)
		(drill 0.254)
		(layers "F.Cu" "B.Cu")
		(net "GND")
	)
	(via
		(at 55.590186 -150.645622)
		(size 0.508)
		(drill 0.254)
		(layers "F.Cu" "B.Cu")
		(net "GND")
	)
	(via
		(at 146.79676 -183.928258)
		(size 0.508)
		(drill 0.254)
		(layers "F.Cu" "B.Cu")
		(net "GND")
	)
	(via
		(at 46.816772 -62.893448)
		(size 0.508)
		(drill 0.254)
		(layers "F.Cu" "B.Cu")
		(net "GND")
	)
	(via
		(at 51.4223 -168.562782)
		(size 0.508)
		(drill 0.254)
		(layers "F.Cu" "B.Cu")
		(net "GND")
	)
	(via
		(at 50.911506 -99.102672)
		(size 0.508)
		(drill 0.254)
		(layers "F.Cu" "B.Cu")
		(net "GND")
	)
	(via
		(at 47.25924 -25.426162)
		(size 0.508)
		(drill 0.254)
		(layers "F.Cu" "B.Cu")
		(net "GND")
	)
	(via
		(at 168.790112 -117.711728)
		(size 0.508)
		(drill 0.254)
		(layers "F.Cu" "B.Cu")
		(net "GND")
	)
	(via
		(at 75.73264 -187.068206)
		(size 0.508)
		(drill 0.254)
		(layers "F.Cu" "B.Cu")
		(net "GND")
	)
	(via
		(at 28.050744 -126.918974)
		(size 0.508)
		(drill 0.254)
		(layers "F.Cu" "B.Cu")
		(net "GND")
	)
	(via
		(at 139.000992 -27.071828)
		(size 0.508)
		(drill 0.254)
		(layers "F.Cu" "B.Cu")
		(net "GND")
	)
	(via
		(at 165.903148 -80.873092)
		(size 0.508)
		(drill 0.254)
		(layers "F.Cu" "B.Cu")
		(net "GND")
	)
	(via
		(at 79.410814 -155.335224)
		(size 0.508)
		(drill 0.254)
		(layers "F.Cu" "B.Cu")
		(net "GND")
	)
	(via
		(at 11.04392 -8.786368)
		(size 0.508)
		(drill 0.254)
		(layers "F.Cu" "B.Cu")
		(net "GND")
	)
	(via
		(at 78.257908 -157.65399)
		(size 0.508)
		(drill 0.254)
		(layers "F.Cu" "B.Cu")
		(net "GND")
	)
	(via
		(at 44.379896 -12.471654)
		(size 0.508)
		(drill 0.254)
		(layers "F.Cu" "B.Cu")
		(net "GND")
	)
	(via
		(at 67.340988 -136.458198)
		(size 0.49022)
		(drill 0.254)
		(layers "F.Cu" "B.Cu")
		(net "GND")
	)
	(via
		(at 104.033574 -180.757322)
		(size 0.508)
		(drill 0.254)
		(layers "F.Cu" "B.Cu")
		(net "GND")
	)
	(via
		(at 154.640534 -102.47503)
		(size 0.508)
		(drill 0.254)
		(layers "F.Cu" "B.Cu")
		(net "GND")
	)
	(via
		(at 62.55131 -90.38717)
		(size 0.508)
		(drill 0.254)
		(layers "F.Cu" "B.Cu")
		(net "GND")
	)
	(via
		(at 87.11057 -74.046842)
		(size 0.508)
		(drill 0.254)
		(layers "F.Cu" "B.Cu")
		(net "GND")
	)
	(via
		(at 84.5058 -84.604606)
		(size 0.508)
		(drill 0.254)
		(layers "F.Cu" "B.Cu")
		(net "GND")
	)
	(via
		(at 72.61606 -79.084678)
		(size 0.508)
		(drill 0.254)
		(layers "F.Cu" "B.Cu")
		(net "GND")
	)
	(via
		(at 64.417194 -74.61631)
		(size 0.508)
		(drill 0.254)
		(layers "F.Cu" "B.Cu")
		(net "GND")
	)
	(via
		(at 11.53414 -5.477002)
		(size 0.508)
		(drill 0.254)
		(layers "F.Cu" "B.Cu")
		(net "GND")
	)
	(via
		(at 194.7926 -145.508726)
		(size 0.508)
		(drill 0.254)
		(layers "F.Cu" "B.Cu")
		(net "GND")
	)
	(via
		(at 9.64946 -115.067588)
		(size 0.508)
		(drill 0.254)
		(layers "F.Cu" "B.Cu")
		(net "GND")
	)
	(via
		(at 175.649128 -145.234406)
		(size 0.508)
		(drill 0.254)
		(layers "F.Cu" "B.Cu")
		(net "GND")
	)
	(via
		(at 28.796488 -126.209552)
		(size 0.508)
		(drill 0.254)
		(layers "F.Cu" "B.Cu")
		(net "GND")
	)
	(via
		(at 153.802334 -152.678638)
		(size 0.508)
		(drill 0.254)
		(layers "F.Cu" "B.Cu")
		(net "GND")
	)
	(via
		(at 105.621836 -176.091088)
		(size 0.508)
		(drill 0.254)
		(layers "F.Cu" "B.Cu")
		(net "GND")
	)
	(via
		(at 44.530772 -70.786498)
		(size 0.508)
		(drill 0.254)
		(layers "F.Cu" "B.Cu")
		(net "GND")
	)
	(via
		(at 65.898522 -30.676342)
		(size 0.508)
		(drill 0.254)
		(layers "F.Cu" "B.Cu")
		(net "GND")
	)
	(via
		(at 184.44464 -27.766264)
		(size 0.508)
		(drill 0.254)
		(layers "F.Cu" "B.Cu")
		(net "GND")
	)
	(via
		(at 47.47895 -90.376248)
		(size 0.508)
		(drill 0.254)
		(layers "F.Cu" "B.Cu")
		(net "GND")
	)
	(via
		(at 58.371486 -148.241258)
		(size 0.508)
		(drill 0.254)
		(layers "F.Cu" "B.Cu")
		(net "GND")
	)
	(via
		(at 61.9506 -184.064148)
		(size 0.508)
		(drill 0.254)
		(layers "F.Cu" "B.Cu")
		(net "GND")
	)
	(via
		(at 79.97444 -93.384624)
		(size 0.508)
		(drill 0.254)
		(layers "F.Cu" "B.Cu")
		(net "GND")
	)
	(via
		(at 71.427848 -85.872066)
		(size 0.508)
		(drill 0.254)
		(layers "F.Cu" "B.Cu")
		(net "GND")
	)
	(via
		(at 81.969102 -16.044418)
		(size 0.508)
		(drill 0.254)
		(layers "F.Cu" "B.Cu")
		(net "GND")
	)
	(via
		(at 162.871658 -75.45578)
		(size 0.508)
		(drill 0.254)
		(layers "F.Cu" "B.Cu")
		(net "GND")
	)
	(via
		(at 73.742042 -138.059414)
		(size 0.49022)
		(drill 0.254)
		(layers "F.Cu" "B.Cu")
		(net "GND")
	)
	(via
		(at 38.299898 -2.348484)
		(size 0.508)
		(drill 0.254)
		(layers "F.Cu" "B.Cu")
		(net "GND")
	)
	(via
		(at 60.833 -25.63495)
		(size 0.508)
		(drill 0.254)
		(layers "F.Cu" "B.Cu")
		(net "GND")
	)
	(via
		(at 157.83814 -177.023014)
		(size 0.508)
		(drill 0.254)
		(layers "F.Cu" "B.Cu")
		(net "GND")
	)
	(via
		(at 54.917086 -124.168662)
		(size 0.508)
		(drill 0.254)
		(layers "F.Cu" "B.Cu")
		(net "GND")
	)
	(via
		(at 86.2584 -157.148022)
		(size 0.508)
		(drill 0.254)
		(layers "F.Cu" "B.Cu")
		(net "GND")
	)
	(via
		(at 121.015506 -201.034904)
		(size 0.508)
		(drill 0.254)
		(layers "F.Cu" "B.Cu")
		(net "GND")
	)
	(via
		(at 58.314336 -165.777672)
		(size 0.508)
		(drill 0.254)
		(layers "F.Cu" "B.Cu")
		(net "GND")
	)
	(via
		(at 25.80386 -113.335562)
		(size 0.508)
		(drill 0.254)
		(layers "F.Cu" "B.Cu")
		(net "GND")
	)
	(via
		(at 180.015642 -200.937368)
		(size 0.508)
		(drill 0.254)
		(layers "F.Cu" "B.Cu")
		(net "GND")
	)
	(via
		(at 34.925 -6.475476)
		(size 0.508)
		(drill 0.254)
		(layers "F.Cu" "B.Cu")
		(net "GND")
	)
	(via
		(at 106.074718 -136.340342)
		(size 0.508)
		(drill 0.254)
		(layers "F.Cu" "B.Cu")
		(net "GND")
	)
	(via
		(at 75.007978 -69.961506)
		(size 0.508)
		(drill 0.254)
		(layers "F.Cu" "B.Cu")
		(net "GND")
	)
	(via
		(at 169.23258 -91.220036)
		(size 0.508)
		(drill 0.254)
		(layers "F.Cu" "B.Cu")
		(net "GND")
	)
	(via
		(at 64.75476 -180.944774)
		(size 0.508)
		(drill 0.254)
		(layers "F.Cu" "B.Cu")
		(net "GND")
	)
	(via
		(at 127.009652 -141.20495)
		(size 0.508)
		(drill 0.254)
		(layers "F.Cu" "B.Cu")
		(net "GND")
	)
	(via
		(at 58.41746 -5.389626)
		(size 0.508)
		(drill 0.254)
		(layers "F.Cu" "B.Cu")
		(net "GND")
	)
	(via
		(at 116.06784 -174.137574)
		(size 0.508)
		(drill 0.254)
		(layers "F.Cu" "B.Cu")
		(net "GND")
	)
	(via
		(at 103.564182 -125.420374)
		(size 0.508)
		(drill 0.254)
		(layers "F.Cu" "B.Cu")
		(net "GND")
	)
	(via
		(at 149.342602 -183.923432)
		(size 0.508)
		(drill 0.254)
		(layers "F.Cu" "B.Cu")
		(net "GND")
	)
	(via
		(at 135.391652 -149.94255)
		(size 0.508)
		(drill 0.254)
		(layers "F.Cu" "B.Cu")
		(net "GND")
	)
	(via
		(at 64.724026 -84.43849)
		(size 0.508)
		(drill 0.254)
		(layers "F.Cu" "B.Cu")
		(net "GND")
	)
	(via
		(at 86.166706 -6.154928)
		(size 0.508)
		(drill 0.254)
		(layers "F.Cu" "B.Cu")
		(net "GND")
	)
	(via
		(at 135.39216 -115.118134)
		(size 0.508)
		(drill 0.254)
		(layers "F.Cu" "B.Cu")
		(net "GND")
	)
	(via
		(at 28.06446 -100.929948)
		(size 0.508)
		(drill 0.254)
		(layers "F.Cu" "B.Cu")
		(net "GND")
	)
	(via
		(at 137.474452 -137.06475)
		(size 0.508)
		(drill 0.254)
		(layers "F.Cu" "B.Cu")
		(net "GND")
	)
	(via
		(at 146.831304 -64.361822)
		(size 0.508)
		(drill 0.254)
		(layers "F.Cu" "B.Cu")
		(net "GND")
	)
	(via
		(at 63.601346 -75.399392)
		(size 0.508)
		(drill 0.254)
		(layers "F.Cu" "B.Cu")
		(net "GND")
	)
	(via
		(at 22.495002 -124.963936)
		(size 0.508)
		(drill 0.254)
		(layers "F.Cu" "B.Cu")
		(net "GND")
	)
	(via
		(at 31.299404 -105.13695)
		(size 0.508)
		(drill 0.254)
		(layers "F.Cu" "B.Cu")
		(net "GND")
	)
	(via
		(at 64.940942 -142.857474)
		(size 0.49022)
		(drill 0.254)
		(layers "F.Cu" "B.Cu")
		(net "GND")
	)
	(via
		(at 11.56462 -104.768142)
		(size 0.508)
		(drill 0.254)
		(layers "F.Cu" "B.Cu")
		(net "GND")
	)
	(via
		(at 62.809374 -80.194658)
		(size 0.508)
		(drill 0.254)
		(layers "F.Cu" "B.Cu")
		(net "GND")
	)
	(via
		(at 115.19662 -186.997848)
		(size 0.508)
		(drill 0.254)
		(layers "F.Cu" "B.Cu")
		(net "GND")
	)
	(via
		(at 57.741566 -129.259076)
		(size 0.49022)
		(drill 0.254)
		(layers "F.Cu" "B.Cu")
		(net "GND")
	)
	(via
		(at 78.230984 -155.330144)
		(size 0.508)
		(drill 0.254)
		(layers "F.Cu" "B.Cu")
		(net "GND")
	)
	(via
		(at 7.691628 -8.779256)
		(size 0.508)
		(drill 0.254)
		(layers "F.Cu" "B.Cu")
		(net "GND")
	)
	(via
		(at 47.319184 -82.896964)
		(size 0.508)
		(drill 0.254)
		(layers "F.Cu" "B.Cu")
		(net "GND")
	)
	(via
		(at 16.2687 -118.285006)
		(size 0.508)
		(drill 0.254)
		(layers "F.Cu" "B.Cu")
		(net "GND")
	)
	(via
		(at 73.70826 -89.52992)
		(size 0.508)
		(drill 0.254)
		(layers "F.Cu" "B.Cu")
		(net "GND")
	)
	(via
		(at 59.67476 -183.97855)
		(size 0.508)
		(drill 0.254)
		(layers "F.Cu" "B.Cu")
		(net "GND")
	)
	(via
		(at 72.942196 -143.659352)
		(size 0.49022)
		(drill 0.254)
		(layers "F.Cu" "B.Cu")
		(net "GND")
	)
	(via
		(at 179.74564 -170.993816)
		(size 0.508)
		(drill 0.254)
		(layers "F.Cu" "B.Cu")
		(net "GND")
	)
	(via
		(at 73.699116 -61.977778)
		(size 0.508)
		(drill 0.254)
		(layers "F.Cu" "B.Cu")
		(net "GND")
	)
	(via
		(at 99.06 -175.189896)
		(size 0.508)
		(drill 0.254)
		(layers "F.Cu" "B.Cu")
		(net "GND")
	)
	(via
		(at 162.094164 -142.486888)
		(size 0.508)
		(drill 0.254)
		(layers "F.Cu" "B.Cu")
		(net "GND")
	)
	(via
		(at 73.930764 -149.983952)
		(size 0.508)
		(drill 0.254)
		(layers "F.Cu" "B.Cu")
		(net "GND")
	)
	(via
		(at 137.012426 -124.741178)
		(size 0.508)
		(drill 0.254)
		(layers "F.Cu" "B.Cu")
		(net "GND")
	)
	(via
		(at 77.622908 -157.65399)
		(size 0.508)
		(drill 0.254)
		(layers "F.Cu" "B.Cu")
		(net "GND")
	)
	(via
		(at 186.55284 -201.080116)
		(size 0.508)
		(drill 0.254)
		(layers "F.Cu" "B.Cu")
		(net "GND")
	)
	(via
		(at 174.646336 -63.94958)
		(size 0.508)
		(drill 0.254)
		(layers "F.Cu" "B.Cu")
		(net "GND")
	)
	(via
		(at 95.13824 -104.754934)
		(size 0.508)
		(drill 0.254)
		(layers "F.Cu" "B.Cu")
		(net "GND")
	)
	(via
		(at 130.83794 -134.31139)
		(size 0.508)
		(drill 0.254)
		(layers "F.Cu" "B.Cu")
		(net "GND")
	)
	(via
		(at 116.4971 -169.301922)
		(size 0.508)
		(drill 0.254)
		(layers "F.Cu" "B.Cu")
		(net "GND")
	)
	(via
		(at 71.491094 -81.722976)
		(size 0.508)
		(drill 0.254)
		(layers "F.Cu" "B.Cu")
		(net "GND")
	)
	(via
		(at 113.486946 -167.011604)
		(size 0.508)
		(drill 0.254)
		(layers "F.Cu" "B.Cu")
		(net "GND")
	)
	(via
		(at 78.522322 -81.769712)
		(size 0.508)
		(drill 0.254)
		(layers "F.Cu" "B.Cu")
		(net "GND")
	)
	(via
		(at 178.059842 -140.629132)
		(size 0.508)
		(drill 0.254)
		(layers "F.Cu" "B.Cu")
		(net "GND")
	)
	(via
		(at 64.141096 -133.258306)
		(size 0.49022)
		(drill 0.254)
		(layers "F.Cu" "B.Cu")
		(net "GND")
	)
	(via
		(at 79.157322 -81.769712)
		(size 0.508)
		(drill 0.254)
		(layers "F.Cu" "B.Cu")
		(net "GND")
	)
	(via
		(at 77.86116 -183.963564)
		(size 0.508)
		(drill 0.254)
		(layers "F.Cu" "B.Cu")
		(net "GND")
	)
	(via
		(at 160.942782 -102.544118)
		(size 0.508)
		(drill 0.254)
		(layers "F.Cu" "B.Cu")
		(net "GND")
	)
	(via
		(at 56.400446 -76.999592)
		(size 0.508)
		(drill 0.254)
		(layers "F.Cu" "B.Cu")
		(net "GND")
	)
	(via
		(at 67.340988 -140.45819)
		(size 0.49022)
		(drill 0.254)
		(layers "F.Cu" "B.Cu")
		(net "GND")
	)
	(via
		(at 66.4845 -19.275044)
		(size 0.508)
		(drill 0.254)
		(layers "F.Cu" "B.Cu")
		(net "GND")
	)
	(via
		(at 167.675052 -92.93479)
		(size 0.508)
		(drill 0.254)
		(layers "F.Cu" "B.Cu")
		(net "GND")
	)
	(via
		(at 70.662546 -4.167632)
		(size 0.508)
		(drill 0.254)
		(layers "F.Cu" "B.Cu")
		(net "GND")
	)
	(via
		(at 167.8178 -51.633628)
		(size 0.508)
		(drill 0.254)
		(layers "F.Cu" "B.Cu")
		(net "GND")
	)
	(via
		(at 100.950268 -23.029418)
		(size 0.508)
		(drill 0.254)
		(layers "F.Cu" "B.Cu")
		(net "GND")
	)
	(via
		(at 68.141088 -142.059914)
		(size 0.49022)
		(drill 0.254)
		(layers "F.Cu" "B.Cu")
		(net "GND")
	)
	(via
		(at 64.600836 -75.876912)
		(size 0.508)
		(drill 0.254)
		(layers "F.Cu" "B.Cu")
		(net "GND")
	)
	(via
		(at 45.601128 -152.510998)
		(size 0.508)
		(drill 0.254)
		(layers "F.Cu" "B.Cu")
		(net "GND")
	)
	(via
		(at 151.62276 -186.862974)
		(size 0.508)
		(drill 0.254)
		(layers "F.Cu" "B.Cu")
		(net "GND")
	)
	(via
		(at 82.763614 -182.811674)
		(size 0.508)
		(drill 0.254)
		(layers "F.Cu" "B.Cu")
		(net "GND")
	)
	(via
		(at 65.6082 -5.661406)
		(size 0.508)
		(drill 0.254)
		(layers "F.Cu" "B.Cu")
		(net "GND")
	)
	(via
		(at 45.232828 -136.564116)
		(size 0.49022)
		(drill 0.254)
		(layers "F.Cu" "B.Cu")
		(net "GND")
	)
	(via
		(at 56.877966 -66.964306)
		(size 0.508)
		(drill 0.254)
		(layers "F.Cu" "B.Cu")
		(net "GND")
	)
	(via
		(at 47.058834 -107.699302)
		(size 0.508)
		(drill 0.254)
		(layers "F.Cu" "B.Cu")
		(net "GND")
	)
	(via
		(at 13.731748 -65.290446)
		(size 0.508)
		(drill 0.254)
		(layers "F.Cu" "B.Cu")
		(net "GND")
	)
	(via
		(at 58.800746 -78.599792)
		(size 0.508)
		(drill 0.254)
		(layers "F.Cu" "B.Cu")
		(net "GND")
	)
	(via
		(at 42.212006 -85.16239)
		(size 0.508)
		(drill 0.254)
		(layers "F.Cu" "B.Cu")
		(net "GND")
	)
	(via
		(at 63.838836 -89.625678)
		(size 0.508)
		(drill 0.254)
		(layers "F.Cu" "B.Cu")
		(net "GND")
	)
	(via
		(at 135.504682 -45.072046)
		(size 0.508)
		(drill 0.254)
		(layers "F.Cu" "B.Cu")
		(net "GND")
	)
	(via
		(at 112.105694 -76.406248)
		(size 0.508)
		(drill 0.254)
		(layers "F.Cu" "B.Cu")
		(net "GND")
	)
	(via
		(at 151.529796 -68.24853)
		(size 0.508)
		(drill 0.254)
		(layers "F.Cu" "B.Cu")
		(net "GND")
	)
	(via
		(at 173.05274 -169.334434)
		(size 0.508)
		(drill 0.254)
		(layers "F.Cu" "B.Cu")
		(net "GND")
	)
	(via
		(at 106.28376 -186.92622)
		(size 0.508)
		(drill 0.254)
		(layers "F.Cu" "B.Cu")
		(net "GND")
	)
	(via
		(at 51.67376 -186.862974)
		(size 0.508)
		(drill 0.254)
		(layers "F.Cu" "B.Cu")
		(net "GND")
	)
	(via
		(at 94.08922 -190.281052)
		(size 0.508)
		(drill 0.254)
		(layers "F.Cu" "B.Cu")
		(net "GND")
	)
	(via
		(at 85.43036 -25.21331)
		(size 0.508)
		(drill 0.254)
		(layers "F.Cu" "B.Cu")
		(net "GND")
	)
	(via
		(at 167.92956 -98.115882)
		(size 0.508)
		(drill 0.254)
		(layers "F.Cu" "B.Cu")
		(net "GND")
	)
	(via
		(at 95.850202 -30.761432)
		(size 0.508)
		(drill 0.254)
		(layers "F.Cu" "B.Cu")
		(net "GND")
	)
	(via
		(at 195.7959 -146.24304)
		(size 0.508)
		(drill 0.254)
		(layers "F.Cu" "B.Cu")
		(net "GND")
	)
	(via
		(at 97.516696 -130.758438)
		(size 0.508)
		(drill 0.254)
		(layers "F.Cu" "B.Cu")
		(net "GND")
	)
	(via
		(at 175.554894 -131.745736)
		(size 0.508)
		(drill 0.254)
		(layers "F.Cu" "B.Cu")
		(net "GND")
	)
	(via
		(at 81.373218 -156.990034)
		(size 0.508)
		(drill 0.254)
		(layers "F.Cu" "B.Cu")
		(net "GND")
	)
	(via
		(at 162.124644 -141.58341)
		(size 0.508)
		(drill 0.254)
		(layers "F.Cu" "B.Cu")
		(net "GND")
	)
	(via
		(at 139.93876 -186.862974)
		(size 0.508)
		(drill 0.254)
		(layers "F.Cu" "B.Cu")
		(net "GND")
	)
	(via
		(at 81.108042 -85.93328)
		(size 0.508)
		(drill 0.254)
		(layers "F.Cu" "B.Cu")
		(net "GND")
	)
	(via
		(at 25.8191 -108.90123)
		(size 0.508)
		(drill 0.254)
		(layers "F.Cu" "B.Cu")
		(net "GND")
	)
	(via
		(at 127.541528 -37.258244)
		(size 0.508)
		(drill 0.254)
		(layers "F.Cu" "B.Cu")
		(net "GND")
	)
	(via
		(at 133.527292 -126.167896)
		(size 0.508)
		(drill 0.254)
		(layers "F.Cu" "B.Cu")
		(net "GND")
	)
	(via
		(at 53.01234 -127.217424)
		(size 0.508)
		(drill 0.254)
		(layers "F.Cu" "B.Cu")
		(net "GND")
	)
	(via
		(at 99.47402 -151.8666)
		(size 0.508)
		(drill 0.254)
		(layers "F.Cu" "B.Cu")
		(net "GND")
	)
	(via
		(at 172.297852 -102.91699)
		(size 0.508)
		(drill 0.254)
		(layers "F.Cu" "B.Cu")
		(net "GND")
	)
	(via
		(at 73.470516 -64.944752)
		(size 0.508)
		(drill 0.254)
		(layers "F.Cu" "B.Cu")
		(net "GND")
	)
	(via
		(at 79.98714 -159.314388)
		(size 0.508)
		(drill 0.254)
		(layers "F.Cu" "B.Cu")
		(net "GND")
	)
	(via
		(at 67.154044 -71.223378)
		(size 0.508)
		(drill 0.254)
		(layers "F.Cu" "B.Cu")
		(net "GND")
	)
	(via
		(at 61.085222 -175.940212)
		(size 0.508)
		(drill 0.254)
		(layers "F.Cu" "B.Cu")
		(net "GND")
	)
	(via
		(at 15.540482 -118.189756)
		(size 0.508)
		(drill 0.254)
		(layers "F.Cu" "B.Cu")
		(net "GND")
	)
	(via
		(at 65.346834 -170.630088)
		(size 0.508)
		(drill 0.254)
		(layers "F.Cu" "B.Cu")
		(net "GND")
	)
	(via
		(at 167.57396 -136.148826)
		(size 0.508)
		(drill 0.254)
		(layers "F.Cu" "B.Cu")
		(net "GND")
	)
	(via
		(at 121.81205 -118.769638)
		(size 0.508)
		(drill 0.254)
		(layers "F.Cu" "B.Cu")
		(net "GND")
	)
	(via
		(at 110.276132 -31.773368)
		(size 0.508)
		(drill 0.254)
		(layers "F.Cu" "B.Cu")
		(net "GND")
	)
	(via
		(at 187.60948 -28.585922)
		(size 0.508)
		(drill 0.254)
		(layers "F.Cu" "B.Cu")
		(net "GND")
	)
	(via
		(at 42.326306 -3.308858)
		(size 0.508)
		(drill 0.254)
		(layers "F.Cu" "B.Cu")
		(net "GND")
	)
	(via
		(at 137.730992 -27.008582)
		(size 0.508)
		(drill 0.254)
		(layers "F.Cu" "B.Cu")
		(net "GND")
	)
	(via
		(at 152.571196 -68.27393)
		(size 0.508)
		(drill 0.254)
		(layers "F.Cu" "B.Cu")
		(net "GND")
	)
	(via
		(at 125.76556 -97.983548)
		(size 0.508)
		(drill 0.254)
		(layers "F.Cu" "B.Cu")
		(net "GND")
	)
	(via
		(at 131.015486 -201.034904)
		(size 0.508)
		(drill 0.254)
		(layers "F.Cu" "B.Cu")
		(net "GND")
	)
	(via
		(at 151.656796 -60.95873)
		(size 0.508)
		(drill 0.254)
		(layers "F.Cu" "B.Cu")
		(net "GND")
	)
	(via
		(at 96.750124 -22.386036)
		(size 0.508)
		(drill 0.254)
		(layers "F.Cu" "B.Cu")
		(net "GND")
	)
	(via
		(at 55.10276 -186.960002)
		(size 0.508)
		(drill 0.254)
		(layers "F.Cu" "B.Cu")
		(net "GND")
	)
	(via
		(at 87.57412 -181.190646)
		(size 0.508)
		(drill 0.254)
		(layers "F.Cu" "B.Cu")
		(net "GND")
	)
	(via
		(at 117.422676 -22.290786)
		(size 0.508)
		(drill 0.254)
		(layers "F.Cu" "B.Cu")
		(net "GND")
	)
	(via
		(at 47.686976 -179.922424)
		(size 0.508)
		(drill 0.254)
		(layers "F.Cu" "B.Cu")
		(net "GND")
	)
	(via
		(at 37.37864 -61.523626)
		(size 0.508)
		(drill 0.254)
		(layers "F.Cu" "B.Cu")
		(net "GND")
	)
	(via
		(at 150.589996 -63.75273)
		(size 0.508)
		(drill 0.254)
		(layers "F.Cu" "B.Cu")
		(net "GND")
	)
	(via
		(at 64.442086 -148.876512)
		(size 0.508)
		(drill 0.254)
		(layers "F.Cu" "B.Cu")
		(net "GND")
	)
	(via
		(at 80.909922 -16.044418)
		(size 0.508)
		(drill 0.254)
		(layers "F.Cu" "B.Cu")
		(net "GND")
	)
	(via
		(at 97.80016 -132.525516)
		(size 0.508)
		(drill 0.254)
		(layers "F.Cu" "B.Cu")
		(net "GND")
	)
	(via
		(at 62.025784 -105.92054)
		(size 0.508)
		(drill 0.254)
		(layers "F.Cu" "B.Cu")
		(net "GND")
	)
	(via
		(at 85.424264 -8.08101)
		(size 0.508)
		(drill 0.254)
		(layers "F.Cu" "B.Cu")
		(net "GND")
	)
	(via
		(at 97.935542 -160.019492)
		(size 0.508)
		(drill 0.254)
		(layers "F.Cu" "B.Cu")
		(net "GND")
	)
	(via
		(at 118.31066 -113.4618)
		(size 0.508)
		(drill 0.254)
		(layers "F.Cu" "B.Cu")
		(net "GND")
	)
	(via
		(at 96.30664 -26.142442)
		(size 0.508)
		(drill 0.254)
		(layers "F.Cu" "B.Cu")
		(net "GND")
	)
	(via
		(at 106.165396 -168.515284)
		(size 0.508)
		(drill 0.254)
		(layers "F.Cu" "B.Cu")
		(net "GND")
	)
	(via
		(at 85.7377 -140.618972)
		(size 0.508)
		(drill 0.254)
		(layers "F.Cu" "B.Cu")
		(net "GND")
	)
	(via
		(at 45.111416 -90.20937)
		(size 0.508)
		(drill 0.254)
		(layers "F.Cu" "B.Cu")
		(net "GND")
	)
	(via
		(at 17.720564 -147.96135)
		(size 0.508)
		(drill 0.254)
		(layers "F.Cu" "B.Cu")
		(net "GND")
	)
	(via
		(at 55.822088 -64.175386)
		(size 0.508)
		(drill 0.254)
		(layers "F.Cu" "B.Cu")
		(net "GND")
	)
	(via
		(at 65.898776 -89.989914)
		(size 0.508)
		(drill 0.254)
		(layers "F.Cu" "B.Cu")
		(net "GND")
	)
	(via
		(at 180.749448 -157.577282)
		(size 0.508)
		(drill 0.254)
		(layers "F.Cu" "B.Cu")
		(net "GND")
	)
	(via
		(at 52.65674 -83.857846)
		(size 0.508)
		(drill 0.254)
		(layers "F.Cu" "B.Cu")
		(net "GND")
	)
	(via
		(at 45.014896 -12.471654)
		(size 0.508)
		(drill 0.254)
		(layers "F.Cu" "B.Cu")
		(net "GND")
	)
	(via
		(at 161.099754 -173.607222)
		(size 0.508)
		(drill 0.254)
		(layers "F.Cu" "B.Cu")
		(net "GND")
	)
	(via
		(at 69.059044 -69.237098)
		(size 0.508)
		(drill 0.254)
		(layers "F.Cu" "B.Cu")
		(net "GND")
	)
	(via
		(at 194.8053 -141.812772)
		(size 0.508)
		(drill 0.254)
		(layers "F.Cu" "B.Cu")
		(net "GND")
	)
	(via
		(at 185.293 -187.2996)
		(size 0.508)
		(drill 0.254)
		(layers "F.Cu" "B.Cu")
		(net "GND")
	)
	(via
		(at 98.77044 -24.89454)
		(size 0.508)
		(drill 0.254)
		(layers "F.Cu" "B.Cu")
		(net "GND")
	)
	(via
		(at 42.121328 -152.485598)
		(size 0.508)
		(drill 0.254)
		(layers "F.Cu" "B.Cu")
		(net "GND")
	)
	(via
		(at 85.350096 -22.396704)
		(size 0.508)
		(drill 0.254)
		(layers "F.Cu" "B.Cu")
		(net "GND")
	)
	(via
		(at 151.50973 -147.041362)
		(size 0.508)
		(drill 0.254)
		(layers "F.Cu" "B.Cu")
		(net "GND")
	)
	(via
		(at 145.24482 -129.390394)
		(size 0.508)
		(drill 0.254)
		(layers "F.Cu" "B.Cu")
		(net "GND")
	)
	(via
		(at 154.628596 -60.95873)
		(size 0.508)
		(drill 0.254)
		(layers "F.Cu" "B.Cu")
		(net "GND")
	)
	(via
		(at 44.418504 -85.483446)
		(size 0.508)
		(drill 0.254)
		(layers "F.Cu" "B.Cu")
		(net "GND")
	)
	(via
		(at 53.311044 -137.150348)
		(size 0.49022)
		(drill 0.254)
		(layers "F.Cu" "B.Cu")
		(net "GND")
	)
	(via
		(at 155.015692 -201.034904)
		(size 0.508)
		(drill 0.254)
		(layers "F.Cu" "B.Cu")
		(net "GND")
	)
	(via
		(at 74.015092 -201.227436)
		(size 0.508)
		(drill 0.254)
		(layers "F.Cu" "B.Cu")
		(net "GND")
	)
	(via
		(at 13.894562 -31.190184)
		(size 0.508)
		(drill 0.254)
		(layers "F.Cu" "B.Cu")
		(net "GND")
	)
	(via
		(at 90.702384 -186.175904)
		(size 0.508)
		(drill 0.254)
		(layers "F.Cu" "B.Cu")
		(net "GND")
	)
	(via
		(at 115.382802 -19.72945)
		(size 0.508)
		(drill 0.254)
		(layers "F.Cu" "B.Cu")
		(net "GND")
	)
	(via
		(at 80.427322 -81.769712)
		(size 0.508)
		(drill 0.254)
		(layers "F.Cu" "B.Cu")
		(net "GND")
	)
	(via
		(at 137.855452 -117.633242)
		(size 0.508)
		(drill 0.254)
		(layers "F.Cu" "B.Cu")
		(net "GND")
	)
	(via
		(at 74.542142 -143.659606)
		(size 0.49022)
		(drill 0.254)
		(layers "F.Cu" "B.Cu")
		(net "GND")
	)
	(via
		(at 91.29014 -80.53832)
		(size 0.508)
		(drill 0.254)
		(layers "F.Cu" "B.Cu")
		(net "GND")
	)
	(via
		(at 174.643034 -43.762168)
		(size 0.508)
		(drill 0.254)
		(layers "F.Cu" "B.Cu")
		(net "GND")
	)
	(via
		(at 49.78654 -31.797752)
		(size 0.508)
		(drill 0.254)
		(layers "F.Cu" "B.Cu")
		(net "GND")
	)
	(via
		(at 166.79164 -186.999372)
		(size 0.508)
		(drill 0.254)
		(layers "F.Cu" "B.Cu")
		(net "GND")
	)
	(via
		(at 78.21676 -187.05703)
		(size 0.508)
		(drill 0.254)
		(layers "F.Cu" "B.Cu")
		(net "GND")
	)
	(via
		(at 79.537814 -139.908534)
		(size 0.508)
		(drill 0.254)
		(layers "F.Cu" "B.Cu")
		(net "GND")
	)
	(via
		(at 136.25576 -109.708442)
		(size 0.508)
		(drill 0.254)
		(layers "F.Cu" "B.Cu")
		(net "GND")
	)
	(via
		(at 78.862682 -16.044418)
		(size 0.508)
		(drill 0.254)
		(layers "F.Cu" "B.Cu")
		(net "GND")
	)
	(via
		(at 162.603434 -79.23911)
		(size 0.508)
		(drill 0.254)
		(layers "F.Cu" "B.Cu")
		(net "GND")
	)
	(via
		(at 62.025784 -110.64494)
		(size 0.508)
		(drill 0.254)
		(layers "F.Cu" "B.Cu")
		(net "GND")
	)
	(via
		(at 165.389052 -106.01579)
		(size 0.508)
		(drill 0.254)
		(layers "F.Cu" "B.Cu")
		(net "GND")
	)
	(via
		(at 104.326182 -124.658374)
		(size 0.508)
		(drill 0.254)
		(layers "F.Cu" "B.Cu")
		(net "GND")
	)
	(via
		(at 179.015644 -200.983596)
		(size 0.508)
		(drill 0.254)
		(layers "F.Cu" "B.Cu")
		(net "GND")
	)
	(via
		(at 11.1379 -153.110438)
		(size 0.508)
		(drill 0.254)
		(layers "F.Cu" "B.Cu")
		(net "GND")
	)
	(via
		(at 167.378888 -40.217598)
		(size 0.508)
		(drill 0.254)
		(layers "F.Cu" "B.Cu")
		(net "GND")
	)
	(via
		(at 113.59896 -184.09412)
		(size 0.508)
		(drill 0.254)
		(layers "F.Cu" "B.Cu")
		(net "GND")
	)
	(via
		(at 172.777912 -114.663728)
		(size 0.508)
		(drill 0.254)
		(layers "F.Cu" "B.Cu")
		(net "GND")
	)
	(via
		(at 137.65276 -186.862974)
		(size 0.508)
		(drill 0.254)
		(layers "F.Cu" "B.Cu")
		(net "GND")
	)
	(via
		(at 149.20976 -166.867332)
		(size 0.508)
		(drill 0.254)
		(layers "F.Cu" "B.Cu")
		(net "GND")
	)
	(via
		(at 97.65919 -140.30071)
		(size 0.508)
		(drill 0.254)
		(layers "F.Cu" "B.Cu")
		(net "GND")
	)
	(via
		(at 12.1666 -105.32364)
		(size 0.508)
		(drill 0.254)
		(layers "F.Cu" "B.Cu")
		(net "GND")
	)
	(via
		(at 38.712648 -9.680448)
		(size 0.508)
		(drill 0.254)
		(layers "F.Cu" "B.Cu")
		(net "GND")
	)
	(via
		(at 79.590138 -144.95653)
		(size 0.508)
		(drill 0.254)
		(layers "F.Cu" "B.Cu")
		(net "GND")
	)
	(via
		(at 163.466272 -155.534614)
		(size 0.508)
		(drill 0.254)
		(layers "F.Cu" "B.Cu")
		(net "GND")
	)
	(via
		(at 106.323638 -69.478652)
		(size 0.508)
		(drill 0.254)
		(layers "F.Cu" "B.Cu")
		(net "GND")
	)
	(via
		(at 53.391562 -27.548078)
		(size 0.508)
		(drill 0.254)
		(layers "F.Cu" "B.Cu")
		(net "GND")
	)
	(via
		(at 46.833536 -136.564624)
		(size 0.49022)
		(drill 0.254)
		(layers "F.Cu" "B.Cu")
		(net "GND")
	)
	(via
		(at 131.474718 -107.427776)
		(size 0.508)
		(drill 0.254)
		(layers "F.Cu" "B.Cu")
		(net "GND")
	)
	(via
		(at 54.000146 -74.599292)
		(size 0.508)
		(drill 0.254)
		(layers "F.Cu" "B.Cu")
		(net "GND")
	)
	(via
		(at 110.203488 -163.860226)
		(size 0.508)
		(drill 0.254)
		(layers "F.Cu" "B.Cu")
		(net "GND")
	)
	(via
		(at 25.8191 -108.090208)
		(size 0.508)
		(drill 0.254)
		(layers "F.Cu" "B.Cu")
		(net "GND")
	)
	(via
		(at 68.141088 -129.258314)
		(size 0.49022)
		(drill 0.254)
		(layers "F.Cu" "B.Cu")
		(net "GND")
	)
	(via
		(at 143.427704 -66.063622)
		(size 0.508)
		(drill 0.254)
		(layers "F.Cu" "B.Cu")
		(net "GND")
	)
	(via
		(at 16.23822 -142.285974)
		(size 0.508)
		(drill 0.254)
		(layers "F.Cu" "B.Cu")
		(net "GND")
	)
	(via
		(at 85.358478 -146.216878)
		(size 0.508)
		(drill 0.254)
		(layers "F.Cu" "B.Cu")
		(net "GND")
	)
	(via
		(at 130.08356 -187.084716)
		(size 0.508)
		(drill 0.254)
		(layers "F.Cu" "B.Cu")
		(net "GND")
	)
	(via
		(at 46.77918 -24.184102)
		(size 0.508)
		(drill 0.254)
		(layers "F.Cu" "B.Cu")
		(net "GND")
	)
	(via
		(at 79.294482 -22.564598)
		(size 0.508)
		(drill 0.254)
		(layers "F.Cu" "B.Cu")
		(net "GND")
	)
	(via
		(at 51.517042 -95.738188)
		(size 0.508)
		(drill 0.254)
		(layers "F.Cu" "B.Cu")
		(net "GND")
	)
	(via
		(at 107.24134 -153.757122)
		(size 0.508)
		(drill 0.254)
		(layers "F.Cu" "B.Cu")
		(net "GND")
	)
	(via
		(at 72.942196 -137.259314)
		(size 0.49022)
		(drill 0.254)
		(layers "F.Cu" "B.Cu")
		(net "GND")
	)
	(via
		(at 134.499858 -67.458336)
		(size 0.508)
		(drill 0.254)
		(layers "F.Cu" "B.Cu")
		(net "GND")
	)
	(via
		(at 48.842422 -86.561168)
		(size 0.508)
		(drill 0.254)
		(layers "F.Cu" "B.Cu")
		(net "GND")
	)
	(via
		(at 57.200546 -76.999592)
		(size 0.508)
		(drill 0.254)
		(layers "F.Cu" "B.Cu")
		(net "GND")
	)
	(via
		(at 135.94842 -164.772594)
		(size 0.508)
		(drill 0.254)
		(layers "F.Cu" "B.Cu")
		(net "GND")
	)
	(via
		(at 168.79824 -49.534572)
		(size 0.508)
		(drill 0.254)
		(layers "F.Cu" "B.Cu")
		(net "GND")
	)
	(via
		(at 64.772286 -85.932772)
		(size 0.508)
		(drill 0.254)
		(layers "F.Cu" "B.Cu")
		(net "GND")
	)
	(via
		(at 63.601346 -73.799192)
		(size 0.508)
		(drill 0.254)
		(layers "F.Cu" "B.Cu")
		(net "GND")
	)
	(via
		(at 148.593302 -139.181586)
		(size 0.508)
		(drill 0.254)
		(layers "F.Cu" "B.Cu")
		(net "GND")
	)
	(via
		(at 71.341996 -138.059414)
		(size 0.49022)
		(drill 0.254)
		(layers "F.Cu" "B.Cu")
		(net "GND")
	)
	(via
		(at 86.262464 -153.273252)
		(size 0.508)
		(drill 0.254)
		(layers "F.Cu" "B.Cu")
		(net "GND")
	)
	(via
		(at 124.7394 -163.665154)
		(size 0.508)
		(drill 0.254)
		(layers "F.Cu" "B.Cu")
		(net "GND")
	)
	(via
		(at 64.363092 -175.858678)
		(size 0.508)
		(drill 0.254)
		(layers "F.Cu" "B.Cu")
		(net "GND")
	)
	(via
		(at 12.74318 -161.77133)
		(size 0.508)
		(drill 0.254)
		(layers "F.Cu" "B.Cu")
		(net "GND")
	)
	(via
		(at 130.904234 -167.35552)
		(size 0.508)
		(drill 0.254)
		(layers "F.Cu" "B.Cu")
		(net "GND")
	)
	(via
		(at 147.193 -158.994602)
		(size 0.508)
		(drill 0.254)
		(layers "F.Cu" "B.Cu")
		(net "GND")
	)
	(via
		(at 66.948304 -86.588092)
		(size 0.508)
		(drill 0.254)
		(layers "F.Cu" "B.Cu")
		(net "GND")
	)
	(via
		(at 72.942196 -142.859252)
		(size 0.49022)
		(drill 0.254)
		(layers "F.Cu" "B.Cu")
		(net "GND")
	)
	(via
		(at 75.08494 -12.775946)
		(size 0.508)
		(drill 0.254)
		(layers "F.Cu" "B.Cu")
		(net "GND")
	)
	(via
		(at 58.39333 -170.604688)
		(size 0.508)
		(drill 0.254)
		(layers "F.Cu" "B.Cu")
		(net "GND")
	)
	(via
		(at 37.48278 -63.254382)
		(size 0.508)
		(drill 0.254)
		(layers "F.Cu" "B.Cu")
		(net "GND")
	)
	(via
		(at 98.833178 -124.992638)
		(size 0.508)
		(drill 0.254)
		(layers "F.Cu" "B.Cu")
		(net "GND")
	)
	(via
		(at 16.0782 -157.92577)
		(size 0.508)
		(drill 0.254)
		(layers "F.Cu" "B.Cu")
		(net "GND")
	)
	(via
		(at 105.088182 -125.420374)
		(size 0.508)
		(drill 0.254)
		(layers "F.Cu" "B.Cu")
		(net "GND")
	)
	(via
		(at 175.649128 -149.298406)
		(size 0.508)
		(drill 0.254)
		(layers "F.Cu" "B.Cu")
		(net "GND")
	)
	(via
		(at 121.755662 -169.841164)
		(size 0.508)
		(drill 0.254)
		(layers "F.Cu" "B.Cu")
		(net "GND")
	)
	(via
		(at 139.02436 -122.94235)
		(size 0.508)
		(drill 0.254)
		(layers "F.Cu" "B.Cu")
		(net "GND")
	)
	(via
		(at 122.953272 -25.39492)
		(size 0.508)
		(drill 0.254)
		(layers "F.Cu" "B.Cu")
		(net "GND")
	)
	(via
		(at 64.861186 -67.705478)
		(size 0.508)
		(drill 0.254)
		(layers "F.Cu" "B.Cu")
		(net "GND")
	)
	(via
		(at 36.014914 -201.09053)
		(size 0.508)
		(drill 0.254)
		(layers "F.Cu" "B.Cu")
		(net "GND")
	)
	(via
		(at 123.61418 -108.253784)
		(size 0.508)
		(drill 0.254)
		(layers "F.Cu" "B.Cu")
		(net "GND")
	)
	(via
		(at 68.141088 -135.658352)
		(size 0.49022)
		(drill 0.254)
		(layers "F.Cu" "B.Cu")
		(net "GND")
	)
	(via
		(at 21.812504 -55.610506)
		(size 0.508)
		(drill 0.254)
		(layers "F.Cu" "B.Cu")
		(net "GND")
	)
	(via
		(at 194.7926 -144.077182)
		(size 0.508)
		(drill 0.254)
		(layers "F.Cu" "B.Cu")
		(net "GND")
	)
	(via
		(at 27.813 -156.647896)
		(size 0.508)
		(drill 0.254)
		(layers "F.Cu" "B.Cu")
		(net "GND")
	)
	(via
		(at 34.231072 -81.036922)
		(size 0.508)
		(drill 0.254)
		(layers "F.Cu" "B.Cu")
		(net "GND")
	)
	(via
		(at 51.78552 -97.859088)
		(size 0.508)
		(drill 0.254)
		(layers "F.Cu" "B.Cu")
		(net "GND")
	)
	(via
		(at 69.440044 -71.223378)
		(size 0.508)
		(drill 0.254)
		(layers "F.Cu" "B.Cu")
		(net "GND")
	)
	(via
		(at 158.038546 -128.65989)
		(size 0.508)
		(drill 0.254)
		(layers "F.Cu" "B.Cu")
		(net "GND")
	)
	(via
		(at 49.290224 -65.201038)
		(size 0.508)
		(drill 0.254)
		(layers "F.Cu" "B.Cu")
		(net "GND")
	)
	(via
		(at 150.492714 -44.680124)
		(size 0.508)
		(drill 0.254)
		(layers "F.Cu" "B.Cu")
		(net "GND")
	)
	(via
		(at 51.183286 -137.122662)
		(size 0.49022)
		(drill 0.254)
		(layers "F.Cu" "B.Cu")
		(net "GND")
	)
	(via
		(at 38.233096 -97.233232)
		(size 0.508)
		(drill 0.254)
		(layers "F.Cu" "B.Cu")
		(net "GND")
	)
	(via
		(at 102.234746 -140.752322)
		(size 0.508)
		(drill 0.254)
		(layers "F.Cu" "B.Cu")
		(net "GND")
	)
	(via
		(at 34.233358 -186.620404)
		(size 0.508)
		(drill 0.254)
		(layers "F.Cu" "B.Cu")
		(net "GND")
	)
	(via
		(at 174.88154 -186.764676)
		(size 0.508)
		(drill 0.254)
		(layers "F.Cu" "B.Cu")
		(net "GND")
	)
	(via
		(at 40.65016 -27.646376)
		(size 0.508)
		(drill 0.254)
		(layers "F.Cu" "B.Cu")
		(net "GND")
	)
	(via
		(at 43.744896 -12.471654)
		(size 0.508)
		(drill 0.254)
		(layers "F.Cu" "B.Cu")
		(net "GND")
	)
	(via
		(at 116.97462 -173.195996)
		(size 0.508)
		(drill 0.254)
		(layers "F.Cu" "B.Cu")
		(net "GND")
	)
	(via
		(at 152.803352 -168.858692)
		(size 0.508)
		(drill 0.254)
		(layers "F.Cu" "B.Cu")
		(net "GND")
	)
	(via
		(at 53.424582 -67.360038)
		(size 0.508)
		(drill 0.254)
		(layers "F.Cu" "B.Cu")
		(net "GND")
	)
	(via
		(at 66.880486 -134.938262)
		(size 0.6604)
		(drill 0.3302)
		(layers "F.Cu" "B.Cu")
		(net "GND")
	)
	(via
		(at 107.421172 -73.533254)
		(size 0.508)
		(drill 0.254)
		(layers "F.Cu" "B.Cu")
		(net "GND")
	)
	(via
		(at 47.273972 -68.779898)
		(size 0.508)
		(drill 0.254)
		(layers "F.Cu" "B.Cu")
		(net "GND")
	)
	(via
		(at 69.015102 -200.32853)
		(size 0.508)
		(drill 0.254)
		(layers "F.Cu" "B.Cu")
		(net "GND")
	)
	(via
		(at 13.0429 -110.15853)
		(size 0.508)
		(drill 0.254)
		(layers "F.Cu" "B.Cu")
		(net "GND")
	)
	(via
		(at 43.744896 -13.741654)
		(size 0.508)
		(drill 0.254)
		(layers "F.Cu" "B.Cu")
		(net "GND")
	)
	(via
		(at 168.95318 -151.369522)
		(size 0.508)
		(drill 0.254)
		(layers "F.Cu" "B.Cu")
		(net "GND")
	)
	(via
		(at 62.025784 -106.58094)
		(size 0.508)
		(drill 0.254)
		(layers "F.Cu" "B.Cu")
		(net "GND")
	)
	(via
		(at 146.271996 -72.64273)
		(size 0.508)
		(drill 0.254)
		(layers "F.Cu" "B.Cu")
		(net "GND")
	)
	(via
		(at 114.848132 -31.643828)
		(size 0.508)
		(drill 0.254)
		(layers "F.Cu" "B.Cu")
		(net "GND")
	)
	(via
		(at 71.297546 -3.532632)
		(size 0.508)
		(drill 0.254)
		(layers "F.Cu" "B.Cu")
		(net "GND")
	)
	(via
		(at 43.336718 -67.900804)
		(size 0.508)
		(drill 0.254)
		(layers "F.Cu" "B.Cu")
		(net "GND")
	)
	(via
		(at 130.33756 -118.369334)
		(size 0.508)
		(drill 0.254)
		(layers "F.Cu" "B.Cu")
		(net "GND")
	)
	(via
		(at 39.397686 -142.532862)
		(size 0.508)
		(drill 0.254)
		(layers "F.Cu" "B.Cu")
		(net "GND")
	)
	(via
		(at 116.256308 -120.77192)
		(size 0.508)
		(drill 0.254)
		(layers "F.Cu" "B.Cu")
		(net "GND")
	)
	(via
		(at 49.38776 -186.848242)
		(size 0.508)
		(drill 0.254)
		(layers "F.Cu" "B.Cu")
		(net "GND")
	)
	(via
		(at 127.875792 -137.21969)
		(size 0.508)
		(drill 0.254)
		(layers "F.Cu" "B.Cu")
		(net "GND")
	)
	(via
		(at 146.1897 -117.801136)
		(size 0.508)
		(drill 0.254)
		(layers "F.Cu" "B.Cu")
		(net "GND")
	)
	(via
		(at 74.9808 -81.654142)
		(size 0.508)
		(drill 0.254)
		(layers "F.Cu" "B.Cu")
		(net "GND")
	)
	(via
		(at 164.42436 -99.893882)
		(size 0.508)
		(drill 0.254)
		(layers "F.Cu" "B.Cu")
		(net "GND")
	)
	(via
		(at 47.8028 -170.821604)
		(size 0.508)
		(drill 0.254)
		(layers "F.Cu" "B.Cu")
		(net "GND")
	)
	(via
		(at 145.983452 -149.20595)
		(size 0.508)
		(drill 0.254)
		(layers "F.Cu" "B.Cu")
		(net "GND")
	)
	(via
		(at 150.362158 -81.11744)
		(size 0.508)
		(drill 0.254)
		(layers "F.Cu" "B.Cu")
		(net "GND")
	)
	(via
		(at 63.333376 -141.258036)
		(size 0.49022)
		(drill 0.254)
		(layers "F.Cu" "B.Cu")
		(net "GND")
	)
	(via
		(at 113.306352 -22.265386)
		(size 0.508)
		(drill 0.254)
		(layers "F.Cu" "B.Cu")
		(net "GND")
	)
	(via
		(at 152.621996 -60.90793)
		(size 0.508)
		(drill 0.254)
		(layers "F.Cu" "B.Cu")
		(net "GND")
	)
	(via
		(at 66.53276 -186.913012)
		(size 0.508)
		(drill 0.254)
		(layers "F.Cu" "B.Cu")
		(net "GND")
	)
	(via
		(at 20.53463 -27.142186)
		(size 0.508)
		(drill 0.254)
		(layers "F.Cu" "B.Cu")
		(net "GND")
	)
	(via
		(at 137.779252 -155.885642)
		(size 0.508)
		(drill 0.254)
		(layers "F.Cu" "B.Cu")
		(net "GND")
	)
	(via
		(at 129.81178 -125.31852)
		(size 0.508)
		(drill 0.254)
		(layers "F.Cu" "B.Cu")
		(net "GND")
	)
	(via
		(at 187.6171 -26.76144)
		(size 0.508)
		(drill 0.254)
		(layers "F.Cu" "B.Cu")
		(net "GND")
	)
	(via
		(at 139.173458 -53.89626)
		(size 0.508)
		(drill 0.254)
		(layers "F.Cu" "B.Cu")
		(net "GND")
	)
	(via
		(at 111.79429 -156.415232)
		(size 0.508)
		(drill 0.254)
		(layers "F.Cu" "B.Cu")
		(net "GND")
	)
	(via
		(at 21.98624 -52.286408)
		(size 0.508)
		(drill 0.254)
		(layers "F.Cu" "B.Cu")
		(net "GND")
	)
	(via
		(at 29.399992 -181.93385)
		(size 0.508)
		(drill 0.254)
		(layers "F.Cu" "B.Cu")
		(net "GND")
	)
	(via
		(at 40.122602 -163.395406)
		(size 0.508)
		(drill 0.254)
		(layers "F.Cu" "B.Cu")
		(net "GND")
	)
	(via
		(at 137.015474 -201.034904)
		(size 0.508)
		(drill 0.254)
		(layers "F.Cu" "B.Cu")
		(net "GND")
	)
	(via
		(at 125.558042 -174.667926)
		(size 0.508)
		(drill 0.254)
		(layers "F.Cu" "B.Cu")
		(net "GND")
	)
	(via
		(at 75.007978 -10.48004)
		(size 0.508)
		(drill 0.254)
		(layers "F.Cu" "B.Cu")
		(net "GND")
	)
	(via
		(at 142.724886 -52.677822)
		(size 0.508)
		(drill 0.254)
		(layers "F.Cu" "B.Cu")
		(net "GND")
	)
	(via
		(at 83.67776 -186.896756)
		(size 0.508)
		(drill 0.254)
		(layers "F.Cu" "B.Cu")
		(net "GND")
	)
	(via
		(at 36.014914 -200.32853)
		(size 0.508)
		(drill 0.254)
		(layers "F.Cu" "B.Cu")
		(net "GND")
	)
	(via
		(at 178.052476 -56.227472)
		(size 0.508)
		(drill 0.254)
		(layers "F.Cu" "B.Cu")
		(net "GND")
	)
	(via
		(at 93.015054 -200.145904)
		(size 0.508)
		(drill 0.254)
		(layers "F.Cu" "B.Cu")
		(net "GND")
	)
	(via
		(at 144.289272 -133.427724)
		(size 0.508)
		(drill 0.254)
		(layers "F.Cu" "B.Cu")
		(net "GND")
	)
	(via
		(at 54.155086 -124.168662)
		(size 0.508)
		(drill 0.254)
		(layers "F.Cu" "B.Cu")
		(net "GND")
	)
	(via
		(at 91.991942 -168.942512)
		(size 0.508)
		(drill 0.254)
		(layers "F.Cu" "B.Cu")
		(net "GND")
	)
	(via
		(at 68.941188 -143.658082)
		(size 0.49022)
		(drill 0.254)
		(layers "F.Cu" "B.Cu")
		(net "GND")
	)
	(via
		(at 89.95918 -78.466696)
		(size 0.508)
		(drill 0.254)
		(layers "F.Cu" "B.Cu")
		(net "GND")
	)
	(via
		(at 72.568562 -2.492502)
		(size 0.508)
		(drill 0.254)
		(layers "F.Cu" "B.Cu")
		(net "GND")
	)
	(via
		(at 44.250102 -30.624526)
		(size 0.508)
		(drill 0.254)
		(layers "F.Cu" "B.Cu")
		(net "GND")
	)
	(via
		(at 105.13822 -162.51174)
		(size 0.508)
		(drill 0.254)
		(layers "F.Cu" "B.Cu")
		(net "GND")
	)
	(via
		(at 85.68182 -94.660466)
		(size 0.508)
		(drill 0.254)
		(layers "F.Cu" "B.Cu")
		(net "GND")
	)
	(via
		(at 138.211052 -134.65175)
		(size 0.508)
		(drill 0.254)
		(layers "F.Cu" "B.Cu")
		(net "GND")
	)
	(via
		(at 33.221676 -125.45314)
		(size 0.508)
		(drill 0.254)
		(layers "F.Cu" "B.Cu")
		(net "GND")
	)
	(via
		(at 59.015122 -201.09053)
		(size 0.508)
		(drill 0.254)
		(layers "F.Cu" "B.Cu")
		(net "GND")
	)
	(via
		(at 175.649128 -146.250406)
		(size 0.508)
		(drill 0.254)
		(layers "F.Cu" "B.Cu")
		(net "GND")
	)
	(via
		(at 70.698614 -182.186326)
		(size 0.508)
		(drill 0.254)
		(layers "F.Cu" "B.Cu")
		(net "GND")
	)
	(via
		(at 129.686558 -106.106214)
		(size 0.508)
		(drill 0.254)
		(layers "F.Cu" "B.Cu")
		(net "GND")
	)
	(via
		(at 95.39605 -187.822586)
		(size 0.508)
		(drill 0.254)
		(layers "F.Cu" "B.Cu")
		(net "GND")
	)
	(via
		(at 63.383414 -148.121624)
		(size 0.508)
		(drill 0.254)
		(layers "F.Cu" "B.Cu")
		(net "GND")
	)
	(via
		(at 101.563932 -63.426594)
		(size 0.508)
		(drill 0.254)
		(layers "F.Cu" "B.Cu")
		(net "GND")
	)
	(via
		(at 66.809366 -67.345306)
		(size 0.508)
		(drill 0.254)
		(layers "F.Cu" "B.Cu")
		(net "GND")
	)
	(via
		(at 193.70802 -26.238708)
		(size 0.508)
		(drill 0.254)
		(layers "F.Cu" "B.Cu")
		(net "GND")
	)
	(via
		(at 91.876118 -176.562512)
		(size 0.508)
		(drill 0.254)
		(layers "F.Cu" "B.Cu")
		(net "GND")
	)
	(via
		(at 143.552672 -173.891956)
		(size 0.508)
		(drill 0.254)
		(layers "F.Cu" "B.Cu")
		(net "GND")
	)
	(via
		(at 124.159264 -61.690758)
		(size 0.508)
		(drill 0.254)
		(layers "F.Cu" "B.Cu")
		(net "GND")
	)
	(via
		(at 144.345152 -181.748938)
		(size 0.508)
		(drill 0.254)
		(layers "F.Cu" "B.Cu")
		(net "GND")
	)
	(via
		(at 64.141096 -135.658352)
		(size 0.49022)
		(drill 0.254)
		(layers "F.Cu" "B.Cu")
		(net "GND")
	)
	(segment
		(start 136.633712 -45.738034)
		(end 136.633712 -46.553882)
		(width 0.508)
		(layer "B.Cu")
		(net "GND")
	)
	(segment
		(start 168.08323 -156.093922)
		(end 168.87698 -156.093922)
		(width 0.508)
		(layer "B.Cu")
		(net "GND")
	)
	(segment
		(start 64.532002 -65.41262)
		(end 64.109346 -65.835276)
		(width 0.4572)
		(layer "B.Cu")
		(net "GND")
	)
	(segment
		(start 56.245252 -99.22637)
		(end 56.054498 -99.035616)
		(width 0.4572)
		(layer "B.Cu")
		(net "GND")
	)
	(segment
		(start 128.255014 -54.282594)
		(end 128.255014 -53.456586)
		(width 0.3302)
		(layer "B.Cu")
		(net "GND")
	)
	(segment
		(start 132.93598 -183.929274)
		(end 132.93598 -184.406794)
		(width 0.508)
		(layer "B.Cu")
		(net "GND")
	)
	(segment
		(start 90.01506 -205.199488)
		(end 90.01506 -200.734676)
		(width 0.508)
		(layer "B.Cu")
		(net "GND")
	)
	(segment
		(start 81.89976 -176.969674)
		(end 81.89976 -177.83302)
		(width 0.254)
		(layer "B.Cu")
		(net "GND")
	)
	(segment
		(start 71.10476 -184.729374)
		(end 71.10476 -183.928004)
		(width 0.508)
		(layer "B.Cu")
		(net "GND")
	)
	(segment
		(start 77.142086 -124.295662)
		(end 77.796136 -124.949712)
		(width 0.508)
		(layer "B.Cu")
		(net "GND")
	)
	(segment
		(start 75.415902 -129.789174)
		(end 75.415902 -130.67284)
		(width 0.4572)
		(layer "B.Cu")
		(net "GND")
	)
	(segment
		(start 54.358032 -97.83191)
		(end 54.022498 -97.496376)
		(width 0.4572)
		(layer "B.Cu")
		(net "GND")
	)
	(segment
		(start 76.570078 -129.788666)
		(end 76.572872 -129.785872)
		(width 0.4572)
		(layer "B.Cu")
		(net "GND")
	)
	(segment
		(start 169.57294 -156.768038)
		(end 169.231564 -157.109414)
		(width 0.508)
		(layer "B.Cu")
		(net "GND")
	)
	(segment
		(start 115.42776 -184.805574)
		(end 115.42776 -184.550558)
		(width 0.508)
		(layer "B.Cu")
		(net "GND")
	)
	(segment
		(start 115.19662 -186.997848)
		(end 115.19662 -187.028074)
		(width 0.508)
		(layer "B.Cu")
		(net "GND")
	)
	(segment
		(start 77.54366 -165.14826)
		(end 78.314296 -164.377624)
		(width 0.508)
		(layer "B.Cu")
		(net "GND")
	)
	(segment
		(start 128.912112 -145.23466)
		(end 127.921512 -145.23466)
		(width 0.4572)
		(layer "B.Cu")
		(net "GND")
	)
	(segment
		(start 156.19476 -186.87415)
		(end 156.19476 -187.472574)
		(width 0.508)
		(layer "B.Cu")
		(net "GND")
	)
	(segment
		(start 63.333376 -140.457936)
		(end 63.340996 -140.457936)
		(width 0.3556)
		(layer "B.Cu")
		(net "GND")
	)
	(segment
		(start 18.01495 -205.199488)
		(end 18.01495 -201.09053)
		(width 0.508)
		(layer "B.Cu")
		(net "GND")
	)
	(segment
		(start 64.823086 -66.202306)
		(end 64.753236 -66.272156)
		(width 0.4572)
		(layer "B.Cu")
		(net "GND")
	)
	(segment
		(start 96.015048 -202.70978)
		(end 95.74784 -202.442572)
		(width 0.508)
		(layer "B.Cu")
		(net "GND")
	)
	(segment
		(start 151.62276 -187.472574)
		(end 151.62276 -186.862974)
		(width 0.508)
		(layer "B.Cu")
		(net "GND")
	)
	(segment
		(start 99.300538 -168.028366)
		(end 99.059746 -168.269158)
		(width 0.4572)
		(layer "B.Cu")
		(net "GND")
	)
	(segment
		(start 102.879652 -67.950334)
		(end 103.072184 -68.142866)
		(width 0.508)
		(layer "B.Cu")
		(net "GND")
	)
	(segment
		(start 99.059746 -168.269158)
		(end 99.059746 -168.980612)
		(width 0.4572)
		(layer "B.Cu")
		(net "GND")
	)
	(segment
		(start 51.014884 -205.199488)
		(end 51.014884 -201.09053)
		(width 0.508)
		(layer "B.Cu")
		(net "GND")
	)
	(segment
		(start 70.309486 -119.850662)
		(end 70.309486 -120.032272)
		(width 0.4572)
		(layer "B.Cu")
		(net "GND")
	)
	(segment
		(start 77.07376 -187.726574)
		(end 77.07376 -187.233306)
		(width 0.508)
		(layer "B.Cu")
		(net "GND")
	)
	(segment
		(start 130.79476 -183.936386)
		(end 130.79476 -184.551574)
		(width 0.508)
		(layer "B.Cu")
		(net "GND")
	)
	(segment
		(start 68.15201 -61.718698)
		(end 67.30365 -61.718698)
		(width 0.4572)
		(layer "B.Cu")
		(net "GND")
	)
	(segment
		(start 83.758278 -30.550358)
		(end 83.758278 -29.82214)
		(width 0.4572)
		(layer "B.Cu")
		(net "GND")
	)
	(segment
		(start 154.632914 -186.88685)
		(end 155.05176 -187.305696)
		(width 0.508)
		(layer "B.Cu")
		(net "GND")
	)
	(segment
		(start 177.230786 -121.58599)
		(end 177.230786 -120.774968)
		(width 0.381)
		(layer "B.Cu")
		(net "GND")
	)
	(segment
		(start 36.763452 -150.910798)
		(end 37.512752 -150.910798)
		(width 0.508)
		(layer "B.Cu")
		(net "GND")
	)
	(segment
		(start 124.545852 -143.00835)
		(end 125.466602 -143.00835)
		(width 0.4572)
		(layer "B.Cu")
		(net "GND")
	)
	(segment
		(start 168.03243 -149.542754)
		(end 168.03243 -150.404322)
		(width 0.508)
		(layer "B.Cu")
		(net "GND")
	)
	(segment
		(start 77.796136 -126.454662)
		(end 77.796136 -125.438662)
		(width 0.508)
		(layer "B.Cu")
		(net "GND")
	)
	(segment
		(start 142.84833 -184.037478)
		(end 142.334234 -184.551574)
		(width 0.508)
		(layer "B.Cu")
		(net "GND")
	)
	(segment
		(start 55.41645 -75.445874)
		(end 55.4101 -75.439524)
		(width 0.381)
		(layer "B.Cu")
		(net "GND")
	)
	(segment
		(start 76.05776 -187.38977)
		(end 76.05776 -187.726574)
		(width 0.254)
		(layer "B.Cu")
		(net "GND")
	)
	(segment
		(start 104.367076 -165.851078)
		(end 104.391206 -165.851078)
		(width 0.4572)
		(layer "B.Cu")
		(net "GND")
	)
	(segment
		(start 135.577072 -45.921422)
		(end 135.577072 -46.550326)
		(width 0.508)
		(layer "B.Cu")
		(net "GND")
	)
	(segment
		(start 124.063252 -146.20875)
		(end 125.492002 -146.20875)
		(width 0.4572)
		(layer "B.Cu")
		(net "GND")
	)
	(segment
		(start 72.04964 -63.891668)
		(end 72.395588 -63.54572)
		(width 0.254)
		(layer "B.Cu")
		(net "GND")
	)
	(segment
		(start 121.64187 -167.494204)
		(end 121.034302 -168.101772)
		(width 0.4572)
		(layer "B.Cu")
		(net "GND")
	)
	(segment
		(start 115.30076 -187.132214)
		(end 115.30076 -187.726574)
		(width 0.508)
		(layer "B.Cu")
		(net "GND")
	)
	(segment
		(start 62.200028 -86.20633)
		(end 61.877448 -85.88375)
		(width 0.381)
		(layer "B.Cu")
		(net "GND")
	)
	(segment
		(start 47.151036 -136.882124)
		(end 47.151036 -137.376662)
		(width 0.508)
		(layer "B.Cu")
		(net "GND")
	)
	(segment
		(start 38.622732 -94.80042)
		(end 38.622732 -95.508064)
		(width 0.4572)
		(layer "B.Cu")
		(net "GND")
	)
	(segment
		(start 78.61935 -162.05962)
		(end 78.61935 -162.340544)
		(width 0.508)
		(layer "B.Cu")
		(net "GND")
	)
	(segment
		(start 129.81178 -125.31852)
		(end 129.143252 -124.649992)
		(width 0.508)
		(layer "B.Cu")
		(net "GND")
	)
	(segment
		(start 53.247798 -132.983478)
		(end 53.701442 -132.452618)
		(width 0.4572)
		(layer "B.Cu")
		(net "GND")
	)
	(segment
		(start 47.024036 -130.226562)
		(end 47.024036 -129.883662)
		(width 0.381)
		(layer "B.Cu")
		(net "GND")
	)
	(segment
		(start 39.397686 -142.532862)
		(end 39.448486 -142.583662)
		(width 0.508)
		(layer "B.Cu")
		(net "GND")
	)
	(segment
		(start 98.8949 -180.667152)
		(end 98.8949 -180.241956)
		(width 0.3302)
		(layer "B.Cu")
		(net "GND")
	)
	(segment
		(start 139.227052 -151.6888)
		(end 139.227052 -152.50795)
		(width 0.4572)
		(layer "B.Cu")
		(net "GND")
	)
	(segment
		(start 88.229694 -72.31126)
		(end 88.3793 -72.161654)
		(width 0.4572)
		(layer "B.Cu")
		(net "GND")
	)
	(segment
		(start 77.54366 -165.809422)
		(end 77.54366 -165.14826)
		(width 0.508)
		(layer "B.Cu")
		(net "GND")
	)
	(segment
		(start 64.532002 -64.810132)
		(end 64.532002 -65.41262)
		(width 0.4572)
		(layer "B.Cu")
		(net "GND")
	)
	(segment
		(start 66.581528 -62.44082)
		(end 66.581528 -62.455806)
		(width 0.4572)
		(layer "B.Cu")
		(net "GND")
	)
	(segment
		(start 47.474632 -89.60104)
		(end 48.202596 -88.873076)
		(width 0.381)
		(layer "B.Cu")
		(net "GND")
	)
	(segment
		(start 132.015484 -201.034904)
		(end 132.015484 -205.199488)
		(width 0.508)
		(layer "B.Cu")
		(net "GND")
	)
	(segment
		(start 176.96053 -119.41556)
		(end 176.487582 -119.41556)
		(width 0.4572)
		(layer "B.Cu")
		(net "GND")
	)
	(segment
		(start 55.007256 -134.008368)
		(end 55.592218 -133.423406)
		(width 0.4572)
		(layer "B.Cu")
		(net "GND")
	)
	(segment
		(start 131.784852 -135.4709)
		(end 130.794252 -135.4709)
		(width 0.4572)
		(layer "B.Cu")
		(net "GND")
	)
	(segment
		(start 64.521588 -64.799718)
		(end 64.532002 -64.810132)
		(width 0.4572)
		(layer "B.Cu")
		(net "GND")
	)
	(segment
		(start 77.5208 -165.832282)
		(end 77.54366 -165.809422)
		(width 0.508)
		(layer "B.Cu")
		(net "GND")
	)
	(segment
		(start 89.258648 -76.678282)
		(end 88.30818 -76.678282)
		(width 0.4572)
		(layer "B.Cu")
		(net "GND")
	)
	(segment
		(start 47.737776 -179.871624)
		(end 49.24171 -179.871624)
		(width 0.4572)
		(layer "B.Cu")
		(net "GND")
	)
	(segment
		(start 51.014884 -201.09053)
		(end 51.014884 -200.32853)
		(width 0.508)
		(layer "B.Cu")
		(net "GND")
	)
	(segment
		(start 114.321082 -166.980362)
		(end 113.518188 -166.980362)
		(width 0.508)
		(layer "B.Cu")
		(net "GND")
	)
	(segment
		(start 51.990498 -97.655888)
		(end 51.990498 -97.096834)
		(width 0.4572)
		(layer "B.Cu")
		(net "GND")
	)
	(segment
		(start 75.471274 -94.869254)
		(end 75.471274 -94.531434)
		(width 0.4572)
		(layer "B.Cu")
		(net "GND")
	)
	(segment
		(start 168.665906 -171.85513)
		(end 169.672 -171.85513)
		(width 0.508)
		(layer "B.Cu")
		(net "GND")
	)
	(segment
		(start 60.81776 -187.726574)
		(end 60.81776 -186.97956)
		(width 0.508)
		(layer "B.Cu")
		(net "GND")
	)
	(segment
		(start 144.667986 -177.096674)
		(end 145.14576 -177.096674)
		(width 0.254)
		(layer "B.Cu")
		(net "GND")
	)
	(segment
		(start 124.636022 -144.97558)
		(end 124.878592 -145.21815)
		(width 0.4572)
		(layer "B.Cu")
		(net "GND")
	)
	(segment
		(start 89.660222 -78.765654)
		(end 89.1794 -78.765654)
		(width 0.4572)
		(layer "B.Cu")
		(net "GND")
	)
	(segment
		(start 115.814856 -184.163462)
		(end 116.3447 -184.163462)
		(width 0.508)
		(layer "B.Cu")
		(net "GND")
	)
	(segment
		(start 53.391562 -27.548078)
		(end 52.793392 -28.146248)
		(width 0.4572)
		(layer "B.Cu")
		(net "GND")
	)
	(segment
		(start 133.893052 -134.49935)
		(end 133.893052 -135.3439)
		(width 0.4572)
		(layer "B.Cu")
		(net "GND")
	)
	(segment
		(start 83.467194 -28.923234)
		(end 83.758278 -29.214318)
		(width 0.508)
		(layer "B.Cu")
		(net "GND")
	)
	(segment
		(start 177.51044 -121.865644)
		(end 177.230786 -121.58599)
		(width 0.381)
		(layer "B.Cu")
		(net "GND")
	)
	(segment
		(start 141.633702 -137.24255)
		(end 142.452852 -137.24255)
		(width 0.4572)
		(layer "B.Cu")
		(net "GND")
	)
	(segment
		(start 113.518188 -166.980362)
		(end 113.486946 -167.011604)
		(width 0.508)
		(layer "B.Cu")
		(net "GND")
	)
	(segment
		(start 67.996562 -22.706838)
		(end 67.996562 -24.723598)
		(width 0.508)
		(layer "B.Cu")
		(net "GND")
	)
	(segment
		(start 56.24576 -187.726574)
		(end 56.24576 -186.927236)
		(width 0.508)
		(layer "B.Cu")
		(net "GND")
	)
	(segment
		(start 65.38976 -187.726574)
		(end 65.38976 -186.954414)
		(width 0.508)
		(layer "B.Cu")
		(net "GND")
	)
	(segment
		(start 69.878702 -98.215196)
		(end 69.878702 -98.467926)
		(width 0.381)
		(layer "B.Cu")
		(net "GND")
	)
	(segment
		(start 141.980666 -48.517048)
		(end 141.980666 -46.496478)
		(width 0.508)
		(layer "B.Cu")
		(net "GND")
	)
	(segment
		(start 52.8447 -134.336282)
		(end 52.8447 -133.626098)
		(width 0.4572)
		(layer "B.Cu")
		(net "GND")
	)
	(segment
		(start 107.015534 -201.034904)
		(end 107.015534 -205.199488)
		(width 0.508)
		(layer "B.Cu")
		(net "GND")
	)
	(segment
		(start 57.852818 -89.546938)
		(end 57.852818 -85.425788)
		(width 0.381)
		(layer "B.Cu")
		(net "GND")
	)
	(segment
		(start 39.193978 -128.906778)
		(end 39.008812 -128.721612)
		(width 0.508)
		(layer "B.Cu")
		(net "GND")
	)
	(segment
		(start 29.014928 -205.199488)
		(end 29.014928 -201.09053)
		(width 0.508)
		(layer "B.Cu")
		(net "GND")
	)
	(segment
		(start 71.137018 -62.482476)
		(end 71.137018 -62.910212)
		(width 0.4572)
		(layer "B.Cu")
		(net "GND")
	)
	(segment
		(start 113.53292 -162.261296)
		(end 113.54181 -162.252406)
		(width 0.4572)
		(layer "B.Cu")
		(net "GND")
	)
	(segment
		(start 68.81876 -185.605674)
		(end 68.81876 -186.853068)
		(width 0.508)
		(layer "B.Cu")
		(net "GND")
	)
	(segment
		(start 141.980666 -46.496478)
		(end 141.989302 -46.487842)
		(width 0.508)
		(layer "B.Cu")
		(net "GND")
	)
	(segment
		(start 75.736196 -187.068206)
		(end 76.05776 -187.38977)
		(width 0.254)
		(layer "B.Cu")
		(net "GND")
	)
	(segment
		(start 183.015636 -205.199488)
		(end 183.015636 -201.336656)
		(width 0.508)
		(layer "B.Cu")
		(net "GND")
	)
	(segment
		(start 64.521588 -63.783718)
		(end 64.521588 -64.799718)
		(width 0.4572)
		(layer "B.Cu")
		(net "GND")
	)
	(segment
		(start 56.945022 -126.518162)
		(end 56.930036 -125.730762)
		(width 0.381)
		(layer "B.Cu")
		(net "GND")
	)
	(segment
		(start 138.370056 -36.42741)
		(end 139.075922 -36.42741)
		(width 0.4572)
		(layer "B.Cu")
		(net "GND")
	)
	(segment
		(start 137.58545 -54.8894)
		(end 138.3538 -54.8894)
		(width 0.508)
		(layer "B.Cu")
		(net "GND")
	)
	(segment
		(start 44.014898 -205.199488)
		(end 44.014898 -201.09053)
		(width 0.508)
		(layer "B.Cu")
		(net "GND")
	)
	(segment
		(start 63.143384 -140.655548)
		(end 62.545722 -140.655548)
		(width 0.3556)
		(layer "B.Cu")
		(net "GND")
	)
	(segment
		(start 152.76576 -186.862974)
		(end 152.76576 -187.472574)
		(width 0.508)
		(layer "B.Cu")
		(net "GND")
	)
	(segment
		(start 58.15076 -172.740574)
		(end 56.969406 -172.740574)
		(width 0.3556)
		(layer "B.Cu")
		(net "GND")
	)
	(segment
		(start 74.906886 -148.876512)
		(end 74.004678 -148.876512)
		(width 0.508)
		(layer "B.Cu")
		(net "GND")
	)
	(segment
		(start 90.06332 -75.717654)
		(end 89.1794 -75.717654)
		(width 0.4572)
		(layer "B.Cu")
		(net "GND")
	)
	(segment
		(start 63.340996 -141.258036)
		(end 63.39332 -141.205712)
		(width 0.4572)
		(layer "B.Cu")
		(net "GND")
	)
	(segment
		(start 42.686732 -94.80042)
		(end 42.686732 -95.51289)
		(width 0.4572)
		(layer "B.Cu")
		(net "GND")
	)
	(segment
		(start 127.009652 -141.20495)
		(end 126.965202 -141.1605)
		(width 0.4572)
		(layer "B.Cu")
		(net "GND")
	)
	(segment
		(start 39.146226 -149.41169)
		(end 39.30777 -149.41169)
		(width 0.508)
		(layer "B.Cu")
		(net "GND")
	)
	(segment
		(start 76.507086 -124.168662)
		(end 75.631548 -124.168662)
		(width 0.508)
		(layer "B.Cu")
		(net "GND")
	)
	(segment
		(start 39.008812 -128.721612)
		(end 38.280086 -128.721612)
		(width 0.508)
		(layer "B.Cu")
		(net "GND")
	)
	(segment
		(start 18.01495 -201.09053)
		(end 18.01495 -200.32853)
		(width 0.508)
		(layer "B.Cu")
		(net "GND")
	)
	(segment
		(start 52.81676 -181.59095)
		(end 52.81676 -181.592474)
		(width 0.508)
		(layer "B.Cu")
		(net "GND")
	)
	(segment
		(start 71.703692 -123.218702)
		(end 70.867016 -124.055378)
		(width 0.4572)
		(layer "B.Cu")
		(net "GND")
	)
	(segment
		(start 125.06452 -150.935944)
		(end 123.862846 -150.935944)
		(width 0.508)
		(layer "B.Cu")
		(net "GND")
	)
	(segment
		(start 108.56976 -184.805574)
		(end 107.42676 -184.805574)
		(width 0.508)
		(layer "B.Cu")
		(net "GND")
	)
	(segment
		(start 79.702406 -29.377386)
		(end 79.702406 -28.923234)
		(width 0.508)
		(layer "B.Cu")
		(net "GND")
	)
	(segment
		(start 168.95318 -151.369522)
		(end 168.82618 -151.496522)
		(width 0.508)
		(layer "B.Cu")
		(net "GND")
	)
	(segment
		(start 78.21676 -187.726574)
		(end 78.21676 -187.05703)
		(width 0.508)
		(layer "B.Cu")
		(net "GND")
	)
	(segment
		(start 129.143252 -124.649992)
		(end 129.143252 -124.4854)
		(width 0.508)
		(layer "B.Cu")
		(net "GND")
	)
	(segment
		(start 64.82207 -69.27977)
		(end 64.971676 -69.429376)
		(width 0.4572)
		(layer "B.Cu")
		(net "GND")
	)
	(segment
		(start 185.293 -188.06795)
		(end 185.293 -187.2996)
		(width 0.508)
		(layer "B.Cu")
		(net "GND")
	)
	(segment
		(start 136.255252 -152.50795)
		(end 136.255252 -151.6888)
		(width 0.4572)
		(layer "B.Cu")
		(net "GND")
	)
	(segment
		(start 149.20468 -168.612312)
		(end 148.565362 -168.612312)
		(width 0.508)
		(layer "B.Cu")
		(net "GND")
	)
	(segment
		(start 101.577394 -167.97655)
		(end 102.403656 -168.802812)
		(width 0.4572)
		(layer "B.Cu")
		(net "GND")
	)
	(segment
		(start 45.232828 -136.564116)
		(end 44.776136 -137.020808)
		(width 0.381)
		(layer "B.Cu")
		(net "GND")
	)
	(segment
		(start 91.502484 -187.842398)
		(end 92.243148 -187.842398)
		(width 0.508)
		(layer "B.Cu")
		(net "GND")
	)
	(segment
		(start 56.28386 -22.130004)
		(end 56.28386 -21.495766)
		(width 0.508)
		(layer "B.Cu")
		(net "GND")
	)
	(segment
		(start 64.7954 -143.802862)
		(end 64.322706 -143.802862)
		(width 0.508)
		(layer "B.Cu")
		(net "GND")
	)
	(segment
		(start 59.333892 -84.126578)
		(end 59.678062 -84.470748)
		(width 0.3048)
		(layer "B.Cu")
		(net "GND")
	)
	(segment
		(start 51.67376 -187.726574)
		(end 51.67376 -186.862974)
		(width 0.508)
		(layer "B.Cu")
		(net "GND")
	)
	(segment
		(start 36.590732 -94.80042)
		(end 36.590732 -95.51035)
		(width 0.4572)
		(layer "B.Cu")
		(net "GND")
	)
	(segment
		(start 166.688516 -173.552358)
		(end 166.82085 -173.684692)
		(width 0.508)
		(layer "B.Cu")
		(net "GND")
	)
	(segment
		(start 55.10276 -185.605674)
		(end 55.10276 -186.960002)
		(width 0.508)
		(layer "B.Cu")
		(net "GND")
	)
	(segment
		(start 63.333376 -141.258036)
		(end 63.340996 -141.258036)
		(width 0.4572)
		(layer "B.Cu")
		(net "GND")
	)
	(segment
		(start 61.877448 -85.88375)
		(end 61.877448 -85.45449)
		(width 0.381)
		(layer "B.Cu")
		(net "GND")
	)
	(segment
		(start 46.112684 -134.084314)
		(end 46.112684 -133.130798)
		(width 0.381)
		(layer "B.Cu")
		(net "GND")
	)
	(segment
		(start 117.45976 -187.726574)
		(end 117.45976 -186.864498)
		(width 0.508)
		(layer "B.Cu")
		(net "GND")
	)
	(segment
		(start 103.072184 -68.142866)
		(end 103.906574 -68.142866)
		(width 0.508)
		(layer "B.Cu")
		(net "GND")
	)
	(segment
		(start 57.161938 -67.978274)
		(end 57.099454 -67.978274)
		(width 0.4572)
		(layer "B.Cu")
		(net "GND")
	)
	(segment
		(start 47.95393 -178.693064)
		(end 47.95393 -178.291744)
		(width 0.508)
		(layer "B.Cu")
		(net "GND")
	)
	(segment
		(start 93.015054 -200.907904)
		(end 93.015054 -200.145904)
		(width 0.508)
		(layer "B.Cu")
		(net "GND")
	)
	(segment
		(start 103.906574 -68.142866)
		(end 104.008174 -68.244466)
		(width 0.508)
		(layer "B.Cu")
		(net "GND")
	)
	(segment
		(start 89.338912 -166.08044)
		(end 89.114884 -166.304468)
		(width 0.254)
		(layer "B.Cu")
		(net "GND")
	)
	(segment
		(start 63.10376 -187.726574)
		(end 63.10376 -186.985402)
		(width 0.508)
		(layer "B.Cu")
		(net "GND")
	)
	(segment
		(start 117.015514 -205.199488)
		(end 117.015514 -201.034904)
		(width 0.508)
		(layer "B.Cu")
		(net "GND")
	)
	(segment
		(start 157.33014 -187.464954)
		(end 157.33776 -187.472574)
		(width 0.508)
		(layer "B.Cu")
		(net "GND")
	)
	(segment
		(start 38.5826 -149.975316)
		(end 39.146226 -149.41169)
		(width 0.508)
		(layer "B.Cu")
		(net "GND")
	)
	(segment
		(start 140.135102 -144.3609)
		(end 141.005052 -144.3609)
		(width 0.4572)
		(layer "B.Cu")
		(net "GND")
	)
	(segment
		(start 51.222402 -181.021482)
		(end 51.67376 -181.47284)
		(width 0.508)
		(layer "B.Cu")
		(net "GND")
	)
	(segment
		(start 76.541376 -161.71545)
		(end 78.27518 -161.71545)
		(width 0.508)
		(layer "B.Cu")
		(net "GND")
	)
	(segment
		(start 124.627132 -147.07235)
		(end 125.365002 -147.07235)
		(width 0.4572)
		(layer "B.Cu")
		(net "GND")
	)
	(segment
		(start 94.270576 -29.925518)
		(end 95.340932 -29.925518)
		(width 0.508)
		(layer "B.Cu")
		(net "GND")
	)
	(segment
		(start 93.834712 -184.815988)
		(end 93.834712 -184.192672)
		(width 0.508)
		(layer "B.Cu")
		(net "GND")
	)
	(segment
		(start 65.898776 -89.989914)
		(end 66.1289 -90.220038)
		(width 0.4572)
		(layer "B.Cu")
		(net "GND")
	)
	(segment
		(start 47.849282 -141.45133)
		(end 47.996348 -141.304264)
		(width 0.4572)
		(layer "B.Cu")
		(net "GND")
	)
	(segment
		(start 61.9506 -184.064148)
		(end 61.9506 -184.795414)
		(width 0.508)
		(layer "B.Cu")
		(net "GND")
	)
	(segment
		(start 63.946024 -87.145114)
		(end 63.936118 -86.64575)
		(width 0.4572)
		(layer "B.Cu")
		(net "GND")
	)
	(segment
		(start 68.48348 -61.78296)
		(end 68.216272 -61.78296)
		(width 0.4572)
		(layer "B.Cu")
		(net "GND")
	)
	(segment
		(start 186.01563 -201.617326)
		(end 186.01563 -205.199488)
		(width 0.508)
		(layer "B.Cu")
		(net "GND")
	)
	(segment
		(start 57.511442 -68.327778)
		(end 57.161938 -67.978274)
		(width 0.4572)
		(layer "B.Cu")
		(net "GND")
	)
	(segment
		(start 130.79222 -135.233918)
		(end 130.794252 -135.23595)
		(width 0.4572)
		(layer "B.Cu")
		(net "GND")
	)
	(segment
		(start 102.403656 -168.802812)
		(end 102.613206 -168.802812)
		(width 0.4572)
		(layer "B.Cu")
		(net "GND")
	)
	(segment
		(start 79.702406 -28.923234)
		(end 83.467194 -28.923234)
		(width 0.508)
		(layer "B.Cu")
		(net "GND")
	)
	(segment
		(start 87.705438 -72.351646)
		(end 87.745824 -72.31126)
		(width 0.4572)
		(layer "B.Cu")
		(net "GND")
	)
	(segment
		(start 112.41532 -60.060586)
		(end 110.604554 -61.871352)
		(width 0.508)
		(layer "B.Cu")
		(net "GND")
	)
	(segment
		(start 113.53292 -162.248596)
		(end 113.53292 -162.261296)
		(width 0.4572)
		(layer "B.Cu")
		(net "GND")
	)
	(segment
		(start 63.601346 -72.198992)
		(end 63.640462 -72.238108)
		(width 0.381)
		(layer "B.Cu")
		(net "GND")
	)
	(segment
		(start 115.42776 -184.550558)
		(end 115.814856 -184.163462)
		(width 0.508)
		(layer "B.Cu")
		(net "GND")
	)
	(segment
		(start 74.60615 -33.073086)
		(end 74.643742 -33.110678)
		(width 0.508)
		(layer "B.Cu")
		(net "GND")
	)
	(segment
		(start 132.93598 -184.406794)
		(end 133.08076 -184.551574)
		(width 0.508)
		(layer "B.Cu")
		(net "GND")
	)
	(segment
		(start 132.03682 -161.204402)
		(end 132.037328 -161.204402)
		(width 0.508)
		(layer "B.Cu")
		(net "GND")
	)
	(segment
		(start 47.700692 -178.946302)
		(end 47.95393 -178.693064)
		(width 0.508)
		(layer "B.Cu")
		(net "GND")
	)
	(segment
		(start 51.222402 -181.024276)
		(end 51.222402 -181.021482)
		(width 0.508)
		(layer "B.Cu")
		(net "GND")
	)
	(segment
		(start 136.255252 -151.6888)
		(end 137.245852 -151.6888)
		(width 0.4572)
		(layer "B.Cu")
		(net "GND")
	)
	(segment
		(start 138.236452 -152.43175)
		(end 138.236452 -151.6888)
		(width 0.4572)
		(layer "B.Cu")
		(net "GND")
	)
	(segment
		(start 91.21267 -168.942512)
		(end 91.21267 -169.958512)
		(width 0.4572)
		(layer "B.Cu")
		(net "GND")
	)
	(segment
		(start 75.631548 -124.168662)
		(end 75.37069 -123.907804)
		(width 0.508)
		(layer "B.Cu")
		(net "GND")
	)
	(segment
		(start 106.988102 -173.118526)
		(end 106.988102 -172.499782)
		(width 0.508)
		(layer "B.Cu")
		(net "GND")
	)
	(segment
		(start 57.573672 -129.259076)
		(end 57.030366 -129.802382)
		(width 0.381)
		(layer "B.Cu")
		(net "GND")
	)
	(segment
		(start 131.988052 -151.6888)
		(end 131.988052 -152.50795)
		(width 0.4572)
		(layer "B.Cu")
		(net "GND")
	)
	(segment
		(start 133.893052 -135.3439)
		(end 133.766052 -135.4709)
		(width 0.4572)
		(layer "B.Cu")
		(net "GND")
	)
	(segment
		(start 72.186546 -26.951686)
		(end 73.04913 -26.951686)
		(width 0.508)
		(layer "B.Cu")
		(net "GND")
	)
	(segment
		(start 46.96206 -132.093462)
		(end 46.681136 -132.093462)
		(width 0.381)
		(layer "B.Cu")
		(net "GND")
	)
	(segment
		(start 47.10176 -181.592474)
		(end 47.10176 -180.974746)
		(width 0.508)
		(layer "B.Cu")
		(net "GND")
	)
	(segment
		(start 93.015054 -205.199488)
		(end 93.015054 -200.907904)
		(width 0.508)
		(layer "B.Cu")
		(net "GND")
	)
	(segment
		(start 74.60615 -31.72714)
		(end 74.60615 -33.073086)
		(width 0.508)
		(layer "B.Cu")
		(net "GND")
	)
	(segment
		(start 119.49176 -187.294774)
		(end 119.49176 -187.726574)
		(width 0.508)
		(layer "B.Cu")
		(net "GND")
	)
	(segment
		(start 67.996562 -24.723598)
		(end 68.48475 -25.211786)
		(width 0.508)
		(layer "B.Cu")
		(net "GND")
	)
	(segment
		(start 56.015128 -205.199488)
		(end 56.015128 -201.09053)
		(width 0.508)
		(layer "B.Cu")
		(net "GND")
	)
	(segment
		(start 135.584438 -45.914056)
		(end 135.577072 -45.921422)
		(width 0.508)
		(layer "B.Cu")
		(net "GND")
	)
	(segment
		(start 51.74488 -84.064094)
		(end 51.02987 -84.779104)
		(width 0.254)
		(layer "B.Cu")
		(net "GND")
	)
	(segment
		(start 137.015474 -201.034904)
		(end 137.015474 -205.199488)
		(width 0.508)
		(layer "B.Cu")
		(net "GND")
	)
	(segment
		(start 145.65376 -187.599574)
		(end 145.65376 -186.862974)
		(width 0.508)
		(layer "B.Cu")
		(net "GND")
	)
	(segment
		(start 95.74784 -201.06132)
		(end 95.74784 -200.29932)
		(width 0.508)
		(layer "B.Cu")
		(net "GND")
	)
	(segment
		(start 131.693158 -35.915854)
		(end 131.493006 -36.116006)
		(width 0.4572)
		(layer "B.Cu")
		(net "GND")
	)
	(segment
		(start 89.95918 -78.466696)
		(end 89.660222 -78.765654)
		(width 0.4572)
		(layer "B.Cu")
		(net "GND")
	)
	(segment
		(start 109.792262 -173.521624)
		(end 110.04931 -173.521624)
		(width 0.508)
		(layer "B.Cu")
		(net "GND")
	)
	(segment
		(start 79.23276 -187.726574)
		(end 79.23276 -187.028074)
		(width 0.508)
		(layer "B.Cu")
		(net "GND")
	)
	(segment
		(start 53.345842 -181.061868)
		(end 52.81676 -181.59095)
		(width 0.508)
		(layer "B.Cu")
		(net "GND")
	)
	(segment
		(start 62.200028 -86.463124)
		(end 62.200028 -86.20633)
		(width 0.381)
		(layer "B.Cu")
		(net "GND")
	)
	(segment
		(start 137.65276 -187.472574)
		(end 137.65276 -186.862974)
		(width 0.508)
		(layer "B.Cu")
		(net "GND")
	)
	(segment
		(start 135.798052 -137.11555)
		(end 135.747252 -137.06475)
		(width 0.4572)
		(layer "B.Cu")
		(net "GND")
	)
	(segment
		(start 101.937566 -167.151812)
		(end 100.82276 -167.151812)
		(width 0.4572)
		(layer "B.Cu")
		(net "GND")
	)
	(segment
		(start 68.344034 -124.530612)
		(end 68.633086 -124.530612)
		(width 0.508)
		(layer "B.Cu")
		(net "GND")
	)
	(segment
		(start 144.32661 -178.395122)
		(end 144.32661 -177.43805)
		(width 0.254)
		(layer "B.Cu")
		(net "GND")
	)
	(segment
		(start 55.4101 -75.439524)
		(end 55.4101 -74.444352)
		(width 0.381)
		(layer "B.Cu")
		(net "GND")
	)
	(segment
		(start 52.81676 -186.862974)
		(end 52.81676 -187.726574)
		(width 0.508)
		(layer "B.Cu")
		(net "GND")
	)
	(segment
		(start 166.27983 -158.608522)
		(end 166.27983 -159.274256)
		(width 0.508)
		(layer "B.Cu")
		(net "GND")
	)
	(segment
		(start 93.834712 -184.192672)
		(end 93.442028 -183.799988)
		(width 0.508)
		(layer "B.Cu")
		(net "GND")
	)
	(segment
		(start 113.01476 -187.726574)
		(end 113.01476 -187.116974)
		(width 0.508)
		(layer "B.Cu")
		(net "GND")
	)
	(segment
		(start 130.137916 -150.06955)
		(end 130.114802 -150.092664)
		(width 0.4572)
		(layer "B.Cu")
		(net "GND")
	)
	(segment
		(start 49.059592 -28.217368)
		(end 49.059592 -28.696158)
		(width 0.4572)
		(layer "B.Cu")
		(net "GND")
	)
	(segment
		(start 61.015118 -201.09053)
		(end 61.015118 -200.32853)
		(width 0.508)
		(layer "B.Cu")
		(net "GND")
	)
	(segment
		(start 135.36676 -184.19826)
		(end 135.36676 -184.551574)
		(width 0.508)
		(layer "B.Cu")
		(net "GND")
	)
	(segment
		(start 138.541252 -134.98195)
		(end 138.541252 -135.4455)
		(width 0.4572)
		(layer "B.Cu")
		(net "GND")
	)
	(segment
		(start 123.799092 -146.47291)
		(end 124.063252 -146.20875)
		(width 0.4572)
		(layer "B.Cu")
		(net "GND")
	)
	(segment
		(start 62.001146 -72.198992)
		(end 62.169802 -72.367648)
		(width 0.4064)
		(layer "B.Cu")
		(net "GND")
	)
	(segment
		(start 44.776136 -137.020808)
		(end 44.692316 -137.070338)
		(width 0.381)
		(layer "B.Cu")
		(net "GND")
	)
	(segment
		(start 164.611558 -182.035196)
		(end 164.611558 -181.246526)
		(width 0.508)
		(layer "B.Cu")
		(net "GND")
	)
	(segment
		(start 130.921252 -36.110926)
		(end 130.926332 -36.116006)
		(width 0.4572)
		(layer "B.Cu")
		(net "GND")
	)
	(segment
		(start 98.8949 -180.241956)
		(end 98.797618 -180.144674)
		(width 0.3302)
		(layer "B.Cu")
		(net "GND")
	)
	(segment
		(start 74.02576 -187.726574)
		(end 74.02576 -187.026804)
		(width 0.508)
		(layer "B.Cu")
		(net "GND")
	)
	(segment
		(start 130.83794 -134.31139)
		(end 130.79222 -134.35711)
		(width 0.4572)
		(layer "B.Cu")
		(net "GND")
	)
	(segment
		(start 154.46121 -171.489624)
		(end 155.105354 -171.489624)
		(width 0.508)
		(layer "B.Cu")
		(net "GND")
	)
	(segment
		(start 155.015692 -201.034904)
		(end 155.015692 -205.199488)
		(width 0.508)
		(layer "B.Cu")
		(net "GND")
	)
	(segment
		(start 88.3793 -71.145654)
		(end 88.3793 -72.161654)
		(width 0.4572)
		(layer "B.Cu")
		(net "GND")
	)
	(segment
		(start 124.508006 -172.378624)
		(end 124.762006 -172.632624)
		(width 0.508)
		(layer "B.Cu")
		(net "GND")
	)
	(segment
		(start 50.974498 -97.096834)
		(end 51.990498 -97.096834)
		(width 0.4572)
		(layer "B.Cu")
		(net "GND")
	)
	(segment
		(start 51.69408 -83.304126)
		(end 51.74488 -84.064094)
		(width 0.254)
		(layer "B.Cu")
		(net "GND")
	)
	(segment
		(start 112.015524 -201.034904)
		(end 112.015524 -205.199488)
		(width 0.508)
		(layer "B.Cu")
		(net "GND")
	)
	(segment
		(start 57.38876 -184.805574)
		(end 57.38876 -183.911494)
		(width 0.508)
		(layer "B.Cu")
		(net "GND")
	)
	(segment
		(start 146.79676 -184.551574)
		(end 146.79676 -183.928258)
		(width 0.508)
		(layer "B.Cu")
		(net "GND")
	)
	(segment
		(start 137.550652 -136.98855)
		(end 137.550652 -136.2456)
		(width 0.4572)
		(layer "B.Cu")
		(net "GND")
	)
	(segment
		(start 62.384686 -131.364228)
		(end 61.944504 -130.924046)
		(width 0.3556)
		(layer "B.Cu")
		(net "GND")
	)
	(segment
		(start 48.24476 -187.726574)
		(end 48.24476 -186.862974)
		(width 0.508)
		(layer "B.Cu")
		(net "GND")
	)
	(segment
		(start 122.015504 -201.034904)
		(end 122.015504 -205.199488)
		(width 0.508)
		(layer "B.Cu")
		(net "GND")
	)
	(segment
		(start 127.035052 -137.97915)
		(end 126.876302 -138.1379)
		(width 0.4572)
		(layer "B.Cu")
		(net "GND")
	)
	(segment
		(start 144.51076 -184.551574)
		(end 144.51076 -183.91886)
		(width 0.508)
		(layer "B.Cu")
		(net "GND")
	)
	(segment
		(start 89.281 -76.65593)
		(end 89.258648 -76.678282)
		(width 0.4572)
		(layer "B.Cu")
		(net "GND")
	)
	(segment
		(start 87.11057 -74.046842)
		(end 87.471758 -73.685654)
		(width 0.4572)
		(layer "B.Cu")
		(net "GND")
	)
	(segment
		(start 64.109346 -66.272156)
		(end 64.109346 -66.588132)
		(width 0.4572)
		(layer "B.Cu")
		(net "GND")
	)
	(segment
		(start 180.015642 -205.199488)
		(end 180.015642 -200.937368)
		(width 0.508)
		(layer "B.Cu")
		(net "GND")
	)
	(segment
		(start 66.777362 -28.994608)
		(end 66.094102 -29.677868)
		(width 0.4572)
		(layer "B.Cu")
		(net "GND")
	)
	(segment
		(start 37.50437 -151.92629)
		(end 36.75634 -151.92629)
		(width 0.508)
		(layer "B.Cu")
		(net "GND")
	)
	(segment
		(start 157.722824 -177.13833)
		(end 156.523944 -177.13833)
		(width 0.508)
		(layer "B.Cu")
		(net "GND")
	)
	(segment
		(start 44.718732 -94.80042)
		(end 44.718732 -95.648272)
		(width 0.4572)
		(layer "B.Cu")
		(net "GND")
	)
	(segment
		(start 186.55284 -201.080116)
		(end 186.55284 -200.318116)
		(width 0.508)
		(layer "B.Cu")
		(net "GND")
	)
	(segment
		(start 24.014938 -201.09053)
		(end 24.014938 -200.32853)
		(width 0.508)
		(layer "B.Cu")
		(net "GND")
	)
	(segment
		(start 134.158482 -41.439084)
		(end 134.796784 -41.439084)
		(width 0.4572)
		(layer "B.Cu")
		(net "GND")
	)
	(segment
		(start 64.753236 -66.272156)
		(end 64.109346 -66.272156)
		(width 0.4572)
		(layer "B.Cu")
		(net "GND")
	)
	(segment
		(start 37.52469 -146.58467)
		(end 37.115496 -146.58467)
		(width 0.508)
		(layer "B.Cu")
		(net "GND")
	)
	(segment
		(start 161.01568 -201.034904)
		(end 161.01568 -205.199488)
		(width 0.508)
		(layer "B.Cu")
		(net "GND")
	)
	(segment
		(start 110.72876 -187.052712)
		(end 110.60176 -186.925712)
		(width 0.508)
		(layer "B.Cu")
		(net "GND")
	)
	(segment
		(start 55.592218 -133.423406)
		(end 55.592218 -133.156452)
		(width 0.4572)
		(layer "B.Cu")
		(net "GND")
	)
	(segment
		(start 110.85576 -184.805574)
		(end 110.85576 -184.07634)
		(width 0.508)
		(layer "B.Cu")
		(net "GND")
	)
	(segment
		(start 134.683246 -39.407084)
		(end 133.946646 -38.670484)
		(width 0.4572)
		(layer "B.Cu")
		(net "GND")
	)
	(segment
		(start 110.604554 -61.871352)
		(end 110.604554 -63.98895)
		(width 0.508)
		(layer "B.Cu")
		(net "GND")
	)
	(segment
		(start 139.252452 -139.1793)
		(end 138.534902 -139.1793)
		(width 0.4572)
		(layer "B.Cu")
		(net "GND")
	)
	(segment
		(start 183.015636 -201.336656)
		(end 183.33466 -201.017632)
		(width 0.508)
		(layer "B.Cu")
		(net "GND")
	)
	(segment
		(start 142.452852 -138.23315)
		(end 141.633702 -138.23315)
		(width 0.4572)
		(layer "B.Cu")
		(net "GND")
	)
	(segment
		(start 168.058338 -152.901904)
		(end 168.809162 -152.901904)
		(width 0.508)
		(layer "B.Cu")
		(net "GND")
	)
	(segment
		(start 116.570252 -165.616128)
		(end 116.570252 -165.620192)
		(width 0.4572)
		(layer "B.Cu")
		(net "GND")
	)
	(segment
		(start 67.298062 -28.994608)
		(end 68.314062 -28.994608)
		(width 0.4572)
		(layer "B.Cu")
		(net "GND")
	)
	(segment
		(start 158.48584 -186.725814)
		(end 158.48076 -186.730894)
		(width 0.508)
		(layer "B.Cu")
		(net "GND")
	)
	(segment
		(start 138.338052 -152.53335)
		(end 138.236452 -152.43175)
		(width 0.4572)
		(layer "B.Cu")
		(net "GND")
	)
	(segment
		(start 93.36024 -30.689042)
		(end 93.507052 -30.689042)
		(width 0.508)
		(layer "B.Cu")
		(net "GND")
	)
	(segment
		(start 131.493006 -36.116006)
		(end 130.926332 -36.116006)
		(width 0.4572)
		(layer "B.Cu")
		(net "GND")
	)
	(segment
		(start 128.255014 -53.456586)
		(end 127.681228 -52.8828)
		(width 0.3302)
		(layer "B.Cu")
		(net "GND")
	)
	(segment
		(start 158.48076 -184.551574)
		(end 158.48076 -183.769762)
		(width 0.508)
		(layer "B.Cu")
		(net "GND")
	)
	(segment
		(start 64.24676 -187.726574)
		(end 64.24676 -187.024772)
		(width 0.508)
		(layer "B.Cu")
		(net "GND")
	)
	(segment
		(start 119.818912 -164.768022)
		(end 120.061482 -165.010592)
		(width 0.4572)
		(layer "B.Cu")
		(net "GND")
	)
	(segment
		(start 185.293 -186.58205)
		(end 185.293 -187.2996)
		(width 0.508)
		(layer "B.Cu")
		(net "GND")
	)
	(segment
		(start 153.908252 -187.101734)
		(end 153.90876 -187.102242)
		(width 0.508)
		(layer "B.Cu")
		(net "GND")
	)
	(segment
		(start 133.946646 -38.670484)
		(end 134.226046 -38.391084)
		(width 0.4572)
		(layer "B.Cu")
		(net "GND")
	)
	(segment
		(start 66.1289 -90.220038)
		(end 66.1289 -92.414598)
		(width 0.4572)
		(layer "B.Cu")
		(net "GND")
	)
	(segment
		(start 66.57975 -62.457584)
		(end 65.598802 -62.457584)
		(width 0.4572)
		(layer "B.Cu")
		(net "GND")
	)
	(segment
		(start 64.109346 -65.835276)
		(end 64.109346 -66.272156)
		(width 0.4572)
		(layer "B.Cu")
		(net "GND")
	)
	(segment
		(start 129.625852 -141.45895)
		(end 130.514852 -141.45895)
		(width 0.4572)
		(layer "B.Cu")
		(net "GND")
	)
	(segment
		(start 166.79164 -186.999372)
		(end 166.79164 -187.79744)
		(width 0.508)
		(layer "B.Cu")
		(net "GND")
	)
	(segment
		(start 78.314296 -164.377624)
		(end 78.43139 -164.377624)
		(width 0.508)
		(layer "B.Cu")
		(net "GND")
	)
	(segment
		(start 140.065252 -142.55115)
		(end 140.947902 -142.55115)
		(width 0.4572)
		(layer "B.Cu")
		(net "GND")
	)
	(segment
		(start 49.820576 -181.000908)
		(end 49.38776 -181.433724)
		(width 0.508)
		(layer "B.Cu")
		(net "GND")
	)
	(segment
		(start 113.14176 -184.805574)
		(end 113.14176 -184.55132)
		(width 0.508)
		(layer "B.Cu")
		(net "GND")
	)
	(segment
		(start 69.96176 -187.726574)
		(end 69.96176 -186.849004)
		(width 0.508)
		(layer "B.Cu")
		(net "GND")
	)
	(segment
		(start 127.015494 -201.034904)
		(end 127.015494 -205.199488)
		(width 0.508)
		(layer "B.Cu")
		(net "GND")
	)
	(segment
		(start 47.349918 -131.705604)
		(end 46.96206 -132.093462)
		(width 0.381)
		(layer "B.Cu")
		(net "GND")
	)
	(segment
		(start 73.31202 -184.225438)
		(end 73.46696 -184.070498)
		(width 0.381)
		(layer "B.Cu")
		(net "GND")
	)
	(segment
		(start 46.96968 -129.191004)
		(end 46.897036 -129.11836)
		(width 0.381)
		(layer "B.Cu")
		(net "GND")
	)
	(segment
		(start 135.967724 -45.072046)
		(end 136.633712 -45.738034)
		(width 0.508)
		(layer "B.Cu")
		(net "GND")
	)
	(segment
		(start 130.794252 -135.23595)
		(end 130.794252 -135.4709)
		(width 0.4572)
		(layer "B.Cu")
		(net "GND")
	)
	(segment
		(start 134.796784 -39.407084)
		(end 134.683246 -39.407084)
		(width 0.4572)
		(layer "B.Cu")
		(net "GND")
	)
	(segment
		(start 64.971676 -69.429376)
		(end 65.001648 -69.429376)
		(width 0.4572)
		(layer "B.Cu")
		(net "GND")
	)
	(segment
		(start 135.504682 -45.072046)
		(end 135.967724 -45.072046)
		(width 0.508)
		(layer "B.Cu")
		(net "GND")
	)
	(segment
		(start 87.471758 -73.685654)
		(end 88.3793 -73.685654)
		(width 0.4572)
		(layer "B.Cu")
		(net "GND")
	)
	(segment
		(start 81.784698 -136.157208)
		(end 81.017872 -136.157208)
		(width 0.4572)
		(layer "B.Cu")
		(net "GND")
	)
	(segment
		(start 124.444252 -143.10995)
		(end 124.545852 -143.00835)
		(width 0.4572)
		(layer "B.Cu")
		(net "GND")
	)
	(segment
		(start 61.720222 -129.91211)
		(end 61.720222 -130.917696)
		(width 0.3556)
		(layer "B.Cu")
		(net "GND")
	)
	(segment
		(start 76.572872 -129.785872)
		(end 77.649832 -129.785872)
		(width 0.4572)
		(layer "B.Cu")
		(net "GND")
	)
	(segment
		(start 78.61554 -87.408258)
		(end 79.066136 -86.957662)
		(width 0.508)
		(layer "B.Cu")
		(net "GND")
	)
	(segment
		(start 139.938252 -149.18055)
		(end 139.957302 -149.1996)
		(width 0.4572)
		(layer "B.Cu")
		(net "GND")
	)
	(segment
		(start 57.099454 -67.978274)
		(end 56.9468 -67.82562)
		(width 0.4572)
		(layer "B.Cu")
		(net "GND")
	)
	(segment
		(start 55.950104 -22.46376)
		(end 56.28386 -22.130004)
		(width 0.508)
		(layer "B.Cu")
		(net "GND")
	)
	(segment
		(start 49.32299 -89.17813)
		(end 49.32299 -88.895936)
		(width 0.381)
		(layer "B.Cu")
		(net "GND")
	)
	(segment
		(start 127.492252 -136.83615)
		(end 127.492252 -136.44372)
		(width 0.4572)
		(layer "B.Cu")
		(net "GND")
	)
	(segment
		(start 93.442028 -183.799988)
		(end 93.09354 -183.799988)
		(width 0.508)
		(layer "B.Cu")
		(net "GND")
	)
	(segment
		(start 104.252776 -165.965378)
		(end 104.367076 -165.851078)
		(width 0.4572)
		(layer "B.Cu")
		(net "GND")
	)
	(segment
		(start 57.65673 -68.327778)
		(end 57.511442 -68.327778)
		(width 0.4572)
		(layer "B.Cu")
		(net "GND")
	)
	(segment
		(start 147.015708 -201.034904)
		(end 147.015708 -205.199488)
		(width 0.508)
		(layer "B.Cu")
		(net "GND")
	)
	(segment
		(start 109.441742 -173.872144)
		(end 109.792262 -173.521624)
		(width 0.508)
		(layer "B.Cu")
		(net "GND")
	)
	(segment
		(start 50.53076 -181.592474)
		(end 50.53076 -180.974746)
		(width 0.508)
		(layer "B.Cu")
		(net "GND")
	)
	(segment
		(start 67.298062 -28.994608)
		(end 66.777362 -28.994608)
		(width 0.4572)
		(layer "B.Cu")
		(net "GND")
	)
	(segment
		(start 132.578602 -137.92835)
		(end 131.937252 -137.92835)
		(width 0.4572)
		(layer "B.Cu")
		(net "GND")
	)
	(segment
		(start 106.28376 -187.726574)
		(end 106.28376 -186.92622)
		(width 0.508)
		(layer "B.Cu")
		(net "GND")
	)
	(segment
		(start 75.96886 -161.142934)
		(end 76.541376 -161.71545)
		(width 0.508)
		(layer "B.Cu")
		(net "GND")
	)
	(segment
		(start 143.367252 -186.906662)
		(end 143.36776 -186.906662)
		(width 0.508)
		(layer "B.Cu")
		(net "GND")
	)
	(segment
		(start 46.750732 -94.80042)
		(end 46.750732 -95.625666)
		(width 0.4572)
		(layer "B.Cu")
		(net "GND")
	)
	(segment
		(start 40.654732 -94.80042)
		(end 40.654732 -95.457772)
		(width 0.4572)
		(layer "B.Cu")
		(net "GND")
	)
	(segment
		(start 169.231564 -157.109414)
		(end 168.074848 -157.109414)
		(width 0.508)
		(layer "B.Cu")
		(net "GND")
	)
	(segment
		(start 118.47576 -187.726574)
		(end 118.47576 -186.940698)
		(width 0.381)
		(layer "B.Cu")
		(net "GND")
	)
	(segment
		(start 36.014914 -201.09053)
		(end 36.014914 -200.32853)
		(width 0.508)
		(layer "B.Cu")
		(net "GND")
	)
	(segment
		(start 65.580006 -70.007734)
		(end 66.076322 -70.007734)
		(width 0.4572)
		(layer "B.Cu")
		(net "GND")
	)
	(segment
		(start 136.576308 -186.858148)
		(end 136.50976 -186.924696)
		(width 0.508)
		(layer "B.Cu")
		(net "GND")
	)
	(segment
		(start 87.394542 -31.596838)
		(end 86.378542 -31.596838)
		(width 0.4572)
		(layer "B.Cu")
		(net "GND")
	)
	(segment
		(start 68.006214 -124.868432)
		(end 68.344034 -124.530612)
		(width 0.508)
		(layer "B.Cu")
		(net "GND")
	)
	(segment
		(start 131.634992 -34.973768)
		(end 130.921252 -34.973768)
		(width 0.4572)
		(layer "B.Cu")
		(net "GND")
	)
	(segment
		(start 69.649086 -124.530612)
		(end 68.633086 -124.530612)
		(width 0.508)
		(layer "B.Cu")
		(net "GND")
	)
	(segment
		(start 61.05017 -27.624278)
		(end 61.51753 -28.091638)
		(width 0.4572)
		(layer "B.Cu")
		(net "GND")
	)
	(segment
		(start 24.014938 -205.199488)
		(end 24.014938 -201.09053)
		(width 0.508)
		(layer "B.Cu")
		(net "GND")
	)
	(segment
		(start 180.213 -188.06795)
		(end 179.47005 -188.06795)
		(width 0.508)
		(layer "B.Cu")
		(net "GND")
	)
	(segment
		(start 95.340932 -30.252162)
		(end 95.850202 -30.761432)
		(width 0.508)
		(layer "B.Cu")
		(net "GND")
	)
	(segment
		(start 138.370056 -35.41141)
		(end 138.370056 -34.39541)
		(width 0.4572)
		(layer "B.Cu")
		(net "GND")
	)
	(segment
		(start 168.82618 -151.496522)
		(end 168.03243 -151.496522)
		(width 0.508)
		(layer "B.Cu")
		(net "GND")
	)
	(segment
		(start 104.008174 -67.228466)
		(end 104.008174 -68.244466)
		(width 0.508)
		(layer "B.Cu")
		(net "GND")
	)
	(segment
		(start 110.72876 -187.726574)
		(end 110.72876 -187.052712)
		(width 0.508)
		(layer "B.Cu")
		(net "GND")
	)
	(segment
		(start 59.67476 -184.805574)
		(end 59.67476 -183.97855)
		(width 0.508)
		(layer "B.Cu")
		(net "GND")
	)
	(segment
		(start 132.145786 -56.250586)
		(end 131.9022 -56.007)
		(width 0.3302)
		(layer "B.Cu")
		(net "GND")
	)
	(segment
		(start 94.08922 -190.281052)
		(end 93.811344 -190.003176)
		(width 0.508)
		(layer "B.Cu")
		(net "GND")
	)
	(segment
		(start 123.862846 -150.935944)
		(end 123.28652 -151.51227)
		(width 0.508)
		(layer "B.Cu")
		(net "GND")
	)
	(segment
		(start 78.27518 -161.71545)
		(end 78.61935 -162.05962)
		(width 0.508)
		(layer "B.Cu")
		(net "GND")
	)
	(segment
		(start 169.015664 -201.034904)
		(end 169.015664 -205.199488)
		(width 0.508)
		(layer "B.Cu")
		(net "GND")
	)
	(segment
		(start 106.988102 -172.499782)
		(end 107.31754 -172.170344)
		(width 0.508)
		(layer "B.Cu")
		(net "GND")
	)
	(segment
		(start 129.625852 -145.11655)
		(end 129.507742 -145.23466)
		(width 0.4572)
		(layer "B.Cu")
		(net "GND")
	)
	(segment
		(start 67.67576 -187.726574)
		(end 67.67576 -186.95162)
		(width 0.508)
		(layer "B.Cu")
		(net "GND")
	)
	(segment
		(start 138.211052 -134.65175)
		(end 138.541252 -134.98195)
		(width 0.4572)
		(layer "B.Cu")
		(net "GND")
	)
	(segment
		(start 52.8447 -133.626098)
		(end 53.247798 -132.983478)
		(width 0.4572)
		(layer "B.Cu")
		(net "GND")
	)
	(segment
		(start 105.14076 -187.726574)
		(end 105.14076 -186.85891)
		(width 0.508)
		(layer "B.Cu")
		(net "GND")
	)
	(segment
		(start 155.05176 -187.305696)
		(end 155.05176 -187.472574)
		(width 0.508)
		(layer "B.Cu")
		(net "GND")
	)
	(segment
		(start 136.50976 -186.924696)
		(end 136.50976 -187.472574)
		(width 0.508)
		(layer "B.Cu")
		(net "GND")
	)
	(segment
		(start 46.032928 -134.16407)
		(end 46.112684 -134.084314)
		(width 0.381)
		(layer "B.Cu")
		(net "GND")
	)
	(segment
		(start 156.141928 -186.821318)
		(end 156.19476 -186.87415)
		(width 0.508)
		(layer "B.Cu")
		(net "GND")
	)
	(segment
		(start 141.633702 -139.19835)
		(end 141.633702 -138.23315)
		(width 0.4572)
		(layer "B.Cu")
		(net "GND")
	)
	(segment
		(start 130.784854 -183.92648)
		(end 130.79476 -183.936386)
		(width 0.508)
		(layer "B.Cu")
		(net "GND")
	)
	(segment
		(start 77.07376 -187.233306)
		(end 76.87564 -187.035186)
		(width 0.508)
		(layer "B.Cu")
		(net "GND")
	)
	(segment
		(start 49.358042 -82.931508)
		(end 49.978818 -82.931508)
		(width 0.381)
		(layer "B.Cu")
		(net "GND")
	)
	(segment
		(start 79.066136 -86.957662)
		(end 79.55026 -86.957662)
		(width 0.508)
		(layer "B.Cu")
		(net "GND")
	)
	(segment
		(start 119.42826 -164.768022)
		(end 119.818912 -164.768022)
		(width 0.4572)
		(layer "B.Cu")
		(net "GND")
	)
	(segment
		(start 87.745824 -72.31126)
		(end 88.229694 -72.31126)
		(width 0.4572)
		(layer "B.Cu")
		(net "GND")
	)
	(segment
		(start 187.015628 -201.542904)
		(end 187.015628 -204.699616)
		(width 0.508)
		(layer "B.Cu")
		(net "GND")
	)
	(segment
		(start 113.5126 -181.520592)
		(end 113.52784 -181.505352)
		(width 0.3556)
		(layer "B.Cu")
		(net "GND")
	)
	(segment
		(start 61.720222 -130.917696)
		(end 61.726572 -130.924046)
		(width 0.3556)
		(layer "B.Cu")
		(net "GND")
	)
	(segment
		(start 103.506524 -165.965378)
		(end 104.252776 -165.965378)
		(width 0.4572)
		(layer "B.Cu")
		(net "GND")
	)
	(segment
		(start 70.867016 -124.055378)
		(end 70.867016 -124.24537)
		(width 0.4572)
		(layer "B.Cu")
		(net "GND")
	)
	(segment
		(start 48.202596 -88.873076)
		(end 48.274732 -88.873076)
		(width 0.381)
		(layer "B.Cu")
		(net "GND")
	)
	(segment
		(start 127.681228 -52.8828)
		(end 124.878084 -52.8828)
		(width 0.3302)
		(layer "B.Cu")
		(net "GND")
	)
	(segment
		(start 61.51753 -28.091638)
		(end 64.794892 -28.091638)
		(width 0.4572)
		(layer "B.Cu")
		(net "GND")
	)
	(segment
		(start 125.365002 -147.07235)
		(end 125.492002 -147.19935)
		(width 0.4572)
		(layer "B.Cu")
		(net "GND")
	)
	(segment
		(start 134.796784 -37.375084)
		(end 134.086092 -37.375084)
		(width 0.4572)
		(layer "B.Cu")
		(net "GND")
	)
	(segment
		(start 46.897036 -129.11836)
		(end 46.897036 -128.359662)
		(width 0.381)
		(layer "B.Cu")
		(net "GND")
	)
	(segment
		(start 62.545722 -140.655548)
		(end 62.537086 -140.646912)
		(width 0.3556)
		(layer "B.Cu")
		(net "GND")
	)
	(segment
		(start 186.55284 -201.080116)
		(end 186.01563 -201.617326)
		(width 0.508)
		(layer "B.Cu")
		(net "GND")
	)
	(segment
		(start 115.910868 -164.956744)
		(end 116.570252 -165.616128)
		(width 0.4572)
		(layer "B.Cu")
		(net "GND")
	)
	(segment
		(start 73.31202 -184.749948)
		(end 73.31202 -184.225438)
		(width 0.381)
		(layer "B.Cu")
		(net "GND")
	)
	(segment
		(start 55.007256 -134.341108)
		(end 55.007256 -134.008368)
		(width 0.4572)
		(layer "B.Cu")
		(net "GND")
	)
	(segment
		(start 134.782052 -137.03935)
		(end 134.756652 -137.01395)
		(width 0.4572)
		(layer "B.Cu")
		(net "GND")
	)
	(segment
		(start 47.996348 -141.304264)
		(end 47.996348 -140.714984)
		(width 0.4572)
		(layer "B.Cu")
		(net "GND")
	)
	(segment
		(start 68.48475 -25.211786)
		(end 68.48475 -25.473406)
		(width 0.508)
		(layer "B.Cu")
		(net "GND")
	)
	(segment
		(start 132.278628 -160.963102)
		(end 132.278628 -159.917892)
		(width 0.508)
		(layer "B.Cu")
		(net "GND")
	)
	(segment
		(start 37.05352 -148.36775)
		(end 37.52469 -147.89658)
		(width 0.508)
		(layer "B.Cu")
		(net "GND")
	)
	(segment
		(start 135.08863 -183.92013)
		(end 135.36676 -184.19826)
		(width 0.508)
		(layer "B.Cu")
		(net "GND")
	)
	(segment
		(start 130.114802 -150.092664)
		(end 130.114802 -151.03475)
		(width 0.4572)
		(layer "B.Cu")
		(net "GND")
	)
	(segment
		(start 49.38776 -181.433724)
		(end 49.38776 -181.584092)
		(width 0.508)
		(layer "B.Cu")
		(net "GND")
	)
	(segment
		(start 120.061482 -165.010592)
		(end 120.370092 -165.010592)
		(width 0.4572)
		(layer "B.Cu")
		(net "GND")
	)
	(segment
		(start 58.800238 -84.238846)
		(end 58.91276 -84.126578)
		(width 0.3048)
		(layer "B.Cu")
		(net "GND")
	)
	(segment
		(start 49.38776 -186.848242)
		(end 49.38776 -187.726574)
		(width 0.508)
		(layer "B.Cu")
		(net "GND")
	)
	(segment
		(start 72.13346 -186.981592)
		(end 71.99376 -187.121292)
		(width 0.508)
		(layer "B.Cu")
		(net "GND")
	)
	(segment
		(start 139.285218 -34.39541)
		(end 138.370056 -34.39541)
		(width 0.4572)
		(layer "B.Cu")
		(net "GND")
	)
	(segment
		(start 157.33014 -186.833002)
		(end 157.33014 -187.464954)
		(width 0.508)
		(layer "B.Cu")
		(net "GND")
	)
	(segment
		(start 51.67376 -181.47284)
		(end 51.67376 -181.584092)
		(width 0.508)
		(layer "B.Cu")
		(net "GND")
	)
	(segment
		(start 48.24476 -181.511956)
		(end 48.24476 -181.592474)
		(width 0.508)
		(layer "B.Cu")
		(net "GND")
	)
	(segment
		(start 57.057036 -130.04038)
		(end 57.030366 -130.01371)
		(width 0.381)
		(layer "B.Cu")
		(net "GND")
	)
	(segment
		(start 125.492002 -144.22755)
		(end 124.596652 -144.22755)
		(width 0.4572)
		(layer "B.Cu")
		(net "GND")
	)
	(segment
		(start 56.054498 -99.035616)
		(end 56.054498 -97.096834)
		(width 0.4572)
		(layer "B.Cu")
		(net "GND")
	)
	(segment
		(start 77.796136 -124.949712)
		(end 77.796136 -125.438662)
		(width 0.508)
		(layer "B.Cu")
		(net "GND")
	)
	(segment
		(start 95.74784 -202.442572)
		(end 95.74784 -201.06132)
		(width 0.508)
		(layer "B.Cu")
		(net "GND")
	)
	(segment
		(start 91.21267 -168.942512)
		(end 91.991942 -168.942512)
		(width 0.508)
		(layer "B.Cu")
		(net "GND")
	)
	(segment
		(start 177.51044 -118.86565)
		(end 176.96053 -119.41556)
		(width 0.4572)
		(layer "B.Cu")
		(net "GND")
	)
	(segment
		(start 71.99376 -187.121292)
		(end 71.99376 -187.726574)
		(width 0.508)
		(layer "B.Cu")
		(net "GND")
	)
	(segment
		(start 135.747252 -137.06475)
		(end 135.747252 -136.271)
		(width 0.4572)
		(layer "B.Cu")
		(net "GND")
	)
	(segment
		(start 94.611444 -187.822586)
		(end 95.39605 -187.822586)
		(width 0.508)
		(layer "B.Cu")
		(net "GND")
	)
	(segment
		(start 74.02576 -187.026804)
		(end 74.11466 -186.937904)
		(width 0.508)
		(layer "B.Cu")
		(net "GND")
	)
	(segment
		(start 139.93876 -187.472574)
		(end 139.93876 -186.862974)
		(width 0.508)
		(layer "B.Cu")
		(net "GND")
	)
	(segment
		(start 133.969252 -151.7142)
		(end 134.985252 -151.7142)
		(width 0.4572)
		(layer "B.Cu")
		(net "GND")
	)
	(segment
		(start 153.90876 -187.102242)
		(end 153.90876 -187.472574)
		(width 0.508)
		(layer "B.Cu")
		(net "GND")
	)
	(segment
		(start 66.787776 -78.649322)
		(end 66.825622 -78.611476)
		(width 0.381)
		(layer "B.Cu")
		(net "GND")
	)
	(segment
		(start 113.54181 -162.252406)
		(end 114.610134 -162.252406)
		(width 0.4572)
		(layer "B.Cu")
		(net "GND")
	)
	(segment
		(start 66.015108 -205.199488)
		(end 66.015108 -201.09053)
		(width 0.508)
		(layer "B.Cu")
		(net "GND")
	)
	(segment
		(start 64.940942 -143.65732)
		(end 64.7954 -143.802862)
		(width 0.508)
		(layer "B.Cu")
		(net "GND")
	)
	(segment
		(start 84.443062 -31.063438)
		(end 84.271358 -31.063438)
		(width 0.4572)
		(layer "B.Cu")
		(net "GND")
	)
	(segment
		(start 68.216272 -61.78296)
		(end 68.15201 -61.718698)
		(width 0.4572)
		(layer "B.Cu")
		(net "GND")
	)
	(segment
		(start 126.876302 -138.1379)
		(end 125.917452 -138.1379)
		(width 0.4572)
		(layer "B.Cu")
		(net "GND")
	)
	(segment
		(start 70.701916 -62.047374)
		(end 71.137018 -62.482476)
		(width 0.4572)
		(layer "B.Cu")
		(net "GND")
	)
	(segment
		(start 121.034302 -168.101772)
		(end 121.034302 -168.560242)
		(width 0.4572)
		(layer "B.Cu")
		(net "GND")
	)
	(segment
		(start 158.48076 -186.730894)
		(end 158.48076 -187.472574)
		(width 0.508)
		(layer "B.Cu")
		(net "GND")
	)
	(segment
		(start 107.42676 -184.805574)
		(end 107.42676 -183.845708)
		(width 0.508)
		(layer "B.Cu")
		(net "GND")
	)
	(segment
		(start 128.305052 -151.7142)
		(end 128.305052 -152.35555)
		(width 0.508)
		(layer "B.Cu")
		(net "GND")
	)
	(segment
		(start 93.507052 -30.689042)
		(end 94.270576 -29.925518)
		(width 0.508)
		(layer "B.Cu")
		(net "GND")
	)
	(segment
		(start 47.362618 -130.565144)
		(end 47.024036 -130.226562)
		(width 0.381)
		(layer "B.Cu")
		(net "GND")
	)
	(segment
		(start 65.001648 -69.429376)
		(end 65.580006 -70.007734)
		(width 0.4572)
		(layer "B.Cu")
		(net "GND")
	)
	(segment
		(start 57.030366 -129.802382)
		(end 57.030366 -130.01371)
		(width 0.381)
		(layer "B.Cu")
		(net "GND")
	)
	(segment
		(start 157.015688 -201.034904)
		(end 157.015688 -205.199488)
		(width 0.508)
		(layer "B.Cu")
		(net "GND")
	)
	(segment
		(start 113.52784 -180.784754)
		(end 113.52276 -180.779674)
		(width 0.3556)
		(layer "B.Cu")
		(net "GND")
	)
	(segment
		(start 63.640462 -72.238108)
		(end 64.247522 -72.238108)
		(width 0.381)
		(layer "B.Cu")
		(net "GND")
	)
	(segment
		(start 93.811344 -190.003176)
		(end 93.811344 -188.838586)
		(width 0.508)
		(layer "B.Cu")
		(net "GND")
	)
	(segment
		(start 129.507742 -145.23466)
		(end 128.912112 -145.23466)
		(width 0.4572)
		(layer "B.Cu")
		(net "GND")
	)
	(segment
		(start 79.23276 -187.028074)
		(end 79.10576 -186.901074)
		(width 0.508)
		(layer "B.Cu")
		(net "GND")
	)
	(segment
		(start 119.7483 -187.038234)
		(end 119.49176 -187.294774)
		(width 0.508)
		(layer "B.Cu")
		(net "GND")
	)
	(segment
		(start 103.506524 -165.966902)
		(end 103.506524 -165.965378)
		(width 0.4572)
		(layer "B.Cu")
		(net "GND")
	)
	(segment
		(start 47.996348 -140.714984)
		(end 47.977044 -140.69568)
		(width 0.4572)
		(layer "B.Cu")
		(net "GND")
	)
	(segment
		(start 63.667894 -97.73412)
		(end 64.182498 -97.219516)
		(width 0.4572)
		(layer "B.Cu")
		(net "GND")
	)
	(segment
		(start 39.448486 -142.583662)
		(end 39.448486 -143.472662)
		(width 0.508)
		(layer "B.Cu")
		(net "GND")
	)
	(segment
		(start 166.82085 -173.684692)
		(end 167.902636 -173.684692)
		(width 0.508)
		(layer "B.Cu")
		(net "GND")
	)
	(segment
		(start 139.193778 -35.41141)
		(end 138.370056 -35.41141)
		(width 0.4572)
		(layer "B.Cu")
		(net "GND")
	)
	(segment
		(start 157.83814 -177.023014)
		(end 157.722824 -177.13833)
		(width 0.508)
		(layer "B.Cu")
		(net "GND")
	)
	(segment
		(start 46.833536 -136.564624)
		(end 47.151036 -136.882124)
		(width 0.508)
		(layer "B.Cu")
		(net "GND")
	)
	(segment
		(start 89.114884 -166.304468)
		(end 87.748872 -166.304468)
		(width 0.254)
		(layer "B.Cu")
		(net "GND")
	)
	(segment
		(start 62.405514 -86.66861)
		(end 62.200028 -86.463124)
		(width 0.381)
		(layer "B.Cu")
		(net "GND")
	)
	(segment
		(start 57.897268 -125.711712)
		(end 58.087006 -125.521974)
		(width 0.508)
		(layer "B.Cu")
		(net "GND")
	)
	(segment
		(start 76.570078 -130.514598)
		(end 76.570078 -129.788666)
		(width 0.4572)
		(layer "B.Cu")
		(net "GND")
	)
	(segment
		(start 83.758278 -29.214318)
		(end 83.758278 -29.82214)
		(width 0.508)
		(layer "B.Cu")
		(net "GND")
	)
	(segment
		(start 157.37586 -186.787282)
		(end 157.33014 -186.833002)
		(width 0.508)
		(layer "B.Cu")
		(net "GND")
	)
	(segment
		(start 50.53076 -186.862974)
		(end 50.53076 -187.726574)
		(width 0.508)
		(layer "B.Cu")
		(net "GND")
	)
	(segment
		(start 140.947902 -142.55115)
		(end 141.005052 -142.6083)
		(width 0.4572)
		(layer "B.Cu")
		(net "GND")
	)
	(segment
		(start 52.793392 -28.146248)
		(end 52.793392 -29.199078)
		(width 0.4572)
		(layer "B.Cu")
		(net "GND")
	)
	(segment
		(start 48.75022 -181.006496)
		(end 48.24476 -181.511956)
		(width 0.508)
		(layer "B.Cu")
		(net "GND")
	)
	(segment
		(start 51.787298 -97.859088)
		(end 51.990498 -97.655888)
		(width 0.4572)
		(layer "B.Cu")
		(net "GND")
	)
	(segment
		(start 132.978652 -151.7142)
		(end 132.978652 -152.48255)
		(width 0.4572)
		(layer "B.Cu")
		(net "GND")
	)
	(segment
		(start 127.508 -59.83605)
		(end 126.76505 -59.83605)
		(width 0.508)
		(layer "B.Cu")
		(net "GND")
	)
	(segment
		(start 48.899826 -89.601294)
		(end 49.32299 -89.17813)
		(width 0.381)
		(layer "B.Cu")
		(net "GND")
	)
	(segment
		(start 124.878084 -52.8828)
		(end 124.725684 -52.7304)
		(width 0.3302)
		(layer "B.Cu")
		(net "GND")
	)
	(segment
		(start 66.581528 -62.455806)
		(end 66.57975 -62.457584)
		(width 0.4572)
		(layer "B.Cu")
		(net "GND")
	)
	(segment
		(start 94.051882 -173.169072)
		(end 94.051882 -173.140624)
		(width 0.4572)
		(layer "B.Cu")
		(net "GND")
	)
	(segment
		(start 58.91276 -84.126578)
		(end 59.333892 -84.126578)
		(width 0.3048)
		(layer "B.Cu")
		(net "GND")
	)
	(segment
		(start 73.83272 -184.749948)
		(end 74.38136 -185.298588)
		(width 0.508)
		(layer "B.Cu")
		(net "GND")
	)
	(segment
		(start 128.305052 -152.35555)
		(end 128.457452 -152.50795)
		(width 0.508)
		(layer "B.Cu")
		(net "GND")
	)
	(segment
		(start 75.73264 -187.068206)
		(end 75.736196 -187.068206)
		(width 0.254)
		(layer "B.Cu")
		(net "GND")
	)
	(segment
		(start 134.226046 -38.391084)
		(end 134.796784 -38.391084)
		(width 0.4572)
		(layer "B.Cu")
		(net "GND")
	)
	(segment
		(start 61.9506 -184.795414)
		(end 61.96076 -184.805574)
		(width 0.508)
		(layer "B.Cu")
		(net "GND")
	)
	(segment
		(start 21.014944 -201.09053)
		(end 21.014944 -200.32853)
		(width 0.508)
		(layer "B.Cu")
		(net "GND")
	)
	(segment
		(start 166.79164 -187.79744)
		(end 165.77564 -187.79744)
		(width 0.508)
		(layer "B.Cu")
		(net "GND")
	)
	(segment
		(start 130.570986 -58.43905)
		(end 131.22275 -58.43905)
		(width 0.508)
		(layer "B.Cu")
		(net "GND")
	)
	(segment
		(start 98.797618 -180.144674)
		(end 97.52076 -180.144674)
		(width 0.3302)
		(layer "B.Cu")
		(net "GND")
	)
	(segment
		(start 54.022498 -97.496376)
		(end 54.022498 -97.096834)
		(width 0.4572)
		(layer "B.Cu")
		(net "GND")
	)
	(segment
		(start 152.015698 -201.034904)
		(end 152.015698 -205.199488)
		(width 0.508)
		(layer "B.Cu")
		(net "GND")
	)
	(segment
		(start 63.39332 -141.205712)
		(end 63.959486 -141.205712)
		(width 0.4572)
		(layer "B.Cu")
		(net "GND")
	)
	(segment
		(start 63.340996 -140.457936)
		(end 63.143384 -140.655548)
		(width 0.3556)
		(layer "B.Cu")
		(net "GND")
	)
	(segment
		(start 57.057036 -131.026662)
		(end 57.057036 -130.04038)
		(width 0.381)
		(layer "B.Cu")
		(net "GND")
	)
	(segment
		(start 69.330062 -28.994608)
		(end 68.314062 -28.994608)
		(width 0.508)
		(layer "B.Cu")
		(net "GND")
	)
	(segment
		(start 59.678062 -84.470748)
		(end 59.821572 -84.470748)
		(width 0.3048)
		(layer "B.Cu")
		(net "GND")
	)
	(segment
		(start 70.309486 -120.032272)
		(end 69.697346 -120.644412)
		(width 0.4572)
		(layer "B.Cu")
		(net "GND")
	)
	(segment
		(start 124.725684 -52.7304)
		(end 124.725684 -52.706524)
		(width 0.3302)
		(layer "B.Cu")
		(net "GND")
	)
	(segment
		(start 72.13346 -186.684158)
		(end 72.13346 -186.981592)
		(width 0.508)
		(layer "B.Cu")
		(net "GND")
	)
	(segment
		(start 57.741566 -129.259076)
		(end 57.573672 -129.259076)
		(width 0.381)
		(layer "B.Cu")
		(net "GND")
	)
	(segment
		(start 64.79413 -142.710662)
		(end 64.322706 -142.710662)
		(width 0.508)
		(layer "B.Cu")
		(net "GND")
	)
	(segment
		(start 124.10821 -172.378624)
		(end 124.508006 -172.378624)
		(width 0.508)
		(layer "B.Cu")
		(net "GND")
	)
	(segment
		(start 37.52469 -147.89658)
		(end 37.52469 -147.577302)
		(width 0.508)
		(layer "B.Cu")
		(net "GND")
	)
	(segment
		(start 142.334234 -184.551574)
		(end 142.22476 -184.551574)
		(width 0.508)
		(layer "B.Cu")
		(net "GND")
	)
	(segment
		(start 115.19662 -187.028074)
		(end 115.30076 -187.132214)
		(width 0.508)
		(layer "B.Cu")
		(net "GND")
	)
	(segment
		(start 60.4012 -76.199492)
		(end 60.252356 -76.348336)
		(width 0.4572)
		(layer "B.Cu")
		(net "GND")
	)
	(segment
		(start 72.395588 -63.54572)
		(end 72.787002 -63.54572)
		(width 0.254)
		(layer "B.Cu")
		(net "GND")
	)
	(segment
		(start 66.53276 -187.726574)
		(end 66.53276 -186.913012)
		(width 0.508)
		(layer "B.Cu")
		(net "GND")
	)
	(segment
		(start 124.878592 -145.21815)
		(end 125.492002 -145.21815)
		(width 0.4572)
		(layer "B.Cu")
		(net "GND")
	)
	(segment
		(start 63.618364 -87.472774)
		(end 63.946024 -87.145114)
		(width 0.4572)
		(layer "B.Cu")
		(net "GND")
	)
	(segment
		(start 37.115496 -146.58467)
		(end 36.83508 -146.304254)
		(width 0.508)
		(layer "B.Cu")
		(net "GND")
	)
	(segment
		(start 58.53176 -187.726574)
		(end 58.53176 -187.048648)
		(width 0.508)
		(layer "B.Cu")
		(net "GND")
	)
	(segment
		(start 130.921252 -34.973768)
		(end 130.921252 -36.110926)
		(width 0.4572)
		(layer "B.Cu")
		(net "GND")
	)
	(segment
		(start 61.015118 -205.199488)
		(end 61.015118 -201.09053)
		(width 0.508)
		(layer "B.Cu")
		(net "GND")
	)
	(segment
		(start 71.015098 -205.199488)
		(end 71.015098 -201.09053)
		(width 0.508)
		(layer "B.Cu")
		(net "GND")
	)
	(segment
		(start 149.33676 -187.472574)
		(end 149.33676 -186.862974)
		(width 0.508)
		(layer "B.Cu")
		(net "GND")
	)
	(segment
		(start 131.93776 -187.472574)
		(end 131.93776 -186.862974)
		(width 0.381)
		(layer "B.Cu")
		(net "GND")
	)
	(segment
		(start 56.930036 -125.730762)
		(end 56.949086 -125.711712)
		(width 0.381)
		(layer "B.Cu")
		(net "GND")
	)
	(segment
		(start 36.014914 -205.199488)
		(end 36.014914 -201.09053)
		(width 0.508)
		(layer "B.Cu")
		(net "GND")
	)
	(segment
		(start 167.994584 -149.5806)
		(end 168.03243 -149.542754)
		(width 0.508)
		(layer "B.Cu")
		(net "GND")
	)
	(segment
		(start 114.610134 -162.252406)
		(end 114.610134 -162.251644)
		(width 0.4572)
		(layer "B.Cu")
		(net "GND")
	)
	(segment
		(start 156.77769 -174.209964)
		(end 156.77769 -175.015144)
		(width 0.508)
		(layer "B.Cu")
		(net "GND")
	)
	(segment
		(start 138.79576 -186.862974)
		(end 138.79576 -187.472574)
		(width 0.508)
		(layer "B.Cu")
		(net "GND")
	)
	(segment
		(start 113.01476 -187.116974)
		(end 112.76076 -186.862974)
		(width 0.508)
		(layer "B.Cu")
		(net "GND")
	)
	(segment
		(start 71.703692 -122.885962)
		(end 71.703692 -123.218702)
		(width 0.4572)
		(layer "B.Cu")
		(net "GND")
	)
	(segment
		(start 142.015464 -201.034904)
		(end 142.015464 -205.199488)
		(width 0.508)
		(layer "B.Cu")
		(net "GND")
	)
	(segment
		(start 119.7483 -187.037472)
		(end 119.7483 -187.038234)
		(width 0.508)
		(layer "B.Cu")
		(net "GND")
	)
	(segment
		(start 76.015088 -205.199488)
		(end 76.015088 -201.09053)
		(width 0.508)
		(layer "B.Cu")
		(net "GND")
	)
	(segment
		(start 21.014944 -205.199488)
		(end 21.014944 -201.09053)
		(width 0.508)
		(layer "B.Cu")
		(net "GND")
	)
	(segment
		(start 150.47976 -184.551574)
		(end 150.47976 -183.837072)
		(width 0.508)
		(layer "B.Cu")
		(net "GND")
	)
	(segment
		(start 132.037328 -161.204402)
		(end 132.278628 -160.963102)
		(width 0.508)
		(layer "B.Cu")
		(net "GND")
	)
	(segment
		(start 138.372088 -164.335206)
		(end 138.372088 -163.812474)
		(width 0.4572)
		(layer "B.Cu")
		(net "GND")
	)
	(segment
		(start 132.775452 -135.4709)
		(end 133.766052 -135.4709)
		(width 0.4572)
		(layer "B.Cu")
		(net "GND")
	)
	(segment
		(start 58.60415 -84.238846)
		(end 58.800238 -84.238846)
		(width 0.3048)
		(layer "B.Cu")
		(net "GND")
	)
	(segment
		(start 141.08176 -186.91225)
		(end 141.08176 -187.548774)
		(width 0.381)
		(layer "B.Cu")
		(net "GND")
	)
	(segment
		(start 86.092792 -31.311088)
		(end 86.092792 -29.793438)
		(width 0.4572)
		(layer "B.Cu")
		(net "GND")
	)
	(segment
		(start 175.90008 -121.476008)
		(end 175.90008 -120.660668)
		(width 0.381)
		(layer "B.Cu")
		(net "GND")
	)
	(segment
		(start 95.340932 -29.925518)
		(end 95.340932 -30.252162)
		(width 0.508)
		(layer "B.Cu")
		(net "GND")
	)
	(segment
		(start 88.3793 -74.701654)
		(end 88.3793 -73.685654)
		(width 0.4572)
		(layer "B.Cu")
		(net "GND")
	)
	(segment
		(start 93.319346 -173.901608)
		(end 94.051882 -173.169072)
		(width 0.4572)
		(layer "B.Cu")
		(net "GND")
	)
	(segment
		(start 64.940942 -142.857474)
		(end 64.79413 -142.710662)
		(width 0.508)
		(layer "B.Cu")
		(net "GND")
	)
	(segment
		(start 128.301496 -37.258244)
		(end 127.541528 -37.258244)
		(width 0.4572)
		(layer "B.Cu")
		(net "GND")
	)
	(segment
		(start 75.743308 -95.141288)
		(end 75.471274 -94.869254)
		(width 0.4572)
		(layer "B.Cu")
		(net "GND")
	)
	(segment
		(start 133.82625 -41.106852)
		(end 134.158482 -41.439084)
		(width 0.4572)
		(layer "B.Cu")
		(net "GND")
	)
	(segment
		(start 134.22376 -186.862974)
		(end 134.22376 -187.472574)
		(width 0.508)
		(layer "B.Cu")
		(net "GND")
	)
	(segment
		(start 67.30365 -61.718698)
		(end 66.581528 -62.44082)
		(width 0.4572)
		(layer "B.Cu")
		(net "GND")
	)
	(segment
		(start 53.95976 -187.726574)
		(end 53.95976 -186.900566)
		(width 0.508)
		(layer "B.Cu")
		(net "GND")
	)
	(segment
		(start 73.31202 -184.749948)
		(end 73.83272 -184.749948)
		(width 0.508)
		(layer "B.Cu")
		(net "GND")
	)
	(segment
		(start 108.44276 -186.851544)
		(end 108.31322 -186.722004)
		(width 0.508)
		(layer "B.Cu")
		(net "GND")
	)
	(segment
		(start 49.650142 -27.626818)
		(end 49.059592 -28.217368)
		(width 0.4572)
		(layer "B.Cu")
		(net "GND")
	)
	(segment
		(start 108.44276 -187.726574)
		(end 108.44276 -186.851544)
		(width 0.508)
		(layer "B.Cu")
		(net "GND")
	)
	(segment
		(start 96.015048 -204.699616)
		(end 96.015048 -202.70978)
		(width 0.508)
		(layer "B.Cu")
		(net "GND")
	)
	(segment
		(start 141.927072 -48.570642)
		(end 141.980666 -48.517048)
		(width 0.508)
		(layer "B.Cu")
		(net "GND")
	)
	(segment
		(start 175.510444 -121.865644)
		(end 175.90008 -121.476008)
		(width 0.381)
		(layer "B.Cu")
		(net "GND")
	)
	(segment
		(start 47.686976 -179.922424)
		(end 47.737776 -179.871624)
		(width 0.4572)
		(layer "B.Cu")
		(net "GND")
	)
	(segment
		(start 81.015078 -205.199488)
		(end 81.015078 -201.09053)
		(width 0.508)
		(layer "B.Cu")
		(net "GND")
	)
	(segment
		(start 84.271358 -31.063438)
		(end 83.758278 -30.550358)
		(width 0.4572)
		(layer "B.Cu")
		(net "GND")
	)
	(segment
		(start 133.969252 -152.48255)
		(end 133.969252 -151.7142)
		(width 0.4572)
		(layer "B.Cu")
		(net "GND")
	)
	(segment
		(start 126.965202 -141.1605)
		(end 126.069852 -141.1605)
		(width 0.4572)
		(layer "B.Cu")
		(net "GND")
	)
	(segment
		(start 66.094102 -29.677868)
		(end 66.094102 -29.865828)
		(width 0.4572)
		(layer "B.Cu")
		(net "GND")
	)
	(segment
		(start 132.997194 -56.250586)
		(end 132.145786 -56.250586)
		(width 0.3302)
		(layer "B.Cu")
		(net "GND")
	)
	(segment
		(start 47.10176 -187.726574)
		(end 47.10176 -186.862974)
		(width 0.508)
		(layer "B.Cu")
		(net "GND")
	)
	(segment
		(start 74.60615 -31.72714)
		(end 74.60615 -30.71114)
		(width 0.508)
		(layer "B.Cu")
		(net "GND")
	)
	(segment
		(start 86.378542 -31.596838)
		(end 86.092792 -31.311088)
		(width 0.4572)
		(layer "B.Cu")
		(net "GND")
	)
	(segment
		(start 61.944504 -130.924046)
		(end 61.726572 -130.924046)
		(width 0.3556)
		(layer "B.Cu")
		(net "GND")
	)
	(segment
		(start 60.252356 -76.348336)
		(end 59.717178 -76.348336)
		(width 0.4572)
		(layer "B.Cu")
		(net "GND")
	)
	(segment
		(start 49.101502 -82.674968)
		(end 49.358042 -82.931508)
		(width 0.381)
		(layer "B.Cu")
		(net "GND")
	)
	(segment
		(start 113.14176 -184.55132)
		(end 113.59896 -184.09412)
		(width 0.508)
		(layer "B.Cu")
		(net "GND")
	)
	(segment
		(start 113.52784 -181.505352)
		(end 113.52784 -180.784754)
		(width 0.3556)
		(layer "B.Cu")
		(net "GND")
	)
	(segment
		(start 44.014898 -201.09053)
		(end 44.014898 -200.32853)
		(width 0.508)
		(layer "B.Cu")
		(net "GND")
	)
	(segment
		(start 165.217602 -173.552358)
		(end 166.688516 -173.552358)
		(width 0.3048)
		(layer "B.Cu")
		(net "GND")
	)
	(segment
		(start 64.182498 -97.219516)
		(end 64.182498 -97.096834)
		(width 0.4572)
		(layer "B.Cu")
		(net "GND")
	)
	(segment
		(start 100.705412 -168.028366)
		(end 99.300538 -168.028366)
		(width 0.4572)
		(layer "B.Cu")
		(net "GND")
	)
	(segment
		(start 56.015128 -201.09053)
		(end 56.015128 -200.32853)
		(width 0.508)
		(layer "B.Cu")
		(net "GND")
	)
	(segment
		(start 186.55284 -201.080116)
		(end 187.015628 -201.542904)
		(width 0.508)
		(layer "B.Cu")
		(net "GND")
	)
	(segment
		(start 51.78552 -97.859088)
		(end 51.787298 -97.859088)
		(width 0.4572)
		(layer "B.Cu")
		(net "GND")
	)
	(segment
		(start 137.474452 -137.06475)
		(end 137.550652 -136.98855)
		(width 0.4572)
		(layer "B.Cu")
		(net "GND")
	)
	(segment
		(start 134.756652 -137.01395)
		(end 134.756652 -136.271)
		(width 0.4572)
		(layer "B.Cu")
		(net "GND")
	)
	(segment
		(start 142.51051 -138.175492)
		(end 142.452852 -138.23315)
		(width 0.4572)
		(layer "B.Cu")
		(net "GND")
	)
	(segment
		(start 57.926478 -89.620598)
		(end 57.852818 -89.546938)
		(width 0.381)
		(layer "B.Cu")
		(net "GND")
	)
	(segment
		(start 69.697346 -120.644412)
		(end 69.395086 -120.644412)
		(width 0.4572)
		(layer "B.Cu")
		(net "GND")
	)
	(segment
		(start 49.978818 -82.931508)
		(end 50.009298 -82.961988)
		(width 0.381)
		(layer "B.Cu")
		(net "GND")
	)
	(segment
		(start 143.36776 -186.906662)
		(end 143.36776 -187.599574)
		(width 0.508)
		(layer "B.Cu")
		(net "GND")
	)
	(segment
		(start 141.007592 -186.838082)
		(end 141.08176 -186.91225)
		(width 0.381)
		(layer "B.Cu")
		(net "GND")
	)
	(segment
		(start 138.525758 -164.488876)
		(end 138.372088 -164.335206)
		(width 0.4572)
		(layer "B.Cu")
		(net "GND")
	)
	(segment
		(start 70.278498 -97.8154)
		(end 69.878702 -98.215196)
		(width 0.381)
		(layer "B.Cu")
		(net "GND")
	)
	(segment
		(start 56.949086 -125.711712)
		(end 57.897268 -125.711712)
		(width 0.508)
		(layer "B.Cu")
		(net "GND")
	)
	(segment
		(start 139.957302 -149.1996)
		(end 141.005052 -149.1996)
		(width 0.4572)
		(layer "B.Cu")
		(net "GND")
	)
	(segment
		(start 141.659102 -139.22375)
		(end 141.633702 -139.19835)
		(width 0.4572)
		(layer "B.Cu")
		(net "GND")
	)
	(segment
		(start 144.32661 -177.43805)
		(end 144.667986 -177.096674)
		(width 0.254)
		(layer "B.Cu")
		(net "GND")
	)
	(segment
		(start 153.908252 -186.85891)
		(end 153.908252 -187.101734)
		(width 0.508)
		(layer "B.Cu")
		(net "GND")
	)
	(segment
		(start 66.825622 -78.611476)
		(end 66.825622 -77.974698)
		(width 0.381)
		(layer "B.Cu")
		(net "GND")
	)
	(segment
		(start 140.090652 -144.40535)
		(end 140.135102 -144.3609)
		(width 0.4572)
		(layer "B.Cu")
		(net "GND")
	)
	(segment
		(start 62.169802 -72.367648)
		(end 62.742572 -72.367648)
		(width 0.4064)
		(layer "B.Cu")
		(net "GND")
	)
	(segment
		(start 130.79222 -134.35711)
		(end 130.79222 -135.233918)
		(width 0.4572)
		(layer "B.Cu")
		(net "GND")
	)
	(segment
		(start 127.875792 -137.21969)
		(end 127.492252 -136.83615)
		(width 0.4572)
		(layer "B.Cu")
		(net "GND")
	)
	(segment
		(start 35.86226 -151.81199)
		(end 36.763452 -150.910798)
		(width 0.508)
		(layer "B.Cu")
		(net "GND")
	)
	(segment
		(start 29.014928 -201.09053)
		(end 29.014928 -200.32853)
		(width 0.508)
		(layer "B.Cu")
		(net "GND")
	)
	(segment
		(start 20.63242 -86.994746)
		(end 14.636496 -92.99067)
		(width 0.254)
		(layer "In6.Cu")
		(net "GND")
	)
	(segment
		(start 7.1755 -111.43996)
		(end 7.1755 -96.861884)
		(width 0.254)
		(layer "In6.Cu")
		(net "GND")
	)
	(segment
		(start 44.1325 -145.5039)
		(end 43.8658 -145.2372)
		(width 0.254)
		(layer "In6.Cu")
		(net "GND")
	)
	(segment
		(start 19.900392 -138.84275)
		(end 18.342864 -137.285222)
		(width 0.254)
		(layer "In6.Cu")
		(net "GND")
	)
	(segment
		(start 42.306494 -149.82444)
		(end 42.31767 -149.835616)
		(width 0.254)
		(layer "In6.Cu")
		(net "GND")
	)
	(segment
		(start 47.918116 -145.64233)
		(end 47.459646 -146.1008)
		(width 0.254)
		(layer "In6.Cu")
		(net "GND")
	)
	(segment
		(start 20.66798 -59.693556)
		(end 20.121118 -59.146694)
		(width 0.254)
		(layer "In6.Cu")
		(net "GND")
	)
	(segment
		(start 20.92198 -75.47229)
		(end 21.57476 -74.81951)
		(width 0.254)
		(layer "In6.Cu")
		(net "GND")
	)
	(segment
		(start 17.2974 -41.328594)
		(end 17.594834 -41.03116)
		(width 0.254)
		(layer "In6.Cu")
		(net "GND")
	)
	(segment
		(start 16.830548 -140.549376)
		(end 15.38732 -139.106148)
		(width 0.254)
		(layer "In6.Cu")
		(net "GND")
	)
	(segment
		(start 36.382198 -146.304254)
		(end 36.83508 -146.304254)
		(width 0.254)
		(layer "In6.Cu")
		(net "GND")
	)
	(segment
		(start 40.207184 -144.348962)
		(end 38.419532 -144.348962)
		(width 0.254)
		(layer "In6.Cu")
		(net "GND")
	)
	(segment
		(start 42.10558 -149.82444)
		(end 42.306494 -149.82444)
		(width 0.254)
		(layer "In6.Cu")
		(net "GND")
	)
	(segment
		(start 56.54294 -146.834098)
		(end 56.52262 -146.854418)
		(width 0.254)
		(layer "In6.Cu")
		(net "GND")
	)
	(segment
		(start 49.039526 -145.784824)
		(end 49.82845 -144.9959)
		(width 0.254)
		(layer "In6.Cu")
		(net "GND")
	)
	(segment
		(start 9.20496 -136.178544)
		(end 9.20496 -136.650222)
		(width 0.254)
		(layer "In6.Cu")
		(net "GND")
	)
	(segment
		(start 13.442188 -135.9281)
		(end 9.64946 -132.135372)
		(width 0.254)
		(layer "In6.Cu")
		(net "GND")
	)
	(segment
		(start 9.64946 -115.067588)
		(end 9.64946 -132.135372)
		(width 0.254)
		(layer "In6.Cu")
		(net "GND")
	)
	(segment
		(start 21.812504 -55.610506)
		(end 24.26208 -58.060082)
		(width 0.254)
		(layer "In6.Cu")
		(net "GND")
	)
	(segment
		(start 18.3261 -57.187592)
		(end 18.755868 -57.187592)
		(width 0.254)
		(layer "In6.Cu")
		(net "GND")
	)
	(segment
		(start 20.66798 -64.436752)
		(end 20.66798 -59.693556)
		(width 0.254)
		(layer "In6.Cu")
		(net "GND")
	)
	(segment
		(start 58.727086 -143.819118)
		(end 61.591444 -140.95476)
		(width 0.254)
		(layer "In6.Cu")
		(net "GND")
	)
	(segment
		(start 16.40078 -55.262272)
		(end 16.40078 -44.769278)
		(width 0.254)
		(layer "In6.Cu")
		(net "GND")
	)
	(segment
		(start 14.636496 -92.99067)
		(end 9.64946 -97.977706)
		(width 0.254)
		(layer "In6.Cu")
		(net "GND")
	)
	(segment
		(start 20.11934 -59.146694)
		(end 20.121118 -59.146694)
		(width 0.254)
		(layer "In6.Cu")
		(net "GND")
	)
	(segment
		(start 49.82845 -144.9959)
		(end 55.01386 -144.9959)
		(width 0.254)
		(layer "In6.Cu")
		(net "GND")
	)
	(segment
		(start 31.83636 -141.758416)
		(end 31.010098 -140.932154)
		(width 0.254)
		(layer "In6.Cu")
		(net "GND")
	)
	(segment
		(start 56.52262 -146.854418)
		(end 56.52262 -146.854926)
		(width 0.254)
		(layer "In6.Cu")
		(net "GND")
	)
	(segment
		(start 21.229066 -54.425342)
		(end 21.812504 -55.00878)
		(width 0.254)
		(layer "In6.Cu")
		(net "GND")
	)
	(segment
		(start 17.4625 -41.914826)
		(end 17.2974 -41.749726)
		(width 0.254)
		(layer "In6.Cu")
		(net "GND")
	)
	(segment
		(start 47.459646 -146.1008)
		(end 44.8564 -146.1008)
		(width 0.254)
		(layer "In6.Cu")
		(net "GND")
	)
	(segment
		(start 33.77184 -139.70127)
		(end 32.91332 -138.84275)
		(width 0.254)
		(layer "In6.Cu")
		(net "GND")
	)
	(segment
		(start 21.812504 -55.00878)
		(end 21.812504 -55.610506)
		(width 0.254)
		(layer "In6.Cu")
		(net "GND")
	)
	(segment
		(start 17.464024 -43.706034)
		(end 17.464024 -42.59453)
		(width 0.254)
		(layer "In6.Cu")
		(net "GND")
	)
	(segment
		(start 59.796172 -146.834098)
		(end 56.757062 -146.834098)
		(width 0.254)
		(layer "In6.Cu")
		(net "GND")
	)
	(segment
		(start 54.14772 -149.229826)
		(end 55.988712 -147.388834)
		(width 0.254)
		(layer "In6.Cu")
		(net "GND")
	)
	(segment
		(start 38.3286 -146.723354)
		(end 38.878256 -147.27301)
		(width 0.254)
		(layer "In6.Cu")
		(net "GND")
	)
	(segment
		(start 38.419532 -144.348962)
		(end 33.77184 -139.70127)
		(width 0.254)
		(layer "In6.Cu")
		(net "GND")
	)
	(segment
		(start 63.333376 -140.457936)
		(end 63.333376 -141.258036)
		(width 0.254)
		(layer "In6.Cu")
		(net "GND")
	)
	(segment
		(start 9.64946 -97.977706)
		(end 9.64946 -115.067588)
		(width 0.254)
		(layer "In6.Cu")
		(net "GND")
	)
	(segment
		(start 31.83636 -141.75486)
		(end 31.83636 -141.758416)
		(width 0.254)
		(layer "In6.Cu")
		(net "GND")
	)
	(segment
		(start 19.96948 -58.996834)
		(end 20.11934 -59.146694)
		(width 0.254)
		(layer "In6.Cu")
		(net "GND")
	)
	(segment
		(start 20.83562 -51.15687)
		(end 21.229066 -51.550316)
		(width 0.254)
		(layer "In6.Cu")
		(net "GND")
	)
	(segment
		(start 58.051954 -144.51076)
		(end 58.727086 -143.835628)
		(width 0.254)
		(layer "In6.Cu")
		(net "GND")
	)
	(segment
		(start 18.755868 -57.187592)
		(end 19.967956 -58.39968)
		(width 0.254)
		(layer "In6.Cu")
		(net "GND")
	)
	(segment
		(start 42.31767 -149.835616)
		(end 46.267624 -149.835616)
		(width 0.254)
		(layer "In6.Cu")
		(net "GND")
	)
	(segment
		(start 48.06061 -145.784824)
		(end 49.039526 -145.784824)
		(width 0.254)
		(layer "In6.Cu")
		(net "GND")
	)
	(segment
		(start 24.42464 -58.830972)
		(end 24.10206 -59.153552)
		(width 0.254)
		(layer "In6.Cu")
		(net "GND")
	)
	(segment
		(start 39.755064 -147.27301)
		(end 41.8084 -149.326346)
		(width 0.254)
		(layer "In6.Cu")
		(net "GND")
	)
	(segment
		(start 24.426672 -58.222642)
		(end 24.426672 -58.830972)
		(width 0.254)
		(layer "In6.Cu")
		(net "GND")
	)
	(segment
		(start 21.57476 -74.81951)
		(end 21.57476 -65.343532)
		(width 0.254)
		(layer "In6.Cu")
		(net "GND")
	)
	(segment
		(start 24.426672 -58.830972)
		(end 24.42464 -58.830972)
		(width 0.254)
		(layer "In6.Cu")
		(net "GND")
	)
	(segment
		(start 21.229066 -51.550316)
		(end 21.229066 -54.425342)
		(width 0.254)
		(layer "In6.Cu")
		(net "GND")
	)
	(segment
		(start 46.267624 -149.835616)
		(end 46.873414 -149.229826)
		(width 0.254)
		(layer "In6.Cu")
		(net "GND")
	)
	(segment
		(start 10.90422 -139.106148)
		(end 9.856978 -138.058906)
		(width 0.254)
		(layer "In6.Cu")
		(net "GND")
	)
	(segment
		(start 24.10206 -59.153552)
		(end 24.10206 -60.423044)
		(width 0.254)
		(layer "In6.Cu")
		(net "GND")
	)
	(segment
		(start 20.63242 -79.426816)
		(end 20.63242 -86.994746)
		(width 0.254)
		(layer "In6.Cu")
		(net "GND")
	)
	(segment
		(start 58.727086 -143.835628)
		(end 58.727086 -143.819118)
		(width 0.254)
		(layer "In6.Cu")
		(net "GND")
	)
	(segment
		(start 15.38732 -139.106148)
		(end 10.90422 -139.106148)
		(width 0.254)
		(layer "In6.Cu")
		(net "GND")
	)
	(segment
		(start 19.96948 -58.39968)
		(end 19.96948 -58.996834)
		(width 0.254)
		(layer "In6.Cu")
		(net "GND")
	)
	(segment
		(start 16.3703 -87.667084)
		(end 16.3703 -80.023462)
		(width 0.254)
		(layer "In6.Cu")
		(net "GND")
	)
	(segment
		(start 17.213326 -140.932154)
		(end 16.830548 -140.549376)
		(width 0.254)
		(layer "In6.Cu")
		(net "GND")
	)
	(segment
		(start 24.26208 -58.060082)
		(end 24.264112 -58.060082)
		(width 0.254)
		(layer "In6.Cu")
		(net "GND")
	)
	(segment
		(start 55.499 -144.51076)
		(end 58.051954 -144.51076)
		(width 0.254)
		(layer "In6.Cu")
		(net "GND")
	)
	(segment
		(start 31.83636 -141.758416)
		(end 36.382198 -146.304254)
		(width 0.254)
		(layer "In6.Cu")
		(net "GND")
	)
	(segment
		(start 56.757062 -146.834098)
		(end 56.54294 -146.834098)
		(width 0.254)
		(layer "In6.Cu")
		(net "GND")
	)
	(segment
		(start 17.594834 -41.03116)
		(end 19.267932 -41.03116)
		(width 0.254)
		(layer "In6.Cu")
		(net "GND")
	)
	(segment
		(start 63.56604 -142.09776)
		(end 63.56604 -143.06423)
		(width 0.254)
		(layer "In6.Cu")
		(net "GND")
	)
	(segment
		(start 20.921472 -75.47229)
		(end 20.92198 -75.47229)
		(width 0.254)
		(layer "In6.Cu")
		(net "GND")
	)
	(segment
		(start 18.342864 -137.285222)
		(end 16.985742 -135.9281)
		(width 0.254)
		(layer "In6.Cu")
		(net "GND")
	)
	(segment
		(start 40.24122 -144.382998)
		(end 40.207184 -144.348962)
		(width 0.254)
		(layer "In6.Cu")
		(net "GND")
	)
	(segment
		(start 41.095422 -145.2372)
		(end 40.24122 -144.382998)
		(width 0.254)
		(layer "In6.Cu")
		(net "GND")
	)
	(segment
		(start 9.20496 -136.650222)
		(end 9.856978 -137.30224)
		(width 0.254)
		(layer "In6.Cu")
		(net "GND")
	)
	(segment
		(start 44.8564 -146.1008)
		(end 44.2595 -145.5039)
		(width 0.254)
		(layer "In6.Cu")
		(net "GND")
	)
	(segment
		(start 44.2595 -145.5039)
		(end 44.1325 -145.5039)
		(width 0.254)
		(layer "In6.Cu")
		(net "GND")
	)
	(segment
		(start 37.25418 -146.723354)
		(end 38.3286 -146.723354)
		(width 0.254)
		(layer "In6.Cu")
		(net "GND")
	)
	(segment
		(start 47.918116 -145.64233)
		(end 48.06061 -145.784824)
		(width 0.254)
		(layer "In6.Cu")
		(net "GND")
	)
	(segment
		(start 7.1755 -134.149084)
		(end 9.20496 -136.178544)
		(width 0.254)
		(layer "In6.Cu")
		(net "GND")
	)
	(segment
		(start 12.507976 -91.529408)
		(end 16.3703 -87.667084)
		(width 0.254)
		(layer "In6.Cu")
		(net "GND")
	)
	(segment
		(start 41.8084 -149.326346)
		(end 41.8084 -149.527006)
		(width 0.254)
		(layer "In6.Cu")
		(net "GND")
	)
	(segment
		(start 16.40078 -44.769278)
		(end 17.464024 -43.706034)
		(width 0.254)
		(layer "In6.Cu")
		(net "GND")
	)
	(segment
		(start 62.533276 -140.457936)
		(end 63.333376 -140.457936)
		(width 0.254)
		(layer "In6.Cu")
		(net "GND")
	)
	(segment
		(start 20.0152 -43.27525)
		(end 20.58162 -43.84167)
		(width 0.254)
		(layer "In6.Cu")
		(net "GND")
	)
	(segment
		(start 19.967956 -58.39968)
		(end 19.96948 -58.39968)
		(width 0.254)
		(layer "In6.Cu")
		(net "GND")
	)
	(segment
		(start 7.1755 -119.907304)
		(end 7.1755 -134.149084)
		(width 0.254)
		(layer "In6.Cu")
		(net "GND")
	)
	(segment
		(start 38.878256 -147.27301)
		(end 39.755064 -147.27301)
		(width 0.254)
		(layer "In6.Cu")
		(net "GND")
	)
	(segment
		(start 61.591444 -140.95476)
		(end 62.036452 -140.95476)
		(width 0.254)
		(layer "In6.Cu")
		(net "GND")
	)
	(segment
		(start 32.91332 -138.84275)
		(end 19.900392 -138.84275)
		(width 0.254)
		(layer "In6.Cu")
		(net "GND")
	)
	(segment
		(start 36.83508 -146.304254)
		(end 37.25418 -146.723354)
		(width 0.254)
		(layer "In6.Cu")
		(net "GND")
	)
	(segment
		(start 20.0152 -44.40809)
		(end 20.58162 -43.84167)
		(width 0.254)
		(layer "In6.Cu")
		(net "GND")
	)
	(segment
		(start 9.856978 -137.30224)
		(end 9.856978 -138.058906)
		(width 0.254)
		(layer "In6.Cu")
		(net "GND")
	)
	(segment
		(start 55.01386 -144.9959)
		(end 55.499 -144.51076)
		(width 0.254)
		(layer "In6.Cu")
		(net "GND")
	)
	(segment
		(start 24.10206 -60.423044)
		(end 23.6728 -60.852304)
		(width 0.254)
		(layer "In6.Cu")
		(net "GND")
	)
	(segment
		(start 21.57476 -65.343532)
		(end 20.66798 -64.436752)
		(width 0.254)
		(layer "In6.Cu")
		(net "GND")
	)
	(segment
		(start 41.8084 -149.527006)
		(end 42.10558 -149.82444)
		(width 0.254)
		(layer "In6.Cu")
		(net "GND")
	)
	(segment
		(start 24.264112 -58.060082)
		(end 24.426672 -58.222642)
		(width 0.254)
		(layer "In6.Cu")
		(net "GND")
	)
	(segment
		(start 56.52262 -146.854926)
		(end 55.988712 -147.388834)
		(width 0.254)
		(layer "In6.Cu")
		(net "GND")
	)
	(segment
		(start 43.8658 -145.2372)
		(end 41.095422 -145.2372)
		(width 0.254)
		(layer "In6.Cu")
		(net "GND")
	)
	(segment
		(start 20.83562 -48.700182)
		(end 20.0152 -47.879762)
		(width 0.254)
		(layer "In6.Cu")
		(net "GND")
	)
	(segment
		(start 17.464024 -42.59453)
		(end 17.4625 -42.593006)
		(width 0.254)
		(layer "In6.Cu")
		(net "GND")
	)
	(segment
		(start 23.6728 -60.852304)
		(end 23.6728 -76.386436)
		(width 0.254)
		(layer "In6.Cu")
		(net "GND")
	)
	(segment
		(start 16.3703 -80.023462)
		(end 20.921472 -75.47229)
		(width 0.254)
		(layer "In6.Cu")
		(net "GND")
	)
	(segment
		(start 7.1755 -96.861884)
		(end 12.507976 -91.529408)
		(width 0.254)
		(layer "In6.Cu")
		(net "GND")
	)
	(segment
		(start 20.0152 -47.879762)
		(end 20.0152 -44.40809)
		(width 0.254)
		(layer "In6.Cu")
		(net "GND")
	)
	(segment
		(start 17.2974 -41.749726)
		(end 17.2974 -41.328594)
		(width 0.254)
		(layer "In6.Cu")
		(net "GND")
	)
	(segment
		(start 63.333376 -141.258036)
		(end 63.333376 -141.865096)
		(width 0.254)
		(layer "In6.Cu")
		(net "GND")
	)
	(segment
		(start 63.333376 -141.865096)
		(end 63.56604 -142.09776)
		(width 0.254)
		(layer "In6.Cu")
		(net "GND")
	)
	(segment
		(start 16.985742 -135.9281)
		(end 13.442188 -135.9281)
		(width 0.254)
		(layer "In6.Cu")
		(net "GND")
	)
	(segment
		(start 7.1755 -119.907304)
		(end 7.1755 -111.43996)
		(width 0.254)
		(layer "In6.Cu")
		(net "GND")
	)
	(segment
		(start 62.036452 -140.95476)
		(end 62.533276 -140.457936)
		(width 0.254)
		(layer "In6.Cu")
		(net "GND")
	)
	(segment
		(start 23.6728 -76.386436)
		(end 20.63242 -79.426816)
		(width 0.254)
		(layer "In6.Cu")
		(net "GND")
	)
	(segment
		(start 18.3261 -57.187592)
		(end 16.40078 -55.262272)
		(width 0.254)
		(layer "In6.Cu")
		(net "GND")
	)
	(segment
		(start 46.873414 -149.229826)
		(end 54.14772 -149.229826)
		(width 0.254)
		(layer "In6.Cu")
		(net "GND")
	)
	(segment
		(start 20.83562 -48.700182)
		(end 20.83562 -51.15687)
		(width 0.254)
		(layer "In6.Cu")
		(net "GND")
	)
	(segment
		(start 31.010098 -140.932154)
		(end 17.213326 -140.932154)
		(width 0.254)
		(layer "In6.Cu")
		(net "GND")
	)
	(segment
		(start 20.0152 -41.778428)
		(end 20.0152 -43.27525)
		(width 0.254)
		(layer "In6.Cu")
		(net "GND")
	)
	(segment
		(start 17.4625 -42.593006)
		(end 17.4625 -41.914826)
		(width 0.254)
		(layer "In6.Cu")
		(net "GND")
	)
	(segment
		(start 19.267932 -41.03116)
		(end 20.0152 -41.778428)
		(width 0.254)
		(layer "In6.Cu")
		(net "GND")
	)
	(segment
		(start 63.56604 -143.06423)
		(end 59.796172 -146.834098)
		(width 0.254)
		(layer "In6.Cu")
		(net "GND")
	)
	(segment
		(start 157.188408 -36.384992)
		(end 154.000454 -39.572946)
		(width 0.1016)
		(layer "F.Cu")
		(net "UART_DTR_P1_N")
	)
	(segment
		(start 146.8882 -41.389808)
		(end 147.293838 -40.98417)
		(width 0.1016)
		(layer "F.Cu")
		(net "UART_DTR_P1_N")
	)
	(segment
		(start 145.571718 -41.389808)
		(end 146.8882 -41.389808)
		(width 0.1016)
		(layer "F.Cu")
		(net "UART_DTR_P1_N")
	)
	(segment
		(start 150.073868 -39.572946)
		(end 149.057868 -39.572946)
		(width 0.1016)
		(layer "F.Cu")
		(net "UART_DTR_P1_N")
	)
	(segment
		(start 148.705062 -39.572946)
		(end 147.293838 -40.98417)
		(width 0.1016)
		(layer "F.Cu")
		(net "UART_DTR_P1_N")
	)
	(segment
		(start 154.000454 -39.572946)
		(end 150.073868 -39.572946)
		(width 0.1016)
		(layer "F.Cu")
		(net "UART_DTR_P1_N")
	)
	(segment
		(start 158.271972 -36.384992)
		(end 157.188408 -36.384992)
		(width 0.1016)
		(layer "F.Cu")
		(net "UART_DTR_P1_N")
	)
	(segment
		(start 149.057868 -39.572946)
		(end 148.705062 -39.572946)
		(width 0.1016)
		(layer "F.Cu")
		(net "UART_DTR_P1_N")
	)
	(via
		(at 147.293838 -40.98417)
		(size 0.508)
		(drill 0.254)
		(layers "F.Cu" "B.Cu")
		(net "UART_DTR_P1_N")
	)
	(segment
		(start 174.646336 -60.284868)
		(end 174.646336 -59.190636)
		(width 0.4064)
		(layer "F.Cu")
		(net "USBPWR_P1")
	)
	(via
		(at 172.79874 -55.208678)
		(size 0.508)
		(drill 0.254)
		(layers "F.Cu" "B.Cu")
		(net "USBPWR_P1")
	)
	(via
		(at 172.77588 -50.98415)
		(size 0.508)
		(drill 0.254)
		(layers "F.Cu" "B.Cu")
		(net "USBPWR_P1")
	)
	(via
		(at 174.646336 -59.190636)
		(size 0.508)
		(drill 0.254)
		(layers "F.Cu" "B.Cu")
		(net "USBPWR_P1")
	)
	(via
		(at 176.15916 -52.253134)
		(size 0.508)
		(drill 0.254)
		(layers "F.Cu" "B.Cu")
		(net "USBPWR_P1")
	)
	(via
		(at 175.76038 -55.07228)
		(size 0.508)
		(drill 0.254)
		(layers "F.Cu" "B.Cu")
		(net "USBPWR_P1")
	)
	(via
		(at 173.16958 -51.692556)
		(size 0.508)
		(drill 0.254)
		(layers "F.Cu" "B.Cu")
		(net "USBPWR_P1")
	)
	(via
		(at 177.2412 -52.293266)
		(size 0.508)
		(drill 0.254)
		(layers "F.Cu" "B.Cu")
		(net "USBPWR_P1")
	)
	(via
		(at 175.21428 -51.686714)
		(size 0.508)
		(drill 0.254)
		(layers "F.Cu" "B.Cu")
		(net "USBPWR_P1")
	)
	(via
		(at 172.3771 -51.68392)
		(size 0.508)
		(drill 0.254)
		(layers "F.Cu" "B.Cu")
		(net "USBPWR_P1")
	)
	(via
		(at 175.77054 -56.174132)
		(size 0.508)
		(drill 0.254)
		(layers "F.Cu" "B.Cu")
		(net "USBPWR_P1")
	)
	(via
		(at 175.68926 -53.8734)
		(size 0.508)
		(drill 0.254)
		(layers "F.Cu" "B.Cu")
		(net "USBPWR_P1")
	)
	(via
		(at 175.21428 -50.840386)
		(size 0.508)
		(drill 0.254)
		(layers "F.Cu" "B.Cu")
		(net "USBPWR_P1")
	)
	(via
		(at 173.19498 -54.595268)
		(size 0.508)
		(drill 0.254)
		(layers "F.Cu" "B.Cu")
		(net "USBPWR_P1")
	)
	(via
		(at 172.4025 -54.586632)
		(size 0.508)
		(drill 0.254)
		(layers "F.Cu" "B.Cu")
		(net "USBPWR_P1")
	)
	(segment
		(start 50.201322 -149.792182)
		(end 50.201322 -149.79269)
		(width 0.1016)
		(layer "F.Cu")
		(net "PLT_RST_LAN1_N")
	)
	(segment
		(start 49.357026 -149.79269)
		(end 49.97196 -149.79269)
		(width 0.1016)
		(layer "F.Cu")
		(net "PLT_RST_LAN1_N")
	)
	(segment
		(start 49.117504 -150.032212)
		(end 49.357026 -149.79269)
		(width 0.1016)
		(layer "F.Cu")
		(net "PLT_RST_LAN1_N")
	)
	(segment
		(start 51.823112 -149.578822)
		(end 50.414682 -149.578822)
		(width 0.1016)
		(layer "F.Cu")
		(net "PLT_RST_LAN1_N")
	)
	(segment
		(start 49.117504 -151.172926)
		(end 49.117504 -150.032212)
		(width 0.1016)
		(layer "F.Cu")
		(net "PLT_RST_LAN1_N")
	)
	(segment
		(start 50.414682 -149.578822)
		(end 50.201322 -149.792182)
		(width 0.1016)
		(layer "F.Cu")
		(net "PLT_RST_LAN1_N")
	)
	(segment
		(start 50.201322 -149.79269)
		(end 49.97196 -149.79269)
		(width 0.1016)
		(layer "F.Cu")
		(net "PLT_RST_LAN1_N")
	)
	(via
		(at 49.97196 -149.79269)
		(size 0.508)
		(drill 0.254)
		(layers "F.Cu" "B.Cu")
		(net "PLT_RST_LAN1_N")
	)
	(via
		(at 158.318454 -49.414176)
		(size 0.6604)
		(drill 0.3302)
		(layers "F.Cu" "B.Cu")
		(net "SATA_RX0_C_DN")
	)
	(segment
		(start 159.101536 -49.908206)
		(end 159.401764 -49.607978)
		(width 0.10414)
		(layer "B.Cu")
		(net "SATA_RX0_C_DN")
	)
	(segment
		(start 156.005276 -49.908206)
		(end 157.824424 -49.908206)
		(width 0.10414)
		(layer "B.Cu")
		(net "SATA_RX0_C_DN")
	)
	(segment
		(start 158.318454 -49.414176)
		(end 158.318454 -49.804066)
		(width 0.10414)
		(layer "B.Cu")
		(net "SATA_RX0_C_DN")
	)
	(segment
		(start 158.422594 -49.908206)
		(end 159.101536 -49.908206)
		(width 0.10414)
		(layer "B.Cu")
		(net "SATA_RX0_C_DN")
	)
	(segment
		(start 158.318454 -49.804066)
		(end 158.422594 -49.908206)
		(width 0.10414)
		(layer "B.Cu")
		(net "SATA_RX0_C_DN")
	)
	(segment
		(start 155.372308 -49.275238)
		(end 156.005276 -49.908206)
		(width 0.10414)
		(layer "B.Cu")
		(net "SATA_RX0_C_DN")
	)
	(segment
		(start 157.824424 -49.908206)
		(end 158.318454 -49.414176)
		(width 0.10414)
		(layer "B.Cu")
		(net "SATA_RX0_C_DN")
	)
	(segment
		(start 156.111956 -66.143124)
		(end 155.756864 -66.498216)
		(width 0.10414)
		(layer "F.Cu")
		(net "SATA_TX0_C_DP")
	)
	(segment
		(start 164.111432 -58.063384)
		(end 164.111432 -58.589418)
		(width 0.10414)
		(layer "F.Cu")
		(net "SATA_TX0_C_DP")
	)
	(segment
		(start 156.557726 -66.143124)
		(end 156.111956 -66.143124)
		(width 0.10414)
		(layer "F.Cu")
		(net "SATA_TX0_C_DP")
	)
	(segment
		(start 165.34511 -51.121564)
		(end 165.34511 -56.829706)
		(width 0.10414)
		(layer "F.Cu")
		(net "SATA_TX0_C_DP")
	)
	(segment
		(start 164.111432 -58.589418)
		(end 156.557726 -66.143124)
		(width 0.10414)
		(layer "F.Cu")
		(net "SATA_TX0_C_DP")
	)
	(segment
		(start 158.6992 -45.708062)
		(end 159.11703 -46.125892)
		(width 0.10414)
		(layer "F.Cu")
		(net "SATA_TX0_C_DP")
	)
	(segment
		(start 159.11703 -46.125892)
		(end 160.349438 -46.125892)
		(width 0.10414)
		(layer "F.Cu")
		(net "SATA_TX0_C_DP")
	)
	(segment
		(start 165.34511 -56.829706)
		(end 164.111432 -58.063384)
		(width 0.10414)
		(layer "F.Cu")
		(net "SATA_TX0_C_DP")
	)
	(segment
		(start 160.349438 -46.125892)
		(end 165.34511 -51.121564)
		(width 0.10414)
		(layer "F.Cu")
		(net "SATA_TX0_C_DP")
	)
	(via
		(at 158.6992 -45.708062)
		(size 0.508)
		(drill 0.254)
		(layers "F.Cu" "B.Cu")
		(net "SATA_TX0_C_DP")
	)
	(segment
		(start 155.372308 -45.465238)
		(end 156.005022 -46.097952)
		(width 0.10414)
		(layer "B.Cu")
		(net "SATA_TX0_C_DP")
	)
	(segment
		(start 158.30931 -46.097952)
		(end 158.6992 -45.708062)
		(width 0.10414)
		(layer "B.Cu")
		(net "SATA_TX0_C_DP")
	)
	(segment
		(start 156.005022 -46.097952)
		(end 158.30931 -46.097952)
		(width 0.10414)
		(layer "B.Cu")
		(net "SATA_TX0_C_DP")
	)
	(segment
		(start 147.89023 -41.88968)
		(end 145.571718 -41.88968)
		(width 0.1016)
		(layer "F.Cu")
		(net "UART_RTS_P1_N")
	)
	(segment
		(start 154.872944 -39.934896)
		(end 152.974802 -39.934896)
		(width 0.1016)
		(layer "F.Cu")
		(net "UART_RTS_P1_N")
	)
	(segment
		(start 148.854414 -42.096182)
		(end 148.096732 -42.096182)
		(width 0.1016)
		(layer "F.Cu")
		(net "UART_RTS_P1_N")
	)
	(segment
		(start 148.096732 -42.096182)
		(end 147.89023 -41.88968)
		(width 0.1016)
		(layer "F.Cu")
		(net "UART_RTS_P1_N")
	)
	(segment
		(start 152.974802 -39.934896)
		(end 150.8506 -42.059098)
		(width 0.1016)
		(layer "F.Cu")
		(net "UART_RTS_P1_N")
	)
	(segment
		(start 157.122876 -37.684964)
		(end 155.811728 -38.996112)
		(width 0.1016)
		(layer "F.Cu")
		(net "UART_RTS_P1_N")
	)
	(segment
		(start 155.811728 -38.996112)
		(end 154.872944 -39.934896)
		(width 0.1016)
		(layer "F.Cu")
		(net "UART_RTS_P1_N")
	)
	(segment
		(start 150.8506 -42.059098)
		(end 150.277322 -42.059098)
		(width 0.1016)
		(layer "F.Cu")
		(net "UART_RTS_P1_N")
	)
	(segment
		(start 150.277322 -42.059098)
		(end 150.055326 -42.281094)
		(width 0.1016)
		(layer "F.Cu")
		(net "UART_RTS_P1_N")
	)
	(segment
		(start 149.039326 -42.281094)
		(end 148.854414 -42.096182)
		(width 0.1016)
		(layer "F.Cu")
		(net "UART_RTS_P1_N")
	)
	(segment
		(start 150.055326 -42.281094)
		(end 149.039326 -42.281094)
		(width 0.1016)
		(layer "F.Cu")
		(net "UART_RTS_P1_N")
	)
	(segment
		(start 158.271972 -37.684964)
		(end 157.122876 -37.684964)
		(width 0.1016)
		(layer "F.Cu")
		(net "UART_RTS_P1_N")
	)
	(via
		(at 155.811728 -38.996112)
		(size 0.508)
		(drill 0.254)
		(layers "F.Cu" "B.Cu")
		(net "UART_RTS_P1_N")
	)
	(segment
		(start 160.405572 -46.796452)
		(end 160.405572 -46.990508)
		(width 0.10414)
		(layer "F.Cu")
		(net "SATA_TX0_C_DN")
	)
	(segment
		(start 164.91077 -51.30165)
		(end 164.91077 -56.64962)
		(width 0.10414)
		(layer "F.Cu")
		(net "SATA_TX0_C_DN")
	)
	(segment
		(start 159.26562 -62.820804)
		(end 159.044386 -63.042038)
		(width 0.10414)
		(layer "F.Cu")
		(net "SATA_TX0_C_DN")
	)
	(segment
		(start 157.182312 -64.904112)
		(end 156.37764 -65.708784)
		(width 0.10414)
		(layer "F.Cu")
		(net "SATA_TX0_C_DN")
	)
	(segment
		(start 157.876748 -64.209676)
		(end 157.655514 -64.43091)
		(width 0.10414)
		(layer "F.Cu")
		(net "SATA_TX0_C_DN")
	)
	(segment
		(start 160.875726 -60.95873)
		(end 160.654492 -61.179964)
		(width 0.10414)
		(layer "F.Cu")
		(net "SATA_TX0_C_DN")
	)
	(segment
		(start 161.348928 -60.737496)
		(end 161.127694 -60.95873)
		(width 0.10414)
		(layer "F.Cu")
		(net "SATA_TX0_C_DN")
	)
	(segment
		(start 160.405572 -46.990508)
		(end 160.626552 -47.211488)
		(width 0.10414)
		(layer "F.Cu")
		(net "SATA_TX0_C_DN")
	)
	(segment
		(start 159.11703 -46.560232)
		(end 160.169352 -46.560232)
		(width 0.10414)
		(layer "F.Cu")
		(net "SATA_TX0_C_DN")
	)
	(segment
		(start 158.571184 -63.51524)
		(end 158.34995 -63.736474)
		(width 0.10414)
		(layer "F.Cu")
		(net "SATA_TX0_C_DN")
	)
	(segment
		(start 159.738822 -62.347602)
		(end 159.486854 -62.347602)
		(width 0.10414)
		(layer "F.Cu")
		(net "SATA_TX0_C_DN")
	)
	(segment
		(start 160.654492 -61.431932)
		(end 160.433258 -61.653166)
		(width 0.10414)
		(layer "F.Cu")
		(net "SATA_TX0_C_DN")
	)
	(segment
		(start 161.348928 -60.485528)
		(end 161.348928 -60.737496)
		(width 0.10414)
		(layer "F.Cu")
		(net "SATA_TX0_C_DN")
	)
	(segment
		(start 161.677604 -48.068484)
		(end 161.677604 -48.26254)
		(width 0.10414)
		(layer "F.Cu")
		(net "SATA_TX0_C_DN")
	)
	(segment
		(start 160.433258 -61.653166)
		(end 160.18129 -61.653166)
		(width 0.10414)
		(layer "F.Cu")
		(net "SATA_TX0_C_DN")
	)
	(segment
		(start 159.960056 -61.8744)
		(end 159.960056 -62.126368)
		(width 0.10414)
		(layer "F.Cu")
		(net "SATA_TX0_C_DN")
	)
	(segment
		(start 161.041588 -47.626524)
		(end 161.262568 -47.847504)
		(width 0.10414)
		(layer "F.Cu")
		(net "SATA_TX0_C_DN")
	)
	(segment
		(start 159.486854 -62.347602)
		(end 159.26562 -62.568836)
		(width 0.10414)
		(layer "F.Cu")
		(net "SATA_TX0_C_DN")
	)
	(segment
		(start 161.82213 -60.264294)
		(end 161.570162 -60.264294)
		(width 0.10414)
		(layer "F.Cu")
		(net "SATA_TX0_C_DN")
	)
	(segment
		(start 158.792418 -63.042038)
		(end 158.571184 -63.263272)
		(width 0.10414)
		(layer "F.Cu")
		(net "SATA_TX0_C_DN")
	)
	(segment
		(start 157.876748 -63.957708)
		(end 157.876748 -64.209676)
		(width 0.10414)
		(layer "F.Cu")
		(net "SATA_TX0_C_DN")
	)
	(segment
		(start 162.31362 -48.898556)
		(end 162.5346 -49.119536)
		(width 0.10414)
		(layer "F.Cu")
		(net "SATA_TX0_C_DN")
	)
	(segment
		(start 161.262568 -47.847504)
		(end 161.456624 -47.847504)
		(width 0.10414)
		(layer "F.Cu")
		(net "SATA_TX0_C_DN")
	)
	(segment
		(start 159.26562 -62.568836)
		(end 159.26562 -62.820804)
		(width 0.10414)
		(layer "F.Cu")
		(net "SATA_TX0_C_DN")
	)
	(segment
		(start 158.097982 -63.736474)
		(end 157.876748 -63.957708)
		(width 0.10414)
		(layer "F.Cu")
		(net "SATA_TX0_C_DN")
	)
	(segment
		(start 157.655514 -64.43091)
		(end 157.403546 -64.43091)
		(width 0.10414)
		(layer "F.Cu")
		(net "SATA_TX0_C_DN")
	)
	(segment
		(start 162.09264 -48.48352)
		(end 162.31362 -48.7045)
		(width 0.10414)
		(layer "F.Cu")
		(net "SATA_TX0_C_DN")
	)
	(segment
		(start 160.626552 -47.211488)
		(end 160.820608 -47.211488)
		(width 0.10414)
		(layer "F.Cu")
		(net "SATA_TX0_C_DN")
	)
	(segment
		(start 160.654492 -61.179964)
		(end 160.654492 -61.431932)
		(width 0.10414)
		(layer "F.Cu")
		(net "SATA_TX0_C_DN")
	)
	(segment
		(start 161.898584 -48.48352)
		(end 162.09264 -48.48352)
		(width 0.10414)
		(layer "F.Cu")
		(net "SATA_TX0_C_DN")
	)
	(segment
		(start 161.041588 -47.432468)
		(end 161.041588 -47.626524)
		(width 0.10414)
		(layer "F.Cu")
		(net "SATA_TX0_C_DN")
	)
	(segment
		(start 159.960056 -62.126368)
		(end 159.738822 -62.347602)
		(width 0.10414)
		(layer "F.Cu")
		(net "SATA_TX0_C_DN")
	)
	(segment
		(start 157.182312 -64.652144)
		(end 157.182312 -64.904112)
		(width 0.10414)
		(layer "F.Cu")
		(net "SATA_TX0_C_DN")
	)
	(segment
		(start 160.18129 -61.653166)
		(end 159.960056 -61.8744)
		(width 0.10414)
		(layer "F.Cu")
		(net "SATA_TX0_C_DN")
	)
	(segment
		(start 163.677092 -58.409332)
		(end 161.82213 -60.264294)
		(width 0.10414)
		(layer "F.Cu")
		(net "SATA_TX0_C_DN")
	)
	(segment
		(start 156.37764 -65.708784)
		(end 155.983432 -65.708784)
		(width 0.10414)
		(layer "F.Cu")
		(net "SATA_TX0_C_DN")
	)
	(segment
		(start 158.571184 -63.263272)
		(end 158.571184 -63.51524)
		(width 0.10414)
		(layer "F.Cu")
		(net "SATA_TX0_C_DN")
	)
	(segment
		(start 159.044386 -63.042038)
		(end 158.792418 -63.042038)
		(width 0.10414)
		(layer "F.Cu")
		(net "SATA_TX0_C_DN")
	)
	(segment
		(start 161.127694 -60.95873)
		(end 160.875726 -60.95873)
		(width 0.10414)
		(layer "F.Cu")
		(net "SATA_TX0_C_DN")
	)
	(segment
		(start 158.6992 -46.978062)
		(end 159.11703 -46.560232)
		(width 0.10414)
		(layer "F.Cu")
		(net "SATA_TX0_C_DN")
	)
	(segment
		(start 163.677092 -57.883298)
		(end 163.677092 -58.409332)
		(width 0.10414)
		(layer "F.Cu")
		(net "SATA_TX0_C_DN")
	)
	(segment
		(start 155.983432 -65.708784)
		(end 155.756864 -65.482216)
		(width 0.10414)
		(layer "F.Cu")
		(net "SATA_TX0_C_DN")
	)
	(segment
		(start 162.728656 -49.119536)
		(end 164.91077 -51.30165)
		(width 0.10414)
		(layer "F.Cu")
		(net "SATA_TX0_C_DN")
	)
	(segment
		(start 162.5346 -49.119536)
		(end 162.728656 -49.119536)
		(width 0.10414)
		(layer "F.Cu")
		(net "SATA_TX0_C_DN")
	)
	(segment
		(start 160.169352 -46.560232)
		(end 160.405572 -46.796452)
		(width 0.10414)
		(layer "F.Cu")
		(net "SATA_TX0_C_DN")
	)
	(segment
		(start 162.31362 -48.7045)
		(end 162.31362 -48.898556)
		(width 0.10414)
		(layer "F.Cu")
		(net "SATA_TX0_C_DN")
	)
	(segment
		(start 161.677604 -48.26254)
		(end 161.898584 -48.48352)
		(width 0.10414)
		(layer "F.Cu")
		(net "SATA_TX0_C_DN")
	)
	(segment
		(start 164.91077 -56.64962)
		(end 163.677092 -57.883298)
		(width 0.10414)
		(layer "F.Cu")
		(net "SATA_TX0_C_DN")
	)
	(segment
		(start 158.34995 -63.736474)
		(end 158.097982 -63.736474)
		(width 0.10414)
		(layer "F.Cu")
		(net "SATA_TX0_C_DN")
	)
	(segment
		(start 161.456624 -47.847504)
		(end 161.677604 -48.068484)
		(width 0.10414)
		(layer "F.Cu")
		(net "SATA_TX0_C_DN")
	)
	(segment
		(start 161.570162 -60.264294)
		(end 161.348928 -60.485528)
		(width 0.10414)
		(layer "F.Cu")
		(net "SATA_TX0_C_DN")
	)
	(segment
		(start 160.820608 -47.211488)
		(end 161.041588 -47.432468)
		(width 0.10414)
		(layer "F.Cu")
		(net "SATA_TX0_C_DN")
	)
	(segment
		(start 157.403546 -64.43091)
		(end 157.182312 -64.652144)
		(width 0.10414)
		(layer "F.Cu")
		(net "SATA_TX0_C_DN")
	)
	(via
		(at 158.6992 -46.978062)
		(size 0.508)
		(drill 0.254)
		(layers "F.Cu" "B.Cu")
		(net "SATA_TX0_C_DN")
	)
	(segment
		(start 155.372308 -47.16526)
		(end 156.005276 -46.532292)
		(width 0.10414)
		(layer "B.Cu")
		(net "SATA_TX0_C_DN")
	)
	(segment
		(start 158.25343 -46.532292)
		(end 158.6992 -46.978062)
		(width 0.10414)
		(layer "B.Cu")
		(net "SATA_TX0_C_DN")
	)
	(segment
		(start 156.005276 -46.532292)
		(end 158.25343 -46.532292)
		(width 0.10414)
		(layer "B.Cu")
		(net "SATA_TX0_C_DN")
	)
	(via
		(at 80.31226 -165.003734)
		(size 0.6604)
		(drill 0.3302)
		(layers "F.Cu" "B.Cu")
		(net "SDC_WAKEUP")
	)
	(segment
		(start 79.68615 -164.377624)
		(end 79.23149 -164.377624)
		(width 0.1016)
		(layer "B.Cu")
		(net "SDC_WAKEUP")
	)
	(segment
		(start 80.97774 -165.66515)
		(end 80.97774 -165.907212)
		(width 0.1016)
		(layer "B.Cu")
		(net "SDC_WAKEUP")
	)
	(segment
		(start 80.31226 -165.003734)
		(end 80.973676 -165.66515)
		(width 0.1016)
		(layer "B.Cu")
		(net "SDC_WAKEUP")
	)
	(segment
		(start 80.97774 -165.907212)
		(end 81.374996 -166.304468)
		(width 0.1016)
		(layer "B.Cu")
		(net "SDC_WAKEUP")
	)
	(segment
		(start 81.374996 -166.304468)
		(end 81.906872 -166.304468)
		(width 0.1016)
		(layer "B.Cu")
		(net "SDC_WAKEUP")
	)
	(segment
		(start 79.23149 -165.393624)
		(end 79.23149 -164.377624)
		(width 0.1016)
		(layer "B.Cu")
		(net "SDC_WAKEUP")
	)
	(segment
		(start 80.31226 -165.003734)
		(end 79.68615 -164.377624)
		(width 0.1016)
		(layer "B.Cu")
		(net "SDC_WAKEUP")
	)
	(segment
		(start 80.973676 -165.66515)
		(end 80.97774 -165.66515)
		(width 0.1016)
		(layer "B.Cu")
		(net "SDC_WAKEUP")
	)
	(via
		(at 158.318454 -50.836576)
		(size 0.6604)
		(drill 0.3302)
		(layers "F.Cu" "B.Cu")
		(net "SATA_RX0_C_DP")
	)
	(segment
		(start 158.318454 -50.836576)
		(end 158.318454 -50.446686)
		(width 0.10414)
		(layer "B.Cu")
		(net "SATA_RX0_C_DP")
	)
	(segment
		(start 155.372308 -50.97526)
		(end 156.005022 -50.342546)
		(width 0.10414)
		(layer "B.Cu")
		(net "SATA_RX0_C_DP")
	)
	(segment
		(start 156.005022 -50.342546)
		(end 157.824424 -50.342546)
		(width 0.10414)
		(layer "B.Cu")
		(net "SATA_RX0_C_DP")
	)
	(segment
		(start 158.318454 -50.446686)
		(end 158.422594 -50.342546)
		(width 0.10414)
		(layer "B.Cu")
		(net "SATA_RX0_C_DP")
	)
	(segment
		(start 158.422594 -50.342546)
		(end 159.120332 -50.342546)
		(width 0.10414)
		(layer "B.Cu")
		(net "SATA_RX0_C_DP")
	)
	(segment
		(start 157.824424 -50.342546)
		(end 158.318454 -50.836576)
		(width 0.10414)
		(layer "B.Cu")
		(net "SATA_RX0_C_DP")
	)
	(segment
		(start 159.120332 -50.342546)
		(end 159.401764 -50.623978)
		(width 0.10414)
		(layer "B.Cu")
		(net "SATA_RX0_C_DP")
	)
	(segment
		(start 137.2616 -27.846528)
		(end 137.2616 -30.079696)
		(width 0.1016)
		(layer "F.Cu")
		(net "SIO_VREF")
	)
	(segment
		(start 136.38657 -26.969466)
		(end 136.38657 -27.332686)
		(width 0.1016)
		(layer "F.Cu")
		(net "SIO_VREF")
	)
	(segment
		(start 137.03554 -27.620468)
		(end 137.2616 -27.846528)
		(width 0.1016)
		(layer "F.Cu")
		(net "SIO_VREF")
	)
	(segment
		(start 136.38657 -27.332686)
		(end 136.674352 -27.620468)
		(width 0.1016)
		(layer "F.Cu")
		(net "SIO_VREF")
	)
	(segment
		(start 136.674352 -27.620468)
		(end 137.03554 -27.620468)
		(width 0.1016)
		(layer "F.Cu")
		(net "SIO_VREF")
	)
	(via
		(at 137.03554 -27.620468)
		(size 0.508)
		(drill 0.254)
		(layers "F.Cu" "B.Cu")
		(net "SIO_VREF")
	)
	(segment
		(start 152.429972 -35.735006)
		(end 150.606252 -35.735006)
		(width 0.1016)
		(layer "F.Cu")
		(net "UART_DSR_P1_N")
	)
	(segment
		(start 144.270476 -42.389806)
		(end 143.071596 -41.190926)
		(width 0.1016)
		(layer "F.Cu")
		(net "UART_DSR_P1_N")
	)
	(segment
		(start 145.571718 -42.389806)
		(end 144.270476 -42.389806)
		(width 0.1016)
		(layer "F.Cu")
		(net "UART_DSR_P1_N")
	)
	(via
		(at 150.606252 -35.735006)
		(size 0.508)
		(drill 0.254)
		(layers "F.Cu" "B.Cu")
		(net "UART_DSR_P1_N")
	)
	(via
		(at 143.071596 -41.190926)
		(size 0.508)
		(drill 0.254)
		(layers "F.Cu" "B.Cu")
		(net "UART_DSR_P1_N")
	)
	(segment
		(start 144.84477 -41.190926)
		(end 144.96034 -41.306496)
		(width 0.1016)
		(layer "B.Cu")
		(net "UART_DSR_P1_N")
	)
	(segment
		(start 150.606252 -37.19195)
		(end 150.606252 -35.735006)
		(width 0.1016)
		(layer "B.Cu")
		(net "UART_DSR_P1_N")
	)
	(segment
		(start 144.96034 -41.306496)
		(end 146.234658 -41.306496)
		(width 0.1016)
		(layer "B.Cu")
		(net "UART_DSR_P1_N")
	)
	(segment
		(start 147.128738 -40.412416)
		(end 147.385786 -40.412416)
		(width 0.1016)
		(layer "B.Cu")
		(net "UART_DSR_P1_N")
	)
	(segment
		(start 146.234658 -41.306496)
		(end 147.128738 -40.412416)
		(width 0.1016)
		(layer "B.Cu")
		(net "UART_DSR_P1_N")
	)
	(segment
		(start 143.071596 -41.190926)
		(end 144.84477 -41.190926)
		(width 0.1016)
		(layer "B.Cu")
		(net "UART_DSR_P1_N")
	)
	(segment
		(start 147.385786 -40.412416)
		(end 150.606252 -37.19195)
		(width 0.1016)
		(layer "B.Cu")
		(net "UART_DSR_P1_N")
	)
	(segment
		(start 152.429972 -35.08502)
		(end 151.241252 -35.08502)
		(width 0.1016)
		(layer "F.Cu")
		(net "UART_RX_P1")
	)
	(segment
		(start 144.512538 -43.389804)
		(end 143.10614 -41.983406)
		(width 0.1016)
		(layer "F.Cu")
		(net "UART_RX_P1")
	)
	(segment
		(start 145.571718 -43.389804)
		(end 144.512538 -43.389804)
		(width 0.1016)
		(layer "F.Cu")
		(net "UART_RX_P1")
	)
	(via
		(at 143.10614 -41.983406)
		(size 0.508)
		(drill 0.254)
		(layers "F.Cu" "B.Cu")
		(net "UART_RX_P1")
	)
	(via
		(at 151.241252 -35.08502)
		(size 0.508)
		(drill 0.254)
		(layers "F.Cu" "B.Cu")
		(net "UART_RX_P1")
	)
	(segment
		(start 151.241252 -37.175186)
		(end 151.241252 -35.08502)
		(width 0.1016)
		(layer "B.Cu")
		(net "UART_RX_P1")
	)
	(segment
		(start 143.10614 -41.983406)
		(end 147.013168 -41.983406)
		(width 0.1016)
		(layer "B.Cu")
		(net "UART_RX_P1")
	)
	(segment
		(start 147.013168 -41.983406)
		(end 147.801838 -41.194736)
		(width 0.1016)
		(layer "B.Cu")
		(net "UART_RX_P1")
	)
	(segment
		(start 147.801838 -41.194736)
		(end 147.801838 -40.6146)
		(width 0.1016)
		(layer "B.Cu")
		(net "UART_RX_P1")
	)
	(segment
		(start 147.801838 -40.6146)
		(end 151.241252 -37.175186)
		(width 0.1016)
		(layer "B.Cu")
		(net "UART_RX_P1")
	)
	(segment
		(start 142.103602 -42.688002)
		(end 139.853416 -42.688002)
		(width 0.1016)
		(layer "F.Cu")
		(net "UART_CTS_P2_N")
	)
	(segment
		(start 9.288018 -20.20316)
		(end 9.288018 -18.57883)
		(width 0.1016)
		(layer "F.Cu")
		(net "UART_CTS_P2_N")
	)
	(segment
		(start 145.571718 -44.889674)
		(end 144.305274 -44.889674)
		(width 0.1016)
		(layer "F.Cu")
		(net "UART_CTS_P2_N")
	)
	(segment
		(start 139.853416 -42.688002)
		(end 139.853416 -42.690288)
		(width 0.1016)
		(layer "F.Cu")
		(net "UART_CTS_P2_N")
	)
	(segment
		(start 144.305274 -44.889674)
		(end 142.103602 -42.688002)
		(width 0.1016)
		(layer "F.Cu")
		(net "UART_CTS_P2_N")
	)
	(via
		(at 139.853416 -42.690288)
		(size 0.508)
		(drill 0.254)
		(layers "F.Cu" "B.Cu")
		(net "UART_CTS_P2_N")
	)
	(via
		(at 9.288018 -18.57883)
		(size 0.508)
		(drill 0.254)
		(layers "F.Cu" "B.Cu")
		(net "UART_CTS_P2_N")
	)
	(segment
		(start 42.865802 -15.116556)
		(end 40.360346 -15.116556)
		(width 0.1143)
		(layer "In7.Cu")
		(net "UART_CTS_P2_N")
	)
	(segment
		(start 113.59134 -13.158724)
		(end 87.948262 -13.158724)
		(width 0.1143)
		(layer "In7.Cu")
		(net "UART_CTS_P2_N")
	)
	(segment
		(start 126.786132 -35.4584)
		(end 126.15926 -34.831528)
		(width 0.1143)
		(layer "In7.Cu")
		(net "UART_CTS_P2_N")
	)
	(segment
		(start 64.939418 -15.308326)
		(end 64.01816 -15.308326)
		(width 0.1143)
		(layer "In7.Cu")
		(net "UART_CTS_P2_N")
	)
	(segment
		(start 37.4142 -13.31849)
		(end 37.4142 -12.99718)
		(width 0.1143)
		(layer "In7.Cu")
		(net "UART_CTS_P2_N")
	)
	(segment
		(start 36.854892 -12.437872)
		(end 36.457636 -12.437872)
		(width 0.1143)
		(layer "In7.Cu")
		(net "UART_CTS_P2_N")
	)
	(segment
		(start 39.510462 -15.414752)
		(end 37.4142 -13.31849)
		(width 0.1143)
		(layer "In7.Cu")
		(net "UART_CTS_P2_N")
	)
	(segment
		(start 20.68703 -9.86409)
		(end 12.879324 -9.86409)
		(width 0.1143)
		(layer "In7.Cu")
		(net "UART_CTS_P2_N")
	)
	(segment
		(start 22.294596 -11.471656)
		(end 20.68703 -9.86409)
		(width 0.1143)
		(layer "In7.Cu")
		(net "UART_CTS_P2_N")
	)
	(segment
		(start 64.01816 -15.308326)
		(end 63.781432 -15.545054)
		(width 0.1143)
		(layer "In7.Cu")
		(net "UART_CTS_P2_N")
	)
	(segment
		(start 36.457636 -12.437872)
		(end 35.49142 -11.471656)
		(width 0.1143)
		(layer "In7.Cu")
		(net "UART_CTS_P2_N")
	)
	(segment
		(start 87.948262 -13.158724)
		(end 86.152482 -14.95552)
		(width 0.1143)
		(layer "In7.Cu")
		(net "UART_CTS_P2_N")
	)
	(segment
		(start 64.95796 -15.326868)
		(end 64.939418 -15.308326)
		(width 0.1143)
		(layer "In7.Cu")
		(net "UART_CTS_P2_N")
	)
	(segment
		(start 132.113782 -39.743634)
		(end 127.828548 -35.4584)
		(width 0.1143)
		(layer "In7.Cu")
		(net "UART_CTS_P2_N")
	)
	(segment
		(start 86.152482 -14.95552)
		(end 66.279268 -14.95552)
		(width 0.1143)
		(layer "In7.Cu")
		(net "UART_CTS_P2_N")
	)
	(segment
		(start 40.06215 -15.414752)
		(end 39.510462 -15.414752)
		(width 0.1143)
		(layer "In7.Cu")
		(net "UART_CTS_P2_N")
	)
	(segment
		(start 123.840494 -34.831528)
		(end 120.97004 -31.961074)
		(width 0.1143)
		(layer "In7.Cu")
		(net "UART_CTS_P2_N")
	)
	(segment
		(start 127.828548 -35.4584)
		(end 126.786132 -35.4584)
		(width 0.1143)
		(layer "In7.Cu")
		(net "UART_CTS_P2_N")
	)
	(segment
		(start 65.90792 -15.326868)
		(end 64.95796 -15.326868)
		(width 0.1143)
		(layer "In7.Cu")
		(net "UART_CTS_P2_N")
	)
	(segment
		(start 119.65178 -19.218402)
		(end 113.801652 -13.368274)
		(width 0.1143)
		(layer "In7.Cu")
		(net "UART_CTS_P2_N")
	)
	(segment
		(start 12.879324 -9.86409)
		(end 9.288018 -13.455396)
		(width 0.1143)
		(layer "In7.Cu")
		(net "UART_CTS_P2_N")
	)
	(segment
		(start 43.2943 -15.545054)
		(end 42.865802 -15.116556)
		(width 0.1143)
		(layer "In7.Cu")
		(net "UART_CTS_P2_N")
	)
	(segment
		(start 63.781432 -15.545054)
		(end 43.2943 -15.545054)
		(width 0.1143)
		(layer "In7.Cu")
		(net "UART_CTS_P2_N")
	)
	(segment
		(start 136.906762 -39.743634)
		(end 132.113782 -39.743634)
		(width 0.1143)
		(layer "In7.Cu")
		(net "UART_CTS_P2_N")
	)
	(segment
		(start 66.279268 -14.95552)
		(end 65.90792 -15.326868)
		(width 0.1143)
		(layer "In7.Cu")
		(net "UART_CTS_P2_N")
	)
	(segment
		(start 120.97004 -31.961074)
		(end 120.97004 -30.836362)
		(width 0.1143)
		(layer "In7.Cu")
		(net "UART_CTS_P2_N")
	)
	(segment
		(start 139.853416 -42.690288)
		(end 136.906762 -39.743634)
		(width 0.1143)
		(layer "In7.Cu")
		(net "UART_CTS_P2_N")
	)
	(segment
		(start 120.97004 -30.836362)
		(end 119.65178 -29.518102)
		(width 0.1143)
		(layer "In7.Cu")
		(net "UART_CTS_P2_N")
	)
	(segment
		(start 9.288018 -13.455396)
		(end 9.288018 -18.57883)
		(width 0.1143)
		(layer "In7.Cu")
		(net "UART_CTS_P2_N")
	)
	(segment
		(start 35.49142 -11.471656)
		(end 22.294596 -11.471656)
		(width 0.1143)
		(layer "In7.Cu")
		(net "UART_CTS_P2_N")
	)
	(segment
		(start 113.801652 -13.368274)
		(end 113.59134 -13.158724)
		(width 0.1143)
		(layer "In7.Cu")
		(net "UART_CTS_P2_N")
	)
	(segment
		(start 37.4142 -12.99718)
		(end 36.854892 -12.437872)
		(width 0.1143)
		(layer "In7.Cu")
		(net "UART_CTS_P2_N")
	)
	(segment
		(start 126.15926 -34.831528)
		(end 123.840494 -34.831528)
		(width 0.1143)
		(layer "In7.Cu")
		(net "UART_CTS_P2_N")
	)
	(segment
		(start 40.360346 -15.116556)
		(end 40.06215 -15.414752)
		(width 0.1143)
		(layer "In7.Cu")
		(net "UART_CTS_P2_N")
	)
	(segment
		(start 119.65178 -29.518102)
		(end 119.65178 -19.218402)
		(width 0.1143)
		(layer "In7.Cu")
		(net "UART_CTS_P2_N")
	)
	(via
		(at 143.78686 -27.720544)
		(size 0.508)
		(drill 0.254)
		(layers "F.Cu" "B.Cu")
		(net "SIO_AVCC")
	)
	(via
		(at 141.73073 -28.001976)
		(size 0.508)
		(drill 0.254)
		(layers "F.Cu" "B.Cu")
		(net "SIO_AVCC")
	)
	(segment
		(start 175.15459 -65.021206)
		(end 174.888652 -64.755268)
		(width 0.10668)
		(layer "F.Cu")
		(net "USB3_L_DP")
	)
	(segment
		(start 173.696376 -63.934848)
		(end 173.696376 -62.734952)
		(width 0.10668)
		(layer "F.Cu")
		(net "USB3_L_DP")
	)
	(segment
		(start 173.696376 -62.020958)
		(end 173.362874 -61.687456)
		(width 0.10668)
		(layer "F.Cu")
		(net "USB3_L_DP")
	)
	(segment
		(start 174.888652 -64.755268)
		(end 174.516796 -64.755268)
		(width 0.10668)
		(layer "F.Cu")
		(net "USB3_L_DP")
	)
	(segment
		(start 173.14164 -61.687456)
		(end 172.793406 -61.339222)
		(width 0.10668)
		(layer "F.Cu")
		(net "USB3_L_DP")
	)
	(segment
		(start 173.362874 -61.687456)
		(end 173.14164 -61.687456)
		(width 0.10668)
		(layer "F.Cu")
		(net "USB3_L_DP")
	)
	(segment
		(start 171.177712 -61.68263)
		(end 171.178728 -61.681614)
		(width 0.10668)
		(layer "F.Cu")
		(net "USB3_L_DP")
	)
	(segment
		(start 173.696376 -62.734952)
		(end 173.696376 -62.020958)
		(width 0.10668)
		(layer "F.Cu")
		(net "USB3_L_DP")
	)
	(segment
		(start 174.516796 -64.755268)
		(end 173.696376 -63.934848)
		(width 0.10668)
		(layer "F.Cu")
		(net "USB3_L_DP")
	)
	(segment
		(start 177.320194 -65.021206)
		(end 175.15459 -65.021206)
		(width 0.10668)
		(layer "F.Cu")
		(net "USB3_L_DP")
	)
	(segment
		(start 180.23713 -63.215774)
		(end 179.125626 -63.215774)
		(width 0.10668)
		(layer "F.Cu")
		(net "USB3_L_DP")
	)
	(segment
		(start 181.09565 -64.074294)
		(end 180.23713 -63.215774)
		(width 0.10668)
		(layer "F.Cu")
		(net "USB3_L_DP")
	)
	(segment
		(start 171.52112 -61.339222)
		(end 171.178728 -61.681614)
		(width 0.10668)
		(layer "F.Cu")
		(net "USB3_L_DP")
	)
	(segment
		(start 170.192446 -61.68263)
		(end 171.177712 -61.68263)
		(width 0.10668)
		(layer "F.Cu")
		(net "USB3_L_DP")
	)
	(segment
		(start 179.125626 -63.215774)
		(end 177.320194 -65.021206)
		(width 0.10668)
		(layer "F.Cu")
		(net "USB3_L_DP")
	)
	(segment
		(start 172.793406 -61.339222)
		(end 171.52112 -61.339222)
		(width 0.10668)
		(layer "F.Cu")
		(net "USB3_L_DP")
	)
	(segment
		(start 182.49265 -63.215774)
		(end 182.062374 -62.785498)
		(width 0.10668)
		(layer "F.Cu")
		(net "USB2_L_DP")
	)
	(segment
		(start 181.620922 -60.98032)
		(end 177.468276 -60.98032)
		(width 0.10668)
		(layer "F.Cu")
		(net "USB2_L_DP")
	)
	(segment
		(start 174.083218 -61.160406)
		(end 173.696376 -60.773564)
		(width 0.10668)
		(layer "F.Cu")
		(net "USB2_L_DP")
	)
	(segment
		(start 174.555912 -58.191654)
		(end 174.555912 -58.475118)
		(width 0.10668)
		(layer "F.Cu")
		(net "USB2_L_DP")
	)
	(segment
		(start 173.696376 -60.773564)
		(end 173.696376 -60.284868)
		(width 0.10668)
		(layer "F.Cu")
		(net "USB2_L_DP")
	)
	(segment
		(start 182.062374 -62.785498)
		(end 182.062374 -61.421772)
		(width 0.10668)
		(layer "F.Cu")
		(net "USB2_L_DP")
	)
	(segment
		(start 173.696376 -59.334654)
		(end 173.696376 -60.284868)
		(width 0.10668)
		(layer "F.Cu")
		(net "USB2_L_DP")
	)
	(segment
		(start 171.820586 -57.63006)
		(end 173.994318 -57.63006)
		(width 0.10668)
		(layer "F.Cu")
		(net "USB2_L_DP")
	)
	(segment
		(start 174.555912 -58.475118)
		(end 173.696376 -59.334654)
		(width 0.10668)
		(layer "F.Cu")
		(net "USB2_L_DP")
	)
	(segment
		(start 175.366426 -61.160406)
		(end 174.083218 -61.160406)
		(width 0.10668)
		(layer "F.Cu")
		(net "USB2_L_DP")
	)
	(segment
		(start 177.468276 -60.98032)
		(end 176.835816 -61.61278)
		(width 0.10668)
		(layer "F.Cu")
		(net "USB2_L_DP")
	)
	(segment
		(start 171.478194 -57.972452)
		(end 171.820586 -57.63006)
		(width 0.10668)
		(layer "F.Cu")
		(net "USB2_L_DP")
	)
	(segment
		(start 170.043602 -57.99709)
		(end 170.998134 -57.99709)
		(width 0.10668)
		(layer "F.Cu")
		(net "USB2_L_DP")
	)
	(segment
		(start 173.994318 -57.63006)
		(end 174.555912 -58.191654)
		(width 0.10668)
		(layer "F.Cu")
		(net "USB2_L_DP")
	)
	(segment
		(start 183.71185 -64.074294)
		(end 182.85333 -63.215774)
		(width 0.10668)
		(layer "F.Cu")
		(net "USB2_L_DP")
	)
	(segment
		(start 170.998134 -57.99709)
		(end 171.022772 -57.972452)
		(width 0.10668)
		(layer "F.Cu")
		(net "USB2_L_DP")
	)
	(segment
		(start 176.835816 -61.61278)
		(end 175.8188 -61.61278)
		(width 0.10668)
		(layer "F.Cu")
		(net "USB2_L_DP")
	)
	(segment
		(start 171.022772 -57.972452)
		(end 171.478194 -57.972452)
		(width 0.10668)
		(layer "F.Cu")
		(net "USB2_L_DP")
	)
	(segment
		(start 182.85333 -63.215774)
		(end 182.49265 -63.215774)
		(width 0.10668)
		(layer "F.Cu")
		(net "USB2_L_DP")
	)
	(segment
		(start 175.8188 -61.61278)
		(end 175.366426 -61.160406)
		(width 0.10668)
		(layer "F.Cu")
		(net "USB2_L_DP")
	)
	(segment
		(start 182.062374 -61.421772)
		(end 181.620922 -60.98032)
		(width 0.10668)
		(layer "F.Cu")
		(net "USB2_L_DP")
	)
	(segment
		(start 174.870872 -58.495438)
		(end 175.596296 -59.220862)
		(width 0.10668)
		(layer "F.Cu")
		(net "USB2_L_DN")
	)
	(segment
		(start 170.043602 -56.98109)
		(end 171.01439 -56.98109)
		(width 0.10668)
		(layer "F.Cu")
		(net "USB2_L_DN")
	)
	(segment
		(start 171.478194 -56.972708)
		(end 171.820586 -57.3151)
		(width 0.10668)
		(layer "F.Cu")
		(net "USB2_L_DN")
	)
	(segment
		(start 174.870872 -58.061098)
		(end 174.870872 -58.495438)
		(width 0.10668)
		(layer "F.Cu")
		(net "USB2_L_DN")
	)
	(segment
		(start 175.943768 -61.29782)
		(end 175.596296 -60.950348)
		(width 0.10668)
		(layer "F.Cu")
		(net "USB2_L_DN")
	)
	(segment
		(start 171.820586 -57.3151)
		(end 174.124874 -57.3151)
		(width 0.10668)
		(layer "F.Cu")
		(net "USB2_L_DN")
	)
	(segment
		(start 182.377334 -62.654942)
		(end 182.377334 -61.291216)
		(width 0.10668)
		(layer "F.Cu")
		(net "USB2_L_DN")
	)
	(segment
		(start 182.862982 -62.900814)
		(end 182.623206 -62.900814)
		(width 0.10668)
		(layer "F.Cu")
		(net "USB2_L_DN")
	)
	(segment
		(start 176.70526 -61.29782)
		(end 175.943768 -61.29782)
		(width 0.10668)
		(layer "F.Cu")
		(net "USB2_L_DN")
	)
	(segment
		(start 182.623206 -62.900814)
		(end 182.377334 -62.654942)
		(width 0.10668)
		(layer "F.Cu")
		(net "USB2_L_DN")
	)
	(segment
		(start 171.01439 -56.98109)
		(end 171.022772 -56.972708)
		(width 0.10668)
		(layer "F.Cu")
		(net "USB2_L_DN")
	)
	(segment
		(start 175.596296 -59.220862)
		(end 175.596296 -60.284868)
		(width 0.10668)
		(layer "F.Cu")
		(net "USB2_L_DN")
	)
	(segment
		(start 175.596296 -60.950348)
		(end 175.596296 -60.284868)
		(width 0.10668)
		(layer "F.Cu")
		(net "USB2_L_DN")
	)
	(segment
		(start 174.124874 -57.3151)
		(end 174.870872 -58.061098)
		(width 0.10668)
		(layer "F.Cu")
		(net "USB2_L_DN")
	)
	(segment
		(start 182.377334 -61.291216)
		(end 181.751478 -60.66536)
		(width 0.10668)
		(layer "F.Cu")
		(net "USB2_L_DN")
	)
	(segment
		(start 171.022772 -56.972708)
		(end 171.478194 -56.972708)
		(width 0.10668)
		(layer "F.Cu")
		(net "USB2_L_DN")
	)
	(segment
		(start 177.33772 -60.66536)
		(end 176.70526 -61.29782)
		(width 0.10668)
		(layer "F.Cu")
		(net "USB2_L_DN")
	)
	(segment
		(start 183.71185 -62.042294)
		(end 183.71185 -62.051946)
		(width 0.10668)
		(layer "F.Cu")
		(net "USB2_L_DN")
	)
	(segment
		(start 183.71185 -62.051946)
		(end 182.862982 -62.900814)
		(width 0.10668)
		(layer "F.Cu")
		(net "USB2_L_DN")
	)
	(segment
		(start 181.751478 -60.66536)
		(end 177.33772 -60.66536)
		(width 0.10668)
		(layer "F.Cu")
		(net "USB2_L_DN")
	)
	(segment
		(start 122.818652 -28.447746)
		(end 122.818652 -26.974292)
		(width 0.1016)
		(layer "F.Cu")
		(net "SIO_COPEN_N")
	)
	(segment
		(start 123.0249 -28.653994)
		(end 122.818652 -28.447746)
		(width 0.1016)
		(layer "F.Cu")
		(net "SIO_COPEN_N")
	)
	(segment
		(start 126.261622 -28.950412)
		(end 126.261622 -30.079696)
		(width 0.1016)
		(layer "F.Cu")
		(net "SIO_COPEN_N")
	)
	(segment
		(start 123.0249 -28.653994)
		(end 123.169172 -28.509722)
		(width 0.1016)
		(layer "F.Cu")
		(net "SIO_COPEN_N")
	)
	(segment
		(start 124.98832 -28.509722)
		(end 125.32741 -28.848812)
		(width 0.1016)
		(layer "F.Cu")
		(net "SIO_COPEN_N")
	)
	(segment
		(start 123.169172 -28.509722)
		(end 124.98832 -28.509722)
		(width 0.1016)
		(layer "F.Cu")
		(net "SIO_COPEN_N")
	)
	(segment
		(start 126.160022 -28.848812)
		(end 126.261622 -28.950412)
		(width 0.1016)
		(layer "F.Cu")
		(net "SIO_COPEN_N")
	)
	(segment
		(start 125.32741 -28.848812)
		(end 126.160022 -28.848812)
		(width 0.1016)
		(layer "F.Cu")
		(net "SIO_COPEN_N")
	)
	(via
		(at 123.0249 -28.653994)
		(size 0.508)
		(drill 0.254)
		(layers "F.Cu" "B.Cu")
		(net "SIO_COPEN_N")
	)
	(segment
		(start 175.596296 -63.911734)
		(end 175.596296 -62.734952)
		(width 0.10668)
		(layer "F.Cu")
		(net "USB3_L_DN")
	)
	(segment
		(start 175.596296 -62.734952)
		(end 175.596296 -62.227206)
		(width 0.10668)
		(layer "F.Cu")
		(net "USB3_L_DN")
	)
	(segment
		(start 180.23713 -62.900814)
		(end 178.99507 -62.900814)
		(width 0.10668)
		(layer "F.Cu")
		(net "USB3_L_DN")
	)
	(segment
		(start 175.174148 -61.805058)
		(end 173.928278 -61.805058)
		(width 0.10668)
		(layer "F.Cu")
		(net "USB3_L_DN")
	)
	(segment
		(start 173.272196 -61.372496)
		(end 172.923962 -61.024262)
		(width 0.10668)
		(layer "F.Cu")
		(net "USB3_L_DN")
	)
	(segment
		(start 177.189638 -64.706246)
		(end 175.285146 -64.706246)
		(width 0.10668)
		(layer "F.Cu")
		(net "USB3_L_DN")
	)
	(segment
		(start 175.596296 -62.227206)
		(end 175.174148 -61.805058)
		(width 0.10668)
		(layer "F.Cu")
		(net "USB3_L_DN")
	)
	(segment
		(start 171.163488 -60.66663)
		(end 171.178728 -60.68187)
		(width 0.10668)
		(layer "F.Cu")
		(net "USB3_L_DN")
	)
	(segment
		(start 172.923962 -61.024262)
		(end 171.52112 -61.024262)
		(width 0.10668)
		(layer "F.Cu")
		(net "USB3_L_DN")
	)
	(segment
		(start 173.928278 -61.805058)
		(end 173.495716 -61.372496)
		(width 0.10668)
		(layer "F.Cu")
		(net "USB3_L_DN")
	)
	(segment
		(start 170.192446 -60.66663)
		(end 171.163488 -60.66663)
		(width 0.10668)
		(layer "F.Cu")
		(net "USB3_L_DN")
	)
	(segment
		(start 181.09565 -62.042294)
		(end 180.23713 -62.900814)
		(width 0.10668)
		(layer "F.Cu")
		(net "USB3_L_DN")
	)
	(segment
		(start 173.495716 -61.372496)
		(end 173.272196 -61.372496)
		(width 0.10668)
		(layer "F.Cu")
		(net "USB3_L_DN")
	)
	(segment
		(start 178.99507 -62.900814)
		(end 177.189638 -64.706246)
		(width 0.10668)
		(layer "F.Cu")
		(net "USB3_L_DN")
	)
	(segment
		(start 175.13046 -64.37757)
		(end 175.596296 -63.911734)
		(width 0.10668)
		(layer "F.Cu")
		(net "USB3_L_DN")
	)
	(segment
		(start 175.13046 -64.55156)
		(end 175.13046 -64.37757)
		(width 0.10668)
		(layer "F.Cu")
		(net "USB3_L_DN")
	)
	(segment
		(start 175.285146 -64.706246)
		(end 175.13046 -64.55156)
		(width 0.10668)
		(layer "F.Cu")
		(net "USB3_L_DN")
	)
	(segment
		(start 171.52112 -61.024262)
		(end 171.178728 -60.68187)
		(width 0.10668)
		(layer "F.Cu")
		(net "USB3_L_DN")
	)
	(segment
		(start 122.451622 -38.889686)
		(end 123.67133 -38.889686)
		(width 0.1016)
		(layer "F.Cu")
		(net "SIO_PWROK2")
	)
	(segment
		(start 123.67133 -38.889686)
		(end 123.915678 -38.645338)
		(width 0.1016)
		(layer "F.Cu")
		(net "SIO_PWROK2")
	)
	(via
		(at 123.915678 -38.645338)
		(size 0.508)
		(drill 0.254)
		(layers "F.Cu" "B.Cu")
		(net "SIO_PWROK2")
	)
	(segment
		(start 125.639576 -39.617904)
		(end 124.66701 -38.645338)
		(width 0.1016)
		(layer "B.Cu")
		(net "SIO_PWROK2")
	)
	(segment
		(start 125.639576 -40.071294)
		(end 125.639576 -39.617904)
		(width 0.1016)
		(layer "B.Cu")
		(net "SIO_PWROK2")
	)
	(segment
		(start 124.66701 -38.645338)
		(end 123.915678 -38.645338)
		(width 0.1016)
		(layer "B.Cu")
		(net "SIO_PWROK2")
	)
	(via
		(at 18.33626 -75.53833)
		(size 0.508)
		(drill 0.254)
		(layers "F.Cu" "B.Cu")
		(net "VCC5_CRTXX")
	)
	(via
		(at 16.971772 -75.560682)
		(size 0.508)
		(drill 0.254)
		(layers "F.Cu" "B.Cu")
		(net "VCC5_CRTXX")
	)
	(via
		(at 19.651472 -75.998324)
		(size 0.508)
		(drill 0.254)
		(layers "F.Cu" "B.Cu")
		(net "VCC5_CRTXX")
	)
	(segment
		(start 121.870724 -24.796242)
		(end 123.191016 -24.796242)
		(width 0.254)
		(layer "F.Cu")
		(net "SIO_VBAT")
	)
	(segment
		(start 123.50496 -25.110186)
		(end 123.50496 -26.77795)
		(width 0.254)
		(layer "F.Cu")
		(net "SIO_VBAT")
	)
	(segment
		(start 124.946918 -27.844242)
		(end 125.621288 -28.518612)
		(width 0.254)
		(layer "F.Cu")
		(net "SIO_VBAT")
	)
	(segment
		(start 123.701302 -26.974292)
		(end 124.063252 -26.974292)
		(width 0.254)
		(layer "F.Cu")
		(net "SIO_VBAT")
	)
	(segment
		(start 123.50496 -26.77795)
		(end 123.701302 -26.974292)
		(width 0.254)
		(layer "F.Cu")
		(net "SIO_VBAT")
	)
	(segment
		(start 124.063252 -27.844242)
		(end 124.946918 -27.844242)
		(width 0.254)
		(layer "F.Cu")
		(net "SIO_VBAT")
	)
	(segment
		(start 121.50598 -26.53538)
		(end 121.50598 -25.160986)
		(width 0.254)
		(layer "F.Cu")
		(net "SIO_VBAT")
	)
	(segment
		(start 125.621288 -28.518612)
		(end 126.296928 -28.518612)
		(width 0.254)
		(layer "F.Cu")
		(net "SIO_VBAT")
	)
	(segment
		(start 126.296928 -28.518612)
		(end 126.761748 -28.983432)
		(width 0.254)
		(layer "F.Cu")
		(net "SIO_VBAT")
	)
	(segment
		(start 126.761748 -28.983432)
		(end 126.761748 -30.079696)
		(width 0.254)
		(layer "F.Cu")
		(net "SIO_VBAT")
	)
	(segment
		(start 124.063252 -26.974292)
		(end 124.063252 -27.844242)
		(width 0.254)
		(layer "F.Cu")
		(net "SIO_VBAT")
	)
	(segment
		(start 123.191016 -24.796242)
		(end 123.50496 -25.110186)
		(width 0.254)
		(layer "F.Cu")
		(net "SIO_VBAT")
	)
	(segment
		(start 121.50598 -25.160986)
		(end 121.870724 -24.796242)
		(width 0.254)
		(layer "F.Cu")
		(net "SIO_VBAT")
	)
	(via
		(at 124.063252 -27.844242)
		(size 0.508)
		(drill 0.254)
		(layers "F.Cu" "B.Cu")
		(net "SIO_VBAT")
	)
	(segment
		(start 19.293332 -65.921382)
		(end 19.293332 -65.045082)
		(width 0.1016)
		(layer "F.Cu")
		(net "I2C_VIDREAR_5V_SCL")
	)
	(segment
		(start 20.044918 -66.997834)
		(end 20.16379 -66.997834)
		(width 0.1016)
		(layer "F.Cu")
		(net "I2C_VIDREAR_5V_SCL")
	)
	(segment
		(start 19.293332 -65.045082)
		(end 18.982436 -64.734186)
		(width 0.1016)
		(layer "F.Cu")
		(net "I2C_VIDREAR_5V_SCL")
	)
	(segment
		(start 19.618706 -66.246756)
		(end 19.618706 -66.571622)
		(width 0.1016)
		(layer "F.Cu")
		(net "I2C_VIDREAR_5V_SCL")
	)
	(segment
		(start 16.757396 -62.977776)
		(end 16.182594 -62.977776)
		(width 0.1016)
		(layer "F.Cu")
		(net "I2C_VIDREAR_5V_SCL")
	)
	(segment
		(start 19.618706 -66.571622)
		(end 20.044918 -66.997834)
		(width 0.1016)
		(layer "F.Cu")
		(net "I2C_VIDREAR_5V_SCL")
	)
	(segment
		(start 20.16379 -66.997834)
		(end 22.15261 -68.986654)
		(width 0.1016)
		(layer "F.Cu")
		(net "I2C_VIDREAR_5V_SCL")
	)
	(segment
		(start 15.286228 -63.487046)
		(end 15.284958 -62.489588)
		(width 0.1016)
		(layer "F.Cu")
		(net "I2C_VIDREAR_5V_SCL")
	)
	(segment
		(start 16.757396 -63.433452)
		(end 16.757396 -62.977776)
		(width 0.1016)
		(layer "F.Cu")
		(net "I2C_VIDREAR_5V_SCL")
	)
	(segment
		(start 19.618706 -66.246756)
		(end 19.293332 -65.921382)
		(width 0.1016)
		(layer "F.Cu")
		(net "I2C_VIDREAR_5V_SCL")
	)
	(segment
		(start 18.05813 -64.734186)
		(end 16.757396 -63.433452)
		(width 0.1016)
		(layer "F.Cu")
		(net "I2C_VIDREAR_5V_SCL")
	)
	(segment
		(start 16.182594 -62.977776)
		(end 15.694406 -62.489588)
		(width 0.1016)
		(layer "F.Cu")
		(net "I2C_VIDREAR_5V_SCL")
	)
	(segment
		(start 15.694406 -62.489588)
		(end 15.284958 -62.489588)
		(width 0.1016)
		(layer "F.Cu")
		(net "I2C_VIDREAR_5V_SCL")
	)
	(segment
		(start 18.982436 -64.734186)
		(end 18.05813 -64.734186)
		(width 0.1016)
		(layer "F.Cu")
		(net "I2C_VIDREAR_5V_SCL")
	)
	(via
		(at 19.618706 -66.246756)
		(size 0.508)
		(drill 0.254)
		(layers "F.Cu" "B.Cu")
		(net "I2C_VIDREAR_5V_SCL")
	)
	(segment
		(start 111.667544 -164.305234)
		(end 111.667036 -164.305234)
		(width 0.1016)
		(layer "F.Cu")
		(net "I2C_PDB_SDA")
	)
	(segment
		(start 111.667036 -164.305234)
		(end 111.127286 -164.844984)
		(width 0.1016)
		(layer "F.Cu")
		(net "I2C_PDB_SDA")
	)
	(segment
		(start 166.116 -187.557664)
		(end 166.28364 -187.79744)
		(width 0.1016)
		(layer "F.Cu")
		(net "I2C_PDB_SDA")
	)
	(segment
		(start 166.116 -187.0456)
		(end 166.116 -187.557664)
		(width 0.1016)
		(layer "F.Cu")
		(net "I2C_PDB_SDA")
	)
	(via
		(at 111.127286 -164.844984)
		(size 0.508)
		(drill 0.254)
		(layers "F.Cu" "B.Cu")
		(net "I2C_PDB_SDA")
	)
	(via
		(at 166.116 -187.0456)
		(size 0.508)
		(drill 0.254)
		(layers "F.Cu" "B.Cu")
		(net "I2C_PDB_SDA")
	)
	(segment
		(start 116.9162 -165.33749)
		(end 116.7892 -165.21049)
		(width 0.1143)
		(layer "In7.Cu")
		(net "I2C_PDB_SDA")
	)
	(segment
		(start 127.94488 -163.109402)
		(end 127.94488 -163.762182)
		(width 0.1143)
		(layer "In7.Cu")
		(net "I2C_PDB_SDA")
	)
	(segment
		(start 140.647674 -163.83)
		(end 140.1318 -163.314126)
		(width 0.1143)
		(layer "In7.Cu")
		(net "I2C_PDB_SDA")
	)
	(segment
		(start 126.037848 -165.669214)
		(end 123.550426 -165.669214)
		(width 0.1143)
		(layer "In7.Cu")
		(net "I2C_PDB_SDA")
	)
	(segment
		(start 129.257552 -162.767772)
		(end 128.28651 -162.767772)
		(width 0.1143)
		(layer "In7.Cu")
		(net "I2C_PDB_SDA")
	)
	(segment
		(start 132.614416 -163.64204)
		(end 130.13182 -163.64204)
		(width 0.1143)
		(layer "In7.Cu")
		(net "I2C_PDB_SDA")
	)
	(segment
		(start 118.491 -165.354)
		(end 116.9162 -165.354)
		(width 0.1143)
		(layer "In7.Cu")
		(net "I2C_PDB_SDA")
	)
	(segment
		(start 166.684706 -181.789832)
		(end 155.69946 -170.804586)
		(width 0.1143)
		(layer "In7.Cu")
		(net "I2C_PDB_SDA")
	)
	(segment
		(start 140.1318 -163.314126)
		(end 132.94233 -163.314126)
		(width 0.1143)
		(layer "In7.Cu")
		(net "I2C_PDB_SDA")
	)
	(segment
		(start 149.557232 -163.314126)
		(end 145.524474 -163.314126)
		(width 0.1143)
		(layer "In7.Cu")
		(net "I2C_PDB_SDA")
	)
	(segment
		(start 165.39464 -184.614566)
		(end 166.684706 -183.3245)
		(width 0.1143)
		(layer "In7.Cu")
		(net "I2C_PDB_SDA")
	)
	(segment
		(start 123.40336 -165.522148)
		(end 120.362218 -165.522148)
		(width 0.1143)
		(layer "In7.Cu")
		(net "I2C_PDB_SDA")
	)
	(segment
		(start 155.09748 -169.172382)
		(end 155.09748 -168.854374)
		(width 0.1143)
		(layer "In7.Cu")
		(net "I2C_PDB_SDA")
	)
	(segment
		(start 127.94488 -163.762182)
		(end 126.037848 -165.669214)
		(width 0.1143)
		(layer "In7.Cu")
		(net "I2C_PDB_SDA")
	)
	(segment
		(start 145.524474 -163.314126)
		(end 145.0086 -163.83)
		(width 0.1143)
		(layer "In7.Cu")
		(net "I2C_PDB_SDA")
	)
	(segment
		(start 132.94233 -163.314126)
		(end 132.614416 -163.64204)
		(width 0.1143)
		(layer "In7.Cu")
		(net "I2C_PDB_SDA")
	)
	(segment
		(start 165.39464 -186.32424)
		(end 165.39464 -184.614566)
		(width 0.1143)
		(layer "In7.Cu")
		(net "I2C_PDB_SDA")
	)
	(segment
		(start 118.63451 -165.21049)
		(end 118.491 -165.354)
		(width 0.1143)
		(layer "In7.Cu")
		(net "I2C_PDB_SDA")
	)
	(segment
		(start 123.550426 -165.669214)
		(end 123.40336 -165.522148)
		(width 0.1143)
		(layer "In7.Cu")
		(net "I2C_PDB_SDA")
	)
	(segment
		(start 128.28651 -162.767772)
		(end 127.94488 -163.109402)
		(width 0.1143)
		(layer "In7.Cu")
		(net "I2C_PDB_SDA")
	)
	(segment
		(start 145.0086 -163.83)
		(end 140.647674 -163.83)
		(width 0.1143)
		(layer "In7.Cu")
		(net "I2C_PDB_SDA")
	)
	(segment
		(start 120.362218 -165.522148)
		(end 120.05056 -165.21049)
		(width 0.1143)
		(layer "In7.Cu")
		(net "I2C_PDB_SDA")
	)
	(segment
		(start 111.331502 -165.0492)
		(end 111.127286 -164.844984)
		(width 0.1143)
		(layer "In7.Cu")
		(net "I2C_PDB_SDA")
	)
	(segment
		(start 166.684706 -183.3245)
		(end 166.684706 -181.789832)
		(width 0.1143)
		(layer "In7.Cu")
		(net "I2C_PDB_SDA")
	)
	(segment
		(start 116.092478 -164.518594)
		(end 115.729258 -164.518594)
		(width 0.1143)
		(layer "In7.Cu")
		(net "I2C_PDB_SDA")
	)
	(segment
		(start 155.69946 -169.774362)
		(end 155.09748 -169.172382)
		(width 0.1143)
		(layer "In7.Cu")
		(net "I2C_PDB_SDA")
	)
	(segment
		(start 115.729258 -164.518594)
		(end 115.198652 -165.0492)
		(width 0.1143)
		(layer "In7.Cu")
		(net "I2C_PDB_SDA")
	)
	(segment
		(start 120.05056 -165.21049)
		(end 118.63451 -165.21049)
		(width 0.1143)
		(layer "In7.Cu")
		(net "I2C_PDB_SDA")
	)
	(segment
		(start 130.13182 -163.64204)
		(end 129.257552 -162.767772)
		(width 0.1143)
		(layer "In7.Cu")
		(net "I2C_PDB_SDA")
	)
	(segment
		(start 155.69946 -170.804586)
		(end 155.69946 -169.774362)
		(width 0.1143)
		(layer "In7.Cu")
		(net "I2C_PDB_SDA")
	)
	(segment
		(start 115.198652 -165.0492)
		(end 111.331502 -165.0492)
		(width 0.1143)
		(layer "In7.Cu")
		(net "I2C_PDB_SDA")
	)
	(segment
		(start 155.09748 -168.854374)
		(end 149.557232 -163.314126)
		(width 0.1143)
		(layer "In7.Cu")
		(net "I2C_PDB_SDA")
	)
	(segment
		(start 166.116 -187.0456)
		(end 165.39464 -186.32424)
		(width 0.1143)
		(layer "In7.Cu")
		(net "I2C_PDB_SDA")
	)
	(segment
		(start 116.784374 -165.21049)
		(end 116.092478 -164.518594)
		(width 0.1143)
		(layer "In7.Cu")
		(net "I2C_PDB_SDA")
	)
	(segment
		(start 116.9162 -165.354)
		(end 116.9162 -165.33749)
		(width 0.1143)
		(layer "In7.Cu")
		(net "I2C_PDB_SDA")
	)
	(segment
		(start 116.7892 -165.21049)
		(end 116.784374 -165.21049)
		(width 0.1143)
		(layer "In7.Cu")
		(net "I2C_PDB_SDA")
	)
	(segment
		(start 167.80764 -186.811666)
		(end 167.4622 -186.466226)
		(width 0.1016)
		(layer "F.Cu")
		(net "I2C_PDB_SCL")
	)
	(segment
		(start 111.669068 -163.51504)
		(end 111.669068 -163.282122)
		(width 0.1016)
		(layer "F.Cu")
		(net "I2C_PDB_SCL")
	)
	(segment
		(start 167.80764 -187.79744)
		(end 167.80764 -186.811666)
		(width 0.1016)
		(layer "F.Cu")
		(net "I2C_PDB_SCL")
	)
	(segment
		(start 110.59668 -164.367718)
		(end 110.81639 -164.367718)
		(width 0.1016)
		(layer "F.Cu")
		(net "I2C_PDB_SCL")
	)
	(segment
		(start 110.81639 -164.367718)
		(end 111.669068 -163.51504)
		(width 0.1016)
		(layer "F.Cu")
		(net "I2C_PDB_SCL")
	)
	(via
		(at 110.59668 -164.367718)
		(size 0.508)
		(drill 0.254)
		(layers "F.Cu" "B.Cu")
		(net "I2C_PDB_SCL")
	)
	(via
		(at 167.4622 -186.466226)
		(size 0.508)
		(drill 0.254)
		(layers "F.Cu" "B.Cu")
		(net "I2C_PDB_SCL")
	)
	(segment
		(start 116.247926 -164.150294)
		(end 116.336318 -164.238686)
		(width 0.1143)
		(layer "In7.Cu")
		(net "I2C_PDB_SCL")
	)
	(segment
		(start 140.3096 -162.945826)
		(end 140.3096 -162.9664)
		(width 0.1143)
		(layer "In7.Cu")
		(net "I2C_PDB_SCL")
	)
	(segment
		(start 149.709886 -162.945826)
		(end 156.00934 -169.24528)
		(width 0.1143)
		(layer "In7.Cu")
		(net "I2C_PDB_SCL")
	)
	(segment
		(start 167.87495 -181.428898)
		(end 167.87495 -186.053476)
		(width 0.1143)
		(layer "In7.Cu")
		(net "I2C_PDB_SCL")
	)
	(segment
		(start 122.215402 -164.700204)
		(end 125.410468 -164.700204)
		(width 0.1143)
		(layer "In7.Cu")
		(net "I2C_PDB_SCL")
	)
	(segment
		(start 115.57254 -164.150294)
		(end 116.247926 -164.150294)
		(width 0.1143)
		(layer "In7.Cu")
		(net "I2C_PDB_SCL")
	)
	(segment
		(start 144.9832 -163.322)
		(end 145.359374 -162.945826)
		(width 0.1143)
		(layer "In7.Cu")
		(net "I2C_PDB_SCL")
	)
	(segment
		(start 127.7112 -162.399472)
		(end 129.411984 -162.399472)
		(width 0.1143)
		(layer "In7.Cu")
		(net "I2C_PDB_SCL")
	)
	(segment
		(start 156.00934 -169.24528)
		(end 156.00934 -169.563288)
		(width 0.1143)
		(layer "In7.Cu")
		(net "I2C_PDB_SCL")
	)
	(segment
		(start 118.11 -164.9222)
		(end 118.745 -164.2872)
		(width 0.1143)
		(layer "In7.Cu")
		(net "I2C_PDB_SCL")
	)
	(segment
		(start 111.271304 -164.367718)
		(end 111.571786 -164.6682)
		(width 0.1143)
		(layer "In7.Cu")
		(net "I2C_PDB_SCL")
	)
	(segment
		(start 145.359374 -162.945826)
		(end 149.709886 -162.945826)
		(width 0.1143)
		(layer "In7.Cu")
		(net "I2C_PDB_SCL")
	)
	(segment
		(start 125.410468 -164.700204)
		(end 127.7112 -162.399472)
		(width 0.1143)
		(layer "In7.Cu")
		(net "I2C_PDB_SCL")
	)
	(segment
		(start 140.3096 -162.9664)
		(end 140.6652 -163.322)
		(width 0.1143)
		(layer "In7.Cu")
		(net "I2C_PDB_SCL")
	)
	(segment
		(start 122.030998 -164.5158)
		(end 122.215402 -164.700204)
		(width 0.1143)
		(layer "In7.Cu")
		(net "I2C_PDB_SCL")
	)
	(segment
		(start 140.6652 -163.322)
		(end 144.9832 -163.322)
		(width 0.1143)
		(layer "In7.Cu")
		(net "I2C_PDB_SCL")
	)
	(segment
		(start 117.269514 -164.9222)
		(end 118.11 -164.9222)
		(width 0.1143)
		(layer "In7.Cu")
		(net "I2C_PDB_SCL")
	)
	(segment
		(start 116.336318 -164.238686)
		(end 116.586 -164.238686)
		(width 0.1143)
		(layer "In7.Cu")
		(net "I2C_PDB_SCL")
	)
	(segment
		(start 119.958612 -164.2872)
		(end 120.187212 -164.5158)
		(width 0.1143)
		(layer "In7.Cu")
		(net "I2C_PDB_SCL")
	)
	(segment
		(start 115.054634 -164.6682)
		(end 115.57254 -164.150294)
		(width 0.1143)
		(layer "In7.Cu")
		(net "I2C_PDB_SCL")
	)
	(segment
		(start 120.187212 -164.5158)
		(end 122.030998 -164.5158)
		(width 0.1143)
		(layer "In7.Cu")
		(net "I2C_PDB_SCL")
	)
	(segment
		(start 132.35686 -163.27374)
		(end 132.684774 -162.945826)
		(width 0.1143)
		(layer "In7.Cu")
		(net "I2C_PDB_SCL")
	)
	(segment
		(start 167.87495 -186.053476)
		(end 167.4622 -186.466226)
		(width 0.1143)
		(layer "In7.Cu")
		(net "I2C_PDB_SCL")
	)
	(segment
		(start 156.00934 -169.563288)
		(end 167.87495 -181.428898)
		(width 0.1143)
		(layer "In7.Cu")
		(net "I2C_PDB_SCL")
	)
	(segment
		(start 116.586 -164.238686)
		(end 117.269514 -164.9222)
		(width 0.1143)
		(layer "In7.Cu")
		(net "I2C_PDB_SCL")
	)
	(segment
		(start 118.745 -164.2872)
		(end 119.958612 -164.2872)
		(width 0.1143)
		(layer "In7.Cu")
		(net "I2C_PDB_SCL")
	)
	(segment
		(start 132.684774 -162.945826)
		(end 140.3096 -162.945826)
		(width 0.1143)
		(layer "In7.Cu")
		(net "I2C_PDB_SCL")
	)
	(segment
		(start 129.411984 -162.399472)
		(end 130.286252 -163.27374)
		(width 0.1143)
		(layer "In7.Cu")
		(net "I2C_PDB_SCL")
	)
	(segment
		(start 110.59668 -164.367718)
		(end 111.271304 -164.367718)
		(width 0.1143)
		(layer "In7.Cu")
		(net "I2C_PDB_SCL")
	)
	(segment
		(start 111.571786 -164.6682)
		(end 115.054634 -164.6682)
		(width 0.1143)
		(layer "In7.Cu")
		(net "I2C_PDB_SCL")
	)
	(segment
		(start 130.286252 -163.27374)
		(end 132.35686 -163.27374)
		(width 0.1143)
		(layer "In7.Cu")
		(net "I2C_PDB_SCL")
	)
	(segment
		(start 53.161946 -157.982158)
		(end 52.2097 -157.982158)
		(width 0.1016)
		(layer "F.Cu")
		(net "LAN1_DISABLE_N")
	)
	(segment
		(start 49.117504 -156.673042)
		(end 49.788572 -156.673042)
		(width 0.1016)
		(layer "F.Cu")
		(net "LAN1_DISABLE_N")
	)
	(segment
		(start 52.2097 -157.982158)
		(end 51.426364 -157.198822)
		(width 0.1016)
		(layer "F.Cu")
		(net "LAN1_DISABLE_N")
	)
	(segment
		(start 78.83652 -120.381268)
		(end 79.14894 -120.068848)
		(width 0.1016)
		(layer "F.Cu")
		(net "LAN1_DISABLE_N")
	)
	(segment
		(start 68.691252 -88.438482)
		(end 68.762118 -88.509348)
		(width 0.1016)
		(layer "F.Cu")
		(net "LAN1_DISABLE_N")
	)
	(segment
		(start 68.762118 -88.509348)
		(end 68.762118 -89.939368)
		(width 0.1016)
		(layer "F.Cu")
		(net "LAN1_DISABLE_N")
	)
	(segment
		(start 49.788572 -156.673042)
		(end 50.314352 -157.198822)
		(width 0.1016)
		(layer "F.Cu")
		(net "LAN1_DISABLE_N")
	)
	(segment
		(start 79.14894 -120.068848)
		(end 79.14894 -109.862112)
		(width 0.1016)
		(layer "F.Cu")
		(net "LAN1_DISABLE_N")
	)
	(segment
		(start 50.314352 -157.198822)
		(end 50.745644 -157.198822)
		(width 0.1016)
		(layer "F.Cu")
		(net "LAN1_DISABLE_N")
	)
	(segment
		(start 68.762118 -89.939368)
		(end 68.441824 -90.259662)
		(width 0.1016)
		(layer "F.Cu")
		(net "LAN1_DISABLE_N")
	)
	(segment
		(start 51.426364 -157.198822)
		(end 50.745644 -157.198822)
		(width 0.1016)
		(layer "F.Cu")
		(net "LAN1_DISABLE_N")
	)
	(via
		(at 50.745644 -157.198822)
		(size 0.508)
		(drill 0.254)
		(layers "F.Cu" "B.Cu")
		(net "LAN1_DISABLE_N")
	)
	(via
		(at 79.14894 -109.862112)
		(size 0.508)
		(drill 0.254)
		(layers "F.Cu" "B.Cu")
		(net "LAN1_DISABLE_N")
	)
	(via
		(at 78.83652 -120.381268)
		(size 0.508)
		(drill 0.254)
		(layers "F.Cu" "B.Cu")
		(net "LAN1_DISABLE_N")
	)
	(via
		(at 68.441824 -90.259662)
		(size 0.508)
		(drill 0.254)
		(layers "F.Cu" "B.Cu")
		(net "LAN1_DISABLE_N")
	)
	(segment
		(start 83.313778 -93.476572)
		(end 83.313778 -103.551482)
		(width 0.1143)
		(layer "In2.Cu")
		(net "LAN1_DISABLE_N")
	)
	(segment
		(start 72.9234 -147.462748)
		(end 72.507348 -147.8788)
		(width 0.1143)
		(layer "In2.Cu")
		(net "LAN1_DISABLE_N")
	)
	(segment
		(start 50.07991 -148.757894)
		(end 51.140106 -149.81809)
		(width 0.1143)
		(layer "In2.Cu")
		(net "LAN1_DISABLE_N")
	)
	(segment
		(start 83.313778 -103.551482)
		(end 81.61401 -105.25125)
		(width 0.1143)
		(layer "In2.Cu")
		(net "LAN1_DISABLE_N")
	)
	(segment
		(start 78.83652 -120.381268)
		(end 78.83652 -132.976112)
		(width 0.1143)
		(layer "In2.Cu")
		(net "LAN1_DISABLE_N")
	)
	(segment
		(start 82.732372 -92.895166)
		(end 83.313778 -93.476572)
		(width 0.1143)
		(layer "In2.Cu")
		(net "LAN1_DISABLE_N")
	)
	(segment
		(start 78.83652 -132.976112)
		(end 78.08341 -133.729222)
		(width 0.1143)
		(layer "In2.Cu")
		(net "LAN1_DISABLE_N")
	)
	(segment
		(start 80.296512 -92.895166)
		(end 82.732372 -92.895166)
		(width 0.1143)
		(layer "In2.Cu")
		(net "LAN1_DISABLE_N")
	)
	(segment
		(start 59.2074 -148.661374)
		(end 58.867802 -149.000972)
		(width 0.1143)
		(layer "In2.Cu")
		(net "LAN1_DISABLE_N")
	)
	(segment
		(start 72.507348 -147.8788)
		(end 67.392296 -147.8788)
		(width 0.1143)
		(layer "In2.Cu")
		(net "LAN1_DISABLE_N")
	)
	(segment
		(start 81.61401 -105.25125)
		(end 81.61401 -106.83113)
		(width 0.1143)
		(layer "In2.Cu")
		(net "LAN1_DISABLE_N")
	)
	(segment
		(start 71.336154 -90.126566)
		(end 77.527912 -90.126566)
		(width 0.1143)
		(layer "In2.Cu")
		(net "LAN1_DISABLE_N")
	)
	(segment
		(start 66.8655 -148.405596)
		(end 63.844678 -148.405596)
		(width 0.1143)
		(layer "In2.Cu")
		(net "LAN1_DISABLE_N")
	)
	(segment
		(start 67.392296 -147.8788)
		(end 66.8655 -148.405596)
		(width 0.1143)
		(layer "In2.Cu")
		(net "LAN1_DISABLE_N")
	)
	(segment
		(start 58.867802 -149.000972)
		(end 52.7685 -149.000972)
		(width 0.1143)
		(layer "In2.Cu")
		(net "LAN1_DISABLE_N")
	)
	(segment
		(start 78.08341 -133.729222)
		(end 78.08341 -145.499328)
		(width 0.1143)
		(layer "In2.Cu")
		(net "LAN1_DISABLE_N")
	)
	(segment
		(start 76.11999 -147.462748)
		(end 72.9234 -147.462748)
		(width 0.1143)
		(layer "In2.Cu")
		(net "LAN1_DISABLE_N")
	)
	(segment
		(start 63.844678 -148.405596)
		(end 63.5889 -148.661374)
		(width 0.1143)
		(layer "In2.Cu")
		(net "LAN1_DISABLE_N")
	)
	(segment
		(start 77.527912 -90.126566)
		(end 80.296512 -92.895166)
		(width 0.1143)
		(layer "In2.Cu")
		(net "LAN1_DISABLE_N")
	)
	(segment
		(start 50.07991 -148.18106)
		(end 50.07991 -148.757894)
		(width 0.1143)
		(layer "In2.Cu")
		(net "LAN1_DISABLE_N")
	)
	(segment
		(start 52.7685 -149.000972)
		(end 51.692048 -147.92452)
		(width 0.1143)
		(layer "In2.Cu")
		(net "LAN1_DISABLE_N")
	)
	(segment
		(start 50.33645 -147.92452)
		(end 50.07991 -148.18106)
		(width 0.1143)
		(layer "In2.Cu")
		(net "LAN1_DISABLE_N")
	)
	(segment
		(start 51.140106 -149.81809)
		(end 51.140106 -156.80436)
		(width 0.1143)
		(layer "In2.Cu")
		(net "LAN1_DISABLE_N")
	)
	(segment
		(start 68.441824 -90.259662)
		(end 71.203058 -90.259662)
		(width 0.1143)
		(layer "In2.Cu")
		(net "LAN1_DISABLE_N")
	)
	(segment
		(start 51.140106 -156.80436)
		(end 50.745644 -157.198822)
		(width 0.1143)
		(layer "In2.Cu")
		(net "LAN1_DISABLE_N")
	)
	(segment
		(start 78.08341 -145.499328)
		(end 76.11999 -147.462748)
		(width 0.1143)
		(layer "In2.Cu")
		(net "LAN1_DISABLE_N")
	)
	(segment
		(start 63.5889 -148.661374)
		(end 59.2074 -148.661374)
		(width 0.1143)
		(layer "In2.Cu")
		(net "LAN1_DISABLE_N")
	)
	(segment
		(start 81.61401 -106.83113)
		(end 79.14894 -109.2962)
		(width 0.1143)
		(layer "In2.Cu")
		(net "LAN1_DISABLE_N")
	)
	(segment
		(start 71.203058 -90.259662)
		(end 71.336154 -90.126566)
		(width 0.1143)
		(layer "In2.Cu")
		(net "LAN1_DISABLE_N")
	)
	(segment
		(start 51.692048 -147.92452)
		(end 50.33645 -147.92452)
		(width 0.1143)
		(layer "In2.Cu")
		(net "LAN1_DISABLE_N")
	)
	(segment
		(start 79.14894 -109.2962)
		(end 79.14894 -109.862112)
		(width 0.1143)
		(layer "In2.Cu")
		(net "LAN1_DISABLE_N")
	)
	(segment
		(start 117.327934 -39.91356)
		(end 117.678708 -39.91356)
		(width 0.1016)
		(layer "F.Cu")
		(net "OSC1_48MHZ")
	)
	(segment
		(start 118.738142 -39.93769)
		(end 118.738142 -40.580564)
		(width 0.1016)
		(layer "F.Cu")
		(net "OSC1_48MHZ")
	)
	(segment
		(start 117.678708 -39.91356)
		(end 118.345712 -40.580564)
		(width 0.1016)
		(layer "F.Cu")
		(net "OSC1_48MHZ")
	)
	(segment
		(start 118.345712 -40.580564)
		(end 118.738142 -40.580564)
		(width 0.1016)
		(layer "F.Cu")
		(net "OSC1_48MHZ")
	)
	(via
		(at 118.738142 -40.580564)
		(size 0.508)
		(drill 0.254)
		(layers "F.Cu" "B.Cu")
		(net "OSC1_48MHZ")
	)
	(segment
		(start 125.76175 -31.19374)
		(end 125.149102 -31.806388)
		(width 0.254)
		(layer "F.Cu")
		(net "SIO_VCCH")
	)
	(segment
		(start 125.149102 -31.806388)
		(end 124.93625 -31.806388)
		(width 0.254)
		(layer "F.Cu")
		(net "SIO_VCCH")
	)
	(segment
		(start 125.76175 -30.079696)
		(end 125.76175 -31.19374)
		(width 0.254)
		(layer "F.Cu")
		(net "SIO_VCCH")
	)
	(via
		(at 125.70714 -33.862264)
		(size 0.508)
		(drill 0.254)
		(layers "F.Cu" "B.Cu")
		(net "SIO_VCCH")
	)
	(via
		(at 124.50445 -31.076392)
		(size 0.6604)
		(drill 0.3302)
		(layers "F.Cu" "B.Cu")
		(net "SIO_VCCH")
	)
	(via
		(at 124.93625 -31.806388)
		(size 0.508)
		(drill 0.254)
		(layers "F.Cu" "B.Cu")
		(net "SIO_VCCH")
	)
	(via
		(at 123.73356 -31.342838)
		(size 0.508)
		(drill 0.254)
		(layers "F.Cu" "B.Cu")
		(net "SIO_VCCH")
	)
	(segment
		(start 47.817532 -159.472884)
		(end 47.817532 -160.417002)
		(width 0.1016)
		(layer "F.Cu")
		(net "SMB_LAN1_CLK")
	)
	(segment
		(start 47.817532 -160.417002)
		(end 48.65624 -161.25571)
		(width 0.1016)
		(layer "F.Cu")
		(net "SMB_LAN1_CLK")
	)
	(segment
		(start 51.66614 -163.83889)
		(end 52.00523 -163.4998)
		(width 0.1016)
		(layer "F.Cu")
		(net "SMB_LAN1_CLK")
	)
	(segment
		(start 48.65624 -161.25571)
		(end 50.60442 -161.25571)
		(width 0.1016)
		(layer "F.Cu")
		(net "SMB_LAN1_CLK")
	)
	(segment
		(start 52.17414 -162.82543)
		(end 51.57851 -162.2298)
		(width 0.1016)
		(layer "F.Cu")
		(net "SMB_LAN1_CLK")
	)
	(segment
		(start 50.60442 -161.25571)
		(end 51.57851 -162.2298)
		(width 0.1016)
		(layer "F.Cu")
		(net "SMB_LAN1_CLK")
	)
	(segment
		(start 51.66614 -165.5318)
		(end 51.66614 -163.83889)
		(width 0.1016)
		(layer "F.Cu")
		(net "SMB_LAN1_CLK")
	)
	(segment
		(start 52.17414 -163.4998)
		(end 52.17414 -162.82543)
		(width 0.1016)
		(layer "F.Cu")
		(net "SMB_LAN1_CLK")
	)
	(segment
		(start 52.00523 -163.4998)
		(end 52.17414 -163.4998)
		(width 0.1016)
		(layer "F.Cu")
		(net "SMB_LAN1_CLK")
	)
	(segment
		(start 52.17414 -166.0398)
		(end 51.66614 -165.5318)
		(width 0.1016)
		(layer "F.Cu")
		(net "SMB_LAN1_CLK")
	)
	(via
		(at 51.57851 -162.2298)
		(size 0.508)
		(drill 0.254)
		(layers "F.Cu" "B.Cu")
		(net "SMB_LAN1_CLK")
	)
	(via
		(at 33.93186 -149.463252)
		(size 0.508)
		(drill 0.254)
		(layers "F.Cu" "B.Cu")
		(net "LAN1_CTRL_P1V9")
	)
	(via
		(at 37.8587 -149.363176)
		(size 0.508)
		(drill 0.254)
		(layers "F.Cu" "B.Cu")
		(net "LAN1_CTRL_P1V9")
	)
	(via
		(at 33.22066 -151.285702)
		(size 0.508)
		(drill 0.254)
		(layers "F.Cu" "B.Cu")
		(net "LAN1_CTRL_P1V9")
	)
	(via
		(at 36.9697 -149.374352)
		(size 0.508)
		(drill 0.254)
		(layers "F.Cu" "B.Cu")
		(net "LAN1_CTRL_P1V9")
	)
	(via
		(at 35.88004 -149.39645)
		(size 0.508)
		(drill 0.254)
		(layers "F.Cu" "B.Cu")
		(net "LAN1_CTRL_P1V9")
	)
	(segment
		(start 38.736778 -153.673048)
		(end 38.19652 -153.13279)
		(width 0.1016)
		(layer "F.Cu")
		(net "LAN1_DIS_REG10")
	)
	(segment
		(start 40.0177 -153.673048)
		(end 38.736778 -153.673048)
		(width 0.1016)
		(layer "F.Cu")
		(net "LAN1_DIS_REG10")
	)
	(via
		(at 38.19652 -153.13279)
		(size 0.508)
		(drill 0.254)
		(layers "F.Cu" "B.Cu")
		(net "LAN1_DIS_REG10")
	)
	(via
		(at 39.15156 -146.76501)
		(size 0.508)
		(drill 0.254)
		(layers "F.Cu" "B.Cu")
		(net "LAN1_DIS_REG10")
	)
	(segment
		(start 38.97122 -146.58467)
		(end 39.15156 -146.76501)
		(width 0.1016)
		(layer "B.Cu")
		(net "LAN1_DIS_REG10")
	)
	(segment
		(start 38.32479 -146.58467)
		(end 38.97122 -146.58467)
		(width 0.1016)
		(layer "B.Cu")
		(net "LAN1_DIS_REG10")
	)
	(segment
		(start 38.32479 -145.56867)
		(end 38.32479 -146.58467)
		(width 0.1016)
		(layer "B.Cu")
		(net "LAN1_DIS_REG10")
	)
	(segment
		(start 38.19652 -151.30907)
		(end 38.19652 -153.13279)
		(width 0.1143)
		(layer "In2.Cu")
		(net "LAN1_DIS_REG10")
	)
	(segment
		(start 39.15156 -150.35403)
		(end 38.19652 -151.30907)
		(width 0.1143)
		(layer "In2.Cu")
		(net "LAN1_DIS_REG10")
	)
	(segment
		(start 39.15156 -146.76501)
		(end 39.15156 -150.35403)
		(width 0.1143)
		(layer "In2.Cu")
		(net "LAN1_DIS_REG10")
	)
	(segment
		(start 76.49464 -179.874672)
		(end 76.49464 -178.794918)
		(width 0.1016)
		(layer "F.Cu")
		(net "UART_SDC_TX")
	)
	(segment
		(start 75.5142 -176.436782)
		(end 76.89088 -175.060102)
		(width 0.1016)
		(layer "F.Cu")
		(net "UART_SDC_TX")
	)
	(segment
		(start 76.05776 -178.358038)
		(end 76.05776 -177.93716)
		(width 0.1016)
		(layer "F.Cu")
		(net "UART_SDC_TX")
	)
	(segment
		(start 76.49464 -178.794918)
		(end 76.05776 -178.358038)
		(width 0.1016)
		(layer "F.Cu")
		(net "UART_SDC_TX")
	)
	(segment
		(start 82.31886 -168.245282)
		(end 83.797648 -168.245282)
		(width 0.1016)
		(layer "F.Cu")
		(net "UART_SDC_TX")
	)
	(segment
		(start 81.768696 -168.795446)
		(end 82.31886 -168.245282)
		(width 0.1016)
		(layer "F.Cu")
		(net "UART_SDC_TX")
	)
	(segment
		(start 77.772006 -170.905424)
		(end 77.97927 -170.905424)
		(width 0.1016)
		(layer "F.Cu")
		(net "UART_SDC_TX")
	)
	(segment
		(start 75.5142 -177.3936)
		(end 75.5142 -177.094134)
		(width 0.1016)
		(layer "F.Cu")
		(net "UART_SDC_TX")
	)
	(segment
		(start 77.97927 -170.905424)
		(end 78.562454 -170.32224)
		(width 0.1016)
		(layer "F.Cu")
		(net "UART_SDC_TX")
	)
	(segment
		(start 76.89088 -171.78655)
		(end 77.772006 -170.905424)
		(width 0.1016)
		(layer "F.Cu")
		(net "UART_SDC_TX")
	)
	(segment
		(start 75.5142 -177.094134)
		(end 75.5142 -176.436782)
		(width 0.1016)
		(layer "F.Cu")
		(net "UART_SDC_TX")
	)
	(segment
		(start 76.89088 -175.060102)
		(end 76.89088 -171.78655)
		(width 0.1016)
		(layer "F.Cu")
		(net "UART_SDC_TX")
	)
	(segment
		(start 79.135224 -170.32224)
		(end 80.662018 -168.795446)
		(width 0.1016)
		(layer "F.Cu")
		(net "UART_SDC_TX")
	)
	(segment
		(start 76.05776 -177.93716)
		(end 75.5142 -177.3936)
		(width 0.1016)
		(layer "F.Cu")
		(net "UART_SDC_TX")
	)
	(segment
		(start 80.662018 -168.795446)
		(end 81.768696 -168.795446)
		(width 0.1016)
		(layer "F.Cu")
		(net "UART_SDC_TX")
	)
	(segment
		(start 78.562454 -170.32224)
		(end 79.135224 -170.32224)
		(width 0.1016)
		(layer "F.Cu")
		(net "UART_SDC_TX")
	)
	(via
		(at 83.797648 -168.245282)
		(size 0.508)
		(drill 0.254)
		(layers "F.Cu" "B.Cu")
		(net "UART_SDC_TX")
	)
	(via
		(at 75.5142 -177.094134)
		(size 0.508)
		(drill 0.254)
		(layers "F.Cu" "B.Cu")
		(net "UART_SDC_TX")
	)
	(segment
		(start 83.94446 -167.429942)
		(end 83.98256 -167.391842)
		(width 0.1016)
		(layer "B.Cu")
		(net "UART_SDC_TX")
	)
	(segment
		(start 83.94446 -168.09847)
		(end 83.94446 -167.429942)
		(width 0.1016)
		(layer "B.Cu")
		(net "UART_SDC_TX")
	)
	(segment
		(start 82.499962 -163.70427)
		(end 81.906872 -163.70427)
		(width 0.1016)
		(layer "B.Cu")
		(net "UART_SDC_TX")
	)
	(segment
		(start 83.98256 -165.186868)
		(end 82.499962 -163.70427)
		(width 0.1016)
		(layer "B.Cu")
		(net "UART_SDC_TX")
	)
	(segment
		(start 83.98256 -167.391842)
		(end 83.98256 -165.186868)
		(width 0.1016)
		(layer "B.Cu")
		(net "UART_SDC_TX")
	)
	(segment
		(start 83.797648 -168.245282)
		(end 83.94446 -168.09847)
		(width 0.1016)
		(layer "B.Cu")
		(net "UART_SDC_TX")
	)
	(segment
		(start 39.501572 -156.71419)
		(end 36.568634 -156.71419)
		(width 0.10414)
		(layer "F.Cu")
		(net "LAN1_MDI2_DP")
	)
	(segment
		(start 33.021016 -157.994096)
		(end 32.582104 -158.433008)
		(width 0.10414)
		(layer "F.Cu")
		(net "LAN1_MDI2_DP")
	)
	(segment
		(start 36.568634 -156.71419)
		(end 35.288728 -157.994096)
		(width 0.10414)
		(layer "F.Cu")
		(net "LAN1_MDI2_DP")
	)
	(segment
		(start 29.583126 -161.431986)
		(end 28.77058 -161.431986)
		(width 0.10414)
		(layer "F.Cu")
		(net "LAN1_MDI2_DP")
	)
	(segment
		(start 32.582104 -158.433008)
		(end 32.582104 -158.432754)
		(width 0.10414)
		(layer "F.Cu")
		(net "LAN1_MDI2_DP")
	)
	(segment
		(start 39.54272 -156.673042)
		(end 39.501572 -156.71419)
		(width 0.10414)
		(layer "F.Cu")
		(net "LAN1_MDI2_DP")
	)
	(segment
		(start 32.582104 -158.432754)
		(end 29.583126 -161.431986)
		(width 0.10414)
		(layer "F.Cu")
		(net "LAN1_MDI2_DP")
	)
	(segment
		(start 40.0177 -156.673042)
		(end 39.54272 -156.673042)
		(width 0.10414)
		(layer "F.Cu")
		(net "LAN1_MDI2_DP")
	)
	(segment
		(start 28.77058 -161.431986)
		(end 27.477974 -161.431986)
		(width 0.10414)
		(layer "F.Cu")
		(net "LAN1_MDI2_DP")
	)
	(segment
		(start 27.477974 -161.431986)
		(end 27.060144 -161.014156)
		(width 0.10414)
		(layer "F.Cu")
		(net "LAN1_MDI2_DP")
	)
	(segment
		(start 35.288728 -157.994096)
		(end 33.021016 -157.994096)
		(width 0.10414)
		(layer "F.Cu")
		(net "LAN1_MDI2_DP")
	)
	(segment
		(start 27.060144 -161.014156)
		(end 26.34615 -161.014156)
		(width 0.10414)
		(layer "F.Cu")
		(net "LAN1_MDI2_DP")
	)
	(via
		(at 28.77058 -161.431986)
		(size 0.4064)
		(drill 0.2032)
		(layers "F.Cu" "B.Cu")
		(net "LAN1_MDI2_DP")
	)
	(segment
		(start 76.37272 -175.133)
		(end 76.37272 -171.28871)
		(width 0.1016)
		(layer "F.Cu")
		(net "UART_SDC_RX")
	)
	(segment
		(start 77.772006 -169.889424)
		(end 77.977746 -169.889424)
		(width 0.1016)
		(layer "F.Cu")
		(net "UART_SDC_RX")
	)
	(segment
		(start 77.977746 -169.889424)
		(end 81.496408 -166.370762)
		(width 0.1016)
		(layer "F.Cu")
		(net "UART_SDC_RX")
	)
	(segment
		(start 75.994768 -179.039012)
		(end 75.994768 -179.874672)
		(width 0.1016)
		(layer "F.Cu")
		(net "UART_SDC_RX")
	)
	(segment
		(start 81.496408 -166.370762)
		(end 82.961226 -166.370762)
		(width 0.1016)
		(layer "F.Cu")
		(net "UART_SDC_RX")
	)
	(segment
		(start 75.0824 -176.42332)
		(end 76.37272 -175.133)
		(width 0.1016)
		(layer "F.Cu")
		(net "UART_SDC_RX")
	)
	(segment
		(start 75.401932 -178.446176)
		(end 75.401932 -178.444652)
		(width 0.1016)
		(layer "F.Cu")
		(net "UART_SDC_RX")
	)
	(segment
		(start 75.401932 -178.446176)
		(end 75.994768 -179.039012)
		(width 0.1016)
		(layer "F.Cu")
		(net "UART_SDC_RX")
	)
	(segment
		(start 75.401932 -178.444652)
		(end 75.0824 -178.12512)
		(width 0.1016)
		(layer "F.Cu")
		(net "UART_SDC_RX")
	)
	(segment
		(start 82.961226 -166.370762)
		(end 83.50504 -166.914576)
		(width 0.1016)
		(layer "F.Cu")
		(net "UART_SDC_RX")
	)
	(segment
		(start 75.0824 -178.12512)
		(end 75.0824 -176.42332)
		(width 0.1016)
		(layer "F.Cu")
		(net "UART_SDC_RX")
	)
	(segment
		(start 76.37272 -171.28871)
		(end 77.772006 -169.889424)
		(width 0.1016)
		(layer "F.Cu")
		(net "UART_SDC_RX")
	)
	(via
		(at 83.50504 -166.914576)
		(size 0.508)
		(drill 0.254)
		(layers "F.Cu" "B.Cu")
		(net "UART_SDC_RX")
	)
	(via
		(at 75.401932 -178.446176)
		(size 0.508)
		(drill 0.254)
		(layers "F.Cu" "B.Cu")
		(net "UART_SDC_RX")
	)
	(segment
		(start 83.67776 -165.59149)
		(end 83.67776 -166.374064)
		(width 0.1016)
		(layer "B.Cu")
		(net "UART_SDC_RX")
	)
	(segment
		(start 83.50504 -166.546784)
		(end 83.50504 -166.914576)
		(width 0.1016)
		(layer "B.Cu")
		(net "UART_SDC_RX")
	)
	(segment
		(start 81.906872 -164.354256)
		(end 82.440526 -164.354256)
		(width 0.1016)
		(layer "B.Cu")
		(net "UART_SDC_RX")
	)
	(segment
		(start 82.440526 -164.354256)
		(end 83.67776 -165.59149)
		(width 0.1016)
		(layer "B.Cu")
		(net "UART_SDC_RX")
	)
	(segment
		(start 83.67776 -166.374064)
		(end 83.50504 -166.546784)
		(width 0.1016)
		(layer "B.Cu")
		(net "UART_SDC_RX")
	)
	(segment
		(start 48.80102 -160.58769)
		(end 50.533554 -160.58769)
		(width 0.1016)
		(layer "F.Cu")
		(net "LAN1_LED_LINK_1000_N")
	)
	(segment
		(start 50.533554 -160.58769)
		(end 51.487324 -161.54146)
		(width 0.1016)
		(layer "F.Cu")
		(net "LAN1_LED_LINK_1000_N")
	)
	(segment
		(start 48.317658 -159.472884)
		(end 48.317658 -160.104328)
		(width 0.1016)
		(layer "F.Cu")
		(net "LAN1_LED_LINK_1000_N")
	)
	(segment
		(start 51.98872 -161.54146)
		(end 52.493418 -162.046158)
		(width 0.1016)
		(layer "F.Cu")
		(net "LAN1_LED_LINK_1000_N")
	)
	(segment
		(start 48.317658 -160.104328)
		(end 48.80102 -160.58769)
		(width 0.1016)
		(layer "F.Cu")
		(net "LAN1_LED_LINK_1000_N")
	)
	(segment
		(start 52.493418 -162.046158)
		(end 53.161946 -162.046158)
		(width 0.1016)
		(layer "F.Cu")
		(net "LAN1_LED_LINK_1000_N")
	)
	(segment
		(start 51.487324 -161.54146)
		(end 51.98872 -161.54146)
		(width 0.1016)
		(layer "F.Cu")
		(net "LAN1_LED_LINK_1000_N")
	)
	(via
		(at 48.80102 -160.58769)
		(size 0.508)
		(drill 0.254)
		(layers "F.Cu" "B.Cu")
		(net "LAN1_LED_LINK_1000_N")
	)
	(segment
		(start 50.82667 -163.4998)
		(end 51.03114 -163.4998)
		(width 0.1016)
		(layer "F.Cu")
		(net "SMB_LAN1_ALT_N")
	)
	(segment
		(start 51.03114 -166.0398)
		(end 50.45456 -165.46322)
		(width 0.1016)
		(layer "F.Cu")
		(net "SMB_LAN1_ALT_N")
	)
	(segment
		(start 51.03114 -163.4998)
		(end 51.03114 -163.38423)
		(width 0.1016)
		(layer "F.Cu")
		(net "SMB_LAN1_ALT_N")
	)
	(segment
		(start 47.31766 -159.472884)
		(end 47.31766 -160.50133)
		(width 0.1016)
		(layer "F.Cu")
		(net "SMB_LAN1_ALT_N")
	)
	(segment
		(start 51.03114 -163.38423)
		(end 50.15992 -162.51301)
		(width 0.1016)
		(layer "F.Cu")
		(net "SMB_LAN1_ALT_N")
	)
	(segment
		(start 47.31766 -160.50133)
		(end 48.5648 -161.74847)
		(width 0.1016)
		(layer "F.Cu")
		(net "SMB_LAN1_ALT_N")
	)
	(segment
		(start 49.39538 -161.74847)
		(end 50.15992 -162.51301)
		(width 0.1016)
		(layer "F.Cu")
		(net "SMB_LAN1_ALT_N")
	)
	(segment
		(start 50.45456 -165.46322)
		(end 50.45456 -163.87191)
		(width 0.1016)
		(layer "F.Cu")
		(net "SMB_LAN1_ALT_N")
	)
	(segment
		(start 50.45456 -163.87191)
		(end 50.82667 -163.4998)
		(width 0.1016)
		(layer "F.Cu")
		(net "SMB_LAN1_ALT_N")
	)
	(segment
		(start 48.5648 -161.74847)
		(end 49.39538 -161.74847)
		(width 0.1016)
		(layer "F.Cu")
		(net "SMB_LAN1_ALT_N")
	)
	(via
		(at 50.15992 -162.51301)
		(size 0.508)
		(drill 0.254)
		(layers "F.Cu" "B.Cu")
		(net "SMB_LAN1_ALT_N")
	)
	(segment
		(start 122.451622 -40.889682)
		(end 120.9167 -40.889682)
		(width 0.1016)
		(layer "F.Cu")
		(net "SIO_PCICLK33")
	)
	(segment
		(start 120.9167 -40.889682)
		(end 120.602502 -41.20388)
		(width 0.1016)
		(layer "F.Cu")
		(net "SIO_PCICLK33")
	)
	(segment
		(start 119.52478 -41.529762)
		(end 120.27662 -41.529762)
		(width 0.1016)
		(layer "F.Cu")
		(net "SIO_PCICLK33")
	)
	(segment
		(start 120.27662 -41.529762)
		(end 120.602502 -41.20388)
		(width 0.1016)
		(layer "F.Cu")
		(net "SIO_PCICLK33")
	)
	(via
		(at 120.602502 -41.20388)
		(size 0.508)
		(drill 0.254)
		(layers "F.Cu" "B.Cu")
		(net "SIO_PCICLK33")
	)
	(segment
		(start 53.161946 -161.030158)
		(end 52.033678 -161.030158)
		(width 0.1016)
		(layer "F.Cu")
		(net "LAN1_LED_LINK_100_N")
	)
	(segment
		(start 50.89652 -159.893)
		(end 50.89652 -159.78759)
		(width 0.1016)
		(layer "F.Cu")
		(net "LAN1_LED_LINK_100_N")
	)
	(segment
		(start 52.033678 -161.030158)
		(end 50.89652 -159.893)
		(width 0.1016)
		(layer "F.Cu")
		(net "LAN1_LED_LINK_100_N")
	)
	(segment
		(start 49.891442 -158.172912)
		(end 50.89652 -159.17799)
		(width 0.1016)
		(layer "F.Cu")
		(net "LAN1_LED_LINK_100_N")
	)
	(segment
		(start 50.89652 -159.17799)
		(end 50.89652 -159.78759)
		(width 0.1016)
		(layer "F.Cu")
		(net "LAN1_LED_LINK_100_N")
	)
	(segment
		(start 49.117504 -158.172912)
		(end 49.891442 -158.172912)
		(width 0.1016)
		(layer "F.Cu")
		(net "LAN1_LED_LINK_100_N")
	)
	(via
		(at 50.89652 -159.78759)
		(size 0.508)
		(drill 0.254)
		(layers "F.Cu" "B.Cu")
		(net "LAN1_LED_LINK_100_N")
	)
	(via
		(at 28.01493 -198.676514)
		(size 0.508)
		(drill 0.254)
		(layers "F.Cu" "B.Cu")
		(net "Net_2330")
	)
	(segment
		(start 28.01493 -198.676514)
		(end 27.58313 -199.108314)
		(width 0.1016)
		(layer "B.Cu")
		(net "Net_2330")
	)
	(segment
		(start 27.58313 -200.347072)
		(end 28.01493 -200.778872)
		(width 0.1016)
		(layer "B.Cu")
		(net "Net_2330")
	)
	(segment
		(start 27.58313 -199.108314)
		(end 27.58313 -200.347072)
		(width 0.1016)
		(layer "B.Cu")
		(net "Net_2330")
	)
	(segment
		(start 28.01493 -200.778872)
		(end 28.01493 -205.199488)
		(width 0.1016)
		(layer "B.Cu")
		(net "Net_2330")
	)
	(segment
		(start 25.04186 -198.753476)
		(end 25.47366 -199.185276)
		(width 0.1016)
		(layer "F.Cu")
		(net "Net_2331")
	)
	(segment
		(start 25.014936 -200.655682)
		(end 25.014936 -205.199488)
		(width 0.1016)
		(layer "F.Cu")
		(net "Net_2331")
	)
	(segment
		(start 25.47366 -200.196958)
		(end 25.014936 -200.655682)
		(width 0.1016)
		(layer "F.Cu")
		(net "Net_2331")
	)
	(segment
		(start 25.47366 -199.185276)
		(end 25.47366 -200.196958)
		(width 0.1016)
		(layer "F.Cu")
		(net "Net_2331")
	)
	(via
		(at 25.04186 -198.753476)
		(size 0.508)
		(drill 0.254)
		(layers "F.Cu" "B.Cu")
		(net "Net_2331")
	)
	(segment
		(start 28.01493 -205.199488)
		(end 28.01493 -199.576436)
		(width 0.1016)
		(layer "F.Cu")
		(net "Net_2332")
	)
	(via
		(at 28.01493 -199.576436)
		(size 0.508)
		(drill 0.254)
		(layers "F.Cu" "B.Cu")
		(net "Net_2332")
	)
	(via
		(at 26.014934 -198.676514)
		(size 0.508)
		(drill 0.254)
		(layers "F.Cu" "B.Cu")
		(net "Net_2333")
	)
	(segment
		(start 25.46096 -199.230488)
		(end 25.46096 -200.370948)
		(width 0.1016)
		(layer "B.Cu")
		(net "Net_2333")
	)
	(segment
		(start 25.46096 -200.370948)
		(end 26.014934 -200.924922)
		(width 0.1016)
		(layer "B.Cu")
		(net "Net_2333")
	)
	(segment
		(start 26.014934 -198.676514)
		(end 25.46096 -199.230488)
		(width 0.1016)
		(layer "B.Cu")
		(net "Net_2333")
	)
	(segment
		(start 26.014934 -200.924922)
		(end 26.014934 -205.199488)
		(width 0.1016)
		(layer "B.Cu")
		(net "Net_2333")
	)
	(via
		(at 27.014932 -199.59066)
		(size 0.508)
		(drill 0.254)
		(layers "F.Cu" "B.Cu")
		(net "Net_2334")
	)
	(segment
		(start 27.014932 -205.199488)
		(end 27.014932 -199.59066)
		(width 0.1016)
		(layer "B.Cu")
		(net "Net_2334")
	)
	(zone
		(layer "F.Cu")
		(hatch none 0.5)
		(connect_pads
			(clearance 0)
		)
		(min_thickness 0.25)
		(keepout
			(tracks allowed)
			(vias allowed)
			(pads allowed)
			(copperpour allowed)
			(footprints allowed)
		)
		(placement
			(enabled no)
			(sheetname "")
		)
		(fill
			(thermal_gap 0.5)
			(thermal_bridge_width 0.5)
			(island_removal_mode 0)
		)
		(polygon
			(pts
				(xy 32.347408 -183.68772) (xy 33.608518 -183.68772) (xy 33.696148 -183.60009) (xy 33.696148 -182.94604)
				(xy 33.38576 -182.635652) (xy 32.408114 -182.635652) (xy 32.307022 -182.736744) (xy 32.307022 -183.647334)
			)
		)
	)
	(zone
		(layer "F.Cu")
		(hatch none 0.5)
		(connect_pads
			(clearance 0)
		)
		(min_thickness 0.25)
		(keepout
			(tracks allowed)
			(vias allowed)
			(pads allowed)
			(copperpour allowed)
			(footprints not_allowed)
		)
		(placement
			(enabled no)
			(sheetname "")
		)
		(fill
			(thermal_gap 0.5)
			(thermal_bridge_width 0.5)
			(island_removal_mode 0)
		)
		(polygon
			(pts
				(arc
					(start 25.999948 -90.300048)
					(mid 24.500078 -88.800178)
					(end 25.999948 -87.300054)
				)
				(arc
					(start 25.999948 -87.300054)
					(mid 27.500072 -88.800178)
					(end 25.999948 -90.300048)
				)
			)
		)
	)
	(zone
		(layer "F.Cu")
		(hatch none 0.5)
		(connect_pads
			(clearance 0)
		)
		(min_thickness 0.25)
		(keepout
			(tracks allowed)
			(vias allowed)
			(pads allowed)
			(copperpour allowed)
			(footprints allowed)
		)
		(placement
			(enabled no)
			(sheetname "")
		)
		(fill
			(thermal_gap 0.5)
			(thermal_bridge_width 0.5)
			(island_removal_mode 0)
		)
		(polygon
			(pts
				(xy 44.12615 -160.288224) (xy 44.12615 -159.634174) (xy 43.815762 -159.323786) (xy 42.838116 -159.323786)
				(xy 42.737024 -159.424878) (xy 42.737024 -160.335468) (xy 42.737024 -160.908746) (xy 42.905426 -161.077148)
				(xy 43.836082 -161.077148) (xy 44.12615 -160.78708)
			)
		)
	)
	(zone
		(layer "F.Cu")
		(hatch none 0.5)
		(connect_pads
			(clearance 0)
		)
		(min_thickness 0.25)
		(keepout
			(tracks allowed)
			(vias allowed)
			(pads allowed)
			(copperpour allowed)
			(footprints not_allowed)
		)
		(placement
			(enabled no)
			(sheetname "")
		)
		(fill
			(thermal_gap 0.5)
			(thermal_bridge_width 0.5)
			(island_removal_mode 0)
		)
		(polygon
			(pts
				(arc
					(start 25.999948 -64.3001)
					(mid 24.500078 -62.80023)
					(end 25.999948 -61.300106)
				)
				(arc
					(start 25.999948 -61.300106)
					(mid 27.500072 -62.80023)
					(end 25.999948 -64.3001)
				)
			)
		)
	)
	(zone
		(layer "F.Cu")
		(hatch none 0.5)
		(connect_pads
			(clearance 0)
		)
		(min_thickness 0.25)
		(keepout
			(tracks allowed)
			(vias allowed)
			(pads allowed)
			(copperpour allowed)
			(footprints not_allowed)
		)
		(placement
			(enabled no)
			(sheetname "")
		)
		(fill
			(thermal_gap 0.5)
			(thermal_bridge_width 0.5)
			(island_removal_mode 0)
		)
		(polygon
			(pts
				(arc
					(start 90.000074 -90.300048)
					(mid 88.500204 -88.800178)
					(end 90.000074 -87.300054)
				)
				(arc
					(start 90.000074 -87.300054)
					(mid 91.500198 -88.800178)
					(end 90.000074 -90.300048)
				)
			)
		)
	)
	(zone
		(layer "F.Cu")
		(hatch none 0.5)
		(connect_pads
			(clearance 0)
		)
		(min_thickness 0.25)
		(keepout
			(tracks allowed)
			(vias allowed)
			(pads allowed)
			(copperpour allowed)
			(footprints not_allowed)
		)
		(placement
			(enabled no)
			(sheetname "")
		)
		(fill
			(thermal_gap 0.5)
			(thermal_bridge_width 0.5)
			(island_removal_mode 0)
		)
		(polygon
			(pts
				(arc
					(start 25.999948 -83.799934)
					(mid 30.999938 -88.799924)
					(end 25.999948 -93.799914)
				)
				(arc
					(start 25.999948 -93.799914)
					(mid 20.999958 -88.799924)
					(end 25.999948 -83.799934)
				)
			)
		)
	)
	(zone
		(layer "F.Cu")
		(hatch none 0.5)
		(connect_pads
			(clearance 0)
		)
		(min_thickness 0.25)
		(keepout
			(tracks allowed)
			(vias allowed)
			(pads allowed)
			(copperpour allowed)
			(footprints allowed)
		)
		(placement
			(enabled no)
			(sheetname "")
		)
		(fill
			(thermal_gap 0.5)
			(thermal_bridge_width 0.5)
			(island_removal_mode 0)
		)
		(polygon
			(pts
				(xy 80.721962 -32.666686) (xy 81.57845 -32.666686) (xy 81.92262 -32.666686) (xy 82.144616 -32.444436)
				(xy 82.144616 -30.661864) (xy 81.76768 -30.284928) (xy 78.759812 -30.284928) (xy 78.566518 -30.478222)
				(xy 78.566518 -32.568642) (xy 78.664562 -32.666686)
			)
		)
	)
	(zone
		(layer "F.Cu")
		(hatch none 0.5)
		(connect_pads
			(clearance 0)
		)
		(min_thickness 0.25)
		(keepout
			(tracks allowed)
			(vias allowed)
			(pads allowed)
			(copperpour allowed)
			(footprints allowed)
		)
		(placement
			(enabled no)
			(sheetname "")
		)
		(fill
			(thermal_gap 0.5)
			(thermal_bridge_width 0.5)
			(island_removal_mode 0)
		)
		(polygon
			(pts
				(xy 54.861206 -137.038334) (xy 55.171594 -136.727946) (xy 55.171594 -135.7503) (xy 55.171594 -135.252714)
				(xy 54.9656 -135.04672) (xy 54.189122 -135.04672) (xy 53.586634 -135.649208) (xy 53.418232 -135.81761)
				(xy 53.418232 -136.24052) (xy 52.910232 -136.74852) (xy 52.65928 -136.74852) (xy 52.29606 -137.11174)
				(xy 52.29606 -137.3886) (xy 52.62372 -137.71626) (xy 54.18328 -137.71626)
			)
		)
	)
	(zone
		(layer "F.Cu")
		(hatch none 0.5)
		(connect_pads
			(clearance 0)
		)
		(min_thickness 0.25)
		(keepout
			(tracks allowed)
			(vias allowed)
			(pads allowed)
			(copperpour allowed)
			(footprints not_allowed)
		)
		(placement
			(enabled no)
			(sheetname "")
		)
		(fill
			(thermal_gap 0.5)
			(thermal_bridge_width 0.5)
			(island_removal_mode 0)
		)
		(polygon
			(pts
				(xy 84.000086 -1.800098) (xy 129.500122 -1.800098) (xy 129.500122 -17.800066) (xy 84.000086 -17.800066)
			)
		)
	)
	(zone
		(net "POWER_SW3_PWR_CTR_12V")
		(layer "F.Cu")
		(hatch none 0.5)
		(connect_pads
			(clearance 0.5)
		)
		(min_thickness 0.25)
		(fill yes
			(thermal_gap 0.5)
			(thermal_bridge_width 0.5)
			(island_removal_mode 0)
		)
		(polygon
			(pts
				(xy 185.8772 -185.166) (xy 184.6072 -185.166) (xy 184.531 -185.0898) (xy 184.531 -184.6834) (xy 184.531 -180.0479)
				(xy 184.52465 -180.04155) (xy 184.52465 -179.63515) (xy 184.52465 -179.45735) (xy 184.5818 -179.4002)
				(xy 184.7596 -179.4002) (xy 185.801 -179.4002) (xy 186.1312 -179.7304) (xy 186.1312 -184.912)
			)
		)
	)
	(zone
		(layer "F.Cu")
		(hatch none 0.5)
		(connect_pads
			(clearance 0)
		)
		(min_thickness 0.25)
		(keepout
			(tracks allowed)
			(vias allowed)
			(pads allowed)
			(copperpour allowed)
			(footprints allowed)
		)
		(placement
			(enabled no)
			(sheetname "")
		)
		(fill
			(thermal_gap 0.5)
			(thermal_bridge_width 0.5)
			(island_removal_mode 0)
		)
		(polygon
			(pts
				(xy 101.082602 -33.778698) (xy 101.35108 -33.778698) (xy 101.63302 -33.496758) (xy 101.63302 -32.025082)
				(xy 101.36124 -31.753302) (xy 99.77882 -31.753302) (xy 99.4537 -32.078422) (xy 99.4537 -33.400492)
				(xy 99.831906 -33.778698)
			)
		)
	)
	(zone
		(layer "F.Cu")
		(hatch none 0.5)
		(connect_pads
			(clearance 0)
		)
		(min_thickness 0.25)
		(keepout
			(tracks allowed)
			(vias allowed)
			(pads allowed)
			(copperpour allowed)
			(footprints allowed)
		)
		(placement
			(enabled no)
			(sheetname "")
		)
		(fill
			(thermal_gap 0.5)
			(thermal_bridge_width 0.5)
			(island_removal_mode 0)
		)
		(polygon
			(pts
				(xy 114.867182 -19.260312) (xy 114.867182 -21.349462) (xy 115.082828 -21.565108) (xy 115.675664 -21.565108)
				(xy 115.837462 -21.40331) (xy 115.837462 -19.475958) (xy 115.608354 -19.24685) (xy 114.880644 -19.24685)
			)
		)
	)
	(zone
		(layer "F.Cu")
		(hatch none 0.5)
		(connect_pads
			(clearance 0)
		)
		(min_thickness 0.25)
		(keepout
			(tracks allowed)
			(vias allowed)
			(pads allowed)
			(copperpour allowed)
			(footprints not_allowed)
		)
		(placement
			(enabled no)
			(sheetname "")
		)
		(fill
			(thermal_gap 0.5)
			(thermal_bridge_width 0.5)
			(island_removal_mode 0)
		)
		(polygon
			(pts
				(arc
					(start 90.000074 -64.3001)
					(mid 88.500204 -62.80023)
					(end 90.000074 -61.300106)
				)
				(arc
					(start 90.000074 -61.300106)
					(mid 91.500198 -62.80023)
					(end 90.000074 -64.3001)
				)
			)
		)
	)
	(zone
		(layer "F.Cu")
		(hatch none 0.5)
		(connect_pads
			(clearance 0)
		)
		(min_thickness 0.25)
		(keepout
			(tracks allowed)
			(vias allowed)
			(pads allowed)
			(copperpour allowed)
			(footprints allowed)
		)
		(placement
			(enabled no)
			(sheetname "")
		)
		(fill
			(thermal_gap 0.5)
			(thermal_bridge_width 0.5)
			(island_removal_mode 0)
		)
		(polygon
			(pts
				(xy 133.563868 -132.359908) (xy 133.019546 -132.90423) (xy 133.306058 -133.190742) (xy 133.85038 -132.64642)
			)
		)
	)
	(zone
		(layer "F.Cu")
		(hatch none 0.5)
		(connect_pads
			(clearance 0)
		)
		(min_thickness 0.25)
		(keepout
			(tracks allowed)
			(vias allowed)
			(pads allowed)
			(copperpour allowed)
			(footprints not_allowed)
		)
		(placement
			(enabled no)
			(sheetname "")
		)
		(fill
			(thermal_gap 0.5)
			(thermal_bridge_width 0.5)
			(island_removal_mode 0)
		)
		(polygon
			(pts
				(xy 39.500048 -46.399958) (xy 32.824928 -46.399958) (xy 32.824928 -19.899884) (xy 111.175038 -19.899884)
				(xy 111.175038 -46.399958) (xy 104.499918 -46.399958) (xy 104.499918 -54.799992) (xy 39.500048 -54.799992)
			)
		)
	)
	(zone
		(layer "F.Cu")
		(hatch none 0.5)
		(connect_pads
			(clearance 0)
		)
		(min_thickness 0.25)
		(keepout
			(tracks not_allowed)
			(vias allowed)
			(pads allowed)
			(copperpour not_allowed)
			(footprints allowed)
		)
		(placement
			(enabled no)
			(sheetname "")
		)
		(fill
			(thermal_gap 0.5)
			(thermal_bridge_width 0.5)
			(island_removal_mode 0)
		)
		(polygon
			(pts
				(arc
					(start 27.177746 -180.539898)
					(mid 26.899379 -180.888127)
					(end 26.800048 -181.322726)
				)
				(arc
					(start 26.800048 -182.79999)
					(mid 25.000204 -184.599834)
					(end 23.200106 -182.79999)
				)
				(arc
					(start 23.200106 -181.322726)
					(mid 23.100605 -180.888123)
					(end 22.822154 -180.539898)
				)
				(arc
					(start 22.822154 -180.539898)
					(mid 24.99995 -174.300023)
					(end 27.177746 -180.539898)
				)
			)
		)
	)
	(zone
		(layer "F.Cu")
		(hatch none 0.5)
		(connect_pads
			(clearance 0)
		)
		(min_thickness 0.25)
		(keepout
			(tracks allowed)
			(vias allowed)
			(pads allowed)
			(copperpour allowed)
			(footprints allowed)
		)
		(placement
			(enabled no)
			(sheetname "")
		)
		(fill
			(thermal_gap 0.5)
			(thermal_bridge_width 0.5)
			(island_removal_mode 0)
		)
		(polygon
			(pts
				(xy 15.449042 -128.837944) (xy 17.100042 -128.837944) (xy 17.187672 -128.750314) (xy 17.187672 -128.009142)
				(xy 17.052798 -127.874268) (xy 15.475712 -127.874268) (xy 15.26032 -128.08966) (xy 15.26032 -128.649222)
			)
		)
	)
	(zone
		(layer "F.Cu")
		(hatch none 0.5)
		(connect_pads
			(clearance 0)
		)
		(min_thickness 0.25)
		(keepout
			(tracks allowed)
			(vias allowed)
			(pads allowed)
			(copperpour allowed)
			(footprints not_allowed)
		)
		(placement
			(enabled no)
			(sheetname "")
		)
		(fill
			(thermal_gap 0.5)
			(thermal_bridge_width 0.5)
			(island_removal_mode 0)
		)
		(polygon
			(pts
				(xy 160.699958 -23.16988) (xy 160.699958 -73.170034) (xy 133.422644 -73.170034) (xy 132.999988 -72.99833)
				(xy 132.999988 -70.037452) (xy 124.800106 -70.037452) (xy 124.800106 -72.99833) (xy 124.37745 -73.170034)
				(xy 120.549924 -73.170034) (xy 120.549924 -23.16988)
			)
		)
	)
	(zone
		(layer "F.Cu")
		(hatch none 0.5)
		(connect_pads
			(clearance 0)
		)
		(min_thickness 0.25)
		(keepout
			(tracks allowed)
			(vias allowed)
			(pads allowed)
			(copperpour allowed)
			(footprints not_allowed)
		)
		(placement
			(enabled no)
			(sheetname "")
		)
		(fill
			(thermal_gap 0.5)
			(thermal_bridge_width 0.5)
			(island_removal_mode 0)
		)
		(polygon
			(pts
				(arc
					(start 122.199908 -12.770104)
					(mid 118.199916 -8.770112)
					(end 122.199908 -4.77012)
				)
				(arc
					(start 122.199908 -4.77012)
					(mid 126.1999 -8.770112)
					(end 122.199908 -12.770104)
				)
			)
		)
	)
	(zone
		(layer "F.Cu")
		(hatch none 0.5)
		(connect_pads
			(clearance 0)
		)
		(min_thickness 0.25)
		(keepout
			(tracks allowed)
			(vias allowed)
			(pads allowed)
			(copperpour allowed)
			(footprints not_allowed)
		)
		(placement
			(enabled no)
			(sheetname "")
		)
		(fill
			(thermal_gap 0.5)
			(thermal_bridge_width 0.5)
			(island_removal_mode 0)
		)
		(polygon
			(pts
				(arc
					(start 105.000044 -87.799926)
					(mid 113.000028 -95.79991)
					(end 105.000044 -103.799894)
				)
				(arc
					(start 105.000044 -103.799894)
					(mid 97.00006 -95.79991)
					(end 105.000044 -87.799926)
				)
			)
		)
	)
	(zone
		(layer "F.Cu")
		(hatch none 0.5)
		(connect_pads
			(clearance 0)
		)
		(min_thickness 0.25)
		(keepout
			(tracks allowed)
			(vias allowed)
			(pads allowed)
			(copperpour allowed)
			(footprints allowed)
		)
		(placement
			(enabled no)
			(sheetname "")
		)
		(fill
			(thermal_gap 0.5)
			(thermal_bridge_width 0.5)
			(island_removal_mode 0)
		)
		(polygon
			(pts
				(xy 150.12416 -72.63511) (xy 150.471124 -72.63511) (xy 150.511764 -72.59447) (xy 150.511764 -72.237092)
				(xy 150.410672 -72.136) (xy 150.143972 -72.136) (xy 150.026116 -72.253856) (xy 150.026116 -72.537066)
			)
		)
	)
	(zone
		(layer "F.Cu")
		(hatch none 0.5)
		(connect_pads
			(clearance 0)
		)
		(min_thickness 0.25)
		(keepout
			(tracks allowed)
			(vias allowed)
			(pads allowed)
			(copperpour allowed)
			(footprints not_allowed)
		)
		(placement
			(enabled no)
			(sheetname "")
		)
		(fill
			(thermal_gap 0.5)
			(thermal_bridge_width 0.5)
			(island_removal_mode 0)
		)
		(polygon
			(pts
				(xy 104.499918 -54.799992) (xy 104.499918 -28.800044) (xy 39.500048 -28.800044) (xy 39.500048 -54.799992)
			)
		)
	)
	(zone
		(layer "F.Cu")
		(hatch none 0.5)
		(connect_pads
			(clearance 0)
		)
		(min_thickness 0.25)
		(keepout
			(tracks allowed)
			(vias allowed)
			(pads allowed)
			(copperpour allowed)
			(footprints allowed)
		)
		(placement
			(enabled no)
			(sheetname "")
		)
		(fill
			(thermal_gap 0.5)
			(thermal_bridge_width 0.5)
			(island_removal_mode 0)
		)
		(polygon
			(pts
				(xy 77.12202 84.197698) (xy 78.140306 84.197698) (xy 78.30566 84.197698) (xy 78.379828 84.271866)
				(xy 78.379828 86.32698) (xy 78.33106 86.375748) (xy 78.153768 86.375748) (xy 77.277214 86.375748)
				(xy 77.020928 86.119462) (xy 77.020928 84.29879)
			)
		)
	)
	(zone
		(layer "F.Cu")
		(hatch none 0.5)
		(connect_pads
			(clearance 0)
		)
		(min_thickness 0.25)
		(keepout
			(tracks not_allowed)
			(vias allowed)
			(pads allowed)
			(copperpour not_allowed)
			(footprints allowed)
		)
		(placement
			(enabled no)
			(sheetname "")
		)
		(fill
			(thermal_gap 0.5)
			(thermal_bridge_width 0.5)
			(island_removal_mode 0)
		)
		(polygon
			(pts
				(arc
					(start 56.000904 -71.398892)
					(mid 55.991696 -71.484033)
					(end 55.964582 -71.565262)
				)
				(arc
					(start 55.64124 -71.797418)
					(mid 55.523215 -71.792016)
					(end 55.411878 -71.75246)
				)
				(xy 55.411878 -71.711312) (xy 55.317644 -71.617078) (xy 55.31231 -71.617078)
				(arc
					(start 55.219854 -71.524622)
					(mid 55.337297 -71.096948)
					(end 55.77713 -71.039482)
				)
				(xy 55.463186 -71.353426) (xy 55.463186 -71.46036) (xy 55.54345 -71.540624) (xy 55.670958 -71.540624)
				(xy 55.9689 -71.242682)
				(arc
					(start 55.969154 -71.242682)
					(mid 55.992862 -71.319193)
					(end 56.000904 -71.398892)
				)
			)
		)
	)
	(zone
		(layer "F.Cu")
		(hatch none 0.5)
		(connect_pads
			(clearance 0)
		)
		(min_thickness 0.25)
		(keepout
			(tracks allowed)
			(vias allowed)
			(pads allowed)
			(copperpour allowed)
			(footprints allowed)
		)
		(placement
			(enabled no)
			(sheetname "")
		)
		(fill
			(thermal_gap 0.5)
			(thermal_bridge_width 0.5)
			(island_removal_mode 0)
		)
		(polygon
			(pts
				(xy 148.980144 -70.196964) (xy 150.558246 -68.618862) (xy 151.462486 -67.714622) (xy 151.462486 -65.800732)
				(xy 151.47671 -65.786508) (xy 151.47671 -64.93002) (xy 151.47671 -64.23025) (xy 150.861776 -63.615316)
				(xy 149.445726 -63.615316) (xy 149.094952 -63.96609) (xy 149.094952 -68.201032) (xy 148.926042 -68.369942)
				(xy 144.481296 -68.369942) (xy 144.259554 -68.591684) (xy 144.259554 -69.13118) (xy 144.259554 -69.879718)
				(xy 144.21231 -69.879718) (xy 144.009872 -70.082156) (xy 144.009872 -70.540626) (xy 144.063974 -70.594728)
				(xy 144.454372 -70.594728) (xy 144.922748 -71.063104) (xy 145.307304 -71.44766) (xy 147.65782 -71.44766)
				(xy 148.042376 -71.063104) (xy 148.626322 -70.479158) (xy 148.69795 -70.479158)
			)
		)
	)
	(zone
		(layer "F.Cu")
		(hatch none 0.5)
		(connect_pads
			(clearance 0)
		)
		(min_thickness 0.25)
		(keepout
			(tracks allowed)
			(vias allowed)
			(pads allowed)
			(copperpour allowed)
			(footprints allowed)
		)
		(placement
			(enabled no)
			(sheetname "")
		)
		(fill
			(thermal_gap 0.5)
			(thermal_bridge_width 0.5)
			(island_removal_mode 0)
		)
		(polygon
			(pts
				(xy 13.41628 -131.242054) (xy 14.67739 -131.242054) (xy 14.76502 -131.154424) (xy 14.76502 -130.500374)
				(xy 14.454632 -130.189986) (xy 13.476986 -130.189986) (xy 13.375894 -130.291078) (xy 13.375894 -131.201668)
			)
		)
	)
	(zone
		(layer "F.Cu")
		(hatch none 0.5)
		(connect_pads
			(clearance 0)
		)
		(min_thickness 0.25)
		(keepout
			(tracks allowed)
			(vias allowed)
			(pads allowed)
			(copperpour allowed)
			(footprints allowed)
		)
		(placement
			(enabled no)
			(sheetname "")
		)
		(fill
			(thermal_gap 0.5)
			(thermal_bridge_width 0.5)
			(island_removal_mode 0)
		)
		(polygon
			(pts
				(xy 40.19423 -157.34665) (xy 40.19423 -156.6926) (xy 40.19423 -152.83561) (xy 39.8526 -152.49398)
				(xy 38.73754 -152.49398) (xy 38.48862 -152.7429) (xy 38.48862 -156.16682) (xy 38.805104 -156.483304)
				(xy 38.805104 -157.393894) (xy 38.805104 -157.967172) (xy 38.973506 -158.135574) (xy 39.904162 -158.135574)
				(xy 40.19423 -157.845506)
			)
		)
	)
	(zone
		(layer "F.Cu")
		(hatch none 0.5)
		(connect_pads
			(clearance 0)
		)
		(min_thickness 0.25)
		(keepout
			(tracks allowed)
			(vias allowed)
			(pads allowed)
			(copperpour allowed)
			(footprints allowed)
		)
		(placement
			(enabled no)
			(sheetname "")
		)
		(fill
			(thermal_gap 0.5)
			(thermal_bridge_width 0.5)
			(island_removal_mode 0)
		)
		(polygon
			(pts
				(xy 11.325098 -59.558174) (xy 15.453106 -59.558174) (xy 17.031208 -57.980072) (xy 17.031208 -55.221886)
				(xy 17.875504 -55.221886) (xy 17.949672 -55.147718) (xy 17.949672 -54.29123) (xy 17.602708 -53.944266)
				(xy 16.86687 -53.944266) (xy 16.8021 -53.879496) (xy 16.41094 -53.879496) (xy 16.073628 -54.216808)
				(xy 16.073628 -57.629298) (xy 15.41272 -58.290206) (xy 10.9347 -58.290206) (xy 10.732516 -58.49239)
				(xy 10.732516 -59.240928) (xy 10.685272 -59.240928) (xy 10.482834 -59.443366) (xy 10.482834 -59.901836)
				(xy 10.536936 -59.955938) (xy 10.927334 -59.955938)
			)
		)
	)
	(zone
		(layer "F.Cu")
		(hatch none 0.5)
		(connect_pads
			(clearance 0)
		)
		(min_thickness 0.25)
		(keepout
			(tracks not_allowed)
			(vias allowed)
			(pads allowed)
			(copperpour not_allowed)
			(footprints allowed)
		)
		(placement
			(enabled no)
			(sheetname "")
		)
		(fill
			(thermal_gap 0.5)
			(thermal_bridge_width 0.5)
			(island_removal_mode 0)
		)
		(polygon
			(pts
				(arc
					(start 122.199908 -4.77012)
					(mid 126.1999 -8.770112)
					(end 122.199908 -12.770104)
				)
				(arc
					(start 122.199908 -12.770104)
					(mid 118.199916 -8.770112)
					(end 122.199908 -4.77012)
				)
			)
		)
	)
	(zone
		(layer "F.Cu")
		(hatch none 0.5)
		(connect_pads
			(clearance 0)
		)
		(min_thickness 0.25)
		(keepout
			(tracks allowed)
			(vias allowed)
			(pads allowed)
			(copperpour allowed)
			(footprints allowed)
		)
		(placement
			(enabled no)
			(sheetname "")
		)
		(fill
			(thermal_gap 0.5)
			(thermal_bridge_width 0.5)
			(island_removal_mode 0)
		)
		(polygon
			(pts
				(xy 104.98709 -154.857704) (xy 104.98709 -154.203654) (xy 104.676702 -153.893266) (xy 103.699056 -153.893266)
				(xy 103.597964 -153.994358) (xy 103.597964 -154.904948) (xy 103.597964 -155.478226) (xy 103.766366 -155.646628)
				(xy 104.697022 -155.646628) (xy 104.98709 -155.35656)
			)
		)
	)
	(zone
		(layer "F.Cu")
		(hatch none 0.5)
		(connect_pads
			(clearance 0)
		)
		(min_thickness 0.25)
		(keepout
			(tracks allowed)
			(vias allowed)
			(pads allowed)
			(copperpour allowed)
			(footprints allowed)
		)
		(placement
			(enabled no)
			(sheetname "")
		)
		(fill
			(thermal_gap 0.5)
			(thermal_bridge_width 0.5)
			(island_removal_mode 0)
		)
		(polygon
			(pts
				(xy 102.791006 -64.841374) (xy 104.880156 -64.841374) (xy 105.095802 -64.625728) (xy 105.095802 -64.032892)
				(xy 104.934004 -63.871094) (xy 103.006652 -63.871094) (xy 102.777544 -64.100202) (xy 102.777544 -64.827912)
			)
		)
	)
	(zone
		(layer "F.Cu")
		(hatch none 0.5)
		(connect_pads
			(clearance 0)
		)
		(min_thickness 0.25)
		(keepout
			(tracks allowed)
			(vias allowed)
			(pads allowed)
			(copperpour allowed)
			(footprints allowed)
		)
		(placement
			(enabled no)
			(sheetname "")
		)
		(fill
			(thermal_gap 0.5)
			(thermal_bridge_width 0.5)
			(island_removal_mode 0)
		)
		(polygon
			(pts
				(xy 9.072626 -45.58157) (xy 9.28497 -45.58157) (xy 9.318752 -45.547788) (xy 9.318752 -44.934124)
				(xy 9.291828 -44.9072) (xy 9.086088 -44.9072) (xy 9.049004 -44.944284) (xy 9.049004 -45.557948)
			)
		)
	)
	(zone
		(layer "F.Cu")
		(hatch none 0.5)
		(connect_pads
			(clearance 0)
		)
		(min_thickness 0.25)
		(keepout
			(tracks allowed)
			(vias allowed)
			(pads allowed)
			(copperpour allowed)
			(footprints not_allowed)
		)
		(placement
			(enabled no)
			(sheetname "")
		)
		(fill
			(thermal_gap 0.5)
			(thermal_bridge_width 0.5)
			(island_removal_mode 0)
		)
		(polygon
			(pts
				(xy 40.699944 -90.099896) (xy 40.699944 -61.500004) (xy 75.300078 -61.500004) (xy 75.300078 -90.099896)
			)
		)
	)
	(zone
		(layer "F.Cu")
		(hatch none 0.5)
		(connect_pads
			(clearance 0)
		)
		(min_thickness 0.25)
		(keepout
			(tracks allowed)
			(vias allowed)
			(pads allowed)
			(copperpour allowed)
			(footprints not_allowed)
		)
		(placement
			(enabled no)
			(sheetname "")
		)
		(fill
			(thermal_gap 0.5)
			(thermal_bridge_width 0.5)
			(island_removal_mode 0)
		)
		(polygon
			(pts
				(xy 186.660028 -206.30007) (xy 186.660028 -189.300104) (xy 104.359964 -189.300104) (xy 104.359964 -206.30007)
				(xy 173.559978 -206.30007)
				(arc
					(start 173.559978 -201.250042)
					(mid 175.509936 -199.300084)
					(end 177.459894 -201.250042)
				)
				(xy 177.459894 -206.30007)
			)
		)
	)
	(zone
		(layer "F.Cu")
		(hatch none 0.5)
		(connect_pads
			(clearance 0)
		)
		(min_thickness 0.25)
		(keepout
			(tracks allowed)
			(vias allowed)
			(pads allowed)
			(copperpour allowed)
			(footprints not_allowed)
		)
		(placement
			(enabled no)
			(sheetname "")
		)
		(fill
			(thermal_gap 0.5)
			(thermal_bridge_width 0.5)
			(island_removal_mode 0)
		)
		(polygon
			(pts
				(arc
					(start 199.00011 -168.699942)
					(mid 198.707217 -169.407047)
					(end 198.000112 -169.69994)
				)
				(xy 185.999882 -169.69994) (xy 185.999882 -101.799898) (xy 199.00011 -101.799898)
			)
		)
	)
	(zone
		(net "POWER_SW1_PWR_CTR_12V")
		(layer "F.Cu")
		(hatch none 0.5)
		(connect_pads
			(clearance 0.5)
		)
		(min_thickness 0.25)
		(fill yes
			(thermal_gap 0.5)
			(thermal_bridge_width 0.5)
			(island_removal_mode 0)
		)
		(polygon
			(pts
				(xy 184.30875 -188.2648) (xy 180.04155 -188.2648) (xy 179.911248 -188.134752) (xy 179.911248 -186.744102)
				(xy 180.37175 -186.2836) (xy 185.4708 -186.2836) (xy 185.7756 -186.5884) (xy 185.7756 -187.2742)
				(xy 185.7756 -188.0362) (xy 185.547 -188.2648) (xy 185.0136 -188.2648)
			)
		)
	)
	(zone
		(layer "F.Cu")
		(hatch none 0.5)
		(connect_pads
			(clearance 0)
		)
		(min_thickness 0.25)
		(keepout
			(tracks allowed)
			(vias allowed)
			(pads allowed)
			(copperpour allowed)
			(footprints not_allowed)
		)
		(placement
			(enabled no)
			(sheetname "")
		)
		(fill
			(thermal_gap 0.5)
			(thermal_bridge_width 0.5)
			(island_removal_mode 0)
		)
		(polygon
			(pts
				(xy 157.699964 -56.455056) (xy 150.64994 -56.455056) (xy 150.64994 -39.854886) (xy 157.699964 -39.854886)
			)
		)
	)
	(zone
		(layer "F.Cu")
		(hatch none 0.5)
		(connect_pads
			(clearance 0)
		)
		(min_thickness 0.25)
		(keepout
			(tracks allowed)
			(vias allowed)
			(pads allowed)
			(copperpour allowed)
			(footprints not_allowed)
		)
		(placement
			(enabled no)
			(sheetname "")
		)
		(fill
			(thermal_gap 0.5)
			(thermal_bridge_width 0.5)
			(island_removal_mode 0)
		)
		(polygon
			(pts
				(xy 86.374986 -6.35) (xy 103.624888 -6.35) (xy 103.624888 -13.24991) (xy 86.374986 -13.24991)
			)
		)
	)
	(zone
		(layer "F.Cu")
		(hatch none 0.5)
		(connect_pads
			(clearance 0)
		)
		(min_thickness 0.25)
		(keepout
			(tracks allowed)
			(vias allowed)
			(pads allowed)
			(copperpour allowed)
			(footprints not_allowed)
		)
		(placement
			(enabled no)
			(sheetname "")
		)
		(fill
			(thermal_gap 0.5)
			(thermal_bridge_width 0.5)
			(island_removal_mode 0)
		)
		(polygon
			(pts
				(arc
					(start 19.99996 -182.79999)
					(mid 24.99995 -187.79998)
					(end 29.99994 -182.79999)
				)
				(arc
					(start 29.99994 -177.8)
					(mid 24.99995 -172.80001)
					(end 19.99996 -177.8)
				)
			)
		)
	)
	(zone
		(layer "F.Cu")
		(hatch none 0.5)
		(connect_pads
			(clearance 0)
		)
		(min_thickness 0.25)
		(keepout
			(tracks allowed)
			(vias allowed)
			(pads allowed)
			(copperpour allowed)
			(footprints allowed)
		)
		(placement
			(enabled no)
			(sheetname "")
		)
		(fill
			(thermal_gap 0.5)
			(thermal_bridge_width 0.5)
			(island_removal_mode 0)
		)
		(polygon
			(pts
				(xy 121.114312 -37.227764) (xy 121.114312 -38.488874) (xy 121.114312 -41.7957) (xy 121.357136 -42.038524)
				(xy 122.34164 -42.038524) (xy 122.712734 -41.66743) (xy 122.712734 -41.586658) (xy 122.975624 -41.323768)
				(xy 123.171204 -41.128188) (xy 123.171204 -38.70706) (xy 122.975624 -38.51148) (xy 122.712734 -38.24859)
				(xy 122.301254 -37.83711) (xy 122.301254 -37.220906) (xy 122.260868 -37.18052) (xy 121.161556 -37.18052)
			)
		)
	)
	(zone
		(layer "F.Cu")
		(hatch none 0.5)
		(connect_pads
			(clearance 0)
		)
		(min_thickness 0.25)
		(keepout
			(tracks allowed)
			(vias allowed)
			(pads allowed)
			(copperpour allowed)
			(footprints allowed)
		)
		(placement
			(enabled no)
			(sheetname "")
		)
		(fill
			(thermal_gap 0.5)
			(thermal_bridge_width 0.5)
			(island_removal_mode 0)
		)
		(polygon
			(pts
				(xy 16.615918 -132.669026) (xy 16.615918 -132.014976) (xy 16.30553 -131.704588) (xy 15.327884 -131.704588)
				(xy 15.226792 -131.80568) (xy 15.226792 -132.71627) (xy 15.226792 -133.289548) (xy 15.395194 -133.45795)
				(xy 16.32585 -133.45795) (xy 16.615918 -133.167882)
			)
		)
	)
	(zone
		(layer "F.Cu")
		(hatch none 0.5)
		(connect_pads
			(clearance 0)
		)
		(min_thickness 0.25)
		(keepout
			(tracks allowed)
			(vias allowed)
			(pads allowed)
			(copperpour allowed)
			(footprints not_allowed)
		)
		(placement
			(enabled no)
			(sheetname "")
		)
		(fill
			(thermal_gap 0.5)
			(thermal_bridge_width 0.5)
			(island_removal_mode 0)
		)
		(polygon
			(pts
				(xy 142.839948 -23.16988) (xy 160.699958 -23.16988) (xy 160.699958 -73.170034)
				(arc
					(start 133.422644 -73.170034)
					(mid 140.332909 -84.312709)
					(end 132.25145 -94.637606)
				)
				(arc
					(start 125.548644 -94.637606)
					(mid 117.46684 -84.312719)
					(end 124.37745 -73.170034)
				)
				(xy 120.549924 -73.170034) (xy 120.549924 -23.16988) (xy 137.16 -23.16988) (xy 137.16 -17.960086)
				(xy 142.839948 -17.960086)
			)
		)
	)
	(zone
		(layer "F.Cu")
		(hatch none 0.5)
		(connect_pads
			(clearance 0)
		)
		(min_thickness 0.25)
		(keepout
			(tracks allowed)
			(vias allowed)
			(pads allowed)
			(copperpour allowed)
			(footprints not_allowed)
		)
		(placement
			(enabled no)
			(sheetname "")
		)
		(fill
			(thermal_gap 0.5)
			(thermal_bridge_width 0.5)
			(island_removal_mode 0)
		)
		(polygon
			(pts
				(xy 14.150086 -75.699874) (xy 14.150086 -91.899994) (xy 2.450084 -91.899994) (xy 2.450084 -75.699874)
			)
		)
	)
	(zone
		(layer "F.Cu")
		(hatch none 0.5)
		(connect_pads
			(clearance 0)
		)
		(min_thickness 0.25)
		(keepout
			(tracks allowed)
			(vias allowed)
			(pads allowed)
			(copperpour allowed)
			(footprints allowed)
		)
		(placement
			(enabled no)
			(sheetname "")
		)
		(fill
			(thermal_gap 0.5)
			(thermal_bridge_width 0.5)
			(island_removal_mode 0)
		)
		(polygon
			(pts
				(xy 135.218932 -130.640836) (xy 135.218932 -129.986786) (xy 134.908544 -129.676398) (xy 133.930898 -129.676398)
				(xy 133.926326 -129.680716) (xy 133.16966 -129.680716) (xy 133.16966 -131.42976) (xy 133.998208 -131.42976)
				(xy 134.928864 -131.42976) (xy 135.218932 -131.139692)
			)
		)
	)
	(zone
		(layer "F.Cu")
		(hatch none 0.5)
		(connect_pads
			(clearance 0)
		)
		(min_thickness 0.25)
		(keepout
			(tracks allowed)
			(vias allowed)
			(pads allowed)
			(copperpour allowed)
			(footprints allowed)
		)
		(placement
			(enabled no)
			(sheetname "")
		)
		(fill
			(thermal_gap 0.5)
			(thermal_bridge_width 0.5)
			(island_removal_mode 0)
		)
		(polygon
			(pts
				(xy 155.15717 -151.568912) (xy 155.15717 -152.222962) (xy 154.84856 -152.531572) (xy 154.84856 -155.73629)
				(xy 155.169616 -156.057346) (xy 155.34132 -156.22905) (xy 156.39796 -156.22905) (xy 156.5529 -156.07411)
				(xy 156.5529 -152.255474) (xy 156.546296 -152.24887) (xy 156.546296 -151.521668) (xy 156.546296 -150.94839)
				(xy 156.377894 -150.779988) (xy 155.447238 -150.779988) (xy 155.15717 -151.070056)
			)
		)
	)
	(zone
		(layer "F.Cu")
		(hatch none 0.5)
		(connect_pads
			(clearance 0)
		)
		(min_thickness 0.25)
		(keepout
			(tracks allowed)
			(vias allowed)
			(pads allowed)
			(copperpour allowed)
			(footprints not_allowed)
		)
		(placement
			(enabled no)
			(sheetname "")
		)
		(fill
			(thermal_gap 0.5)
			(thermal_bridge_width 0.5)
			(island_removal_mode 0)
		)
		(polygon
			(pts
				(xy 129.500122 -1.800098) (xy 129.500122 -17.800066) (xy 84.000086 -17.800066) (xy 84.000086 -1.800098)
			)
		)
	)
	(zone
		(layer "F.Cu")
		(hatch none 0.5)
		(connect_pads
			(clearance 0)
		)
		(min_thickness 0.25)
		(keepout
			(tracks allowed)
			(vias allowed)
			(pads allowed)
			(copperpour allowed)
			(footprints allowed)
		)
		(placement
			(enabled no)
			(sheetname "")
		)
		(fill
			(thermal_gap 0.5)
			(thermal_bridge_width 0.5)
			(island_removal_mode 0)
		)
		(polygon
			(pts
				(xy 44.34967 -164.009324) (xy 44.34967 -163.355274) (xy 44.039282 -163.044886) (xy 43.061636 -163.044886)
				(xy 42.960544 -163.145978) (xy 42.960544 -164.056568) (xy 42.960544 -164.629846) (xy 43.128946 -164.798248)
				(xy 44.059602 -164.798248) (xy 44.34967 -164.50818)
			)
		)
	)
	(zone
		(layer "F.Cu")
		(hatch none 0.5)
		(connect_pads
			(clearance 0)
		)
		(min_thickness 0.25)
		(keepout
			(tracks not_allowed)
			(vias allowed)
			(pads allowed)
			(copperpour not_allowed)
			(footprints allowed)
		)
		(placement
			(enabled no)
			(sheetname "")
		)
		(fill
			(thermal_gap 0.5)
			(thermal_bridge_width 0.5)
			(island_removal_mode 0)
		)
		(polygon
			(pts
				(arc
					(start 105.000044 -97.799906)
					(mid 103.000048 -95.79991)
					(end 105.000044 -93.799914)
				)
				(arc
					(start 105.000044 -93.799914)
					(mid 107.00004 -95.79991)
					(end 105.000044 -97.799906)
				)
			)
		)
	)
	(zone
		(layer "F.Cu")
		(hatch none 0.5)
		(connect_pads
			(clearance 0)
		)
		(min_thickness 0.25)
		(keepout
			(tracks allowed)
			(vias allowed)
			(pads allowed)
			(copperpour allowed)
			(footprints allowed)
		)
		(placement
			(enabled no)
			(sheetname "")
		)
		(fill
			(thermal_gap 0.5)
			(thermal_bridge_width 0.5)
			(island_removal_mode 0)
		)
		(polygon
			(pts
				(xy 152.209246 -156.031692) (xy 152.978866 -156.031692) (xy 152.978866 -155.626562) (xy 152.209246 -155.626562)
			)
		)
	)
	(zone
		(layer "F.Cu")
		(hatch none 0.5)
		(connect_pads
			(clearance 0)
		)
		(min_thickness 0.25)
		(keepout
			(tracks allowed)
			(vias allowed)
			(pads allowed)
			(copperpour allowed)
			(footprints allowed)
		)
		(placement
			(enabled no)
			(sheetname "")
		)
		(fill
			(thermal_gap 0.5)
			(thermal_bridge_width 0.5)
			(island_removal_mode 0)
		)
		(polygon
			(pts
				(xy 163.961318 -104.770682) (xy 163.961318 -106.129582) (xy 165.575488 -106.129582) (xy 166.56304 -106.129582)
				(xy 166.581328 -106.111294) (xy 168.091104 -106.111294) (xy 168.731946 -106.111294) (xy 168.783 -106.06024)
				(xy 168.783 -104.80548) (xy 168.73728 -104.75976) (xy 168.335198 -104.75976) (xy 168.286176 -104.808782)
				(xy 168.248076 -104.770682) (xy 166.897304 -104.770682)
			)
		)
	)
	(zone
		(layer "F.Cu")
		(hatch none 0.5)
		(connect_pads
			(clearance 0)
		)
		(min_thickness 0.25)
		(keepout
			(tracks allowed)
			(vias allowed)
			(pads allowed)
			(copperpour allowed)
			(footprints allowed)
		)
		(placement
			(enabled no)
			(sheetname "")
		)
		(fill
			(thermal_gap 0.5)
			(thermal_bridge_width 0.5)
			(island_removal_mode 0)
		)
		(polygon
			(pts
				(xy 89.623646 82.480912) (xy 90.99931 82.480912) (xy 91.120722 82.602324) (xy 91.120722 83.46567)
				(xy 91.093798 83.492594) (xy 89.704672 83.492594) (xy 89.47531 83.263232) (xy 89.47531 82.629248)
			)
		)
	)
	(zone
		(layer "F.Cu")
		(hatch none 0.5)
		(connect_pads
			(clearance 0)
		)
		(min_thickness 0.25)
		(keepout
			(tracks allowed)
			(vias not_allowed)
			(pads allowed)
			(copperpour not_allowed)
			(footprints allowed)
		)
		(placement
			(enabled no)
			(sheetname "")
		)
		(fill
			(thermal_gap 0.5)
			(thermal_bridge_width 0.5)
			(island_removal_mode 0)
		)
		(polygon
			(pts
				(xy -142.816326 -209.653632) (xy -142.816326 -206.834232) (xy -142.765526 -206.834232) (xy -142.765526 -209.653632)
				(xy -139.946126 -209.653632) (xy -139.920726 -209.653632) (xy -139.920726 -208.104232) (xy -139.920726 -206.808832)
				(xy -142.816326 -206.808832) (xy -142.816326 -206.758032) (xy -139.920726 -206.758032) (xy -139.869926 -206.758032)
				(xy -139.869926 -208.104232) (xy -139.869926 -209.653632) (xy -139.869926 -209.704432) (xy -139.895326 -209.704432)
				(xy -142.816326 -209.704432)
			)
		)
	)
	(zone
		(layer "F.Cu")
		(hatch none 0.5)
		(connect_pads
			(clearance 0)
		)
		(min_thickness 0.25)
		(keepout
			(tracks not_allowed)
			(vias allowed)
			(pads allowed)
			(copperpour not_allowed)
			(footprints allowed)
		)
		(placement
			(enabled no)
			(sheetname "")
		)
		(fill
			(thermal_gap 0.5)
			(thermal_bridge_width 0.5)
			(island_removal_mode 0)
		)
		(polygon
			(pts
				(arc
					(start 177.255678 -180.42636)
					(mid 176.993408 -180.769328)
					(end 176.900078 -181.1909)
				)
				(arc
					(start 176.900078 -182.749952)
					(mid 175.000158 -184.649872)
					(end 173.099984 -182.749952)
				)
				(arc
					(start 173.099984 -181.1909)
					(mid 173.006668 -180.769345)
					(end 172.744384 -180.42636)
				)
				(arc
					(start 172.744384 -180.42636)
					(mid 175.000255 -174.24973)
					(end 177.255678 -180.42636)
				)
			)
		)
	)
	(zone
		(layer "F.Cu")
		(hatch none 0.5)
		(connect_pads
			(clearance 0)
		)
		(min_thickness 0.25)
		(keepout
			(tracks allowed)
			(vias allowed)
			(pads allowed)
			(copperpour allowed)
			(footprints allowed)
		)
		(placement
			(enabled no)
			(sheetname "")
		)
		(fill
			(thermal_gap 0.5)
			(thermal_bridge_width 0.5)
			(island_removal_mode 0)
		)
		(polygon
			(pts
				(xy 37.61232 -8.94207) (xy 38.93439 -8.94207) (xy 39.312596 -8.563864) (xy 39.312596 -7.74827) (xy 39.050976 -7.48665)
				(xy 37.451538 -7.48665) (xy 37.441378 -7.47649) (xy 37.233098 -7.47649) (xy 37.050218 -7.65937)
				(xy 37.050218 -8.69569) (xy 37.296598 -8.94207)
			)
		)
	)
	(zone
		(layer "F.Cu")
		(hatch none 0.5)
		(connect_pads
			(clearance 0)
		)
		(min_thickness 0.25)
		(keepout
			(tracks allowed)
			(vias allowed)
			(pads allowed)
			(copperpour allowed)
			(footprints allowed)
		)
		(placement
			(enabled no)
			(sheetname "")
		)
		(fill
			(thermal_gap 0.5)
			(thermal_bridge_width 0.5)
			(island_removal_mode 0)
		)
		(polygon
			(pts
				(xy 52.500784 -152.47112) (xy 53.259228 -152.47112) (xy 53.316632 -152.413716) (xy 53.316632 -152.221692)
				(xy 53.28285 -152.18791) (xy 52.517294 -152.18791) (xy 52.43322 -152.271984) (xy 52.43322 -152.403556)
			)
		)
	)
	(zone
		(layer "F.Cu")
		(hatch none 0.5)
		(connect_pads
			(clearance 0)
		)
		(min_thickness 0.25)
		(keepout
			(tracks allowed)
			(vias allowed)
			(pads allowed)
			(copperpour allowed)
			(footprints allowed)
		)
		(placement
			(enabled no)
			(sheetname "")
		)
		(fill
			(thermal_gap 0.5)
			(thermal_bridge_width 0.5)
			(island_removal_mode 0)
		)
		(polygon
			(pts
				(xy 172.35932 -99.650042) (xy 171.00042 -99.650042) (xy 171.00042 -101.264212) (xy 171.00042 -102.251764)
				(xy 171.018708 -102.270052) (xy 171.018708 -103.779828) (xy 171.21378 -103.9749) (xy 172.32122 -103.9749)
				(xy 172.35932 -103.9368) (xy 172.35932 -102.586028)
			)
		)
	)
	(zone
		(layer "F.Cu")
		(hatch none 0.5)
		(connect_pads
			(clearance 0)
		)
		(min_thickness 0.25)
		(keepout
			(tracks allowed)
			(vias allowed)
			(pads allowed)
			(copperpour allowed)
			(footprints allowed)
		)
		(placement
			(enabled no)
			(sheetname "")
		)
		(fill
			(thermal_gap 0.5)
			(thermal_bridge_width 0.5)
			(island_removal_mode 0)
		)
		(polygon
			(pts
				(xy 72.715882 -122.49023) (xy 72.715882 -123.25985) (xy 73.121012 -123.25985) (xy 73.121012 -122.49023)
			)
		)
	)
	(zone
		(layer "F.Cu")
		(hatch none 0.5)
		(connect_pads
			(clearance 0)
		)
		(min_thickness 0.25)
		(keepout
			(tracks not_allowed)
			(vias allowed)
			(pads allowed)
			(copperpour not_allowed)
			(footprints allowed)
		)
		(placement
			(enabled no)
			(sheetname "")
		)
		(fill
			(thermal_gap 0.5)
			(thermal_bridge_width 0.5)
			(island_removal_mode 0)
		)
		(polygon
			(pts
				(arc
					(start 122.199908 -11.474958)
					(mid 119.495062 -8.770112)
					(end 122.199908 -6.065012)
				)
				(arc
					(start 122.199908 -6.065012)
					(mid 124.905008 -8.770112)
					(end 122.199908 -11.474958)
				)
			)
		)
	)
	(zone
		(layer "F.Cu")
		(hatch none 0.5)
		(connect_pads
			(clearance 0)
		)
		(min_thickness 0.25)
		(keepout
			(tracks allowed)
			(vias allowed)
			(pads allowed)
			(copperpour allowed)
			(footprints allowed)
		)
		(placement
			(enabled no)
			(sheetname "")
		)
		(fill
			(thermal_gap 0.5)
			(thermal_bridge_width 0.5)
			(island_removal_mode 0)
		)
		(polygon
			(pts
				(xy 38.0492 -12.899136) (xy 38.0492 -12.1158) (xy 37.700204 -11.766804) (xy 36.023804 -11.766804)
				(xy 35.86988 -11.920982) (xy 35.86988 -12.937998) (xy 36.254944 -13.323316) (xy 37.62502 -13.323316)
			)
		)
	)
	(zone
		(layer "F.Cu")
		(hatch none 0.5)
		(connect_pads
			(clearance 0)
		)
		(min_thickness 0.25)
		(keepout
			(tracks allowed)
			(vias allowed)
			(pads allowed)
			(copperpour allowed)
			(footprints allowed)
		)
		(placement
			(enabled no)
			(sheetname "")
		)
		(fill
			(thermal_gap 0.5)
			(thermal_bridge_width 0.5)
			(island_removal_mode 0)
		)
		(polygon
			(pts
				(xy 54.151022 -31.777178) (xy 54.4195 -31.777178) (xy 54.70144 -31.495238) (xy 54.70144 -30.023562)
				(xy 54.42966 -29.751782) (xy 52.84724 -29.751782) (xy 52.52212 -30.076902) (xy 52.52212 -31.398972)
				(xy 52.900326 -31.777178)
			)
		)
	)
	(zone
		(layer "F.Cu")
		(hatch none 0.5)
		(connect_pads
			(clearance 0)
		)
		(min_thickness 0.25)
		(keepout
			(tracks allowed)
			(vias allowed)
			(pads allowed)
			(copperpour allowed)
			(footprints not_allowed)
		)
		(placement
			(enabled no)
			(sheetname "")
		)
		(fill
			(thermal_gap 0.5)
			(thermal_bridge_width 0.5)
			(island_removal_mode 0)
		)
		(polygon
			(pts
				(arc
					(start 170.000168 -26.800048)
					(mid 174.999904 -31.749996)
					(end 179.99964 -26.800048)
				)
				(arc
					(start 179.999894 -21.750274)
					(mid 174.999904 -16.75003)
					(end 169.999914 -21.750274)
				)
			)
		)
	)
	(zone
		(layer "F.Cu")
		(hatch none 0.5)
		(connect_pads
			(clearance 0)
		)
		(min_thickness 0.25)
		(keepout
			(tracks allowed)
			(vias allowed)
			(pads allowed)
			(copperpour allowed)
			(footprints not_allowed)
		)
		(placement
			(enabled no)
			(sheetname "")
		)
		(fill
			(thermal_gap 0.5)
			(thermal_bridge_width 0.5)
			(island_removal_mode 0)
		)
		(polygon
			(pts
				(xy 137.16 -17.960086) (xy 142.839948 -17.960086) (xy 142.839948 -23.640034) (xy 137.16 -23.640034)
			)
		)
	)
	(zone
		(layer "F.Cu")
		(hatch none 0.5)
		(connect_pads
			(clearance 0)
		)
		(min_thickness 0.25)
		(keepout
			(tracks allowed)
			(vias allowed)
			(pads allowed)
			(copperpour allowed)
			(footprints allowed)
		)
		(placement
			(enabled no)
			(sheetname "")
		)
		(fill
			(thermal_gap 0.5)
			(thermal_bridge_width 0.5)
			(island_removal_mode 0)
		)
		(polygon
			(pts
				(xy 170.18762 -95.828104) (xy 170.283378 -95.732346) (xy 170.283378 -94.488) (xy 167.915844 -94.488)
				(xy 167.915844 -96.10217) (xy 167.915844 -97.089722) (xy 168.250108 -97.423986) (xy 169.909236 -97.423986)
				(xy 170.18762 -97.145602)
			)
		)
	)
	(zone
		(layer "F.Cu")
		(hatch none 0.5)
		(connect_pads
			(clearance 0)
		)
		(min_thickness 0.25)
		(keepout
			(tracks allowed)
			(vias allowed)
			(pads allowed)
			(copperpour allowed)
			(footprints not_allowed)
		)
		(placement
			(enabled no)
			(sheetname "")
		)
		(fill
			(thermal_gap 0.5)
			(thermal_bridge_width 0.5)
			(island_removal_mode 0)
		)
		(polygon
			(pts
				(xy 183.410098 -0.999998) (xy 183.410098 -9.500108) (xy 176.589944 -9.500108) (xy 176.589944 -0.999998)
			)
		)
	)
	(zone
		(layer "F.Cu")
		(hatch none 0.5)
		(connect_pads
			(clearance 0)
		)
		(min_thickness 0.25)
		(keepout
			(tracks allowed)
			(vias allowed)
			(pads allowed)
			(copperpour allowed)
			(footprints allowed)
		)
		(placement
			(enabled no)
			(sheetname "")
		)
		(fill
			(thermal_gap 0.5)
			(thermal_bridge_width 0.5)
			(island_removal_mode 0)
		)
		(polygon
			(pts
				(xy 106.870754 -138.360658) (xy 106.870754 -139.129262) (xy 106.882946 -139.141454) (xy 106.09834 -139.92606)
				(xy 106.09834 -141.22146) (xy 106.78668 -141.9098) (xy 107.57408 -141.9098) (xy 110.36935 -139.11453)
				(xy 115.86591 -139.11453) (xy 116.53012 -138.45032) (xy 116.53012 -136.15416) (xy 114.92992 -134.55396)
				(xy 114.92992 -131.32054) (xy 114.31016 -130.70078) (xy 112.58296 -130.70078) (xy 110.9091 -132.37464)
				(xy 105.07218 -132.37464) (xy 104.04348 -133.40334) (xy 104.04348 -135.8646) (xy 100.67036 -135.8646)
				(xy 100.45954 -136.07542) (xy 100.45954 -137.55116) (xy 100.63988 -137.7315) (xy 104.04348 -137.7315)
				(xy 106.870754 -137.7315)
			)
		)
	)
	(zone
		(layer "F.Cu")
		(hatch none 0.5)
		(connect_pads
			(clearance 0)
		)
		(min_thickness 0.25)
		(keepout
			(tracks allowed)
			(vias allowed)
			(pads allowed)
			(copperpour allowed)
			(footprints not_allowed)
		)
		(placement
			(enabled no)
			(sheetname "")
		)
		(fill
			(thermal_gap 0.5)
			(thermal_bridge_width 0.5)
			(island_removal_mode 0)
		)
		(polygon
			(pts
				(arc
					(start 132.999988 -72.99833)
					(mid 140.343188 -84.084998)
					(end 132.25145 -94.637606)
				)
				(arc
					(start 125.548644 -94.637606)
					(mid 117.456922 -84.084991)
					(end 124.800106 -72.99833)
				)
				(xy 124.800106 -70.037452) (xy 132.999988 -70.037452)
			)
		)
	)
	(zone
		(layer "F.Cu")
		(hatch none 0.5)
		(connect_pads
			(clearance 0)
		)
		(min_thickness 0.25)
		(keepout
			(tracks allowed)
			(vias allowed)
			(pads allowed)
			(copperpour allowed)
			(footprints allowed)
		)
		(placement
			(enabled no)
			(sheetname "")
		)
		(fill
			(thermal_gap 0.5)
			(thermal_bridge_width 0.5)
			(island_removal_mode 0)
		)
		(polygon
			(pts
				(xy 124.420122 -146.713702) (xy 124.420122 -148.251164) (xy 124.420122 -149.161754) (xy 124.420122 -149.735032)
				(xy 124.588524 -149.903434) (xy 125.51918 -149.903434) (xy 125.88875 -149.903434) (xy 126.191518 -149.600666)
				(xy 126.364238 -149.427946) (xy 126.364238 -145.082006) (xy 126.346966 -145.064734) (xy 126.50978 -144.90192)
				(xy 126.50978 -140.65758) (xy 127.0381 -140.12926) (xy 127.09652 -140.12926) (xy 127.09652 -137.64768)
				(xy 127.08128 -137.63244) (xy 125.1585 -137.63244) (xy 124.420122 -138.370818) (xy 124.420122 -145.316702)
			)
		)
	)
	(zone
		(layer "F.Cu")
		(hatch none 0.5)
		(connect_pads
			(clearance 0)
		)
		(min_thickness 0.25)
		(keepout
			(tracks allowed)
			(vias allowed)
			(pads allowed)
			(copperpour allowed)
			(footprints not_allowed)
		)
		(placement
			(enabled no)
			(sheetname "")
		)
		(fill
			(thermal_gap 0.5)
			(thermal_bridge_width 0.5)
			(island_removal_mode 0)
		)
		(polygon
			(pts
				(xy 96.799908 -55.79999) (xy 96.799908 -95.79991) (xy 18.999962 -95.79991) (xy 18.999962 -55.79999)
			)
		)
	)
	(zone
		(layer "F.Cu")
		(hatch none 0.5)
		(connect_pads
			(clearance 0)
		)
		(min_thickness 0.25)
		(keepout
			(tracks allowed)
			(vias allowed)
			(pads allowed)
			(copperpour allowed)
			(footprints not_allowed)
		)
		(placement
			(enabled no)
			(sheetname "")
		)
		(fill
			(thermal_gap 0.5)
			(thermal_bridge_width 0.5)
			(island_removal_mode 0)
		)
		(polygon
			(pts
				(arc
					(start 19.99996 -26.800048)
					(mid 24.99995 -31.800038)
					(end 29.99994 -26.800048)
				)
				(arc
					(start 29.99994 -21.800058)
					(mid 24.99995 -16.800068)
					(end 19.99996 -21.800058)
				)
			)
		)
	)
	(zone
		(layer "F.Cu")
		(hatch none 0.5)
		(connect_pads
			(clearance 0)
		)
		(min_thickness 0.25)
		(keepout
			(tracks allowed)
			(vias allowed)
			(pads allowed)
			(copperpour allowed)
			(footprints allowed)
		)
		(placement
			(enabled no)
			(sheetname "")
		)
		(fill
			(thermal_gap 0.5)
			(thermal_bridge_width 0.5)
			(island_removal_mode 0)
		)
		(polygon
			(pts
				(xy 89.23655 -126.040642) (xy 89.452196 -125.824996) (xy 89.452196 -125.23216) (xy 89.290398 -125.070362)
				(xy 87.363046 -125.070362) (xy 87.133938 -125.29947) (xy 87.133938 -126.02718) (xy 87.1474 -126.040642)
				(xy 87.662258 -126.5555) (xy 88.721692 -126.5555)
			)
		)
	)
	(zone
		(layer "F.Cu")
		(hatch none 0.5)
		(connect_pads
			(clearance 0)
		)
		(min_thickness 0.25)
		(keepout
			(tracks allowed)
			(vias allowed)
			(pads allowed)
			(copperpour allowed)
			(footprints allowed)
		)
		(placement
			(enabled no)
			(sheetname "")
		)
		(fill
			(thermal_gap 0.5)
			(thermal_bridge_width 0.5)
			(island_removal_mode 0)
		)
		(polygon
			(pts
				(xy 109.941106 -67.27571) (xy 111.841534 -67.27571) (xy 112.515396 -66.601848) (xy 112.515396 -65.60439)
				(xy 112.097566 -65.18656) (xy 110.825026 -63.91402) (xy 110.20552 -63.91402) (xy 109.873796 -64.245744)
				(xy 109.873796 -65.685162) (xy 109.873796 -67.2084)
			)
		)
	)
	(zone
		(layer "F.Cu")
		(hatch none 0.5)
		(connect_pads
			(clearance 0)
		)
		(min_thickness 0.25)
		(keepout
			(tracks allowed)
			(vias allowed)
			(pads allowed)
			(copperpour allowed)
			(footprints not_allowed)
		)
		(placement
			(enabled no)
			(sheetname "")
		)
		(fill
			(thermal_gap 0.5)
			(thermal_bridge_width 0.5)
			(island_removal_mode 0)
		)
		(polygon
			(pts
				(xy 12.249912 -35.08756) (xy 8.999982 -35.08756) (xy 8.999982 -66.487548) (xy 12.249912 -66.487548)
			)
		)
	)
	(zone
		(layer "F.Cu")
		(hatch none 0.5)
		(connect_pads
			(clearance 0)
		)
		(min_thickness 0.25)
		(keepout
			(tracks allowed)
			(vias allowed)
			(pads allowed)
			(copperpour allowed)
			(footprints allowed)
		)
		(placement
			(enabled no)
			(sheetname "")
		)
		(fill
			(thermal_gap 0.5)
			(thermal_bridge_width 0.5)
			(island_removal_mode 0)
		)
		(polygon
			(pts
				(xy 173.081442 -116.202968) (xy 172.841158 -116.202968) (xy 172.783754 -116.260372) (xy 172.783754 -116.452396)
				(xy 172.817536 -116.486178) (xy 173.583092 -116.486178) (xy 174.222918 -116.486178) (xy 174.241714 -116.467382)
				(xy 174.241714 -116.129054) (xy 174.241714 -115.949476) (xy 174.110396 -115.818158) (xy 173.466252 -115.818158)
			)
		)
	)
	(zone
		(layer "F.Cu")
		(hatch none 0.5)
		(connect_pads
			(clearance 0)
		)
		(min_thickness 0.25)
		(keepout
			(tracks allowed)
			(vias allowed)
			(pads allowed)
			(copperpour allowed)
			(footprints not_allowed)
		)
		(placement
			(enabled no)
			(sheetname "")
		)
		(fill
			(thermal_gap 0.5)
			(thermal_bridge_width 0.5)
			(island_removal_mode 0)
		)
		(polygon
			(pts
				(arc
					(start 0.999998 -72.300084)
					(mid 1.146482 -71.946442)
					(end 1.500124 -71.799958)
				)
				(arc
					(start 6.500114 -71.799958)
					(mid 8.267788 -71.067764)
					(end 8.999982 -69.30009)
				)
				(xy 8.999982 -66.487548) (xy 12.249912 -66.487548) (xy 12.249912 -35.08756) (xy 8.999982 -35.08756)
				(arc
					(start 8.999982 -32.29991)
					(mid 8.267788 -30.532236)
					(end 6.500114 -29.800042)
				)
				(arc
					(start 1.500124 -29.800042)
					(mid 1.146482 -29.653558)
					(end 0.999998 -29.299916)
				)
				(arc
					(start 0.999998 -1.999996)
					(mid 1.292891 -1.292891)
					(end 1.999996 -0.999998)
				)
				(xy 16.59001 -0.999998) (xy 16.59001 -9.500108) (xy 23.40991 -9.500108) (xy 23.40991 -0.999998)
				(xy 176.589944 -0.999998) (xy 176.589944 -9.500108) (xy 183.410098 -9.500108) (xy 183.410098 -0.999998)
				(arc
					(start 198.000112 -0.999998)
					(mid 198.707217 -1.292891)
					(end 199.00011 -1.999996)
				)
				(arc
					(start 199.00011 -30.649926)
					(mid 198.853626 -31.003568)
					(end 198.499984 -31.150052)
				)
				(arc
					(start 198.20001 -31.150052)
					(mid 196.432247 -31.882231)
					(end 195.699888 -33.64992)
				)
				(xy 195.699888 -35.150044) (xy 179.399946 -35.150044) (xy 179.399946 -50.950114) (xy 195.699888 -50.950114)
				(xy 195.699888 -55.150004) (xy 179.399946 -55.150004) (xy 179.399946 -70.950074) (xy 195.699888 -70.950074)
				(arc
					(start 195.699888 -72.650096)
					(mid 196.432247 -74.417785)
					(end 198.20001 -75.149964)
				)
				(arc
					(start 198.499984 -75.149964)
					(mid 198.853626 -75.296448)
					(end 199.00011 -75.65009)
				)
				(xy 199.00011 -101.799898)
				(arc
					(start 110.291626 -101.799898)
					(mid 112.483388 -92.971436)
					(end 105.000044 -87.799926)
				)
				(arc
					(start 105.000044 -87.799926)
					(mid 97.516756 -92.971457)
					(end 99.708462 -101.799898)
				)
				(xy 0.999998 -101.799898)
			)
		)
	)
	(zone
		(layer "F.Cu")
		(hatch none 0.5)
		(connect_pads
			(clearance 0)
		)
		(min_thickness 0.25)
		(keepout
			(tracks allowed)
			(vias allowed)
			(pads allowed)
			(copperpour allowed)
			(footprints allowed)
		)
		(placement
			(enabled no)
			(sheetname "")
		)
		(fill
			(thermal_gap 0.5)
			(thermal_bridge_width 0.5)
			(island_removal_mode 0)
		)
		(polygon
			(pts
				(xy 17.315434 -131.28244) (xy 18.576544 -131.28244) (xy 18.664174 -131.19481) (xy 18.664174 -130.54076)
				(xy 18.353786 -130.230372) (xy 17.37614 -130.230372) (xy 17.275048 -130.331464) (xy 17.275048 -131.242054)
			)
		)
	)
	(zone
		(layer "F.Cu")
		(hatch none 0.5)
		(connect_pads
			(clearance 0)
		)
		(min_thickness 0.25)
		(keepout
			(tracks allowed)
			(vias allowed)
			(pads allowed)
			(copperpour allowed)
			(footprints not_allowed)
		)
		(placement
			(enabled no)
			(sheetname "")
		)
		(fill
			(thermal_gap 0.5)
			(thermal_bridge_width 0.5)
			(island_removal_mode 0)
		)
		(polygon
			(pts
				(arc
					(start 25.999948 -57.799986)
					(mid 30.999938 -62.799976)
					(end 25.999948 -67.799966)
				)
				(arc
					(start 25.999948 -67.799966)
					(mid 20.999958 -62.799976)
					(end 25.999948 -57.799986)
				)
			)
		)
	)
	(zone
		(layer "F.Cu")
		(hatch none 0.5)
		(connect_pads
			(clearance 0)
		)
		(min_thickness 0.25)
		(keepout
			(tracks allowed)
			(vias allowed)
			(pads allowed)
			(copperpour allowed)
			(footprints allowed)
		)
		(placement
			(enabled no)
			(sheetname "")
		)
		(fill
			(thermal_gap 0.5)
			(thermal_bridge_width 0.5)
			(island_removal_mode 0)
		)
		(polygon
			(pts
				(xy 163.859972 -144.485614) (xy 163.859972 -143.831564) (xy 163.549584 -143.521176) (xy 162.571938 -143.521176)
				(xy 160.521396 -143.521176) (xy 160.221422 -143.82115) (xy 160.221422 -144.56029) (xy 160.327086 -144.666208)
				(xy 163.859972 -144.666208)
			)
		)
	)
	(zone
		(layer "F.Cu")
		(hatch none 0.5)
		(connect_pads
			(clearance 0)
		)
		(min_thickness 0.25)
		(keepout
			(tracks allowed)
			(vias allowed)
			(pads allowed)
			(copperpour allowed)
			(footprints not_allowed)
		)
		(placement
			(enabled no)
			(sheetname "")
		)
		(fill
			(thermal_gap 0.5)
			(thermal_bridge_width 0.5)
			(island_removal_mode 0)
		)
		(polygon
			(pts
				(arc
					(start 169.999914 -182.749952)
					(mid 174.999904 -187.749942)
					(end 179.999894 -182.749952)
				)
				(arc
					(start 179.999894 -177.749962)
					(mid 174.999904 -172.749972)
					(end 169.999914 -177.749962)
				)
			)
		)
	)
	(zone
		(layer "F.Cu")
		(hatch none 0.5)
		(connect_pads
			(clearance 0)
		)
		(min_thickness 0.25)
		(keepout
			(tracks allowed)
			(vias allowed)
			(pads allowed)
			(copperpour allowed)
			(footprints allowed)
		)
		(placement
			(enabled no)
			(sheetname "")
		)
		(fill
			(thermal_gap 0.5)
			(thermal_bridge_width 0.5)
			(island_removal_mode 0)
		)
		(polygon
			(pts
				(xy 132.160772 -133.23189) (xy 131.61645 -133.776212) (xy 131.902962 -134.062724) (xy 132.447284 -133.518402)
			)
		)
	)
	(zone
		(layer "F.Cu")
		(hatch none 0.5)
		(connect_pads
			(clearance 0)
		)
		(min_thickness 0.25)
		(keepout
			(tracks allowed)
			(vias allowed)
			(pads allowed)
			(copperpour allowed)
			(footprints not_allowed)
		)
		(placement
			(enabled no)
			(sheetname "")
		)
		(fill
			(thermal_gap 0.5)
			(thermal_bridge_width 0.5)
			(island_removal_mode 0)
		)
		(polygon
			(pts
				(arc
					(start 90.000074 -83.799934)
					(mid 95.000064 -88.799924)
					(end 90.000074 -93.799914)
				)
				(arc
					(start 90.000074 -93.799914)
					(mid 85.000084 -88.799924)
					(end 90.000074 -83.799934)
				)
			)
		)
	)
	(zone
		(layer "F.Cu")
		(hatch none 0.5)
		(connect_pads
			(clearance 0)
		)
		(min_thickness 0.25)
		(keepout
			(tracks allowed)
			(vias allowed)
			(pads allowed)
			(copperpour allowed)
			(footprints not_allowed)
		)
		(placement
			(enabled no)
			(sheetname "")
		)
		(fill
			(thermal_gap 0.5)
			(thermal_bridge_width 0.5)
			(island_removal_mode 0)
		)
		(polygon
			(pts
				(xy 32.824928 -19.899884) (xy 111.175038 -19.899884) (xy 111.175038 -46.399958) (xy 104.499918 -46.399958)
				(xy 104.499918 -28.800044) (xy 39.500048 -28.800044) (xy 39.500048 -46.399958) (xy 32.824928 -46.399958)
			)
		)
	)
	(zone
		(layer "F.Cu")
		(hatch none 0.5)
		(connect_pads
			(clearance 0)
		)
		(min_thickness 0.25)
		(keepout
			(tracks allowed)
			(vias allowed)
			(pads allowed)
			(copperpour allowed)
			(footprints allowed)
		)
		(placement
			(enabled no)
			(sheetname "")
		)
		(fill
			(thermal_gap 0.5)
			(thermal_bridge_width 0.5)
			(island_removal_mode 0)
		)
		(polygon
			(pts
				(xy 44.145962 -32.673798) (xy 44.41444 -32.673798) (xy 44.69638 -32.391858) (xy 44.69638 -30.920182)
				(xy 44.4246 -30.648402) (xy 42.84218 -30.648402) (xy 42.51706 -30.973522) (xy 42.51706 -32.295592)
				(xy 42.895266 -32.673798)
			)
		)
	)
	(zone
		(layer "F.Cu")
		(hatch none 0.5)
		(connect_pads
			(clearance 0)
		)
		(min_thickness 0.25)
		(keepout
			(tracks allowed)
			(vias allowed)
			(pads allowed)
			(copperpour allowed)
			(footprints allowed)
		)
		(placement
			(enabled no)
			(sheetname "")
		)
		(fill
			(thermal_gap 0.5)
			(thermal_bridge_width 0.5)
			(island_removal_mode 0)
		)
		(polygon
			(pts
				(xy 49.112424 -153.889456) (xy 49.112424 -155.426918) (xy 49.112424 -156.337508) (xy 49.112424 -156.910786)
				(xy 49.280826 -157.079188) (xy 50.211482 -157.079188) (xy 50.581052 -157.079188) (xy 50.88382 -156.77642)
				(xy 51.05654 -156.6037) (xy 51.05654 -152.25776) (xy 50.8127 -152.01392) (xy 50.64252 -152.01392)
				(xy 49.59096 -152.01392) (xy 49.112424 -152.492456)
			)
		)
	)
	(zone
		(layer "F.Cu")
		(hatch none 0.5)
		(connect_pads
			(clearance 0)
		)
		(min_thickness 0.25)
		(keepout
			(tracks not_allowed)
			(vias allowed)
			(pads allowed)
			(copperpour not_allowed)
			(footprints allowed)
		)
		(placement
			(enabled no)
			(sheetname "")
		)
		(fill
			(thermal_gap 0.5)
			(thermal_bridge_width 0.5)
			(island_removal_mode 0)
		)
		(polygon
			(pts
				(arc
					(start 27.177746 -24.539956)
					(mid 26.899379 -24.888185)
					(end 26.800048 -25.322784)
				)
				(arc
					(start 26.800048 -26.800048)
					(mid 25.000204 -28.599892)
					(end 23.200106 -26.800048)
				)
				(arc
					(start 23.200106 -25.322784)
					(mid 23.100605 -24.888181)
					(end 22.822154 -24.539956)
				)
				(arc
					(start 22.822154 -24.539956)
					(mid 24.99995 -18.300081)
					(end 27.177746 -24.539956)
				)
			)
		)
	)
	(zone
		(layer "F.Cu")
		(hatch none 0.5)
		(connect_pads
			(clearance 0)
		)
		(min_thickness 0.25)
		(keepout
			(tracks allowed)
			(vias allowed)
			(pads allowed)
			(copperpour allowed)
			(footprints allowed)
		)
		(placement
			(enabled no)
			(sheetname "")
		)
		(fill
			(thermal_gap 0.5)
			(thermal_bridge_width 0.5)
			(island_removal_mode 0)
		)
		(polygon
			(pts
				(xy 166.836598 -149.987254) (xy 166.6875 -149.838156) (xy 165.7858 -149.838156) (xy 165.77945 -149.844506)
				(xy 165.55847 -149.844506) (xy 165.44544 -149.957536) (xy 165.44544 -150.165308) (xy 165.452044 -150.171912)
				(xy 165.452044 -152.852374) (xy 165.452044 -153.762964) (xy 165.452044 -154.336242) (xy 165.620446 -154.504644)
				(xy 166.551102 -154.504644) (xy 166.995348 -154.504644) (xy 167.073326 -154.426666) (xy 167.073326 -153.732992)
				(xy 167.073326 -150.223982)
			)
		)
	)
	(zone
		(layer "F.Cu")
		(hatch none 0.5)
		(connect_pads
			(clearance 0)
		)
		(min_thickness 0.25)
		(keepout
			(tracks allowed)
			(vias allowed)
			(pads allowed)
			(copperpour allowed)
			(footprints allowed)
		)
		(placement
			(enabled no)
			(sheetname "")
		)
		(fill
			(thermal_gap 0.5)
			(thermal_bridge_width 0.5)
			(island_removal_mode 0)
		)
		(polygon
			(pts
				(xy 81.42859 -154.814524) (xy 81.42859 -154.160474) (xy 81.118202 -153.850086) (xy 80.140556 -153.850086)
				(xy 80.039464 -153.951178) (xy 80.039464 -154.861768) (xy 80.039464 -155.435046) (xy 80.207866 -155.603448)
				(xy 81.138522 -155.603448) (xy 81.42859 -155.31338)
			)
		)
	)
	(zone
		(layer "F.Cu")
		(hatch none 0.5)
		(connect_pads
			(clearance 0)
		)
		(min_thickness 0.25)
		(keepout
			(tracks allowed)
			(vias allowed)
			(pads allowed)
			(copperpour allowed)
			(footprints not_allowed)
		)
		(placement
			(enabled no)
			(sheetname "")
		)
		(fill
			(thermal_gap 0.5)
			(thermal_bridge_width 0.5)
			(island_removal_mode 0)
		)
		(polygon
			(pts
				(xy 95.659956 -206.30007) (xy 95.659956 -189.300104) (xy 13.359892 -189.300104) (xy 13.359892 -206.30007)
				(xy 82.559906 -206.30007)
				(arc
					(start 82.559906 -201.250042)
					(mid 84.510118 -199.29983)
					(end 86.460076 -201.250042)
				)
				(xy 86.460076 -206.30007)
			)
		)
	)
	(zone
		(layer "F.Cu")
		(hatch none 0.5)
		(connect_pads
			(clearance 0)
		)
		(min_thickness 0.25)
		(keepout
			(tracks not_allowed)
			(vias allowed)
			(pads allowed)
			(copperpour not_allowed)
			(footprints allowed)
		)
		(placement
			(enabled no)
			(sheetname "")
		)
		(fill
			(thermal_gap 0.5)
			(thermal_bridge_width 0.5)
			(island_removal_mode 0)
		)
		(polygon
			(pts
				(arc
					(start 177.255678 -24.426164)
					(mid 176.993266 -24.76923)
					(end 176.900078 -25.190958)
				)
				(arc
					(start 176.900078 -26.75001)
					(mid 175.000158 -28.64993)
					(end 173.099984 -26.75001)
				)
				(arc
					(start 173.099984 -25.190958)
					(mid 173.006722 -24.769264)
					(end 172.744384 -24.426164)
				)
				(arc
					(start 172.744384 -24.426164)
					(mid 175.000255 -18.249982)
					(end 177.255678 -24.426164)
				)
			)
		)
	)
	(zone
		(layer "F.Cu")
		(hatch none 0.5)
		(connect_pads
			(clearance 0)
		)
		(min_thickness 0.25)
		(keepout
			(tracks allowed)
			(vias allowed)
			(pads allowed)
			(copperpour allowed)
			(footprints allowed)
		)
		(placement
			(enabled no)
			(sheetname "")
		)
		(fill
			(thermal_gap 0.5)
			(thermal_bridge_width 0.5)
			(island_removal_mode 0)
		)
		(polygon
			(pts
				(xy 20.230338 -54.335934) (xy 21.491448 -54.335934) (xy 21.59254 -54.234842) (xy 21.59254 -53.43906)
				(xy 21.302472 -53.148992) (xy 20.22348 -53.148992) (xy 20.183094 -53.189378) (xy 20.183094 -54.28869)
			)
		)
	)
	(zone
		(layer "F.Cu")
		(hatch none 0.5)
		(connect_pads
			(clearance 0)
		)
		(min_thickness 0.25)
		(keepout
			(tracks allowed)
			(vias allowed)
			(pads allowed)
			(copperpour allowed)
			(footprints not_allowed)
		)
		(placement
			(enabled no)
			(sheetname "")
		)
		(fill
			(thermal_gap 0.5)
			(thermal_bridge_width 0.5)
			(island_removal_mode 0)
		)
		(polygon
			(pts
				(xy 103.624888 -6.35) (xy 103.624888 -13.24991) (xy 86.374986 -13.24991) (xy 86.374986 -6.35)
			)
		)
	)
	(zone
		(layer "F.Cu")
		(hatch none 0.5)
		(connect_pads
			(clearance 0)
		)
		(min_thickness 0.25)
		(keepout
			(tracks allowed)
			(vias allowed)
			(pads allowed)
			(copperpour allowed)
			(footprints allowed)
		)
		(placement
			(enabled no)
			(sheetname "")
		)
		(fill
			(thermal_gap 0.5)
			(thermal_bridge_width 0.5)
			(island_removal_mode 0)
		)
		(polygon
			(pts
				(xy 73.43267 -120.659398) (xy 74.20229 -120.659398) (xy 74.20229 -120.254268) (xy 73.43267 -120.254268)
			)
		)
	)
	(zone
		(layer "F.Cu")
		(hatch none 0.5)
		(connect_pads
			(clearance 0)
		)
		(min_thickness 0.25)
		(keepout
			(tracks allowed)
			(vias allowed)
			(pads allowed)
			(copperpour allowed)
			(footprints allowed)
		)
		(placement
			(enabled no)
			(sheetname "")
		)
		(fill
			(thermal_gap 0.5)
			(thermal_bridge_width 0.5)
			(island_removal_mode 0)
		)
		(polygon
			(pts
				(xy 141.006068 -141.565884) (xy 141.006068 -143.103346) (xy 141.006068 -144.013936) (xy 141.006068 -144.587214)
				(xy 141.17447 -144.755616) (xy 142.105126 -144.755616) (xy 142.474696 -144.755616) (xy 142.474696 -141.48308)
				(xy 141.006068 -141.48308)
			)
		)
	)
	(zone
		(layer "F.Cu")
		(hatch none 0.5)
		(connect_pads
			(clearance 0)
		)
		(min_thickness 0.25)
		(keepout
			(tracks allowed)
			(vias allowed)
			(pads allowed)
			(copperpour allowed)
			(footprints allowed)
		)
		(placement
			(enabled no)
			(sheetname "")
		)
		(fill
			(thermal_gap 0.5)
			(thermal_bridge_width 0.5)
			(island_removal_mode 0)
		)
		(polygon
			(pts
				(xy 126.874524 -120.905524) (xy 127.436626 -120.905524) (xy 129.35331 -122.822208) (xy 130.081274 -122.822208)
				(xy 130.081274 -122.804174) (xy 130.535934 -123.258834) (xy 132.864606 -123.258834) (xy 133.737858 -123.258834)
				(xy 134.04723 -122.949462) (xy 135.06958 -121.927112) (xy 135.247634 -121.749058) (xy 136.86028 -121.749058)
				(xy 137.467086 -121.749058) (xy 137.821924 -121.39422) (xy 137.821924 -120.064276) (xy 138.63193 -119.25427)
				(xy 138.63193 -118.447058) (xy 138.91387 -118.165118) (xy 140.252704 -118.165118) (xy 141.053058 -117.364764)
				(xy 141.053058 -116.7384) (xy 142.21714 -115.574318) (xy 142.21714 -114.46764) (xy 141.894052 -114.144552)
				(xy 140.98016 -114.144552) (xy 140.234416 -114.144552) (xy 137.88771 -111.797846) (xy 135.01116 -111.797846)
				(xy 133.22554 -111.797846) (xy 131.276852 -109.849158) (xy 131.154678 -109.849158) (xy 129.972054 -109.849158)
				(xy 129.454656 -110.366556) (xy 129.454656 -112.351566) (xy 127.728726 -114.077496) (xy 127.728726 -115.722146)
				(xy 126.74727 -116.703602) (xy 126.74727 -120.77827)
			)
		)
	)
	(zone
		(layer "F.Cu")
		(hatch none 0.5)
		(connect_pads
			(clearance 0)
		)
		(min_thickness 0.25)
		(keepout
			(tracks allowed)
			(vias allowed)
			(pads allowed)
			(copperpour allowed)
			(footprints allowed)
		)
		(placement
			(enabled no)
			(sheetname "")
		)
		(fill
			(thermal_gap 0.5)
			(thermal_bridge_width 0.5)
			(island_removal_mode 0)
		)
		(polygon
			(pts
				(xy 59.172602 -32.714438) (xy 59.44108 -32.714438) (xy 59.72302 -32.432498) (xy 59.72302 -30.960822)
				(xy 59.45124 -30.689042) (xy 57.86882 -30.689042) (xy 57.5437 -31.014162) (xy 57.5437 -32.336232)
				(xy 57.921906 -32.714438)
			)
		)
	)
	(zone
		(layer "F.Cu")
		(hatch none 0.5)
		(connect_pads
			(clearance 0)
		)
		(min_thickness 0.25)
		(keepout
			(tracks allowed)
			(vias allowed)
			(pads allowed)
			(copperpour allowed)
			(footprints allowed)
		)
		(placement
			(enabled no)
			(sheetname "")
		)
		(fill
			(thermal_gap 0.5)
			(thermal_bridge_width 0.5)
			(island_removal_mode 0)
		)
		(polygon
			(pts
				(xy 164.756592 -147.969224) (xy 164.756592 -147.315174) (xy 164.446204 -147.004786) (xy 163.468558 -147.004786)
				(xy 163.463986 -147.009104) (xy 161.449258 -147.009104) (xy 161.262822 -147.19554) (xy 161.262822 -148.35124)
				(xy 161.66973 -148.758148) (xy 163.535868 -148.758148) (xy 164.466524 -148.758148) (xy 164.756592 -148.46808)
			)
		)
	)
	(zone
		(net "POWER_SW1_PWR_CTR_12V_R")
		(layer "F.Cu")
		(hatch none 0.5)
		(connect_pads
			(clearance 0.5)
		)
		(min_thickness 0.25)
		(fill yes
			(thermal_gap 0.5)
			(thermal_bridge_width 0.5)
			(island_removal_mode 0)
		)
		(polygon
			(pts
				(xy 180.203348 -190.458852) (xy 179.76215 -190.0174) (xy 179.76215 -188.8744) (xy 180.09235 -188.5442)
				(xy 184.23255 -188.5442) (xy 184.9374 -188.5442) (xy 185.5216 -188.5442) (xy 185.7756 -188.7982)
				(xy 185.7756 -189.9412) (xy 185.257948 -190.458852)
			)
		)
	)
	(zone
		(layer "F.Cu")
		(hatch none 0.5)
		(connect_pads
			(clearance 0)
		)
		(min_thickness 0.25)
		(keepout
			(tracks allowed)
			(vias allowed)
			(pads allowed)
			(copperpour allowed)
			(footprints allowed)
		)
		(placement
			(enabled no)
			(sheetname "")
		)
		(fill
			(thermal_gap 0.5)
			(thermal_bridge_width 0.5)
			(island_removal_mode 0)
		)
		(polygon
			(pts
				(xy 158.599378 -101.835712) (xy 159.357822 -101.835712) (xy 159.415226 -101.778308) (xy 159.415226 -101.586284)
				(xy 159.381444 -101.552502) (xy 158.615888 -101.552502) (xy 158.531814 -101.636576) (xy 158.531814 -101.768148)
			)
		)
	)
	(zone
		(layer "F.Cu")
		(hatch none 0.5)
		(connect_pads
			(clearance 0)
		)
		(min_thickness 0.25)
		(keepout
			(tracks allowed)
			(vias allowed)
			(pads allowed)
			(copperpour allowed)
			(footprints allowed)
		)
		(placement
			(enabled no)
			(sheetname "")
		)
		(fill
			(thermal_gap 0.5)
			(thermal_bridge_width 0.5)
			(island_removal_mode 0)
		)
		(polygon
			(pts
				(xy 33.98901 -177.798222) (xy 33.98901 -177.144172) (xy 33.678622 -176.833784) (xy 32.700976 -176.833784)
				(xy 32.599884 -176.934876) (xy 32.599884 -177.845466) (xy 32.599884 -178.418744) (xy 32.768286 -178.587146)
				(xy 33.698942 -178.587146) (xy 33.98901 -178.297078)
			)
		)
	)
	(zone
		(layer "F.Cu")
		(hatch none 0.5)
		(connect_pads
			(clearance 0)
		)
		(min_thickness 0.25)
		(keepout
			(tracks allowed)
			(vias allowed)
			(pads allowed)
			(copperpour allowed)
			(footprints not_allowed)
		)
		(placement
			(enabled no)
			(sheetname "")
		)
		(fill
			(thermal_gap 0.5)
			(thermal_bridge_width 0.5)
			(island_removal_mode 0)
		)
		(polygon
			(pts
				(arc
					(start 90.000074 -57.799986)
					(mid 95.000064 -62.799976)
					(end 90.000074 -67.799966)
				)
				(arc
					(start 90.000074 -67.799966)
					(mid 85.000084 -62.799976)
					(end 90.000074 -57.799986)
				)
			)
		)
	)
	(zone
		(layer "F.Cu")
		(hatch none 0.5)
		(connect_pads
			(clearance 0)
		)
		(min_thickness 0.25)
		(keepout
			(tracks allowed)
			(vias allowed)
			(pads allowed)
			(copperpour allowed)
			(footprints allowed)
		)
		(placement
			(enabled no)
			(sheetname "")
		)
		(fill
			(thermal_gap 0.5)
			(thermal_bridge_width 0.5)
			(island_removal_mode 0)
		)
		(polygon
			(pts
				(xy 20.199858 -56.385968) (xy 21.460968 -56.385968) (xy 21.56206 -56.284876) (xy 21.56206 -55.489094)
				(xy 21.271992 -55.199026) (xy 20.193 -55.199026) (xy 20.152614 -55.239412) (xy 20.152614 -56.338724)
			)
		)
	)
	(zone
		(layer "F.Cu")
		(hatch none 0.5)
		(connect_pads
			(clearance 0)
		)
		(min_thickness 0.25)
		(keepout
			(tracks allowed)
			(vias allowed)
			(pads allowed)
			(copperpour allowed)
			(footprints not_allowed)
		)
		(placement
			(enabled no)
			(sheetname "")
		)
		(fill
			(thermal_gap 0.5)
			(thermal_bridge_width 0.5)
			(island_removal_mode 0)
		)
		(polygon
			(pts
				(xy 179.399946 -35.150044) (xy 195.699888 -35.150044) (xy 195.699888 -50.950114) (xy 179.399946 -50.950114)
			)
		)
	)
	(zone
		(layer "F.Cu")
		(hatch none 0.5)
		(connect_pads
			(clearance 0)
		)
		(min_thickness 0.25)
		(keepout
			(tracks allowed)
			(vias allowed)
			(pads allowed)
			(copperpour allowed)
			(footprints allowed)
		)
		(placement
			(enabled no)
			(sheetname "")
		)
		(fill
			(thermal_gap 0.5)
			(thermal_bridge_width 0.5)
			(island_removal_mode 0)
		)
		(polygon
			(pts
				(xy 165.344094 -183.980836) (xy 165.242748 -183.87949) (xy 164.117528 -183.87949) (xy 164.077142 -183.919876)
				(xy 164.077142 -184.53989) (xy 164.077142 -185.038746) (xy 164.104066 -185.06567) (xy 165.303454 -185.06567)
				(xy 165.512496 -184.856628) (xy 165.512496 -184.149238)
			)
		)
	)
	(zone
		(layer "F.Cu")
		(hatch none 0.5)
		(connect_pads
			(clearance 0)
		)
		(min_thickness 0.25)
		(keepout
			(tracks allowed)
			(vias allowed)
			(pads allowed)
			(copperpour allowed)
			(footprints allowed)
		)
		(placement
			(enabled no)
			(sheetname "")
		)
		(fill
			(thermal_gap 0.5)
			(thermal_bridge_width 0.5)
			(island_removal_mode 0)
		)
		(polygon
			(pts
				(xy 69.11594 -7.051294) (xy 69.11594 -6.566916) (xy 68.84416 -6.295136) (xy 67.26174 -6.295136)
				(xy 66.93662 -6.620256) (xy 66.93662 -7.056374) (xy 67.1449 -7.264654) (xy 68.90258 -7.264654)
			)
		)
	)
	(zone
		(layer "F.Cu")
		(hatch none 0.5)
		(connect_pads
			(clearance 0)
		)
		(min_thickness 0.25)
		(keepout
			(tracks allowed)
			(vias allowed)
			(pads allowed)
			(copperpour allowed)
			(footprints allowed)
		)
		(placement
			(enabled no)
			(sheetname "")
		)
		(fill
			(thermal_gap 0.5)
			(thermal_bridge_width 0.5)
			(island_removal_mode 0)
		)
		(polygon
			(pts
				(xy 39.1668 -9.911842) (xy 39.1668 -11.233912) (xy 39.545006 -11.612118) (xy 40.3606 -11.612118)
				(xy 40.62222 -11.350498) (xy 40.62222 -9.75106) (xy 40.63238 -9.7409) (xy 40.63238 -9.53262) (xy 40.4495 -9.34974)
				(xy 39.41318 -9.34974) (xy 39.1668 -9.59612)
			)
		)
	)
	(zone
		(layer "F.Cu")
		(hatch none 0.5)
		(connect_pads
			(clearance 0)
		)
		(min_thickness 0.25)
		(keepout
			(tracks allowed)
			(vias allowed)
			(pads allowed)
			(copperpour allowed)
			(footprints allowed)
		)
		(placement
			(enabled no)
			(sheetname "")
		)
		(fill
			(thermal_gap 0.5)
			(thermal_bridge_width 0.5)
			(island_removal_mode 0)
		)
		(polygon
			(pts
				(xy 71.06539 -125.426978) (xy 71.83501 -125.426978) (xy 72.28332 -124.978668) (xy 72.28332 -124.91212)
				(xy 72.1487 -124.7775) (xy 71.15556 -124.7775) (xy 71.06539 -124.86767) (xy 71.06539 -125.021848)
			)
		)
	)
	(zone
		(layer "F.Cu")
		(hatch none 0.5)
		(connect_pads
			(clearance 0)
		)
		(min_thickness 0.25)
		(keepout
			(tracks allowed)
			(vias allowed)
			(pads allowed)
			(copperpour allowed)
			(footprints not_allowed)
		)
		(placement
			(enabled no)
			(sheetname "")
		)
		(fill
			(thermal_gap 0.5)
			(thermal_bridge_width 0.5)
			(island_removal_mode 0)
		)
		(polygon
			(pts
				(xy 2.450084 -91.899994) (xy 2.450084 -75.699874) (xy 14.150086 -75.699874) (xy 14.150086 -91.899994)
			)
		)
	)
	(zone
		(layer "F.Cu")
		(hatch none 0.5)
		(connect_pads
			(clearance 0)
		)
		(min_thickness 0.25)
		(keepout
			(tracks allowed)
			(vias allowed)
			(pads allowed)
			(copperpour allowed)
			(footprints allowed)
		)
		(placement
			(enabled no)
			(sheetname "")
		)
		(fill
			(thermal_gap 0.5)
			(thermal_bridge_width 0.5)
			(island_removal_mode 0)
		)
		(polygon
			(pts
				(xy 79.155544 82.022442) (xy 81.314798 82.022442) (xy 81.314798 83.883754) (xy 79.17815 83.883754)
				(xy 79.116174 83.821778) (xy 79.116174 82.061812)
			)
		)
	)
	(zone
		(layer "F.Cu")
		(hatch none 0.5)
		(connect_pads
			(clearance 0)
		)
		(min_thickness 0.25)
		(keepout
			(tracks allowed)
			(vias allowed)
			(pads allowed)
			(copperpour allowed)
			(footprints allowed)
		)
		(placement
			(enabled no)
			(sheetname "")
		)
		(fill
			(thermal_gap 0.5)
			(thermal_bridge_width 0.5)
			(island_removal_mode 0)
		)
		(polygon
			(pts
				(xy 162.306762 -104.003856) (xy 162.40252 -104.099614) (xy 163.646866 -104.099614) (xy 163.646866 -101.73208)
				(xy 163.646866 -100.715826) (xy 163.646866 -98.729546) (xy 163.07816 -98.16084) (xy 161.29762 -98.16084)
				(xy 161.055812 -98.402648) (xy 161.055812 -100.330508) (xy 161.055812 -103.772208) (xy 161.28746 -104.003856)
			)
		)
	)
	(zone
		(layer "F.Cu")
		(hatch none 0.5)
		(connect_pads
			(clearance 0)
		)
		(min_thickness 0.25)
		(keepout
			(tracks allowed)
			(vias allowed)
			(pads allowed)
			(copperpour allowed)
			(footprints not_allowed)
		)
		(placement
			(enabled no)
			(sheetname "")
		)
		(fill
			(thermal_gap 0.5)
			(thermal_bridge_width 0.5)
			(island_removal_mode 0)
		)
		(polygon
			(pts
				(xy 179.399946 -55.150004) (xy 195.699888 -55.150004) (xy 195.699888 -70.950074) (xy 179.399946 -70.950074)
			)
		)
	)
	(zone
		(layer "F.Cu")
		(hatch none 0.5)
		(connect_pads
			(clearance 0)
		)
		(min_thickness 0.25)
		(keepout
			(tracks allowed)
			(vias allowed)
			(pads allowed)
			(copperpour allowed)
			(footprints not_allowed)
		)
		(placement
			(enabled no)
			(sheetname "")
		)
		(fill
			(thermal_gap 0.5)
			(thermal_bridge_width 0.5)
			(island_removal_mode 0)
		)
		(polygon
			(pts
				(xy 150.64994 -39.854886) (xy 157.699964 -39.854886) (xy 157.699964 -56.455056) (xy 150.64994 -56.455056)
			)
		)
	)
	(zone
		(layer "F.Cu")
		(hatch none 0.5)
		(connect_pads
			(clearance 0)
		)
		(min_thickness 0.25)
		(keepout
			(tracks allowed)
			(vias allowed)
			(pads allowed)
			(copperpour allowed)
			(footprints not_allowed)
		)
		(placement
			(enabled no)
			(sheetname "")
		)
		(fill
			(thermal_gap 0.5)
			(thermal_bridge_width 0.5)
			(island_removal_mode 0)
		)
		(polygon
			(pts
				(arc
					(start 1.999996 -169.69994)
					(mid 1.292891 -169.407047)
					(end 0.999998 -168.699942)
				)
				(xy 0.999998 -101.799898) (xy 13.999972 -101.799898) (xy 13.999972 -169.69994)
			)
		)
	)
	(zone
		(layer "F.Cu")
		(hatch none 0.5)
		(connect_pads
			(clearance 0)
		)
		(min_thickness 0.25)
		(keepout
			(tracks allowed)
			(vias allowed)
			(pads allowed)
			(copperpour allowed)
			(footprints allowed)
		)
		(placement
			(enabled no)
			(sheetname "")
		)
		(fill
			(thermal_gap 0.5)
			(thermal_bridge_width 0.5)
			(island_removal_mode 0)
		)
		(polygon
			(pts
				(xy 70.423024 -31.89478) (xy 70.518782 -31.990538) (xy 72.432672 -31.990538) (xy 72.446896 -32.004762)
				(xy 73.303384 -32.004762) (xy 74.003154 -32.004762) (xy 75.401678 -32.004762) (xy 75.6539 -31.75254)
				(xy 75.6539 -30.14726) (xy 75.129644 -29.623004) (xy 74.267314 -29.623004) (xy 70.148958 -29.623004)
				(xy 69.161406 -29.623004) (xy 68.827142 -29.957268) (xy 68.827142 -31.616396) (xy 69.105526 -31.89478)
			)
		)
	)
	(zone
		(layer "F.Cu")
		(hatch none 0.5)
		(connect_pads
			(clearance 0)
		)
		(min_thickness 0.25)
		(keepout
			(tracks allowed)
			(vias allowed)
			(pads allowed)
			(copperpour allowed)
			(footprints not_allowed)
		)
		(placement
			(enabled no)
			(sheetname "")
		)
		(fill
			(thermal_gap 0.5)
			(thermal_bridge_width 0.5)
			(island_removal_mode 0)
		)
		(polygon
			(pts
				(arc
					(start 105.000044 -100.7999)
					(mid 100.000054 -95.79991)
					(end 105.000044 -90.79992)
				)
				(arc
					(start 105.000044 -90.79992)
					(mid 110.000034 -95.79991)
					(end 105.000044 -100.7999)
				)
			)
		)
	)
	(zone
		(layer "F.Cu")
		(hatch none 0.5)
		(connect_pads
			(clearance 0)
		)
		(min_thickness 0.25)
		(keepout
			(tracks allowed)
			(vias allowed)
			(pads allowed)
			(copperpour allowed)
			(footprints not_allowed)
		)
		(placement
			(enabled no)
			(sheetname "")
		)
		(fill
			(thermal_gap 0.5)
			(thermal_bridge_width 0.5)
			(island_removal_mode 0)
		)
		(polygon
			(pts
				(xy 40.699944 -61.500004) (xy 75.300078 -61.500004) (xy 75.300078 -90.099896) (xy 40.699944 -90.099896)
			)
		)
	)
	(zone
		(layer "F.Cu")
		(hatch none 0.5)
		(connect_pads
			(clearance 0)
		)
		(min_thickness 0.25)
		(keepout
			(tracks allowed)
			(vias allowed)
			(pads allowed)
			(copperpour allowed)
			(footprints allowed)
		)
		(placement
			(enabled no)
			(sheetname "")
		)
		(fill
			(thermal_gap 0.5)
			(thermal_bridge_width 0.5)
			(island_removal_mode 0)
		)
		(polygon
			(pts
				(xy 135.510016 -109.989874) (xy 135.510016 -109.335824) (xy 135.199628 -109.025436) (xy 134.221982 -109.025436)
				(xy 134.21741 -109.029754) (xy 133.460744 -109.029754) (xy 133.460744 -110.778798) (xy 134.289292 -110.778798)
				(xy 135.219948 -110.778798) (xy 135.510016 -110.48873)
			)
		)
	)
	(zone
		(layer "F.Cu")
		(hatch none 0.5)
		(connect_pads
			(clearance 0)
		)
		(min_thickness 0.25)
		(keepout
			(tracks allowed)
			(vias allowed)
			(pads allowed)
			(copperpour allowed)
			(footprints allowed)
		)
		(placement
			(enabled no)
			(sheetname "")
		)
		(fill
			(thermal_gap 0.5)
			(thermal_bridge_width 0.5)
			(island_removal_mode 0)
		)
		(polygon
			(pts
				(xy 128.02362 -136.562846) (xy 131.06019 -136.562846) (xy 131.074922 -136.577578) (xy 132.36194 -136.577578)
				(xy 132.36194 -134.508748) (xy 132.32638 -134.473188) (xy 129.8956 -134.473188) (xy 129.8956 -133.24078)
				(xy 129.74828 -133.09346) (xy 128.88214 -133.09346) (xy 128.778 -133.1976) (xy 128.778 -134.414768)
				(xy 128.71958 -134.473188) (xy 128.02362 -134.473188)
			)
		)
	)
	(zone
		(layer "F.Cu")
		(hatch none 0.5)
		(connect_pads
			(clearance 0)
		)
		(min_thickness 0.25)
		(keepout
			(tracks allowed)
			(vias allowed)
			(pads allowed)
			(copperpour allowed)
			(footprints not_allowed)
		)
		(placement
			(enabled no)
			(sheetname "")
		)
		(fill
			(thermal_gap 0.5)
			(thermal_bridge_width 0.5)
			(island_removal_mode 0)
		)
		(polygon
			(pts
				(xy 23.40991 -0.999998) (xy 23.40991 -9.500108) (xy 16.59001 -9.500108) (xy 16.59001 -0.999998)
			)
		)
	)
	(zone
		(layer "F.Cu")
		(hatch none 0.5)
		(connect_pads
			(clearance 0)
		)
		(min_thickness 0.25)
		(keepout
			(tracks allowed)
			(vias allowed)
			(pads allowed)
			(copperpour allowed)
			(footprints allowed)
		)
		(placement
			(enabled no)
			(sheetname "")
		)
		(fill
			(thermal_gap 0.5)
			(thermal_bridge_width 0.5)
			(island_removal_mode 0)
		)
		(polygon
			(pts
				(xy 8.699246 -49.40173) (xy 9.960356 -49.40173) (xy 13.267182 -49.40173) (xy 13.510006 -49.158906)
				(xy 13.510006 -48.174402) (xy 13.138912 -47.803308) (xy 13.05814 -47.803308) (xy 12.79525 -47.540418)
				(xy 9.982962 -47.540418) (xy 9.720072 -47.803308) (xy 9.308592 -48.214788) (xy 8.692388 -48.214788)
				(xy 8.652002 -48.255174) (xy 8.652002 -49.354486)
			)
		)
	)
	(zone
		(layer "F.Cu")
		(hatch none 0.5)
		(connect_pads
			(clearance 0)
		)
		(min_thickness 0.25)
		(keepout
			(tracks allowed)
			(vias allowed)
			(pads allowed)
			(copperpour allowed)
			(footprints allowed)
		)
		(placement
			(enabled no)
			(sheetname "")
		)
		(fill
			(thermal_gap 0.5)
			(thermal_bridge_width 0.5)
			(island_removal_mode 0)
		)
		(polygon
			(pts
				(xy 89.604342 -33.954466) (xy 89.87282 -33.954466) (xy 90.15476 -33.672526) (xy 90.15476 -32.20085)
				(xy 89.88298 -31.92907) (xy 88.30056 -31.92907) (xy 87.97544 -32.25419) (xy 87.97544 -33.57626)
				(xy 88.353646 -33.954466)
			)
		)
	)
	(zone
		(layer "F.Cu")
		(hatch none 0.5)
		(connect_pads
			(clearance 0)
		)
		(min_thickness 0.25)
		(keepout
			(tracks allowed)
			(vias allowed)
			(pads allowed)
			(copperpour allowed)
			(footprints allowed)
		)
		(placement
			(enabled no)
			(sheetname "")
		)
		(fill
			(thermal_gap 0.5)
			(thermal_bridge_width 0.5)
			(island_removal_mode 0)
		)
		(polygon
			(pts
				(xy 83.09483 -84.751418) (xy 83.09483 -83.127088) (xy 82.933286 -82.965544) (xy 82.09788 -82.965544)
				(xy 81.848198 -83.215226) (xy 81.51368 -83.549744) (xy 81.51368 -85.92312) (xy 81.74228 -86.15172)
				(xy 82.04962 -86.15172) (xy 82.97164 -86.15172) (xy 83.09483 -86.02853)
			)
		)
	)
	(zone
		(layer "F.Cu")
		(hatch none 0.5)
		(connect_pads
			(clearance 0)
		)
		(min_thickness 0.25)
		(keepout
			(tracks allowed)
			(vias allowed)
			(pads allowed)
			(copperpour allowed)
			(footprints allowed)
		)
		(placement
			(enabled no)
			(sheetname "")
		)
		(fill
			(thermal_gap 0.5)
			(thermal_bridge_width 0.5)
			(island_removal_mode 0)
		)
		(polygon
			(pts
				(xy 81.80705 86.540848) (xy 81.80705 87.862664) (xy 79.670402 87.862664) (xy 79.608426 87.800688)
				(xy 79.608426 86.540848)
			)
		)
	)
	(zone
		(layer "F.Cu")
		(hatch none 0.5)
		(connect_pads
			(clearance 0)
		)
		(min_thickness 0.25)
		(keepout
			(tracks allowed)
			(vias allowed)
			(pads allowed)
			(copperpour allowed)
			(footprints not_allowed)
		)
		(placement
			(enabled no)
			(sheetname "")
		)
		(fill
			(thermal_gap 0.5)
			(thermal_bridge_width 0.5)
			(island_removal_mode 0)
		)
		(polygon
			(pts
				(xy 18.999962 -55.79999) (xy 96.799908 -55.79999) (xy 96.799908 -95.79991) (xy 18.999962 -95.79991)
			)
		)
	)
	(zone
		(layer "F.Cu")
		(hatch none 0.5)
		(connect_pads
			(clearance 0)
		)
		(min_thickness 0.25)
		(keepout
			(tracks allowed)
			(vias allowed)
			(pads allowed)
			(copperpour allowed)
			(footprints allowed)
		)
		(placement
			(enabled no)
			(sheetname "")
		)
		(fill
			(thermal_gap 0.5)
			(thermal_bridge_width 0.5)
			(island_removal_mode 0)
		)
		(polygon
			(pts
				(xy 43.907456 -110.887002) (xy 44.561506 -110.887002) (xy 44.871894 -110.576614) (xy 44.871894 -109.598968)
				(xy 44.770802 -109.497876) (xy 43.860212 -109.497876) (xy 43.286934 -109.497876) (xy 43.118532 -109.666278)
				(xy 43.118532 -110.596934) (xy 43.4086 -110.887002)
			)
		)
	)
	(zone
		(layer "F.Cu")
		(hatch none 0.5)
		(connect_pads
			(clearance 0)
		)
		(min_thickness 0.25)
		(keepout
			(tracks allowed)
			(vias allowed)
			(pads allowed)
			(copperpour allowed)
			(footprints allowed)
		)
		(placement
			(enabled no)
			(sheetname "")
		)
		(fill
			(thermal_gap 0.5)
			(thermal_bridge_width 0.5)
			(island_removal_mode 0)
		)
		(polygon
			(pts
				(xy 57.094628 -58.203338) (xy 58.355738 -58.203338) (xy 58.358532 -58.200544) (xy 66.955924 -58.200544)
				(xy 67.546728 -57.60974) (xy 66.026284 -56.089296) (xy 60.904628 -56.089296) (xy 57.655714 -52.840382)
				(xy 57.33542 -52.840382) (xy 56.903366 -53.272436) (xy 56.903366 -56.831992) (xy 57.08777 -57.016396)
				(xy 57.047384 -57.056782) (xy 57.047384 -58.156094)
			)
		)
	)
	(zone
		(layers "F.Cu" "B.Cu" "In1.Cu" "In2.Cu" "In3.Cu" "In4.Cu" "In5.Cu" "In6.Cu"
			"In7.Cu" "In8.Cu"
		)
		(name "Package Keepin")
		(hatch none 0.5)
		(connect_pads
			(clearance 0)
		)
		(min_thickness 0.25)
		(keepout
			(tracks allowed)
			(vias allowed)
			(pads allowed)
			(copperpour allowed)
			(footprints allowed)
		)
		(placement
			(enabled no)
			(sheetname "")
		)
		(fill
			(thermal_gap 0.5)
			(thermal_bridge_width 0.5)
			(island_removal_mode 0)
		)
		(polygon
			(pts
				(arc
					(start 198.984108 -75.65009)
					(mid 198.842311 -75.307763)
					(end 198.499984 -75.165966)
				)
				(arc
					(start 198.20001 -75.165966)
					(mid 196.420931 -74.4291)
					(end 195.683886 -72.650096)
				)
				(arc
					(start 195.683886 -33.64992)
					(mid 196.420931 -31.870916)
					(end 198.20001 -31.13405)
				)
				(arc
					(start 198.499984 -31.13405)
					(mid 198.842311 -30.992253)
					(end 198.984108 -30.649926)
				)
				(arc
					(start 198.984108 -1.999996)
					(mid 198.695902 -1.304206)
					(end 198.000112 -1.016)
				)
				(arc
					(start 1.999996 -1.016)
					(mid 1.304206 -1.304206)
					(end 1.016 -1.999996)
				)
				(arc
					(start 1.016 -29.299916)
					(mid 1.157797 -29.642243)
					(end 1.500124 -29.78404)
				)
				(arc
					(start 6.500114 -29.78404)
					(mid 8.279103 -30.520921)
					(end 9.015984 -32.29991)
				)
				(arc
					(start 9.015984 -69.30009)
					(mid 8.279103 -71.079079)
					(end 6.500114 -71.81596)
				)
				(arc
					(start 1.500124 -71.81596)
					(mid 1.157797 -71.957757)
					(end 1.016 -72.300084)
				)
				(arc
					(start 1.016 -168.699942)
					(mid 1.304206 -169.395732)
					(end 1.999996 -169.683938)
				)
				(arc
					(start 10.359898 -169.683938)
					(mid 12.492529 -170.567303)
					(end 13.375894 -172.699934)
				)
				(xy 13.375894 -207.683608) (xy 82.543904 -207.683608)
				(arc
					(start 82.543904 -201.250042)
					(mid 84.510118 -199.283828)
					(end 86.476078 -201.250042)
				)
				(xy 86.476078 -207.683608) (xy 95.643954 -207.683608)
				(arc
					(start 95.643954 -188.250068)
					(mid 100.00996 -183.884062)
					(end 104.375966 -188.250068)
				)
				(xy 104.375966 -207.683608) (xy 173.543976 -207.683608)
				(arc
					(start 173.543976 -201.250042)
					(mid 175.509936 -199.284082)
					(end 177.475896 -201.250042)
				)
				(xy 177.475896 -207.683608) (xy 186.644026 -207.683608)
				(arc
					(start 186.644026 -172.699934)
					(mid 187.527391 -170.567303)
					(end 189.660022 -169.683938)
				)
				(arc
					(start 198.000112 -169.683938)
					(mid 198.695902 -169.395732)
					(end 198.984108 -168.699942)
				)
			)
		)
	)
	(zone
		(layers "F.Cu" "B.Cu" "In1.Cu" "In2.Cu" "In3.Cu" "In4.Cu" "In5.Cu" "In6.Cu"
			"In7.Cu" "In8.Cu"
		)
		(name "Route Keepin")
		(hatch none 0.5)
		(connect_pads
			(clearance 0)
		)
		(min_thickness 0.25)
		(keepout
			(tracks allowed)
			(vias allowed)
			(pads allowed)
			(copperpour allowed)
			(footprints allowed)
		)
		(placement
			(enabled no)
			(sheetname "")
		)
		(fill
			(thermal_gap 0.5)
			(thermal_bridge_width 0.5)
			(island_removal_mode 0)
		)
		(polygon
			(pts
				(arc
					(start 198.000112 -170.191938)
					(mid 199.055112 -169.754942)
					(end 199.492108 -168.699942)
				)
				(arc
					(start 199.492108 -75.65009)
					(mid 199.201522 -74.948552)
					(end 198.499984 -74.657966)
				)
				(arc
					(start 198.20001 -74.657966)
					(mid 196.780142 -74.06989)
					(end 196.191886 -72.650096)
				)
				(arc
					(start 196.191886 -33.64992)
					(mid 196.780142 -32.230126)
					(end 198.20001 -31.64205)
				)
				(arc
					(start 198.499984 -31.64205)
					(mid 199.201522 -31.351464)
					(end 199.492108 -30.649926)
				)
				(arc
					(start 199.492108 -1.999996)
					(mid 199.055112 -0.944996)
					(end 198.000112 -0.508)
				)
				(arc
					(start 1.999996 -0.508)
					(mid 0.944996 -0.944996)
					(end 0.508 -1.999996)
				)
				(arc
					(start 0.508 -29.299916)
					(mid 0.798586 -30.001454)
					(end 1.500124 -30.29204)
				)
				(arc
					(start 6.500114 -30.29204)
					(mid 7.919892 -30.880132)
					(end 8.507984 -32.29991)
				)
				(arc
					(start 8.507984 -69.30009)
					(mid 7.919892 -70.719868)
					(end 6.500114 -71.30796)
				)
				(arc
					(start 1.500124 -71.30796)
					(mid 0.798586 -71.598546)
					(end 0.508 -72.300084)
				)
				(xy 0.508 -165.177724) (xy 0.461264 -165.130988) (xy -1.572006 -165.130988) (xy -1.883664 -164.81933)
				(xy -1.883664 -0.66548) (xy -2.475738 -0.073406) (xy -17.095724 -0.073406) (xy -18.125694 -1.103376)
				(xy -18.125694 -207.43037) (xy -16.972534 -208.58353) (xy -2.22758 -208.58353) (xy -2.102866 -208.458816)
				(xy -2.102866 -167.729662) (xy -1.807972 -167.434768) (xy 0.508 -167.434768)
				(arc
					(start 0.508 -168.699942)
					(mid 0.944996 -169.754942)
					(end 1.999996 -170.191938)
				)
				(arc
					(start 10.359898 -170.191938)
					(mid 12.133319 -170.926513)
					(end 12.867894 -172.699934)
				)
				(xy 12.867894 -207.98663) (xy 13.073888 -208.191608) (xy 82.855054 -208.191608) (xy 83.051904 -207.995774)
				(arc
					(start 83.051904 -201.250042)
					(mid 84.510118 -199.791828)
					(end 85.968078 -201.250042)
				)
				(xy 85.968078 -207.985868) (xy 86.174834 -208.191608) (xy 95.955612 -208.191608) (xy 96.151954 -207.995266)
				(arc
					(start 96.151954 -188.250068)
					(mid 100.00996 -184.392062)
					(end 103.867966 -188.250068)
				)
				(xy 103.867966 -207.986376) (xy 104.074214 -208.191608) (xy 173.855634 -208.191608) (xy 173.983904 -208.0641)
				(xy 174.051976 -207.996028)
				(arc
					(start 174.051976 -201.250042)
					(mid 175.509936 -199.792082)
					(end 176.967896 -201.250042)
				)
				(xy 176.967896 -207.985106) (xy 177.175414 -208.191608) (xy 186.95416 -208.191608) (xy 187.152026 -207.994758)
				(arc
					(start 187.152026 -172.699934)
					(mid 187.886601 -170.926513)
					(end 189.660022 -170.191938)
				)
			)
		)
	)
	(zone
		(layers "F.Cu" "B.Cu" "In2.Cu" "In3.Cu" "In4.Cu" "In6.Cu" "In7.Cu")
		(hatch none 0.5)
		(connect_pads
			(clearance 0)
		)
		(min_thickness 0.25)
		(keepout
			(tracks not_allowed)
			(vias allowed)
			(pads allowed)
			(copperpour not_allowed)
			(footprints allowed)
		)
		(placement
			(enabled no)
			(sheetname "")
		)
		(fill yes
			(thermal_gap 0.5)
			(thermal_bridge_width 0.5)
			(island_removal_mode 0)
		)
		(polygon
			(pts
				(arc
					(start 177.583084 -180.814726)
					(mid 175.000158 -173.741934)
					(end 172.417232 -180.814726)
				)
				(arc
					(start 172.417232 -180.814726)
					(mid 172.546293 -180.98347)
					(end 172.592238 -181.1909)
				)
				(arc
					(start 172.592238 -182.749952)
					(mid 175.000158 -185.157872)
					(end 177.408078 -182.749952)
				)
				(arc
					(start 177.408078 -181.1909)
					(mid 177.453957 -180.98344)
					(end 177.583084 -180.814726)
				)
			)
		)
	)
	(zone
		(layers "F.Cu" "B.Cu" "In2.Cu" "In3.Cu" "In4.Cu" "In6.Cu" "In7.Cu")
		(hatch none 0.5)
		(connect_pads
			(clearance 0)
		)
		(min_thickness 0.25)
		(keepout
			(tracks not_allowed)
			(vias allowed)
			(pads allowed)
			(copperpour not_allowed)
			(footprints allowed)
		)
		(placement
			(enabled no)
			(sheetname "")
		)
		(fill yes
			(thermal_gap 0.5)
			(thermal_bridge_width 0.5)
			(island_removal_mode 0)
		)
		(polygon
			(pts
				(arc
					(start 27.493976 -24.93772)
					(mid 25.000303 -17.792088)
					(end 22.506178 -24.93772)
				)
				(arc
					(start 22.506178 -24.93772)
					(mid 22.643202 -25.108989)
					(end 22.692106 -25.322784)
				)
				(arc
					(start 22.692106 -26.800048)
					(mid 25.000204 -29.108146)
					(end 27.308048 -26.800048)
				)
				(arc
					(start 27.308048 -25.322784)
					(mid 27.356942 -25.108959)
					(end 27.493976 -24.93772)
				)
			)
		)
	)
	(zone
		(layers "F.Cu" "B.Cu" "In2.Cu" "In3.Cu" "In4.Cu" "In6.Cu" "In7.Cu")
		(hatch none 0.5)
		(connect_pads
			(clearance 0)
		)
		(min_thickness 0.25)
		(keepout
			(tracks not_allowed)
			(vias allowed)
			(pads allowed)
			(copperpour not_allowed)
			(footprints allowed)
		)
		(placement
			(enabled no)
			(sheetname "")
		)
		(fill yes
			(thermal_gap 0.5)
			(thermal_bridge_width 0.5)
			(island_removal_mode 0)
		)
		(polygon
			(pts
				(arc
					(start 177.583084 -24.81453)
					(mid 175.000255 -17.742187)
					(end 172.416978 -24.81453)
				)
				(arc
					(start 172.416978 -24.81453)
					(mid 172.546093 -24.983389)
					(end 172.591984 -25.190958)
				)
				(arc
					(start 172.591984 -26.75001)
					(mid 175.000158 -29.158184)
					(end 177.408078 -26.75001)
				)
				(arc
					(start 177.408078 -25.190958)
					(mid 177.453903 -24.983359)
					(end 177.583084 -24.81453)
				)
			)
		)
	)
	(zone
		(layers "F.Cu" "B.Cu" "In2.Cu" "In3.Cu" "In4.Cu" "In6.Cu" "In7.Cu")
		(hatch none 0.5)
		(connect_pads
			(clearance 0)
		)
		(min_thickness 0.25)
		(keepout
			(tracks not_allowed)
			(vias allowed)
			(pads allowed)
			(copperpour not_allowed)
			(footprints allowed)
		)
		(placement
			(enabled no)
			(sheetname "")
		)
		(fill yes
			(thermal_gap 0.5)
			(thermal_bridge_width 0.5)
			(island_removal_mode 0)
		)
		(polygon
			(pts
				(arc
					(start 27.493976 -180.937662)
					(mid 25.000303 -173.79203)
					(end 22.506178 -180.937662)
				)
				(arc
					(start 22.506178 -180.937662)
					(mid 22.643202 -181.108931)
					(end 22.692106 -181.322726)
				)
				(arc
					(start 22.692106 -182.79999)
					(mid 25.000204 -185.108088)
					(end 27.308048 -182.79999)
				)
				(arc
					(start 27.308048 -181.322726)
					(mid 27.356942 -181.108901)
					(end 27.493976 -180.937662)
				)
			)
		)
	)
	(zone
		(layer "B.Cu")
		(hatch none 0.5)
		(connect_pads
			(clearance 0)
		)
		(min_thickness 0.25)
		(keepout
			(tracks not_allowed)
			(vias allowed)
			(pads allowed)
			(copperpour not_allowed)
			(footprints allowed)
		)
		(placement
			(enabled no)
			(sheetname "")
		)
		(fill
			(thermal_gap 0.5)
			(thermal_bridge_width 0.5)
			(island_removal_mode 0)
		)
		(polygon
			(pts
				(arc
					(start 26.800048 -26.800048)
					(mid 25.000204 -28.599892)
					(end 23.200106 -26.800048)
				)
				(arc
					(start 23.200106 -25.322784)
					(mid 23.100605 -24.888181)
					(end 22.822154 -24.539956)
				)
				(arc
					(start 22.822154 -24.539956)
					(mid 24.99995 -18.300081)
					(end 27.177746 -24.539956)
				)
				(arc
					(start 27.177746 -24.539956)
					(mid 26.899379 -24.888185)
					(end 26.800048 -25.322784)
				)
			)
		)
	)
	(zone
		(layer "B.Cu")
		(hatch none 0.5)
		(connect_pads
			(clearance 0)
		)
		(min_thickness 0.25)
		(keepout
			(tracks not_allowed)
			(vias allowed)
			(pads allowed)
			(copperpour not_allowed)
			(footprints allowed)
		)
		(placement
			(enabled no)
			(sheetname "")
		)
		(fill
			(thermal_gap 0.5)
			(thermal_bridge_width 0.5)
			(island_removal_mode 0)
		)
		(polygon
			(pts
				(arc
					(start 122.199908 -6.065012)
					(mid 119.494808 -8.770112)
					(end 122.199908 -11.474958)
				)
				(arc
					(start 122.199908 -11.474958)
					(mid 124.904754 -8.770112)
					(end 122.199908 -6.065012)
				)
			)
		)
	)
	(zone
		(net "GND")
		(layer "B.Cu")
		(hatch none 0.5)
		(connect_pads
			(clearance 0.5)
		)
		(min_thickness 0.25)
		(fill yes
			(thermal_gap 0.5)
			(thermal_bridge_width 0.5)
			(island_removal_mode 0)
		)
		(polygon
			(pts
				(xy 53.6448 -80.479646) (xy 52.932584 -81.192116) (xy 52.932584 -81.600294) (xy 52.926742 -81.605882)
				(xy 52.926742 -81.933542) (xy 52.962556 -82.021172)
				(arc
					(start 52.977034 -82.037428)
					(mid 53.088688 -82.297503)
					(end 53.020976 -82.572352)
				)
				(xy 53.001164 -82.603594) (xy 53.001164 -82.866992) (xy 53.252116 -83.117944) (xy 53.521356 -83.117944)
				(xy 53.694584 -83.290918) (xy 55.247794 -83.290918)
				(arc
					(start 55.300626 -83.23834)
					(mid 55.328293 -83.196983)
					(end 55.337964 -83.14817)
				)
				(xy 55.337964 -82.861658) (xy 55.435246 -82.764376) (xy 55.435246 -82.654902) (xy 55.518558 -82.57159)
				(xy 56.401716 -82.57159) (xy 56.47944 -82.493866)
				(arc
					(start 56.47944 -82.03438)
					(mid 56.442243 -81.944577)
					(end 56.35244 -81.90738)
				)
				(xy 56.114188 -81.90738) (xy 56.015128 -81.80832) (xy 56.015128 -80.003142) (xy 56.21528 -79.802736)
				(xy 56.21528 -79.785464) (xy 56.23306 -79.785464) (xy 56.290972 -79.727298) (xy 56.44261 -79.727298)
				(xy 56.70804 -79.461868) (xy 56.70804 -79.04861) (xy 56.904382 -78.852268) (xy 58.919618 -78.852268)
				(xy 59.068462 -78.703424) (xy 59.068462 -78.442312) (xy 58.932572 -78.306422) (xy 58.449464 -78.306422)
				(xy 58.449464 -78.30185) (xy 54.734714 -78.30185)
				(arc
					(start 54.557676 -78.478888)
					(mid 54.543293 -78.511186)
					(end 54.538372 -78.546198)
				)
				(xy 54.538372 -79.81823) (xy 54.53634 -79.820262) (xy 54.53634 -79.854806) (xy 54.331108 -80.060038)
				(arc
					(start 53.7718 -80.060038)
					(mid 53.681997 -80.097235)
					(end 53.6448 -80.187038)
				)
			)
		)
	)
	(zone
		(layer "B.Cu")
		(hatch none 0.5)
		(connect_pads
			(clearance 0)
		)
		(min_thickness 0.25)
		(keepout
			(tracks allowed)
			(vias allowed)
			(pads allowed)
			(copperpour allowed)
			(footprints not_allowed)
		)
		(placement
			(enabled no)
			(sheetname "")
		)
		(fill
			(thermal_gap 0.5)
			(thermal_bridge_width 0.5)
			(island_removal_mode 0)
		)
		(polygon
			(pts
				(arc
					(start 25.999948 -64.3001)
					(mid 27.499818 -62.80023)
					(end 25.999948 -61.300106)
				)
				(arc
					(start 25.999948 -61.300106)
					(mid 24.499824 -62.80023)
					(end 25.999948 -64.3001)
				)
			)
		)
	)
	(zone
		(layer "B.Cu")
		(hatch none 0.5)
		(connect_pads
			(clearance 0)
		)
		(min_thickness 0.25)
		(keepout
			(tracks allowed)
			(vias allowed)
			(pads allowed)
			(copperpour allowed)
			(footprints not_allowed)
		)
		(placement
			(enabled no)
			(sheetname "")
		)
		(fill
			(thermal_gap 0.5)
			(thermal_bridge_width 0.5)
			(island_removal_mode 0)
		)
		(polygon
			(pts
				(arc
					(start 122.199908 -0.769874)
					(mid 114.19967 -8.770112)
					(end 122.199908 -16.770096)
				)
				(arc
					(start 122.199908 -16.770096)
					(mid 130.199892 -8.770112)
					(end 122.199908 -0.769874)
				)
			)
		)
	)
	(zone
		(layer "B.Cu")
		(hatch none 0.5)
		(connect_pads
			(clearance 0)
		)
		(min_thickness 0.25)
		(keepout
			(tracks allowed)
			(vias allowed)
			(pads allowed)
			(copperpour allowed)
			(footprints not_allowed)
		)
		(placement
			(enabled no)
			(sheetname "")
		)
		(fill
			(thermal_gap 0.5)
			(thermal_bridge_width 0.5)
			(island_removal_mode 0)
		)
		(polygon
			(pts
				(arc
					(start 90.000074 -93.799914)
					(mid 95.000064 -88.799924)
					(end 90.000074 -83.799934)
				)
				(arc
					(start 90.000074 -83.799934)
					(mid 85.000084 -88.799924)
					(end 90.000074 -93.799914)
				)
			)
		)
	)
	(zone
		(layer "B.Cu")
		(hatch none 0.5)
		(connect_pads
			(clearance 0)
		)
		(min_thickness 0.25)
		(keepout
			(tracks allowed)
			(vias allowed)
			(pads allowed)
			(copperpour allowed)
			(footprints not_allowed)
		)
		(placement
			(enabled no)
			(sheetname "")
		)
		(fill
			(thermal_gap 0.5)
			(thermal_bridge_width 0.5)
			(island_removal_mode 0)
		)
		(polygon
			(pts
				(arc
					(start 25.999948 -83.799934)
					(mid 20.999958 -88.799924)
					(end 25.999948 -93.799914)
				)
				(arc
					(start 25.999948 -93.799914)
					(mid 30.999938 -88.799924)
					(end 25.999948 -83.799934)
				)
			)
		)
	)
	(zone
		(layer "B.Cu")
		(hatch none 0.5)
		(connect_pads
			(clearance 0)
		)
		(min_thickness 0.25)
		(keepout
			(tracks allowed)
			(vias allowed)
			(pads allowed)
			(copperpour allowed)
			(footprints not_allowed)
		)
		(placement
			(enabled no)
			(sheetname "")
		)
		(fill
			(thermal_gap 0.5)
			(thermal_bridge_width 0.5)
			(island_removal_mode 0)
		)
		(polygon
			(pts
				(arc
					(start 122.199908 -13.770102)
					(mid 127.199898 -8.770112)
					(end 122.199908 -3.770122)
				)
				(arc
					(start 122.199908 -3.770122)
					(mid 117.199918 -8.770112)
					(end 122.199908 -13.770102)
				)
			)
		)
	)
	(zone
		(layer "B.Cu")
		(hatch none 0.5)
		(connect_pads
			(clearance 0)
		)
		(min_thickness 0.25)
		(keepout
			(tracks allowed)
			(vias allowed)
			(pads allowed)
			(copperpour allowed)
			(footprints not_allowed)
		)
		(placement
			(enabled no)
			(sheetname "")
		)
		(fill
			(thermal_gap 0.5)
			(thermal_bridge_width 0.5)
			(island_removal_mode 0)
		)
		(polygon
			(pts
				(arc
					(start 90.000074 -67.799966)
					(mid 95.000064 -62.799976)
					(end 90.000074 -57.799986)
				)
				(arc
					(start 90.000074 -57.799986)
					(mid 85.000084 -62.799976)
					(end 90.000074 -67.799966)
				)
			)
		)
	)
	(zone
		(layer "B.Cu")
		(hatch none 0.5)
		(connect_pads
			(clearance 0)
		)
		(min_thickness 0.25)
		(keepout
			(tracks allowed)
			(vias allowed)
			(pads allowed)
			(copperpour allowed)
			(footprints not_allowed)
		)
		(placement
			(enabled no)
			(sheetname "")
		)
		(fill
			(thermal_gap 0.5)
			(thermal_bridge_width 0.5)
			(island_removal_mode 0)
		)
		(polygon
			(pts
				(arc
					(start 129.999994 -182.79999)
					(mid 125.000004 -177.8)
					(end 120.000014 -182.79999)
				)
				(xy 120.000014 -189.300104) (xy 129.999994 -189.300104)
			)
		)
	)
	(zone
		(layer "B.Cu")
		(hatch none 0.5)
		(connect_pads
			(clearance 0)
		)
		(min_thickness 0.25)
		(keepout
			(tracks allowed)
			(vias allowed)
			(pads allowed)
			(copperpour allowed)
			(footprints allowed)
		)
		(placement
			(enabled no)
			(sheetname "")
		)
		(fill
			(thermal_gap 0.5)
			(thermal_bridge_width 0.5)
			(island_removal_mode 0)
		)
		(polygon
			(pts
				(xy 66.907664 -104.216454) (xy 67.504818 -104.216454) (xy 67.532504 -104.188768) (xy 67.532504 -103.65359)
				(xy 67.487546 -103.608632) (xy 66.942208 -103.608632) (xy 66.85915 -103.69169) (xy 66.85915 -104.16794)
			)
		)
	)
	(zone
		(layer "B.Cu")
		(hatch none 0.5)
		(connect_pads
			(clearance 0)
		)
		(min_thickness 0.25)
		(keepout
			(tracks allowed)
			(vias allowed)
			(pads allowed)
			(copperpour allowed)
			(footprints not_allowed)
		)
		(placement
			(enabled no)
			(sheetname "")
		)
		(fill
			(thermal_gap 0.5)
			(thermal_bridge_width 0.5)
			(island_removal_mode 0)
		)
		(polygon
			(pts
				(arc
					(start 0.999998 -29.299916)
					(mid 1.146482 -29.653558)
					(end 1.500124 -29.800042)
				)
				(arc
					(start 6.500114 -29.800042)
					(mid 8.267788 -30.532236)
					(end 8.999982 -32.29991)
				)
				(xy 8.999982 -35.08756) (xy 8.999982 -66.487548)
				(arc
					(start 8.999982 -69.30009)
					(mid 8.267788 -71.067764)
					(end 6.500114 -71.799958)
				)
				(arc
					(start 1.500124 -71.799958)
					(mid 1.146482 -71.946442)
					(end 0.999998 -72.300084)
				)
				(xy 0.999998 -101.799898)
				(arc
					(start 0.999998 -168.699942)
					(mid 1.292891 -169.407047)
					(end 1.999996 -169.69994)
				)
				(arc
					(start 10.359898 -169.69994)
					(mid 12.481214 -170.578618)
					(end 13.359892 -172.699934)
				)
				(xy 13.359892 -189.300104) (xy 80.000094 -189.300104)
				(arc
					(start 80.000094 -182.79999)
					(mid 85.000084 -177.8)
					(end 90.000074 -182.79999)
				)
				(xy 90.000074 -189.300104) (xy 95.659956 -189.300104)
				(arc
					(start 95.659956 -188.250068)
					(mid 100.00996 -183.900064)
					(end 104.359964 -188.250068)
				)
				(xy 104.359964 -189.300104) (xy 120.000014 -189.300104)
				(arc
					(start 120.000014 -182.79999)
					(mid 125.000004 -177.8)
					(end 129.999994 -182.79999)
				)
				(xy 129.999994 -189.300104) (xy 186.660028 -189.300104)
				(arc
					(start 186.660028 -172.699934)
					(mid 187.538706 -170.578618)
					(end 189.660022 -169.69994)
				)
				(arc
					(start 198.000112 -169.69994)
					(mid 198.707217 -169.407047)
					(end 199.00011 -168.699942)
				)
				(xy 199.00011 -101.799898)
				(arc
					(start 199.00011 -75.65009)
					(mid 198.853626 -75.296448)
					(end 198.499984 -75.149964)
				)
				(arc
					(start 198.20001 -75.149964)
					(mid 196.432247 -74.417785)
					(end 195.699888 -72.650096)
				)
				(xy 195.699888 -70.950074) (xy 195.699888 -55.150004) (xy 195.699888 -50.950114) (xy 195.699888 -35.150044)
				(arc
					(start 195.699888 -33.64992)
					(mid 196.432247 -31.882231)
					(end 198.20001 -31.150052)
				)
				(arc
					(start 198.499984 -31.150052)
					(mid 198.853626 -31.003568)
					(end 199.00011 -30.649926)
				)
				(arc
					(start 199.00011 -1.999996)
					(mid 198.707217 -1.292891)
					(end 198.000112 -0.999998)
				)
				(xy 183.410098 -0.999998) (xy 176.589944 -0.999998)
				(arc
					(start 124.1044 -0.999998)
					(mid 130.142504 -9.729273)
					(end 122.199908 -16.770096)
				)
				(arc
					(start 122.199908 -16.770096)
					(mid 114.25763 -9.729262)
					(end 120.295416 -0.999998)
				)
				(xy 23.40991 -0.999998) (xy 16.59001 -0.999998)
				(arc
					(start 1.999996 -0.999998)
					(mid 1.292891 -1.292891)
					(end 0.999998 -1.999996)
				)
			)
		)
	)
	(zone
		(layer "B.Cu")
		(hatch none 0.5)
		(connect_pads
			(clearance 0)
		)
		(min_thickness 0.25)
		(keepout
			(tracks allowed)
			(vias allowed)
			(pads allowed)
			(copperpour allowed)
			(footprints not_allowed)
		)
		(placement
			(enabled no)
			(sheetname "")
		)
		(fill
			(thermal_gap 0.5)
			(thermal_bridge_width 0.5)
			(island_removal_mode 0)
		)
		(polygon
			(pts
				(arc
					(start 30.999684 -177.749962)
					(mid 24.99995 -171.800057)
					(end 19.000216 -177.749962)
				)
				(arc
					(start 18.999962 -182.799736)
					(mid 24.99995 -188.799978)
					(end 30.999938 -182.799736)
				)
			)
		)
	)
	(zone
		(layer "B.Cu")
		(hatch none 0.5)
		(connect_pads
			(clearance 0)
		)
		(min_thickness 0.25)
		(keepout
			(tracks allowed)
			(vias allowed)
			(pads allowed)
			(copperpour allowed)
			(footprints not_allowed)
		)
		(placement
			(enabled no)
			(sheetname "")
		)
		(fill
			(thermal_gap 0.5)
			(thermal_bridge_width 0.5)
			(island_removal_mode 0)
		)
		(polygon
			(pts
				(xy 13.359892 -206.30007) (xy 82.559906 -206.30007)
				(arc
					(start 82.559906 -201.250042)
					(mid 84.510118 -199.29983)
					(end 86.460076 -201.250042)
				)
				(xy 86.460076 -206.30007) (xy 95.659956 -206.30007) (xy 95.659956 -189.300104) (xy 13.359892 -189.300104)
			)
		)
	)
	(zone
		(layer "B.Cu")
		(hatch none 0.5)
		(connect_pads
			(clearance 0)
		)
		(min_thickness 0.25)
		(keepout
			(tracks allowed)
			(vias allowed)
			(pads allowed)
			(copperpour allowed)
			(footprints not_allowed)
		)
		(placement
			(enabled no)
			(sheetname "")
		)
		(fill
			(thermal_gap 0.5)
			(thermal_bridge_width 0.5)
			(island_removal_mode 0)
		)
		(polygon
			(pts
				(arc
					(start 90.000074 -90.300048)
					(mid 91.499944 -88.800178)
					(end 90.000074 -87.300054)
				)
				(arc
					(start 90.000074 -87.300054)
					(mid 88.49995 -88.800178)
					(end 90.000074 -90.300048)
				)
			)
		)
	)
	(zone
		(layer "B.Cu")
		(hatch none 0.5)
		(connect_pads
			(clearance 0)
		)
		(min_thickness 0.25)
		(keepout
			(tracks allowed)
			(vias allowed)
			(pads allowed)
			(copperpour allowed)
			(footprints allowed)
		)
		(placement
			(enabled no)
			(sheetname "")
		)
		(fill
			(thermal_gap 0.5)
			(thermal_bridge_width 0.5)
			(island_removal_mode 0)
		)
		(polygon
			(pts
				(xy 80.965548 -78.470506) (xy 83.063842 -78.470506) (xy 83.231736 -78.302612) (xy 83.231736 -77.06487)
				(xy 82.969354 -76.802488) (xy 80.828896 -76.802488) (xy 80.493362 -77.138022) (xy 80.493362 -77.99832)
			)
		)
	)
	(zone
		(layer "B.Cu")
		(hatch none 0.5)
		(connect_pads
			(clearance 0)
		)
		(min_thickness 0.25)
		(keepout
			(tracks allowed)
			(vias allowed)
			(pads allowed)
			(copperpour allowed)
			(footprints not_allowed)
		)
		(placement
			(enabled no)
			(sheetname "")
		)
		(fill
			(thermal_gap 0.5)
			(thermal_bridge_width 0.5)
			(island_removal_mode 0)
		)
		(polygon
			(pts
				(arc
					(start 30.999684 -21.75002)
					(mid 24.99995 -15.800115)
					(end 19.000216 -21.75002)
				)
				(arc
					(start 18.95856 -26.749756)
					(mid 24.99995 -32.841647)
					(end 31.04134 -26.749756)
				)
			)
		)
	)
	(zone
		(layer "B.Cu")
		(hatch none 0.5)
		(connect_pads
			(clearance 0)
		)
		(min_thickness 0.25)
		(keepout
			(tracks allowed)
			(vias allowed)
			(pads allowed)
			(copperpour allowed)
			(footprints not_allowed)
		)
		(placement
			(enabled no)
			(sheetname "")
		)
		(fill
			(thermal_gap 0.5)
			(thermal_bridge_width 0.5)
			(island_removal_mode 0)
		)
		(polygon
			(pts
				(arc
					(start 168.999916 -177.749962)
					(mid 174.999904 -171.749974)
					(end 180.999892 -177.749962)
				)
				(arc
					(start 180.999892 -182.749952)
					(mid 174.999904 -188.74994)
					(end 168.999916 -182.749952)
				)
			)
		)
	)
	(zone
		(layer "B.Cu")
		(hatch none 0.5)
		(connect_pads
			(clearance 0)
		)
		(min_thickness 0.25)
		(keepout
			(tracks not_allowed)
			(vias allowed)
			(pads allowed)
			(copperpour not_allowed)
			(footprints allowed)
		)
		(placement
			(enabled no)
			(sheetname "")
		)
		(fill
			(thermal_gap 0.5)
			(thermal_bridge_width 0.5)
			(island_removal_mode 0)
		)
		(polygon
			(pts
				(arc
					(start 122.199908 -3.770122)
					(mid 117.199918 -8.770112)
					(end 122.199908 -13.770102)
				)
				(arc
					(start 122.199908 -13.770102)
					(mid 127.199898 -8.770112)
					(end 122.199908 -3.770122)
				)
			)
		)
	)
	(zone
		(layer "B.Cu")
		(hatch none 0.5)
		(connect_pads
			(clearance 0)
		)
		(min_thickness 0.25)
		(keepout
			(tracks not_allowed)
			(vias allowed)
			(pads allowed)
			(copperpour not_allowed)
			(footprints allowed)
		)
		(placement
			(enabled no)
			(sheetname "")
		)
		(fill
			(thermal_gap 0.5)
			(thermal_bridge_width 0.5)
			(island_removal_mode 0)
		)
		(polygon
			(pts
				(arc
					(start 105.000044 -97.799906)
					(mid 107.00004 -95.79991)
					(end 105.000044 -93.799914)
				)
				(arc
					(start 105.000044 -93.799914)
					(mid 103.000048 -95.79991)
					(end 105.000044 -97.799906)
				)
			)
		)
	)
	(zone
		(layer "B.Cu")
		(hatch none 0.5)
		(connect_pads
			(clearance 0)
		)
		(min_thickness 0.25)
		(keepout
			(tracks allowed)
			(vias allowed)
			(pads allowed)
			(copperpour allowed)
			(footprints not_allowed)
		)
		(placement
			(enabled no)
			(sheetname "")
		)
		(fill
			(thermal_gap 0.5)
			(thermal_bridge_width 0.5)
			(island_removal_mode 0)
		)
		(polygon
			(pts
				(arc
					(start 25.999948 -93.799914)
					(mid 30.999938 -88.799924)
					(end 25.999948 -83.799934)
				)
				(arc
					(start 25.999948 -83.799934)
					(mid 20.999958 -88.799924)
					(end 25.999948 -93.799914)
				)
			)
		)
	)
	(zone
		(layer "B.Cu")
		(hatch none 0.5)
		(connect_pads
			(clearance 0)
		)
		(min_thickness 0.25)
		(keepout
			(tracks allowed)
			(vias allowed)
			(pads allowed)
			(copperpour allowed)
			(footprints allowed)
		)
		(placement
			(enabled no)
			(sheetname "")
		)
		(fill
			(thermal_gap 0.5)
			(thermal_bridge_width 0.5)
			(island_removal_mode 0)
		)
		(polygon
			(pts
				(xy 118.552214 -144.737328) (xy 119.149368 -144.737328) (xy 119.177054 -144.709642) (xy 119.177054 -144.174464)
				(xy 119.132096 -144.129506) (xy 118.586758 -144.129506) (xy 118.5037 -144.212564) (xy 118.5037 -144.688814)
			)
		)
	)
	(zone
		(layer "B.Cu")
		(hatch none 0.5)
		(connect_pads
			(clearance 0)
		)
		(min_thickness 0.25)
		(keepout
			(tracks allowed)
			(vias allowed)
			(pads allowed)
			(copperpour allowed)
			(footprints not_allowed)
		)
		(placement
			(enabled no)
			(sheetname "")
		)
		(fill
			(thermal_gap 0.5)
			(thermal_bridge_width 0.5)
			(island_removal_mode 0)
		)
		(polygon
			(pts
				(arc
					(start 90.000074 -182.79999)
					(mid 85.000084 -177.8)
					(end 80.000094 -182.79999)
				)
				(xy 80.000094 -189.300104) (xy 90.000074 -189.300104)
			)
		)
	)
	(zone
		(layer "B.Cu")
		(hatch none 0.5)
		(connect_pads
			(clearance 0)
		)
		(min_thickness 0.25)
		(keepout
			(tracks not_allowed)
			(vias allowed)
			(pads allowed)
			(copperpour not_allowed)
			(footprints allowed)
		)
		(placement
			(enabled no)
			(sheetname "")
		)
		(fill
			(thermal_gap 0.5)
			(thermal_bridge_width 0.5)
			(island_removal_mode 0)
		)
		(polygon
			(pts
				(arc
					(start 176.900078 -182.749952)
					(mid 175.000158 -184.649872)
					(end 173.099984 -182.749952)
				)
				(arc
					(start 173.099984 -181.1909)
					(mid 173.006668 -180.769345)
					(end 172.744384 -180.42636)
				)
				(arc
					(start 172.744384 -180.42636)
					(mid 175.000255 -174.24973)
					(end 177.255678 -180.42636)
				)
				(arc
					(start 177.255678 -180.42636)
					(mid 176.993408 -180.769328)
					(end 176.900078 -181.1909)
				)
			)
		)
	)
	(zone
		(layer "B.Cu")
		(hatch none 0.5)
		(connect_pads
			(clearance 0)
		)
		(min_thickness 0.25)
		(keepout
			(tracks allowed)
			(vias allowed)
			(pads allowed)
			(copperpour allowed)
			(footprints not_allowed)
		)
		(placement
			(enabled no)
			(sheetname "")
		)
		(fill
			(thermal_gap 0.5)
			(thermal_bridge_width 0.5)
			(island_removal_mode 0)
		)
		(polygon
			(pts
				(xy 186.660028 -189.300104) (xy 104.359964 -189.300104) (xy 104.359964 -206.30007) (xy 173.559978 -206.30007)
				(arc
					(start 173.559978 -201.250042)
					(mid 175.509936 -199.300084)
					(end 177.459894 -201.250042)
				)
				(xy 177.459894 -206.30007) (xy 186.660028 -206.30007)
			)
		)
	)
	(zone
		(layer "B.Cu")
		(hatch none 0.5)
		(connect_pads
			(clearance 0)
		)
		(min_thickness 0.25)
		(keepout
			(tracks not_allowed)
			(vias allowed)
			(pads allowed)
			(copperpour not_allowed)
			(footprints allowed)
		)
		(placement
			(enabled no)
			(sheetname "")
		)
		(fill
			(thermal_gap 0.5)
			(thermal_bridge_width 0.5)
			(island_removal_mode 0)
		)
		(polygon
			(pts
				(arc
					(start 176.900078 -26.75001)
					(mid 175.000158 -28.64993)
					(end 173.099984 -26.75001)
				)
				(arc
					(start 173.099984 -25.190958)
					(mid 173.006722 -24.769264)
					(end 172.744384 -24.426164)
				)
				(arc
					(start 172.744384 -24.426164)
					(mid 175.000255 -18.249982)
					(end 177.255678 -24.426164)
				)
				(arc
					(start 177.255678 -24.426164)
					(mid 176.993266 -24.76923)
					(end 176.900078 -25.190958)
				)
			)
		)
	)
	(zone
		(layer "B.Cu")
		(hatch none 0.5)
		(connect_pads
			(clearance 0)
		)
		(min_thickness 0.25)
		(keepout
			(tracks allowed)
			(vias allowed)
			(pads allowed)
			(copperpour allowed)
			(footprints not_allowed)
		)
		(placement
			(enabled no)
			(sheetname "")
		)
		(fill
			(thermal_gap 0.5)
			(thermal_bridge_width 0.5)
			(island_removal_mode 0)
		)
		(polygon
			(pts
				(arc
					(start 25.999948 -90.300048)
					(mid 27.499818 -88.800178)
					(end 25.999948 -87.300054)
				)
				(arc
					(start 25.999948 -87.300054)
					(mid 24.499824 -88.800178)
					(end 25.999948 -90.300048)
				)
			)
		)
	)
	(zone
		(layer "B.Cu")
		(hatch none 0.5)
		(connect_pads
			(clearance 0)
		)
		(min_thickness 0.25)
		(keepout
			(tracks allowed)
			(vias allowed)
			(pads allowed)
			(copperpour allowed)
			(footprints not_allowed)
		)
		(placement
			(enabled no)
			(sheetname "")
		)
		(fill
			(thermal_gap 0.5)
			(thermal_bridge_width 0.5)
			(island_removal_mode 0)
		)
		(polygon
			(pts
				(arc
					(start 180.999892 -21.75002)
					(mid 174.999904 -15.750032)
					(end 168.999916 -21.75002)
				)
				(arc
					(start 168.999916 -26.75001)
					(mid 174.999904 -32.749998)
					(end 180.999892 -26.75001)
				)
			)
		)
	)
	(zone
		(layer "B.Cu")
		(hatch none 0.5)
		(connect_pads
			(clearance 0)
		)
		(min_thickness 0.25)
		(keepout
			(tracks allowed)
			(vias allowed)
			(pads allowed)
			(copperpour allowed)
			(footprints not_allowed)
		)
		(placement
			(enabled no)
			(sheetname "")
		)
		(fill
			(thermal_gap 0.5)
			(thermal_bridge_width 0.5)
			(island_removal_mode 0)
		)
		(polygon
			(pts
				(arc
					(start 111.000032 -95.79991)
					(mid 105.000044 -101.799898)
					(end 99.000056 -95.79991)
				)
				(arc
					(start 99.000056 -90.79992)
					(mid 105.000044 -84.799932)
					(end 111.000032 -90.79992)
				)
			)
		)
	)
	(zone
		(layer "B.Cu")
		(hatch none 0.5)
		(connect_pads
			(clearance 0)
		)
		(min_thickness 0.25)
		(keepout
			(tracks allowed)
			(vias allowed)
			(pads allowed)
			(copperpour allowed)
			(footprints not_allowed)
		)
		(placement
			(enabled no)
			(sheetname "")
		)
		(fill
			(thermal_gap 0.5)
			(thermal_bridge_width 0.5)
			(island_removal_mode 0)
		)
		(polygon
			(pts
				(arc
					(start 25.999948 -67.799966)
					(mid 30.999938 -62.799976)
					(end 25.999948 -57.799986)
				)
				(arc
					(start 25.999948 -57.799986)
					(mid 20.999958 -62.799976)
					(end 25.999948 -67.799966)
				)
			)
		)
	)
	(zone
		(layer "B.Cu")
		(hatch none 0.5)
		(connect_pads
			(clearance 0)
		)
		(min_thickness 0.25)
		(keepout
			(tracks not_allowed)
			(vias allowed)
			(pads allowed)
			(copperpour not_allowed)
			(footprints allowed)
		)
		(placement
			(enabled no)
			(sheetname "")
		)
		(fill
			(thermal_gap 0.5)
			(thermal_bridge_width 0.5)
			(island_removal_mode 0)
		)
		(polygon
			(pts
				(arc
					(start 26.800048 -182.79999)
					(mid 25.000204 -184.599834)
					(end 23.200106 -182.79999)
				)
				(arc
					(start 23.200106 -181.322726)
					(mid 23.100605 -180.888123)
					(end 22.822154 -180.539898)
				)
				(arc
					(start 22.822154 -180.539898)
					(mid 24.99995 -174.300023)
					(end 27.177746 -180.539898)
				)
				(arc
					(start 27.177746 -180.539898)
					(mid 26.899379 -180.888127)
					(end 26.800048 -181.322726)
				)
			)
		)
	)
	(zone
		(layer "B.Cu")
		(hatch none 0.5)
		(connect_pads
			(clearance 0)
		)
		(min_thickness 0.25)
		(keepout
			(tracks allowed)
			(vias allowed)
			(pads allowed)
			(copperpour allowed)
			(footprints not_allowed)
		)
		(placement
			(enabled no)
			(sheetname "")
		)
		(fill
			(thermal_gap 0.5)
			(thermal_bridge_width 0.5)
			(island_removal_mode 0)
		)
		(polygon
			(pts
				(arc
					(start 90.000074 -64.3001)
					(mid 91.499944 -62.80023)
					(end 90.000074 -61.300106)
				)
				(arc
					(start 90.000074 -61.300106)
					(mid 88.49995 -62.80023)
					(end 90.000074 -64.3001)
				)
			)
		)
	)
	(zone
		(layer "B.Cu")
		(hatch none 0.5)
		(connect_pads
			(clearance 0)
		)
		(min_thickness 0.25)
		(keepout
			(tracks allowed)
			(vias allowed)
			(pads allowed)
			(copperpour allowed)
			(footprints not_allowed)
		)
		(placement
			(enabled no)
			(sheetname "")
		)
		(fill
			(thermal_gap 0.5)
			(thermal_bridge_width 0.5)
			(island_removal_mode 0)
		)
		(polygon
			(pts
				(arc
					(start 90.000074 -57.799986)
					(mid 85.000084 -62.799976)
					(end 90.000074 -67.799966)
				)
				(arc
					(start 90.000074 -67.799966)
					(mid 95.000064 -62.799976)
					(end 90.000074 -57.799986)
				)
			)
		)
	)
	(zone
		(layer "B.Cu")
		(hatch none 0.5)
		(connect_pads
			(clearance 0)
		)
		(min_thickness 0.25)
		(keepout
			(tracks allowed)
			(vias allowed)
			(pads allowed)
			(copperpour allowed)
			(footprints not_allowed)
		)
		(placement
			(enabled no)
			(sheetname "")
		)
		(fill
			(thermal_gap 0.5)
			(thermal_bridge_width 0.5)
			(island_removal_mode 0)
		)
		(polygon
			(pts
				(arc
					(start 90.000074 -83.799934)
					(mid 85.000084 -88.799924)
					(end 90.000074 -93.799914)
				)
				(arc
					(start 90.000074 -93.799914)
					(mid 95.000064 -88.799924)
					(end 90.000074 -83.799934)
				)
			)
		)
	)
	(zone
		(layer "B.Cu")
		(hatch none 0.5)
		(connect_pads
			(clearance 0)
		)
		(min_thickness 0.25)
		(keepout
			(tracks allowed)
			(vias allowed)
			(pads allowed)
			(copperpour allowed)
			(footprints not_allowed)
		)
		(placement
			(enabled no)
			(sheetname "")
		)
		(fill
			(thermal_gap 0.5)
			(thermal_bridge_width 0.5)
			(island_removal_mode 0)
		)
		(polygon
			(pts
				(arc
					(start 25.999948 -57.799986)
					(mid 20.999958 -62.799976)
					(end 25.999948 -67.799966)
				)
				(arc
					(start 25.999948 -67.799966)
					(mid 30.999938 -62.799976)
					(end 25.999948 -57.799986)
				)
			)
		)
	)
	(zone
		(layers "B.Cu" "In2.Cu" "In6.Cu" "In7.Cu")
		(hatch none 0.5)
		(connect_pads
			(clearance 0)
		)
		(min_thickness 0.25)
		(keepout
			(tracks not_allowed)
			(vias allowed)
			(pads allowed)
			(copperpour not_allowed)
			(footprints allowed)
		)
		(placement
			(enabled no)
			(sheetname "")
		)
		(fill yes
			(thermal_gap 0.5)
			(thermal_bridge_width 0.5)
			(island_removal_mode 0)
		)
		(polygon
			(pts
				(arc
					(start 56.000904 -71.398892)
					(mid 55.199788 -71.398892)
					(end 56.000904 -71.398892)
				)
			)
		)
	)
	(zone
		(layer "In2.Cu")
		(hatch none 0.5)
		(connect_pads
			(clearance 0)
		)
		(min_thickness 0.25)
		(keepout
			(tracks allowed)
			(vias allowed)
			(pads allowed)
			(copperpour allowed)
			(footprints allowed)
		)
		(placement
			(enabled no)
			(sheetname "")
		)
		(fill
			(thermal_gap 0.5)
			(thermal_bridge_width 0.5)
			(island_removal_mode 0)
		)
		(polygon
			(pts
				(xy 46.822614 -58.13933) (xy 52.2732 -58.13933) (xy 52.567078 -57.845452) (xy 52.567078 -55.919624)
				(xy 52.07762 -55.430166) (xy 46.887892 -55.430166) (xy 45.974 -56.344058) (xy 45.974 -57.290716)
			)
		)
	)
	(zone
		(layer "In2.Cu")
		(hatch none 0.5)
		(connect_pads
			(clearance 0)
		)
		(min_thickness 0.25)
		(keepout
			(tracks allowed)
			(vias allowed)
			(pads allowed)
			(copperpour allowed)
			(footprints allowed)
		)
		(placement
			(enabled no)
			(sheetname "")
		)
		(fill
			(thermal_gap 0.5)
			(thermal_bridge_width 0.5)
			(island_removal_mode 0)
		)
		(polygon
			(pts
				(xy 78.601062 -63.302642) (xy 79.450184 -63.302642) (xy 79.625444 -63.127382) (xy 79.625444 -61.90107)
				(xy 79.463646 -61.739272) (xy 78.816708 -61.739272) (xy 78.560676 -61.995304) (xy 78.560676 -63.262256)
			)
		)
	)
	(zone
		(layer "In2.Cu")
		(hatch none 0.5)
		(connect_pads
			(clearance 0)
		)
		(min_thickness 0.25)
		(keepout
			(tracks allowed)
			(vias allowed)
			(pads allowed)
			(copperpour allowed)
			(footprints allowed)
		)
		(placement
			(enabled no)
			(sheetname "")
		)
		(fill
			(thermal_gap 0.5)
			(thermal_bridge_width 0.5)
			(island_removal_mode 0)
		)
		(polygon
			(pts
				(xy 65.3923 -68.28028) (xy 67.609466 -68.28028) (xy 67.676776 -68.21297) (xy 67.676776 -67.559428)
				(xy 67.589146 -67.471798) (xy 65.533524 -67.471798) (xy 65.37198 -67.633342) (xy 65.37198 -68.25996)
			)
		)
	)
	(zone
		(layer "In2.Cu")
		(hatch none 0.5)
		(connect_pads
			(clearance 0)
		)
		(min_thickness 0.25)
		(keepout
			(tracks allowed)
			(vias allowed)
			(pads allowed)
			(copperpour allowed)
			(footprints allowed)
		)
		(placement
			(enabled no)
			(sheetname "")
		)
		(fill
			(thermal_gap 0.5)
			(thermal_bridge_width 0.5)
			(island_removal_mode 0)
		)
		(polygon
			(pts
				(xy 57.899808 -31.532576) (xy 57.899808 -32.381698) (xy 58.075068 -32.556958) (xy 59.30138 -32.556958)
				(xy 59.463178 -32.39516) (xy 59.463178 -31.748222) (xy 59.207146 -31.49219) (xy 57.940194 -31.49219)
			)
		)
	)
	(zone
		(layer "In2.Cu")
		(hatch none 0.5)
		(connect_pads
			(clearance 0)
		)
		(min_thickness 0.25)
		(keepout
			(tracks allowed)
			(vias allowed)
			(pads allowed)
			(copperpour allowed)
			(footprints allowed)
		)
		(placement
			(enabled no)
			(sheetname "")
		)
		(fill
			(thermal_gap 0.5)
			(thermal_bridge_width 0.5)
			(island_removal_mode 0)
		)
		(polygon
			(pts
				(xy 88.870282 -33.626298) (xy 89.719404 -33.626298) (xy 89.894664 -33.451038) (xy 89.894664 -32.224726)
				(xy 89.732866 -32.062928) (xy 89.085928 -32.062928) (xy 88.829896 -32.31896) (xy 88.829896 -33.585912)
			)
		)
	)
	(zone
		(layer "In2.Cu")
		(hatch none 0.5)
		(connect_pads
			(clearance 0)
		)
		(min_thickness 0.25)
		(keepout
			(tracks allowed)
			(vias allowed)
			(pads allowed)
			(copperpour allowed)
			(footprints allowed)
		)
		(placement
			(enabled no)
			(sheetname "")
		)
		(fill
			(thermal_gap 0.5)
			(thermal_bridge_width 0.5)
			(island_removal_mode 0)
		)
		(polygon
			(pts
				(xy 64.397382 -57.83072) (xy 65.246504 -57.83072) (xy 65.421764 -57.65546) (xy 65.421764 -56.429148)
				(xy 65.259966 -56.26735) (xy 64.613028 -56.26735) (xy 64.356996 -56.523382) (xy 64.356996 -57.790334)
			)
		)
	)
	(zone
		(layer "In2.Cu")
		(hatch none 0.5)
		(connect_pads
			(clearance 0)
		)
		(min_thickness 0.25)
		(keepout
			(tracks allowed)
			(vias allowed)
			(pads allowed)
			(copperpour allowed)
			(footprints allowed)
		)
		(placement
			(enabled no)
			(sheetname "")
		)
		(fill
			(thermal_gap 0.5)
			(thermal_bridge_width 0.5)
			(island_removal_mode 0)
		)
		(polygon
			(pts
				(xy 48.359568 -57.85739) (xy 49.58588 -57.85739) (xy 49.747678 -57.695592) (xy 49.747678 -57.048654)
				(xy 49.491646 -56.792622) (xy 48.224694 -56.792622) (xy 48.184308 -56.833008) (xy 47.276512 -56.833008)
				(xy 47.0916 -57.01792) (xy 47.0916 -57.64276) (xy 47.30623 -57.85739)
			)
		)
	)
	(zone
		(layer "In2.Cu")
		(hatch none 0.5)
		(connect_pads
			(clearance 0)
		)
		(min_thickness 0.25)
		(keepout
			(tracks allowed)
			(vias allowed)
			(pads allowed)
			(copperpour allowed)
			(footprints allowed)
		)
		(placement
			(enabled no)
			(sheetname "")
		)
		(fill
			(thermal_gap 0.5)
			(thermal_bridge_width 0.5)
			(island_removal_mode 0)
		)
		(polygon
			(pts
				(xy 79.091028 -30.74416) (xy 79.091028 -31.459424) (xy 79.266288 -31.634684) (xy 80.4926 -31.634684)
				(xy 80.494632 -31.632652) (xy 82.189828 -31.632652) (xy 82.41284 -31.40964) (xy 82.41284 -30.79242)
				(xy 82.190336 -30.569916) (xy 80.398366 -30.569916) (xy 79.265272 -30.569916)
			)
		)
	)
	(zone
		(layer "In2.Cu")
		(hatch none 0.5)
		(connect_pads
			(clearance 0)
		)
		(min_thickness 0.25)
		(keepout
			(tracks allowed)
			(vias allowed)
			(pads allowed)
			(copperpour allowed)
			(footprints allowed)
		)
		(placement
			(enabled no)
			(sheetname "")
		)
		(fill
			(thermal_gap 0.5)
			(thermal_bridge_width 0.5)
			(island_removal_mode 0)
		)
		(polygon
			(pts
				(xy 76.000102 -32.038036) (xy 76.849224 -32.038036) (xy 77.024484 -31.862776) (xy 77.024484 -30.636464)
				(xy 76.862686 -30.474666) (xy 76.215748 -30.474666) (xy 75.959716 -30.730698) (xy 75.959716 -31.99765)
			)
		)
	)
	(zone
		(layer "In2.Cu")
		(hatch none 0.5)
		(connect_pads
			(clearance 0)
		)
		(min_thickness 0.25)
		(keepout
			(tracks allowed)
			(vias allowed)
			(pads allowed)
			(copperpour allowed)
			(footprints allowed)
		)
		(placement
			(enabled no)
			(sheetname "")
		)
		(fill
			(thermal_gap 0.5)
			(thermal_bridge_width 0.5)
			(island_removal_mode 0)
		)
		(polygon
			(pts
				(xy 74.953622 -31.945834) (xy 75.802744 -31.945834) (xy 75.978004 -31.770574) (xy 75.978004 -30.544262)
				(xy 75.816206 -30.382464) (xy 75.169268 -30.382464) (xy 74.913236 -30.638496) (xy 74.913236 -31.905448)
			)
		)
	)
	(zone
		(layer "In2.Cu")
		(hatch none 0.5)
		(connect_pads
			(clearance 0)
		)
		(min_thickness 0.25)
		(keepout
			(tracks allowed)
			(vias allowed)
			(pads allowed)
			(copperpour allowed)
			(footprints allowed)
		)
		(placement
			(enabled no)
			(sheetname "")
		)
		(fill
			(thermal_gap 0.5)
			(thermal_bridge_width 0.5)
			(island_removal_mode 0)
		)
		(polygon
			(pts
				(xy 48.392842 -31.92526) (xy 49.241964 -31.92526) (xy 49.417224 -31.75) (xy 49.417224 -30.523688)
				(xy 49.255426 -30.36189) (xy 48.608488 -30.36189) (xy 44.32681 -30.36189) (xy 43.98518 -30.70352)
				(xy 43.98518 -33.26384) (xy 44.54906 -33.82772) (xy 46.490382 -33.82772)
			)
		)
	)
	(zone
		(layer "In2.Cu")
		(hatch none 0.5)
		(connect_pads
			(clearance 0)
		)
		(min_thickness 0.25)
		(keepout
			(tracks allowed)
			(vias allowed)
			(pads allowed)
			(copperpour allowed)
			(footprints allowed)
		)
		(placement
			(enabled no)
			(sheetname "")
		)
		(fill
			(thermal_gap 0.5)
			(thermal_bridge_width 0.5)
			(island_removal_mode 0)
		)
		(polygon
			(pts
				(xy 66.629788 -30.548834) (xy 66.629788 -31.397956) (xy 66.805048 -31.573216) (xy 68.03136 -31.573216)
				(xy 69.039994 -31.573216) (xy 69.10832 -31.50489) (xy 69.10832 -30.57525) (xy 69.022976 -30.489906)
				(xy 67.955668 -30.489906) (xy 67.937126 -30.508448) (xy 66.670174 -30.508448)
			)
		)
	)
	(zone
		(layers "In2.Cu" "In3.Cu" "In4.Cu" "In6.Cu" "In7.Cu")
		(hatch none 0.5)
		(connect_pads
			(clearance 0)
		)
		(min_thickness 0.25)
		(keepout
			(tracks not_allowed)
			(vias allowed)
			(pads allowed)
			(copperpour not_allowed)
			(footprints allowed)
		)
		(placement
			(enabled no)
			(sheetname "")
		)
		(fill yes
			(thermal_gap 0.5)
			(thermal_bridge_width 0.5)
			(island_removal_mode 0)
		)
		(polygon
			(pts
				(arc
					(start 27.539188 -24.901398)
					(mid 25.000712 -17.791393)
					(end 22.462236 -24.901398)
				)
				(arc
					(start 22.462236 -24.901398)
					(mid 22.595339 -25.071336)
					(end 22.64283 -25.28189)
				)
				(arc
					(start 22.64283 -26.79954)
					(mid 25.000966 -29.157676)
					(end 27.358848 -26.79954)
				)
				(arc
					(start 27.358848 -25.28189)
					(mid 27.406274 -25.071389)
					(end 27.539188 -24.901398)
				)
			)
		)
	)
	(zone
		(layers "In2.Cu" "In3.Cu" "In4.Cu" "In6.Cu" "In7.Cu")
		(hatch none 0.5)
		(connect_pads
			(clearance 0)
		)
		(min_thickness 0.25)
		(keepout
			(tracks not_allowed)
			(vias allowed)
			(pads allowed)
			(copperpour not_allowed)
			(footprints allowed)
		)
		(placement
			(enabled no)
			(sheetname "")
		)
		(fill yes
			(thermal_gap 0.5)
			(thermal_bridge_width 0.5)
			(island_removal_mode 0)
		)
		(polygon
			(pts
				(arc
					(start 27.539188 -180.902102)
					(mid 25.000712 -173.792097)
					(end 22.462236 -180.902102)
				)
				(arc
					(start 22.462236 -180.902102)
					(mid 22.595339 -181.07204)
					(end 22.64283 -181.282594)
				)
				(arc
					(start 22.64283 -182.800244)
					(mid 25.000966 -185.15838)
					(end 27.358848 -182.800244)
				)
				(arc
					(start 27.358848 -181.282594)
					(mid 27.406274 -181.072093)
					(end 27.539188 -180.902102)
				)
			)
		)
	)
	(zone
		(layers "In2.Cu" "In6.Cu" "In7.Cu")
		(hatch none 0.5)
		(connect_pads
			(clearance 0)
		)
		(min_thickness 0.25)
		(keepout
			(tracks not_allowed)
			(vias allowed)
			(pads allowed)
			(copperpour not_allowed)
			(footprints allowed)
		)
		(placement
			(enabled no)
			(sheetname "")
		)
		(fill yes
			(thermal_gap 0.5)
			(thermal_bridge_width 0.5)
			(island_removal_mode 0)
		)
		(polygon
			(pts
				(arc
					(start 159.1056 -45.709586)
					(mid 158.700216 -45.30166)
					(end 158.2928 -45.707554)
				)
				(xy 158.2928 -46.97222)
				(arc
					(start 158.293054 -46.972474)
					(mid 158.696405 -47.387857)
					(end 159.1056 -46.978062)
				)
				(xy 159.105346 -46.966632) (xy 159.106108 -46.96587) (xy 159.106108 -45.710094)
			)
		)
	)
	(zone
		(layers "In2.Cu" "In6.Cu" "In7.Cu")
		(hatch none 0.5)
		(connect_pads
			(clearance 0)
		)
		(min_thickness 0.25)
		(keepout
			(tracks not_allowed)
			(vias allowed)
			(pads allowed)
			(copperpour not_allowed)
			(footprints allowed)
		)
		(placement
			(enabled no)
			(sheetname "")
		)
		(fill yes
			(thermal_gap 0.5)
			(thermal_bridge_width 0.5)
			(island_removal_mode 0)
		)
		(polygon
			(pts
				(arc
					(start 161.686748 -49.562258)
					(mid 161.281364 -49.154332)
					(end 160.873948 -49.560226)
				)
				(xy 160.873948 -50.824892)
				(arc
					(start 160.874202 -50.825146)
					(mid 161.277553 -51.240529)
					(end 161.686748 -50.830734)
				)
				(xy 161.686494 -50.819304) (xy 161.687256 -50.818542) (xy 161.687256 -49.562766)
			)
		)
	)
	(zone
		(layer "In3.Cu")
		(hatch none 0.5)
		(connect_pads
			(clearance 0)
		)
		(min_thickness 0.25)
		(keepout
			(tracks not_allowed)
			(vias allowed)
			(pads allowed)
			(copperpour not_allowed)
			(footprints allowed)
		)
		(placement
			(enabled no)
			(sheetname "")
		)
		(fill
			(thermal_gap 0.5)
			(thermal_bridge_width 0.5)
			(island_removal_mode 0)
		)
		(polygon
			(pts
				(arc
					(start 82.807302 -149.792182)
					(mid 81.749646 -149.792182)
					(end 82.807302 -149.792182)
				)
			)
		)
	)
	(zone
		(layers "In3.Cu" "In4.Cu")
		(hatch none 0.5)
		(connect_pads
			(clearance 0)
		)
		(min_thickness 0.25)
		(keepout
			(tracks not_allowed)
			(vias allowed)
			(pads allowed)
			(copperpour not_allowed)
			(footprints allowed)
		)
		(placement
			(enabled no)
			(sheetname "")
		)
		(fill yes
			(thermal_gap 0.5)
			(thermal_bridge_width 0.5)
			(island_removal_mode 0)
		)
		(polygon
			(pts
				(arc
					(start 110.029244 -95.79991)
					(mid 105.000044 -90.77071)
					(end 99.970844 -95.79991)
				)
				(arc
					(start 99.742244 -95.79991)
					(mid 105.000044 -90.54211)
					(end 110.257844 -95.79991)
				)
			)
		)
	)
	(zone
		(layers "In3.Cu" "In4.Cu")
		(hatch none 0.5)
		(connect_pads
			(clearance 0)
		)
		(min_thickness 0.25)
		(keepout
			(tracks not_allowed)
			(vias allowed)
			(pads allowed)
			(copperpour not_allowed)
			(footprints allowed)
		)
		(placement
			(enabled no)
			(sheetname "")
		)
		(fill yes
			(thermal_gap 0.5)
			(thermal_bridge_width 0.5)
			(island_removal_mode 0)
		)
		(polygon
			(pts
				(arc
					(start 110.029244 -95.79991)
					(mid 105.000044 -100.82911)
					(end 99.970844 -95.79991)
				)
				(arc
					(start 99.742244 -95.79991)
					(mid 105.000044 -101.05771)
					(end 110.257844 -95.79991)
				)
			)
		)
	)
	(zone
		(net "P3V3_NODE1")
		(layer "In4.Cu")
		(hatch none 0.5)
		(connect_pads
			(clearance 0.5)
		)
		(min_thickness 0.25)
		(fill yes
			(thermal_gap 0.5)
			(thermal_bridge_width 0.5)
			(island_removal_mode 0)
		)
		(polygon
			(pts
				(arc
					(start 1.999996 -1.016)
					(mid 1.304206 -1.304206)
					(end 1.016 -1.999996)
				)
				(arc
					(start 1.016 -29.299916)
					(mid 1.157797 -29.642243)
					(end 1.500124 -29.78404)
				)
				(arc
					(start 6.500114 -29.78404)
					(mid 8.279103 -30.520921)
					(end 9.015984 -32.29991)
				)
				(arc
					(start 9.015984 -69.30009)
					(mid 8.279103 -71.079079)
					(end 6.500114 -71.81596)
				)
				(arc
					(start 1.500124 -71.81596)
					(mid 1.157797 -71.957757)
					(end 1.016 -72.300084)
				)
				(arc
					(start 1.016 -168.699942)
					(mid 1.304206 -169.395732)
					(end 1.999996 -169.683938)
				)
				(arc
					(start 10.359898 -169.683938)
					(mid 12.492529 -170.567303)
					(end 13.375894 -172.699934)
				)
				(xy 13.375894 -207.683608) (xy 82.543904 -207.683608)
				(arc
					(start 82.543904 -201.250042)
					(mid 84.510118 -199.283828)
					(end 86.476078 -201.250042)
				)
				(xy 86.476078 -207.683608) (xy 95.643954 -207.683608)
				(arc
					(start 95.643954 -188.250068)
					(mid 95.934272 -186.684573)
					(end 96.766634 -185.32729)
				)
				(xy 64.381126 -185.32729) (xy 58.25109 -179.197254) (xy 58.25109 -163.01593) (xy 60.75426 -160.51276)
				(xy 66.88201 -160.51276) (xy 67.603624 -161.234374) (xy 67.603624 -170.778678) (xy 68.02882 -171.203874)
				(xy 74.842116 -171.203874) (xy 76.35621 -169.68978) (xy 79.654654 -169.68978) (xy 81.626964 -171.66209)
				(xy 89.027 -171.66209) (xy 91.059254 -169.629836) (xy 92.4052 -169.629836) (xy 92.972382 -170.197018)
				(xy 92.972382 -173.368462) (xy 93.21546 -173.61154) (xy 121.095516 -173.61154) (xy 121.354596 -173.87062)
				(xy 125.014736 -173.87062) (xy 127.959104 -176.814988) (xy 127.959104 -182.961788) (xy 128.654556 -183.65724)
				(xy 139.475464 -183.65724) (xy 140.07846 -183.054244) (xy 140.07846 -170.699684) (xy 140.549884 -170.22826)
				(xy 147.506944 -170.22826) (xy 169.61358 -148.121624) (xy 169.61358 -74.613516) (xy 149.970744 -54.97068)
				(xy 140.161264 -54.97068) (xy 132.98678 -47.796196) (xy 132.98678 -21.070824) (xy 135.320024 -18.73758)
				(xy 147.526756 -18.73758) (xy 148.65858 -19.869404) (xy 148.65858 -27.09164) (xy 163.808664 -27.09164)
				(xy 166.122604 -24.7777)
				(arc
					(start 172.373798 -24.7777)
					(mid 175.000254 -17.741952)
					(end 177.626264 -24.7777)
				)
				(xy 178.926744 -24.7777) (xy 179.698904 -24.00554) (xy 191.433196 -24.00554) (xy 191.88176 -24.454104)
				(xy 191.88176 -31.776416) (xy 190.234316 -33.42386) (xy 183.422036 -33.42386) (xy 178.25974 -38.586156)
				(xy 178.25974 -69.561964) (xy 181.94274 -73.244964) (xy 181.94274 -158.230316) (xy 162.45332 -177.719736)
				(xy 162.45332 -207.683608) (xy 173.543976 -207.683608)
				(arc
					(start 173.543976 -201.250042)
					(mid 175.509936 -199.284082)
					(end 177.475896 -201.250042)
				)
				(xy 177.475896 -207.683608) (xy 186.644026 -207.683608)
				(arc
					(start 186.644026 -172.699934)
					(mid 187.527391 -170.567303)
					(end 189.660022 -169.683938)
				)
				(arc
					(start 198.000112 -169.683938)
					(mid 198.695902 -169.395732)
					(end 198.984108 -168.699942)
				)
				(arc
					(start 198.984108 -75.65009)
					(mid 198.842311 -75.307763)
					(end 198.499984 -75.165966)
				)
				(arc
					(start 198.20001 -75.165966)
					(mid 196.420931 -74.4291)
					(end 195.683886 -72.650096)
				)
				(arc
					(start 195.683886 -33.64992)
					(mid 196.420931 -31.870916)
					(end 198.20001 -31.13405)
				)
				(arc
					(start 198.499984 -31.13405)
					(mid 198.842311 -30.992253)
					(end 198.984108 -30.649926)
				)
				(arc
					(start 198.984108 -1.999996)
					(mid 198.695902 -1.304206)
					(end 198.000112 -1.016)
				)
			)
		)
		(polygon
			(pts
				(arc
					(start 176.408588 -173.99762)
					(mid 171.541416 -175.724906)
					(end 172.417232 -180.814726)
				)
				(arc
					(start 172.417232 -180.814726)
					(mid 172.546293 -180.98347)
					(end 172.592238 -181.1909)
				)
				(xy 172.592238 -182.749952) (xy 172.592238 -182.750206) (xy 172.592238 -182.960264)
				(arc
					(start 172.602398 -182.970424)
					(mid 175.000158 -185.157827)
					(end 177.397918 -182.970424)
				)
				(xy 177.408078 -182.960264) (xy 177.408078 -182.750206) (xy 177.408078 -182.749952)
				(arc
					(start 177.408078 -181.1909)
					(mid 177.453957 -180.98344)
					(end 177.583084 -180.814726)
				)
				(arc
					(start 177.593498 -180.805836)
					(mid 178.97876 -177.265705)
					(end 176.784762 -174.161196)
				)
				(xy 176.51476 -173.891448)
			)
		)
		(polygon
			(pts
				(arc
					(start 27.816302 -181.330346)
					(mid 25.000204 -173.284056)
					(end 22.184106 -181.330346)
				)
				(xy 22.184106 -183.220868)
				(arc
					(start 22.221698 -183.25846)
					(mid 25.000204 -185.616067)
					(end 27.77871 -183.25846)
				)
				(xy 27.816302 -183.220868)
			)
		)
		(polygon
			(pts
				(xy 78.309216 -104.57942) (xy 67.679824 -104.57942) (xy 66.85788 -105.401364) (xy 66.85788 -110.534196)
				(xy 67.743324 -111.41964) (xy 70.077584 -111.41964) (xy 70.4723 -111.814356) (xy 70.4723 -123.709176)
				(xy 74.136504 -127.37338) (xy 78.551024 -127.37338) (xy 88.18118 -137.003536) (xy 88.18118 -145.812764)
				(xy 88.0872 -145.906744) (xy 88.0872 -158.555436) (xy 88.683084 -159.15132) (xy 95.84944 -159.15132)
				(xy 95.84944 -163.071556) (xy 96.511364 -163.73348) (xy 120.838976 -163.73348) (xy 122.48642 -162.086036)
				(xy 122.48642 -127.712724) (xy 121.331736 -126.55804) (xy 116.729764 -126.55804) (xy 115.8113 -127.476504)
				(xy 115.8113 -145.452084) (xy 114.210084 -147.0533) (xy 97.1931 -147.0533) (xy 97.1931 -129.632964)
				(xy 95.576136 -128.016) (xy 88.415876 -128.016) (xy 80.4418 -120.041924) (xy 80.4418 -106.712004)
			)
		)
		(polygon
			(pts
				(arc
					(start 27.49423 -24.93772)
					(mid 25.48048 -17.820809)
					(end 21.8313 -24.254206)
				)
				(xy 21.8313 -24.26716)
				(arc
					(start 21.880068 -24.316182)
					(mid 22.165945 -24.634197)
					(end 22.48408 -24.91994)
				)
				(arc
					(start 22.59965 -25.03551)
					(mid 22.668425 -25.171886)
					(end 22.692106 -25.322784)
				)
				(xy 22.692106 -27.01036)
				(arc
					(start 22.702774 -27.021028)
					(mid 25.000192 -29.108081)
					(end 27.29738 -27.021028)
				)
				(xy 27.308048 -27.01036)
				(arc
					(start 27.308048 -25.322784)
					(mid 27.357032 -25.109027)
					(end 27.493976 -24.93772)
				)
			)
		)
		(polygon
			(pts
				(xy 83.379056 -15.91056) (xy 49.884584 -15.91056) (xy 48.60036 -17.194784) (xy 48.60036 -69.259196)
				(xy 48.667924 -69.32676) (xy 28.360624 -69.32676) (xy 25.2984 -72.388984) (xy 25.2984 -90.123264)
				(xy 15.22984 -100.191824) (xy 15.22984 -117.148356) (xy 15.721584 -117.6401) (xy 34.095436 -117.6401)
				(xy 55.9181 -95.817436) (xy 55.9181 -81.296256) (xy 56.155336 -81.05902) (xy 64.232282 -81.05902)
				(xy 64.91986 -81.746598) (xy 64.91986 -89.795096) (xy 65.564004 -90.43924) (xy 86.209124 -90.43924)
				(xy 91.2876 -95.517716) (xy 91.2876 -109.739176) (xy 98.888804 -117.34038) (xy 120.711976 -117.34038)
				(xy 122.65914 -115.393216) (xy 122.65914 -86.054184) (xy 106.317796 -69.71284) (xy 81.151476 -69.71284)
				(xy 81.08442 -69.645784) (xy 81.08442 -26.378916) (xy 84.42706 -23.036276) (xy 84.42706 -16.958564)
			)
		)
	)
	(zone
		(net "P5V_NODE1")
		(layer "In4.Cu")
		(hatch none 0.5)
		(connect_pads
			(clearance 0.5)
		)
		(min_thickness 0.25)
		(fill yes
			(thermal_gap 0.5)
			(thermal_bridge_width 0.5)
			(island_removal_mode 0)
		)
		(polygon
			(pts
				(arc
					(start 187.103004 -32.91586)
					(mid 187.161761 -32.901318)
					(end 187.207144 -32.86125)
				)
				(arc
					(start 187.207144 -32.86125)
					(mid 187.52058 -32.697318)
					(end 187.834016 -32.86125)
				)
				(xy 187.851796 -32.887158) (xy 187.906914 -32.91586) (xy 189.323726 -32.91586) (xy 189.388496 -32.871664)
				(arc
					(start 189.40272 -32.834834)
					(mid 189.648647 -32.607612)
					(end 189.979046 -32.66186)
				)
				(arc
					(start 189.979046 -32.66186)
					(mid 190.147397 -32.707673)
					(end 190.30569 -32.634174)
				)
				(xy 191.27597 -31.663894) (xy 191.294512 -31.603696)
				(arc
					(start 191.28867 -31.572708)
					(mid 191.290337 -31.421227)
					(end 191.3509 -31.282386)
				)
				(xy 191.37376 -31.249366) (xy 191.37376 -24.664416) (xy 191.222884 -24.51354) (xy 179.909216 -24.51354)
				(xy 179.137056 -25.2857)
				(arc
					(start 177.53584 -25.2857)
					(mid 177.446037 -25.322897)
					(end 177.40884 -25.4127)
				)
				(xy 177.40884 -26.75001) (xy 177.408078 -26.803858) (xy 177.408078 -26.960322) (xy 177.399188 -26.969212)
				(arc
					(start 177.394362 -27.013662)
					(mid 175.000018 -29.158913)
					(end 172.6057 -27.013408)
				)
				(xy 172.600874 -26.968958) (xy 172.592238 -26.960322) (xy 172.592238 -26.813764) (xy 172.591476 -26.75001)
				(arc
					(start 172.591476 -25.4127)
					(mid 172.554279 -25.322897)
					(end 172.464476 -25.2857)
				)
				(xy 166.332916 -25.2857) (xy 164.018976 -27.59964)
				(arc
					(start 155.419806 -27.59964)
					(mid 155.374042 -27.608172)
					(end 155.334462 -27.63266)
				)
				(arc
					(start 155.334462 -27.63266)
					(mid 155.077922 -27.731774)
					(end 154.821382 -27.63266)
				)
				(arc
					(start 154.821382 -27.63266)
					(mid 154.781783 -27.60822)
					(end 154.736038 -27.59964)
				)
				(xy 148.15058 -27.59964) (xy 148.15058 -20.079716) (xy 147.316444 -19.24558) (xy 135.530336 -19.24558)
				(xy 133.49478 -21.281136) (xy 133.49478 -24.846788) (xy 133.524498 -24.902414)
				(arc
					(start 133.551168 -24.920448)
					(mid 133.720042 -25.237186)
					(end 133.551168 -25.553924)
				)
				(xy 133.524498 -25.571958) (xy 133.49478 -25.627584) (xy 133.49478 -47.585884) (xy 140.371576 -54.46268)
				(xy 150.181056 -54.46268) (xy 170.12158 -74.403204)
				(arc
					(start 170.12158 -92.304616)
					(mid 170.132451 -92.356026)
					(end 170.163236 -92.398596)
				)
				(arc
					(start 170.163236 -92.398596)
					(mid 170.28853 -92.681298)
					(end 170.163236 -92.964)
				)
				(arc
					(start 170.163236 -92.964)
					(mid 170.132498 -93.006591)
					(end 170.12158 -93.05798)
				)
				(arc
					(start 170.12158 -95.449898)
					(mid 170.137699 -95.511568)
					(end 170.181778 -95.557594)
				)
				(arc
					(start 170.181778 -95.557594)
					(mid 170.362286 -95.881952)
					(end 170.181778 -96.20631)
				)
				(arc
					(start 170.181778 -96.20631)
					(mid 170.137745 -96.252362)
					(end 170.12158 -96.314006)
				)
				(xy 170.12158 -97.681796) (xy 170.165522 -97.746312)
				(arc
					(start 170.202352 -97.760536)
					(mid 170.444795 -98.115882)
					(end 170.202352 -98.471228)
				)
				(xy 170.165522 -98.485452) (xy 170.12158 -98.549968) (xy 170.12158 -99.951286) (xy 170.161712 -100.01377)
				(arc
					(start 170.196002 -100.029264)
					(mid 170.419337 -100.376482)
					(end 170.196002 -100.7237)
				)
				(arc
					(start 170.196002 -100.7237)
					(mid 170.141817 -100.770549)
					(end 170.12158 -100.83927)
				)
				(xy 170.12158 -101.872796) (xy 170.165522 -101.937312)
				(arc
					(start 170.202352 -101.951536)
					(mid 170.444795 -102.306882)
					(end 170.202352 -102.662228)
				)
				(arc
					(start 170.202352 -102.662228)
					(mid 170.14372 -102.708818)
					(end 170.12158 -102.780338)
				)
				(xy 170.12158 -103.329486) (xy 170.161712 -103.39197)
				(arc
					(start 170.196002 -103.407464)
					(mid 170.419337 -103.754682)
					(end 170.196002 -104.1019)
				)
				(xy 170.161712 -104.117394) (xy 170.12158 -104.179878)
				(arc
					(start 170.12158 -105.612946)
					(mid 170.129983 -105.658375)
					(end 170.154092 -105.697782)
				)
				(arc
					(start 170.154092 -105.697782)
					(mid 170.251388 -105.95229)
					(end 170.154092 -106.206798)
				)
				(arc
					(start 170.154092 -106.206798)
					(mid 170.129997 -106.24621)
					(end 170.12158 -106.291634)
				)
				(arc
					(start 170.12158 -118.39067)
					(mid 170.147369 -118.467386)
					(end 170.21429 -118.512844)
				)
				(arc
					(start 170.21429 -118.512844)
					(mid 170.492467 -118.880128)
					(end 170.21429 -119.247412)
				)
				(xy 170.172888 -119.259096) (xy 170.12158 -119.32666) (xy 170.12158 -130.361944)
				(arc
					(start 170.140884 -130.392932)
					(mid 170.199028 -130.59537)
					(end 170.140884 -130.797808)
				)
				(xy 170.12158 -130.828796) (xy 170.12158 -133.789674)
				(arc
					(start 170.14444 -133.82244)
					(mid 170.212804 -134.040372)
					(end 170.14444 -134.258304)
				)
				(xy 170.12158 -134.29107)
				(arc
					(start 170.12158 -134.895844)
					(mid 170.130738 -134.943198)
					(end 170.156886 -134.983728)
				)
				(arc
					(start 170.156886 -134.983728)
					(mid 170.262621 -135.24738)
					(end 170.156886 -135.511032)
				)
				(arc
					(start 170.156886 -135.511032)
					(mid 170.13073 -135.551559)
					(end 170.12158 -135.598916)
				)
				(xy 170.12158 -148.331936) (xy 158.876746 -159.57677) (xy 158.857696 -159.629856)
				(arc
					(start 158.86049 -159.658304)
					(mid 158.750512 -159.964632)
					(end 158.444184 -160.07461)
				)
				(arc
					(start 158.444184 -160.07461)
					(mid 158.38914 -160.081467)
					(end 158.34233 -160.111186)
				)
				(xy 156.978858 -161.474658) (xy 156.959808 -161.52876)
				(arc
					(start 156.962856 -161.557462)
					(mid 156.853358 -161.868334)
					(end 156.542486 -161.977832)
				)
				(xy 156.513784 -161.974784) (xy 156.459682 -161.993834) (xy 151.834088 -166.619428)
				(arc
					(start 151.826468 -166.63162)
					(mid 151.77317 -166.698464)
					(end 151.706326 -166.751762)
				)
				(xy 151.694134 -166.759382) (xy 147.717256 -170.73626) (xy 140.760196 -170.73626) (xy 140.58646 -170.909996)
				(xy 140.58646 -183.264556) (xy 139.84224 -184.008776)
				(arc
					(start 139.836652 -184.051194)
					(mid 139.579551 -184.362488)
					(end 139.18692 -184.268618)
				)
				(arc
					(start 139.18692 -184.268618)
					(mid 139.111418 -184.231668)
					(end 139.02944 -184.250076)
				)
				(arc
					(start 139.02944 -184.250076)
					(mid 138.8309 -184.307726)
					(end 138.631422 -184.253378)
				)
				(arc
					(start 138.631422 -184.253378)
					(mid 138.548889 -184.236499)
					(end 138.473942 -184.274968)
				)
				(arc
					(start 138.473942 -184.274968)
					(mid 138.16329 -184.392812)
					(end 137.878058 -184.22239)
				)
				(xy 137.860278 -184.195466) (xy 137.804144 -184.16524)
				(arc
					(start 135.435086 -184.16524)
					(mid 135.388702 -184.174113)
					(end 135.348726 -184.199276)
				)
				(arc
					(start 135.348726 -184.199276)
					(mid 135.08863 -184.30167)
					(end 134.828534 -184.199276)
				)
				(arc
					(start 134.828534 -184.199276)
					(mid 134.78858 -184.174057)
					(end 134.742174 -184.16524)
				)
				(arc
					(start 133.292088 -184.16524)
					(mid 133.244069 -184.174668)
					(end 133.203188 -184.201562)
				)
				(arc
					(start 133.203188 -184.201562)
					(mid 132.93598 -184.310772)
					(end 132.668772 -184.201562)
				)
				(arc
					(start 132.668772 -184.201562)
					(mid 132.627886 -184.17468)
					(end 132.579872 -184.16524)
				)
				(arc
					(start 131.138168 -184.16524)
					(mid 131.090512 -184.174418)
					(end 131.049776 -184.2008)
				)
				(arc
					(start 131.049776 -184.2008)
					(mid 130.784854 -184.30784)
					(end 130.519932 -184.2008)
				)
				(arc
					(start 130.519932 -184.2008)
					(mid 130.479197 -184.174416)
					(end 130.43154 -184.16524)
				)
				(arc
					(start 129.852928 -184.16524)
					(mid 129.805908 -184.174265)
					(end 129.765552 -184.200038)
				)
				(arc
					(start 129.765552 -184.200038)
					(mid 129.50317 -184.304617)
					(end 129.240788 -184.200038)
				)
				(arc
					(start 129.240788 -184.200038)
					(mid 129.200442 -184.17424)
					(end 129.153412 -184.16524)
				)
				(arc
					(start 128.907032 -184.16524)
					(mid 128.859013 -184.174668)
					(end 128.818132 -184.201562)
				)
				(arc
					(start 128.818132 -184.201562)
					(mid 128.407886 -184.283295)
					(end 128.169416 -183.939688)
				)
				(xy 128.167892 -183.888888) (xy 127.451104 -183.1721) (xy 127.451104 -177.0253) (xy 125.464824 -175.03902)
				(arc
					(start 125.43663 -175.029622)
					(mid 125.28826 -174.937708)
					(end 125.196346 -174.789338)
				)
				(xy 125.186948 -174.761144) (xy 124.804424 -174.37862) (xy 122.475752 -174.37862)
				(arc
					(start 122.443748 -174.399956)
					(mid 122.231658 -174.464364)
					(end 122.019568 -174.399956)
				)
				(xy 121.987564 -174.37862) (xy 121.144284 -174.37862) (xy 120.885204 -174.11954) (xy 117.596412 -174.11954)
				(arc
					(start 117.563138 -174.143924)
					(mid 117.33784 -174.217559)
					(end 117.112542 -174.143924)
				)
				(xy 117.079268 -174.11954) (xy 112.205516 -174.11954)
				(arc
					(start 112.170972 -174.146718)
					(mid 111.934752 -174.22867)
					(end 111.698532 -174.146718)
				)
				(xy 111.663988 -174.11954)
				(arc
					(start 109.785912 -174.11954)
					(mid 109.739726 -174.128236)
					(end 109.699806 -174.153068)
				)
				(arc
					(start 109.699806 -174.153068)
					(mid 109.441742 -174.253609)
					(end 109.183678 -174.153068)
				)
				(arc
					(start 109.183678 -174.153068)
					(mid 109.14379 -174.128154)
					(end 109.097572 -174.11954)
				)
				(xy 101.73208 -174.11954)
				(arc
					(start 101.722936 -174.12081)
					(mid 101.667818 -174.124813)
					(end 101.6127 -174.12081)
				)
				(xy 101.603556 -174.11954)
				(arc
					(start 93.69298 -174.11954)
					(mid 93.642063 -174.130194)
					(end 93.599762 -174.160434)
				)
				(arc
					(start 93.599762 -174.160434)
					(mid 93.299585 -174.282703)
					(end 93.013784 -174.129954)
				)
				(xy 93.008196 -174.122588) (xy 92.464382 -173.578774) (xy 92.464382 -173.259496) (xy 92.422472 -173.195996)
				(arc
					(start 92.38742 -173.18101)
					(mid 92.155835 -172.830236)
					(end 92.38742 -172.479462)
				)
				(xy 92.422472 -172.464476) (xy 92.464382 -172.400976) (xy 92.464382 -172.21327)
				(arc
					(start 92.436188 -172.178218)
					(mid 92.351406 -171.938442)
					(end 92.436188 -171.698666)
				)
				(xy 92.464382 -171.663614) (xy 92.464382 -171.177712)
				(arc
					(start 92.440506 -171.144438)
					(mid 92.369093 -170.922188)
					(end 92.440506 -170.699938)
				)
				(xy 92.464382 -170.666664) (xy 92.464382 -170.40733) (xy 92.194888 -170.137836)
				(arc
					(start 92.141802 -170.137836)
					(mid 91.906357 -170.234877)
					(end 91.66225 -170.16222)
				)
				(xy 91.628976 -170.137836) (xy 91.269566 -170.137836) (xy 89.237312 -172.17009) (xy 81.416652 -172.17009)
				(xy 79.444342 -170.19778) (xy 76.566522 -170.19778) (xy 75.052428 -171.711874) (xy 71.504302 -171.711874)
				(xy 71.441818 -171.751752)
				(arc
					(start 71.42607 -171.78528)
					(mid 71.080122 -172.00613)
					(end 70.734174 -171.78528)
				)
				(arc
					(start 70.734174 -171.78528)
					(mid 70.687228 -171.731768)
					(end 70.618858 -171.711874)
				)
				(xy 67.818508 -171.711874) (xy 67.095624 -170.98899) (xy 67.095624 -169.92092)
				(arc
					(start 67.088766 -169.901108)
					(mid 67.068158 -169.77741)
					(end 67.088766 -169.653712)
				)
				(xy 67.095624 -169.6339) (xy 67.095624 -161.444686) (xy 66.671698 -161.02076) (xy 60.964572 -161.02076)
				(xy 59.938412 -162.04692)
				(arc
					(start 59.929522 -162.078162)
					(mid 59.832825 -162.241815)
					(end 59.669172 -162.338512)
				)
				(xy 59.63793 -162.347402) (xy 58.75909 -163.226242) (xy 58.75909 -170.49496)
				(arc
					(start 58.7629 -170.510454)
					(mid 58.774725 -170.604688)
					(end 58.7629 -170.698922)
				)
				(xy 58.75909 -170.714416) (xy 58.75909 -178.986942) (xy 60.357512 -180.585364) (xy 60.420758 -180.603398)
				(arc
					(start 60.453016 -180.595778)
					(mid 60.810146 -180.697372)
					(end 60.91174 -181.054502)
				)
				(xy 60.90412 -181.08676) (xy 60.922154 -181.150006) (xy 64.591438 -184.81929) (xy 89.775792 -184.81929)
				(arc
					(start 89.810336 -184.791604)
					(mid 90.04808 -184.708485)
					(end 90.285824 -184.791604)
				)
				(xy 90.320368 -184.81929) (xy 92.208858 -184.81929) (xy 92.27439 -184.77357)
				(arc
					(start 92.288106 -184.735724)
					(mid 92.6465 -184.485014)
					(end 93.004894 -184.735724)
				)
				(arc
					(start 93.004894 -184.735724)
					(mid 93.051403 -184.796347)
					(end 93.124274 -184.81929)
				)
				(arc
					(start 97.309686 -184.81929)
					(mid 101.916842 -184.322534)
					(end 104.375966 -188.250068)
				)
				(arc
					(start 104.375966 -207.556608)
					(mid 104.413163 -207.646411)
					(end 104.502966 -207.683608)
				)
				(arc
					(start 161.81832 -207.683608)
					(mid 161.908123 -207.646411)
					(end 161.94532 -207.556608)
				)
				(arc
					(start 161.94532 -194.995038)
					(mid 161.934704 -194.944207)
					(end 161.90468 -194.90182)
				)
				(arc
					(start 161.90468 -194.90182)
					(mid 161.782353 -194.621912)
					(end 161.90468 -194.342004)
				)
				(arc
					(start 161.90468 -194.342004)
					(mid 161.934771 -194.299647)
					(end 161.94532 -194.248786)
				)
				(arc
					(start 161.94532 -193.967862)
					(mid 161.935201 -193.918185)
					(end 161.906458 -193.876422)
				)
				(arc
					(start 161.906458 -193.876422)
					(mid 161.789838 -193.601848)
					(end 161.906458 -193.327274)
				)
				(arc
					(start 161.906458 -193.327274)
					(mid 161.935203 -193.285512)
					(end 161.94532 -193.235834)
				)
				(xy 161.94532 -186.847988)
				(arc
					(start 161.933128 -186.822334)
					(mid 161.896525 -186.659266)
					(end 161.933128 -186.496198)
				)
				(xy 161.94532 -186.470544) (xy 161.94532 -177.509424) (xy 170.138598 -169.316146) (xy 170.157902 -169.263314)
				(arc
					(start 170.155616 -169.23512)
					(mid 170.265914 -168.932668)
					(end 170.568366 -168.82237)
				)
				(xy 170.59656 -168.824656) (xy 170.649392 -168.805352) (xy 181.43474 -158.020004)
				(arc
					(start 181.43474 -157.896306)
					(mid 181.426044 -157.85012)
					(end 181.401212 -157.8102)
				)
				(arc
					(start 181.401212 -157.8102)
					(mid 181.300193 -157.551628)
					(end 181.401212 -157.293056)
				)
				(arc
					(start 181.401212 -157.293056)
					(mid 181.426126 -157.253168)
					(end 181.43474 -157.20695)
				)
				(xy 181.43474 -122.489468)
				(arc
					(start 181.404006 -122.453654)
					(mid 181.311824 -122.204988)
					(end 181.404006 -121.956322)
				)
				(xy 181.43474 -121.920508) (xy 181.43474 -116.896388)
				(arc
					(start 181.416706 -116.866162)
					(mid 181.362608 -116.670328)
					(end 181.416706 -116.474494)
				)
				(xy 181.43474 -116.444268)
				(arc
					(start 181.43474 -116.000276)
					(mid 181.41453 -115.931538)
					(end 181.360318 -115.884706)
				)
				(arc
					(start 181.360318 -115.884706)
					(mid 181.136834 -115.537488)
					(end 181.360318 -115.19027)
				)
				(arc
					(start 181.360318 -115.19027)
					(mid 181.414503 -115.143421)
					(end 181.43474 -115.0747)
				)
				(xy 181.43474 -73.455276) (xy 177.75174 -69.772276) (xy 177.75174 -56.465216)
				(arc
					(start 177.731674 -56.43372)
					(mid 177.671094 -56.227472)
					(end 177.731674 -56.021224)
				)
				(xy 177.75174 -55.989728) (xy 177.75174 -55.336948)
				(arc
					(start 177.728626 -55.304182)
					(mid 177.659013 -55.084472)
					(end 177.728626 -54.864762)
				)
				(xy 177.75174 -54.831996) (xy 177.75174 -38.375844)
				(arc
					(start 178.909472 -37.218112)
					(mid 178.943342 -37.156754)
					(end 178.939444 -37.086794)
				)
				(arc
					(start 178.939444 -37.086794)
					(mid 179.392582 -35.115502)
					(end 181.363874 -34.662364)
				)
				(arc
					(start 181.363874 -34.662364)
					(mid 181.43382 -34.666202)
					(end 181.495192 -34.632392)
				)
				(xy 183.211724 -32.91586) (xy 184.13095 -32.91586) (xy 184.184036 -32.889698)
				(arc
					(start 184.20207 -32.865822)
					(mid 184.5056 -32.715444)
					(end 184.80913 -32.865822)
				)
				(xy 184.827164 -32.889698) (xy 184.88025 -32.91586)
			)
		)
	)
	(zone
		(layers "In6.Cu" "In7.Cu")
		(hatch none 0.5)
		(connect_pads
			(clearance 0)
		)
		(min_thickness 0.25)
		(keepout
			(tracks not_allowed)
			(vias allowed)
			(pads allowed)
			(copperpour not_allowed)
			(footprints allowed)
		)
		(placement
			(enabled no)
			(sheetname "")
		)
		(fill yes
			(thermal_gap 0.5)
			(thermal_bridge_width 0.5)
			(island_removal_mode 0)
		)
		(polygon
			(pts
				(arc
					(start 156.222954 -45.463714)
					(mid 155.372308 -44.614591)
					(end 154.521662 -45.463714)
				)
				(xy 154.521408 -45.463714) (xy 154.521408 -47.188374)
				(arc
					(start 154.52217 -47.188374)
					(mid 155.383867 -48.011198)
					(end 156.222954 -47.16526)
				)
				(xy 156.222954 -47.15637)
			)
		)
	)
	(zone
		(layers "In6.Cu" "In7.Cu")
		(hatch none 0.5)
		(connect_pads
			(clearance 0)
		)
		(min_thickness 0.25)
		(keepout
			(tracks not_allowed)
			(vias allowed)
			(pads allowed)
			(copperpour not_allowed)
			(footprints allowed)
		)
		(placement
			(enabled no)
			(sheetname "")
		)
		(fill yes
			(thermal_gap 0.5)
			(thermal_bridge_width 0.5)
			(island_removal_mode 0)
		)
		(polygon
			(pts
				(arc
					(start 156.222954 -49.273714)
					(mid 155.372308 -48.424591)
					(end 154.521662 -49.273714)
				)
				(xy 154.521408 -49.273714) (xy 154.521408 -50.998374)
				(arc
					(start 154.52217 -50.998374)
					(mid 155.383867 -51.821198)
					(end 156.222954 -50.97526)
				)
				(xy 156.222954 -50.96637)
			)
		)
	)
	(zone
		(layer "In7.Cu")
		(hatch none 0.5)
		(connect_pads
			(clearance 0)
		)
		(min_thickness 0.25)
		(keepout
			(tracks allowed)
			(vias allowed)
			(pads allowed)
			(copperpour allowed)
			(footprints allowed)
		)
		(placement
			(enabled no)
			(sheetname "")
		)
		(fill
			(thermal_gap 0.5)
			(thermal_bridge_width 0.5)
			(island_removal_mode 0)
		)
		(polygon
			(pts
				(xy 80.002126 -33.418018) (xy 83.800188 -33.418018) (xy 84.679282 -33.418018) (xy 84.90458 -33.19272)
				(xy 84.90458 -32.374078) (xy 84.051902 -31.5214) (xy 84.051902 -29.97708) (xy 84.009738 -29.934916)
				(xy 79.981044 -29.934916) (xy 79.666338 -30.249622) (xy 79.666338 -33.08223)
			)
		)
	)
	(zone
		(layer "In7.Cu")
		(hatch none 0.5)
		(connect_pads
			(clearance 0)
		)
		(min_thickness 0.25)
		(keepout
			(tracks allowed)
			(vias allowed)
			(pads allowed)
			(copperpour allowed)
			(footprints allowed)
		)
		(placement
			(enabled no)
			(sheetname "")
		)
		(fill
			(thermal_gap 0.5)
			(thermal_bridge_width 0.5)
			(island_removal_mode 0)
		)
		(polygon
			(pts
				(xy 96.3295 -30.201616) (xy 95.558864 -30.201616) (xy 95.244158 -30.516322) (xy 95.244158 -31.74746)
				(xy 95.510096 -32.013144) (xy 96.39046 -32.013144) (xy 96.697292 -31.706312) (xy 96.697292 -30.569408)
			)
		)
	)
	(zone
		(layer "In7.Cu")
		(hatch none 0.5)
		(connect_pads
			(clearance 0)
		)
		(min_thickness 0.25)
		(keepout
			(tracks allowed)
			(vias allowed)
			(pads allowed)
			(copperpour allowed)
			(footprints allowed)
		)
		(placement
			(enabled no)
			(sheetname "")
		)
		(fill
			(thermal_gap 0.5)
			(thermal_bridge_width 0.5)
			(island_removal_mode 0)
		)
		(polygon
			(pts
				(xy 62.923928 -59.017662) (xy 66.72199 -59.017662) (xy 66.973704 -58.765948) (xy 66.973704 -55.576724)
				(xy 66.93154 -55.53456) (xy 62.902846 -55.53456) (xy 62.58814 -55.849266) (xy 62.58814 -58.681874)
			)
		)
	)
	(zone
		(layer "In7.Cu")
		(hatch none 0.5)
		(connect_pads
			(clearance 0)
		)
		(min_thickness 0.25)
		(keepout
			(tracks allowed)
			(vias allowed)
			(pads allowed)
			(copperpour allowed)
			(footprints allowed)
		)
		(placement
			(enabled no)
			(sheetname "")
		)
		(fill
			(thermal_gap 0.5)
			(thermal_bridge_width 0.5)
			(island_removal_mode 0)
		)
		(polygon
			(pts
				(xy 101.94544 -33.87852) (xy 101.94544 -32.47644) (xy 101.61778 -32.14878) (xy 99.42322 -32.14878)
				(xy 99.056698 -32.515302) (xy 99.056698 -33.79724) (xy 99.435158 -34.1757) (xy 101.64826 -34.1757)
			)
		)
	)
	(zone
		(layer "In7.Cu")
		(hatch none 0.5)
		(connect_pads
			(clearance 0)
		)
		(min_thickness 0.25)
		(keepout
			(tracks allowed)
			(vias allowed)
			(pads allowed)
			(copperpour allowed)
			(footprints allowed)
		)
		(placement
			(enabled no)
			(sheetname "")
		)
		(fill
			(thermal_gap 0.5)
			(thermal_bridge_width 0.5)
			(island_removal_mode 0)
		)
		(polygon
			(pts
				(xy 88.282526 -34.093658) (xy 92.080588 -34.093658) (xy 92.659962 -34.093658) (xy 93.16212 -33.5915)
				(xy 93.16212 -32.125412) (xy 93.211396 -32.125412) (xy 93.71203 -31.624778) (xy 93.71203 -31.233364)
				(xy 93.539056 -31.06039) (xy 93.26245 -31.06039) (xy 93.16212 -30.96006) (xy 92.57792 -30.37586)
				(xy 87.27186 -30.37586) (xy 86.995 -30.65272) (xy 86.995 -31.636462) (xy 87.946738 -32.5882) (xy 87.946738 -33.75787)
			)
		)
	)
	(zone
		(layer "In7.Cu")
		(hatch none 0.5)
		(connect_pads
			(clearance 0)
		)
		(min_thickness 0.25)
		(keepout
			(tracks allowed)
			(vias allowed)
			(pads allowed)
			(copperpour allowed)
			(footprints allowed)
		)
		(placement
			(enabled no)
			(sheetname "")
		)
		(fill
			(thermal_gap 0.5)
			(thermal_bridge_width 0.5)
			(island_removal_mode 0)
		)
		(polygon
			(pts
				(xy 67.576446 -30.465522) (xy 67.576446 -31.314644) (xy 67.751706 -31.489904) (xy 68.978018 -31.489904)
				(xy 69.457062 -31.489904) (xy 69.457062 -30.406594) (xy 68.902326 -30.406594) (xy 68.883784 -30.425136)
				(xy 67.616832 -30.425136)
			)
		)
	)
	(zone
		(layer "In7.Cu")
		(hatch none 0.5)
		(connect_pads
			(clearance 0)
		)
		(min_thickness 0.25)
		(keepout
			(tracks allowed)
			(vias allowed)
			(pads allowed)
			(copperpour allowed)
			(footprints allowed)
		)
		(placement
			(enabled no)
			(sheetname "")
		)
		(fill
			(thermal_gap 0.5)
			(thermal_bridge_width 0.5)
			(island_removal_mode 0)
		)
		(polygon
			(pts
				(xy 43.482006 -33.009078) (xy 47.280068 -33.009078) (xy 47.531782 -32.757364) (xy 47.531782 -29.56814)
				(xy 47.489618 -29.525976) (xy 43.460924 -29.525976) (xy 43.146218 -29.840682) (xy 43.146218 -32.67329)
			)
		)
	)
	(zone
		(layer "In7.Cu")
		(hatch none 0.5)
		(connect_pads
			(clearance 0)
		)
		(min_thickness 0.25)
		(keepout
			(tracks allowed)
			(vias allowed)
			(pads allowed)
			(copperpour allowed)
			(footprints allowed)
		)
		(placement
			(enabled no)
			(sheetname "")
		)
		(fill
			(thermal_gap 0.5)
			(thermal_bridge_width 0.5)
			(island_removal_mode 0)
		)
		(polygon
			(pts
				(xy 76.760832 -139.389358) (xy 77.29982 -139.389358) (xy 77.340206 -139.348972) (xy 77.340206 -138.183112)
				(xy 77.279754 -138.12266) (xy 76.747116 -138.12266) (xy 76.605892 -138.263884) (xy 76.605892 -139.234418)
			)
		)
	)
	(zone
		(layer "Cmts.User")
		(hatch none 0.5)
		(connect_pads
			(clearance 0)
		)
		(min_thickness 0.25)
		(keepout
			(tracks allowed)
			(vias allowed)
			(pads allowed)
			(copperpour allowed)
			(footprints allowed)
		)
		(placement
			(enabled no)
			(sheetname "")
		)
		(fill
			(thermal_gap 0.5)
			(thermal_bridge_width 0.5)
			(island_removal_mode 0)
		)
		(polygon
			(pts
				(xy 104.291638 -20.5486) (xy 104.291638 -30.380686) (xy 39.865554 -30.380686) (xy 39.865554 -20.5486)
			)
		)
	)
	(zone
		(layer "Cmts.User")
		(hatch none 0.5)
		(connect_pads
			(clearance 0)
		)
		(min_thickness 0.25)
		(keepout
			(tracks allowed)
			(vias allowed)
			(pads allowed)
			(copperpour allowed)
			(footprints allowed)
		)
		(placement
			(enabled no)
			(sheetname "")
		)
		(fill
			(thermal_gap 0.5)
			(thermal_bridge_width 0.5)
			(island_removal_mode 0)
		)
		(polygon
			(pts
				(xy 76.61402 -119.508016) (xy 77.5716 -119.508016) (xy 77.5716 -121.1707) (xy 76.61402 -121.1707)
			)
		)
	)
	(zone
		(layer "Cmts.User")
		(hatch none 0.5)
		(connect_pads
			(clearance 0)
		)
		(min_thickness 0.25)
		(keepout
			(tracks allowed)
			(vias allowed)
			(pads allowed)
			(copperpour allowed)
			(footprints allowed)
		)
		(placement
			(enabled no)
			(sheetname "")
		)
		(fill
			(thermal_gap 0.5)
			(thermal_bridge_width 0.5)
			(island_removal_mode 0)
		)
		(polygon
			(pts
				(xy 48.10506 -133.65734) (xy 48.10506 -138.61796) (xy 48.10506 -139.62126) (xy 47.227744 -140.498576)
				(xy 46.224444 -140.498576) (xy 44.78528 -140.498576) (xy 43.170856 -142.113) (xy 42.84726 -142.113)
				(xy 42.76598 -142.113) (xy 41.05402 -140.40104) (xy 41.05402 -137.91946) (xy 39.02456 -135.89) (xy 39.02456 -134.64286)
				(xy 40.23614 -133.43128) (xy 40.23614 -129.45618) (xy 41.60774 -128.08458) (xy 45.86986 -128.08458)
				(xy 47.30496 -129.51968) (xy 47.30496 -130.37058) (xy 47.30496 -132.85724)
			)
		)
	)
	(zone
		(layer "Cmts.User")
		(hatch none 0.5)
		(connect_pads
			(clearance 0)
		)
		(min_thickness 0.25)
		(keepout
			(tracks allowed)
			(vias allowed)
			(pads allowed)
			(copperpour allowed)
			(footprints allowed)
		)
		(placement
			(enabled no)
			(sheetname "")
		)
		(fill
			(thermal_gap 0.5)
			(thermal_bridge_width 0.5)
			(island_removal_mode 0)
		)
		(polygon
			(pts
				(xy -20.702778 -156.860494) (xy -13.184378 -156.860494) (xy -13.184378 -170.297094) (xy -20.702778 -170.297094)
			)
		)
	)
	(zone
		(layer "Cmts.User")
		(hatch none 0.5)
		(connect_pads
			(clearance 0)
		)
		(min_thickness 0.25)
		(keepout
			(tracks allowed)
			(vias allowed)
			(pads allowed)
			(copperpour allowed)
			(footprints allowed)
		)
		(placement
			(enabled no)
			(sheetname "")
		)
		(fill
			(thermal_gap 0.5)
			(thermal_bridge_width 0.5)
			(island_removal_mode 0)
		)
		(polygon
			(pts
				(xy 73.81748 -86.97214) (xy 73.81748 -91.99372) (xy 70.45452 -91.99372) (xy 68.99529 -93.45295)
				(xy 65.201546 -93.45295) (xy 55.042816 -93.45295) (xy 54.064408 -92.474542) (xy 54.064408 -91.99372)
				(xy 39.27348 -91.99372) (xy 39.27348 -70.2056) (xy 38.04158 -68.9737) (xy 38.04158 -66.9671) (xy 37.11956 -66.04508)
				(xy 35.90798 -66.04508) (xy 34.80308 -64.94018) (xy 34.80308 -63.87338) (xy 35.39744 -63.27902)
				(xy 38.37178 -63.27902) (xy 39.27348 -62.37732) (xy 39.27348 -60.962032) (xy 39.27348 -59.304682)
				(xy 40.046402 -58.53176) (xy 41.72204 -58.53176) (xy 43.07078 -57.18302) (xy 56.1213 -57.18302)
				(xy 57.00141 -58.06313) (xy 67.879214 -58.06313) (xy 68.579238 -57.363106) (xy 70.263512 -57.363106)
				(xy 70.55104 -57.650634) (xy 70.55104 -57.85866) (xy 71.22414 -58.53176) (xy 77.465682 -58.53176)
				(xy 78.731872 -59.79795) (xy 78.731872 -62.598808) (xy 78.731872 -77.423772) (xy 76.116942 -80.038702)
				(xy 76.116942 -84.672678)
			)
		)
	)
	(zone
		(layer "Cmts.User")
		(hatch none 0.5)
		(connect_pads
			(clearance 0)
		)
		(min_thickness 0.25)
		(keepout
			(tracks allowed)
			(vias allowed)
			(pads allowed)
			(copperpour allowed)
			(footprints allowed)
		)
		(placement
			(enabled no)
			(sheetname "")
		)
		(fill
			(thermal_gap 0.5)
			(thermal_bridge_width 0.5)
			(island_removal_mode 0)
		)
		(polygon
			(pts
				(xy 58.287666 -125.378718) (xy 70.35292 -125.378718) (xy 70.367906 -125.363732) (xy 72.347328 -125.363732)
				(xy 72.36206 -125.378718) (xy 75.305666 -125.378718) (xy 75.305666 -142.269718) (xy 75.305666 -144.403318)
				(xy 61.19368 -144.403318) (xy 60.159138 -145.43786) (xy 57.264808 -145.43786) (xy 56.230266 -144.403318)
				(xy 56.230266 -141.8463) (xy 54.730396 -140.34643) (xy 54.730396 -139.045696) (xy 54.730396 -127.362966)
				(xy 56.230266 -125.863096) (xy 56.230266 -125.378718)
			)
		)
	)
)
